(kicad_pcb
	(version 20260206)
	(generator "pcbnew")
	(generator_version "10.0")
	(general
		(thickness 1.6)
		(legacy_teardrops no)
	)
	(paper "A4")
	(layers
		(0 "F.Cu" signal "TOP")
		(4 "In1.Cu" signal "L2GND")
		(6 "In2.Cu" signal "L3")
		(8 "In3.Cu" signal "L4VCC")
		(10 "In4.Cu" signal "L5VCC")
		(12 "In5.Cu" signal "L6")
		(14 "In6.Cu" signal "L7GND")
		(2 "B.Cu" signal "BOTTOM")
		(9 "F.Adhes" user "F.Adhesive")
		(11 "B.Adhes" user "B.Adhesive")
		(13 "F.Paste" user "Package Geometry/Pastemask Top")
		(15 "B.Paste" user "Package Geometry/Pastemask Bottom")
		(5 "F.SilkS" user "Ref Des/Silkscreen Top")
		(7 "B.SilkS" user "Ref Des/Silkscreen Bottom")
		(1 "F.Mask" user "Board Geometry/Soldermask Top")
		(3 "B.Mask" user "Board Geometry/Soldermask Bottom")
		(17 "Dwgs.User" user "User.Drawings")
		(19 "Cmts.User" user "User.Comments")
		(21 "Eco1.User" user "User.Eco1")
		(23 "Eco2.User" user "User.Eco2")
		(25 "Edge.Cuts" user "Board Geometry/Outline")
		(27 "Margin" user)
		(31 "F.CrtYd" user "Package Geometry/Place Bound Top")
		(29 "B.CrtYd" user "Package Geometry/Place Bound Bottom")
		(35 "F.Fab" user "Ref Des/Assembly Top")
		(33 "B.Fab" user "Ref Des/Assembly Bottom")
	)
	(setup
		(pad_to_mask_clearance 0)
		(allow_soldermask_bridges_in_footprints no)
		(tenting
			(front yes)
			(back yes)
		)
		(covering
			(front no)
			(back no)
		)
		(plugging
			(front no)
			(back no)
		)
		(capping no)
		(filling no)
		(pcbplotparams
			(layerselection 0x00000000_00000000_55555555_5755f5ff)
			(plot_on_all_layers_selection 0x00000000_00000000_00000000_00000000)
			(disableapertmacros no)
			(usegerberextensions no)
			(usegerberattributes yes)
			(usegerberadvancedattributes yes)
			(creategerberjobfile yes)
			(dashed_line_dash_ratio 12)
			(dashed_line_gap_ratio 3)
			(svgprecision 4)
			(plotframeref no)
			(mode 1)
			(useauxorigin no)
			(pdf_front_fp_property_popups yes)
			(pdf_back_fp_property_popups yes)
			(pdf_metadata yes)
			(pdf_single_document no)
			(dxfpolygonmode yes)
			(dxfimperialunits yes)
			(dxfusepcbnewfont yes)
			(psnegative no)
			(psa4output no)
			(plot_black_and_white yes)
			(sketchpadsonfab no)
			(plotpadnumbers no)
			(hidednponfab no)
			(sketchdnponfab yes)
			(crossoutdnponfab yes)
			(subtractmaskfromsilk no)
			(outputformat 1)
			(mirror no)
			(drillshape 1)
			(scaleselection 1)
			(outputdirectory "")
		)
	)
	(footprint ""
		(layer "F.Cu")
		(at 20.642326 -131.34086 90)
		(property "Reference" "R357"
			(at 0 0 90)
			(layer "F.SilkS")
			(hide yes)
			(effects
				(font
					(size 1.27 1.27)
				)
			)
		)
		(property "Value" "3K3R2F-2-GP"
			(at 0.064008 -3.993896 90)
			(unlocked yes)
			(layer "F.Fab")
			(hide yes)
			(effects
				(font
					(size 1.016 1.016)
					(thickness 0.1524)
				)
			)
		)
		(property "Device Type" "R402H16"
			(at 0.064008 -5.517896 90)
			(unlocked yes)
			(layer "F.Fab")
			(hide yes)
			(effects
				(font
					(size 1.016 1.016)
					(thickness 0.1524)
				)
			)
		)
		(duplicate_pad_numbers_are_jumpers no)
		(fp_line
			(start 0.508 -0.9398)
			(end -0.508 -0.9398)
			(stroke
				(width 0.1524)
				(type default)
			)
			(layer "F.SilkS")
		)
		(fp_line
			(start -0.508 -0.9398)
			(end -0.508 0.9398)
			(stroke
				(width 0.1524)
				(type default)
			)
			(layer "F.SilkS")
		)
		(fp_rect
			(start -0.508 0.9398)
			(end 0.508 -0.9398)
			(stroke
				(width 0)
				(type default)
			)
			(fill no)
			(layer "F.CrtYd")
		)
		(fp_rect
			(start -0.508 0.9398)
			(end 0.508 -0.9398)
			(stroke
				(width 0)
				(type default)
			)
			(fill no)
			(layer "F.Fab")
		)
		(pad "1" smd custom
			(at 0 -0.4445 90)
			(size 0.1397 0.1397)
			(layers "F.Cu" "F.Mask" "F.Paste")
			(net "P3V3_STBY")
			(options
				(clearance outline)
				(anchor circle)
			)
			(primitives
				(gr_poly
					(pts
						(arc
							(start -0.1778 -0.2794)
							(mid -0.249642 -0.249642)
							(end -0.2794 -0.1778)
						)
						(arc
							(start -0.2794 0.1778)
							(mid -0.249642 0.249642)
							(end -0.1778 0.2794)
						)
						(arc
							(start 0.1778 0.2794)
							(mid 0.249642 0.249642)
							(end 0.2794 0.1778)
						)
						(arc
							(start 0.2794 -0.1778)
							(mid 0.249642 -0.249642)
							(end 0.1778 -0.2794)
						)
					)
					(width 0)
					(fill yes)
				)
			)
		)
		(pad "2" smd custom
			(at 0 0.4445 90)
			(size 0.1397 0.1397)
			(layers "F.Cu" "F.Mask" "F.Paste")
			(net "ROMA20")
			(options
				(clearance outline)
				(anchor circle)
			)
			(primitives
				(gr_poly
					(pts
						(arc
							(start -0.1778 -0.2794)
							(mid -0.249642 -0.249642)
							(end -0.2794 -0.1778)
						)
						(arc
							(start -0.2794 0.1778)
							(mid -0.249642 0.249642)
							(end -0.1778 0.2794)
						)
						(arc
							(start 0.1778 0.2794)
							(mid 0.249642 0.249642)
							(end 0.2794 0.1778)
						)
						(arc
							(start 0.2794 -0.1778)
							(mid 0.249642 -0.249642)
							(end 0.1778 -0.2794)
						)
					)
					(width 0)
					(fill yes)
				)
			)
		)
	)
	(footprint ""
		(layer "F.Cu")
		(at 205.3844 -25.0698 90)
		(property "Reference" "R2968"
			(at 0 0 90)
			(layer "F.SilkS")
			(hide yes)
			(effects
				(font
					(size 1.27 1.27)
				)
			)
		)
		(property "Value" "0R2J-2-GP"
			(at 0.064008 -3.993896 90)
			(unlocked yes)
			(layer "F.Fab")
			(hide yes)
			(effects
				(font
					(size 1.016 1.016)
					(thickness 0.1524)
				)
			)
		)
		(property "Device Type" "R402H16"
			(at 0.064008 -5.517896 90)
			(unlocked yes)
			(layer "F.Fab")
			(hide yes)
			(effects
				(font
					(size 1.016 1.016)
					(thickness 0.1524)
				)
			)
		)
		(duplicate_pad_numbers_are_jumpers no)
		(fp_line
			(start 0.508 -0.9398)
			(end -0.508 -0.9398)
			(stroke
				(width 0.1524)
				(type default)
			)
			(layer "F.SilkS")
		)
		(fp_line
			(start -0.508 -0.9398)
			(end -0.508 0.9398)
			(stroke
				(width 0.1524)
				(type default)
			)
			(layer "F.SilkS")
		)
		(fp_rect
			(start -0.508 0.9398)
			(end 0.508 -0.9398)
			(stroke
				(width 0)
				(type default)
			)
			(fill no)
			(layer "F.CrtYd")
		)
		(fp_rect
			(start -0.508 0.9398)
			(end 0.508 -0.9398)
			(stroke
				(width 0)
				(type default)
			)
			(fill no)
			(layer "F.Fab")
		)
		(pad "1" smd custom
			(at 0 -0.4445 90)
			(size 0.1397 0.1397)
			(layers "F.Cu" "F.Mask" "F.Paste")
			(net "U56_SDA")
			(options
				(clearance outline)
				(anchor circle)
			)
			(primitives
				(gr_poly
					(pts
						(arc
							(start -0.1778 -0.2794)
							(mid -0.249642 -0.249642)
							(end -0.2794 -0.1778)
						)
						(arc
							(start -0.2794 0.1778)
							(mid -0.249642 0.249642)
							(end -0.1778 0.2794)
						)
						(arc
							(start 0.1778 0.2794)
							(mid 0.249642 0.249642)
							(end 0.2794 0.1778)
						)
						(arc
							(start 0.2794 -0.1778)
							(mid 0.249642 -0.249642)
							(end 0.1778 -0.2794)
						)
					)
					(width 0)
					(fill yes)
				)
			)
		)
		(pad "2" smd custom
			(at 0 0.4445 90)
			(size 0.1397 0.1397)
			(layers "F.Cu" "F.Mask" "F.Paste")
			(net "BMC_I2C8_CLKBUF1_SDA")
			(options
				(clearance outline)
				(anchor circle)
			)
			(primitives
				(gr_poly
					(pts
						(arc
							(start -0.1778 -0.2794)
							(mid -0.249642 -0.249642)
							(end -0.2794 -0.1778)
						)
						(arc
							(start -0.2794 0.1778)
							(mid -0.249642 0.249642)
							(end -0.1778 0.2794)
						)
						(arc
							(start 0.1778 0.2794)
							(mid 0.249642 0.249642)
							(end 0.2794 0.1778)
						)
						(arc
							(start 0.2794 -0.1778)
							(mid 0.249642 -0.249642)
							(end 0.1778 -0.2794)
						)
					)
					(width 0)
					(fill yes)
				)
			)
		)
	)
	(footprint ""
		(layer "F.Cu")
		(at 204.208126 -212.420454 180)
		(property "Reference" "C114"
			(at 0 0 180)
			(layer "F.SilkS")
			(hide yes)
			(effects
				(font
					(size 1.27 1.27)
				)
			)
		)
		(property "Value" "SCD22U10V2KX-1GP"
			(at 1.1811 -2.7051 180)
			(unlocked yes)
			(layer "F.Fab")
			(hide yes)
			(effects
				(font
					(size 1.016 1.016)
					(thickness 0.1524)
				)
			)
		)
		(property "Device Type" "C402H22"
			(at 1.1811 -4.2291 180)
			(unlocked yes)
			(layer "F.Fab")
			(hide yes)
			(effects
				(font
					(size 1.016 1.016)
					(thickness 0.1524)
				)
			)
		)
		(duplicate_pad_numbers_are_jumpers no)
		(fp_rect
			(start -0.4318 0.9525)
			(end 0.4318 -0.9525)
			(stroke
				(width 0)
				(type default)
			)
			(fill no)
			(layer "F.CrtYd")
		)
		(fp_rect
			(start -0.4318 0.9525)
			(end 0.4318 -0.9525)
			(stroke
				(width 0)
				(type default)
			)
			(fill no)
			(layer "F.Fab")
		)
		(pad "1" smd custom
			(at 0 -0.4445 180)
			(size 0.1524 0.1524)
			(layers "F.Cu" "F.Mask" "F.Paste")
			(net "PCIE_TX_CAP_N41")
			(options
				(clearance outline)
				(anchor circle)
			)
			(primitives
				(gr_poly
					(pts
						(arc
							(start 0.3048 -0.2032)
							(mid 0.275042 -0.275042)
							(end 0.2032 -0.3048)
						)
						(arc
							(start -0.2032 -0.3048)
							(mid -0.275042 -0.275042)
							(end -0.3048 -0.2032)
						)
						(arc
							(start -0.3048 0.2032)
							(mid -0.275042 0.275042)
							(end -0.2032 0.3048)
						)
						(arc
							(start 0.2032 0.3048)
							(mid 0.275042 0.275042)
							(end 0.3048 0.2032)
						)
					)
					(width 0)
					(fill yes)
				)
			)
		)
		(pad "2" smd custom
			(at 0 0.4445 180)
			(size 0.1524 0.1524)
			(layers "F.Cu" "F.Mask" "F.Paste")
			(net "PCIE_TX_N41")
			(options
				(clearance outline)
				(anchor circle)
			)
			(primitives
				(gr_poly
					(pts
						(arc
							(start 0.3048 -0.2032)
							(mid 0.275042 -0.275042)
							(end 0.2032 -0.3048)
						)
						(arc
							(start -0.2032 -0.3048)
							(mid -0.275042 -0.275042)
							(end -0.3048 -0.2032)
						)
						(arc
							(start -0.3048 0.2032)
							(mid -0.275042 0.275042)
							(end -0.2032 0.3048)
						)
						(arc
							(start 0.2032 0.3048)
							(mid 0.275042 0.275042)
							(end 0.3048 0.2032)
						)
					)
					(width 0)
					(fill yes)
				)
			)
		)
	)
	(footprint ""
		(layer "F.Cu")
		(at 310.374792 -33.555686)
		(property "Reference" "C19"
			(at 0 0 0)
			(layer "F.SilkS")
			(hide yes)
			(effects
				(font
					(size 1.27 1.27)
				)
			)
		)
		(property "Value" "SCD22U10V2KX-1GP"
			(at 1.1811 -2.7051 0)
			(unlocked yes)
			(layer "F.Fab")
			(hide yes)
			(effects
				(font
					(size 1.016 1.016)
					(thickness 0.1524)
				)
			)
		)
		(property "Device Type" "C402H22"
			(at 1.1811 -4.2291 0)
			(unlocked yes)
			(layer "F.Fab")
			(hide yes)
			(effects
				(font
					(size 1.016 1.016)
					(thickness 0.1524)
				)
			)
		)
		(duplicate_pad_numbers_are_jumpers no)
		(fp_rect
			(start -0.4318 0.9525)
			(end 0.4318 -0.9525)
			(stroke
				(width 0)
				(type default)
			)
			(fill no)
			(layer "F.CrtYd")
		)
		(fp_rect
			(start -0.4318 0.9525)
			(end 0.4318 -0.9525)
			(stroke
				(width 0)
				(type default)
			)
			(fill no)
			(layer "F.Fab")
		)
		(pad "1" smd custom
			(at 0 -0.4445)
			(size 0.1524 0.1524)
			(layers "F.Cu" "F.Mask" "F.Paste")
			(net "PCIE_TX_CAP_P9")
			(options
				(clearance outline)
				(anchor circle)
			)
			(primitives
				(gr_poly
					(pts
						(arc
							(start 0.3048 -0.2032)
							(mid 0.275042 -0.275042)
							(end 0.2032 -0.3048)
						)
						(arc
							(start -0.2032 -0.3048)
							(mid -0.275042 -0.275042)
							(end -0.3048 -0.2032)
						)
						(arc
							(start -0.3048 0.2032)
							(mid -0.275042 0.275042)
							(end -0.2032 0.3048)
						)
						(arc
							(start 0.2032 0.3048)
							(mid 0.275042 0.275042)
							(end 0.3048 0.2032)
						)
					)
					(width 0)
					(fill yes)
				)
			)
		)
		(pad "2" smd custom
			(at 0 0.4445)
			(size 0.1524 0.1524)
			(layers "F.Cu" "F.Mask" "F.Paste")
			(net "PCIE_TX_P9")
			(options
				(clearance outline)
				(anchor circle)
			)
			(primitives
				(gr_poly
					(pts
						(arc
							(start 0.3048 -0.2032)
							(mid 0.275042 -0.275042)
							(end 0.2032 -0.3048)
						)
						(arc
							(start -0.2032 -0.3048)
							(mid -0.275042 -0.275042)
							(end -0.3048 -0.2032)
						)
						(arc
							(start -0.3048 0.2032)
							(mid -0.275042 0.275042)
							(end -0.2032 0.3048)
						)
						(arc
							(start 0.2032 0.3048)
							(mid 0.275042 0.275042)
							(end 0.3048 0.2032)
						)
					)
					(width 0)
					(fill yes)
				)
			)
		)
	)
	(footprint ""
		(layer "F.Cu")
		(at 53.756052 -110.19663 90)
		(property "Reference" "U37"
			(at 0 0 90)
			(layer "F.SilkS")
			(hide yes)
			(effects
				(font
					(size 1.27 1.27)
				)
			)
		)
		(property "Value" "2N7002DW-7F-GP"
			(at -2.3622 -8.2042 90)
			(unlocked yes)
			(layer "F.Fab")
			(hide yes)
			(effects
				(font
					(size 1.016 1.016)
					(thickness 0.1524)
				)
			)
		)
		(property "Device Type" "SOT-363H44"
			(at -2.3622 -10.1092 90)
			(unlocked yes)
			(layer "F.Fab")
			(hide yes)
			(effects
				(font
					(size 1.016 1.016)
					(thickness 0.1524)
				)
			)
		)
		(duplicate_pad_numbers_are_jumpers no)
		(fp_line
			(start 1.4478 -1.7018)
			(end -1.4478 -1.7018)
			(stroke
				(width 0.1524)
				(type default)
			)
			(layer "F.SilkS")
		)
		(fp_line
			(start -1.4478 -1.7018)
			(end -1.4478 1.7018)
			(stroke
				(width 0.1524)
				(type default)
			)
			(layer "F.SilkS")
		)
		(fp_line
			(start -1.27 1.524)
			(end -1.27 0.6604)
			(stroke
				(width 0.4826)
				(type default)
			)
			(layer "F.SilkS")
		)
		(fp_line
			(start 1.4478 1.7018)
			(end 1.4478 -1.7018)
			(stroke
				(width 0.1524)
				(type default)
			)
			(layer "F.SilkS")
		)
		(fp_line
			(start -1.4478 1.7018)
			(end 1.4478 1.7018)
			(stroke
				(width 0.1524)
				(type default)
			)
			(layer "F.SilkS")
		)
		(fp_poly
			(pts
				(xy -1.524 -1.778) (xy 1.524 -1.778) (xy 1.524 1.778) (xy -1.524 1.778)
			)
			(stroke
				(width 0)
				(type default)
			)
			(fill no)
			(layer "F.CrtYd")
		)
		(fp_poly
			(pts
				(xy -1.524 -1.778) (xy 1.524 -1.778) (xy 1.524 1.778) (xy -1.524 1.778)
			)
			(stroke
				(width 0)
				(type default)
			)
			(fill no)
			(layer "F.Fab")
		)
		(pad "1" smd rect
			(at -0.65024 0.9398 90)
			(size 0.4064 1.016)
			(layers "F.Cu" "F.Mask" "F.Paste")
			(net "BMC_I2C13_MINI7_SCL_S")
		)
		(pad "2" smd rect
			(at 0 0.9398 90)
			(size 0.4064 1.016)
			(layers "F.Cu" "F.Mask" "F.Paste")
			(net "I2C7_LS_G2")
		)
		(pad "3" smd rect
			(at 0.65024 0.9398 90)
			(size 0.4064 1.016)
			(layers "F.Cu" "F.Mask" "F.Paste")
			(net "BMC_I2C13_MINI7_SDA")
		)
		(pad "4" smd rect
			(at 0.65024 -0.9398 90)
			(size 0.4064 1.016)
			(layers "F.Cu" "F.Mask" "F.Paste")
			(net "BMC_I2C13_MINI7_SDA_S")
		)
		(pad "5" smd rect
			(at 0 -0.9398 90)
			(size 0.4064 1.016)
			(layers "F.Cu" "F.Mask" "F.Paste")
			(net "I2C7_LS_G1")
		)
		(pad "6" smd rect
			(at -0.65024 -0.9398 90)
			(size 0.4064 1.016)
			(layers "F.Cu" "F.Mask" "F.Paste")
			(net "BMC_I2C13_MINI7_SCL")
		)
	)
	(footprint ""
		(layer "F.Cu")
		(at 316.606936 -36.885118 90)
		(property "Reference" "R254"
			(at 0 0 90)
			(layer "F.SilkS")
			(hide yes)
			(effects
				(font
					(size 1.27 1.27)
				)
			)
		)
		(property "Value" "4K7R2F-GP"
			(at 0.064008 -3.993896 90)
			(unlocked yes)
			(layer "F.Fab")
			(hide yes)
			(effects
				(font
					(size 1.016 1.016)
					(thickness 0.1524)
				)
			)
		)
		(property "Device Type" "R402H16"
			(at 0.064008 -5.517896 90)
			(unlocked yes)
			(layer "F.Fab")
			(hide yes)
			(effects
				(font
					(size 1.016 1.016)
					(thickness 0.1524)
				)
			)
		)
		(duplicate_pad_numbers_are_jumpers no)
		(fp_line
			(start 0.508 -0.9398)
			(end -0.508 -0.9398)
			(stroke
				(width 0.1524)
				(type default)
			)
			(layer "F.SilkS")
		)
		(fp_line
			(start -0.508 -0.9398)
			(end -0.508 0.9398)
			(stroke
				(width 0.1524)
				(type default)
			)
			(layer "F.SilkS")
		)
		(fp_rect
			(start -0.508 0.9398)
			(end 0.508 -0.9398)
			(stroke
				(width 0)
				(type default)
			)
			(fill no)
			(layer "F.CrtYd")
		)
		(fp_rect
			(start -0.508 0.9398)
			(end 0.508 -0.9398)
			(stroke
				(width 0)
				(type default)
			)
			(fill no)
			(layer "F.Fab")
		)
		(pad "1" smd custom
			(at 0 -0.4445 90)
			(size 0.1397 0.1397)
			(layers "F.Cu" "F.Mask" "F.Paste")
			(net "P3V3_STBY")
			(options
				(clearance outline)
				(anchor circle)
			)
			(primitives
				(gr_poly
					(pts
						(arc
							(start -0.1778 -0.2794)
							(mid -0.249642 -0.249642)
							(end -0.2794 -0.1778)
						)
						(arc
							(start -0.2794 0.1778)
							(mid -0.249642 0.249642)
							(end -0.1778 0.2794)
						)
						(arc
							(start 0.1778 0.2794)
							(mid 0.249642 0.249642)
							(end 0.2794 0.1778)
						)
						(arc
							(start 0.2794 -0.1778)
							(mid 0.249642 -0.249642)
							(end 0.1778 -0.2794)
						)
					)
					(width 0)
					(fill yes)
				)
			)
		)
		(pad "2" smd custom
			(at 0 0.4445 90)
			(size 0.1397 0.1397)
			(layers "F.Cu" "F.Mask" "F.Paste")
			(net "CLK_P_8_R")
			(options
				(clearance outline)
				(anchor circle)
			)
			(primitives
				(gr_poly
					(pts
						(arc
							(start -0.1778 -0.2794)
							(mid -0.249642 -0.249642)
							(end -0.2794 -0.1778)
						)
						(arc
							(start -0.2794 0.1778)
							(mid -0.249642 0.249642)
							(end -0.1778 0.2794)
						)
						(arc
							(start 0.1778 0.2794)
							(mid 0.249642 0.249642)
							(end 0.2794 0.1778)
						)
						(arc
							(start 0.2794 -0.1778)
							(mid 0.249642 -0.249642)
							(end 0.1778 -0.2794)
						)
					)
					(width 0)
					(fill yes)
				)
			)
		)
	)
	(footprint ""
		(layer "F.Cu")
		(at 26.0604 -77.9018 90)
		(property "Reference" "C632"
			(at 0 0 90)
			(layer "F.SilkS")
			(hide yes)
			(effects
				(font
					(size 1.27 1.27)
				)
			)
		)
		(property "Value" "SCD1U16V2KX-3GP"
			(at 1.1811 -2.7051 90)
			(unlocked yes)
			(layer "F.Fab")
			(hide yes)
			(effects
				(font
					(size 1.016 1.016)
					(thickness 0.1524)
				)
			)
		)
		(property "Device Type" "C402H22"
			(at 1.1811 -4.2291 90)
			(unlocked yes)
			(layer "F.Fab")
			(hide yes)
			(effects
				(font
					(size 1.016 1.016)
					(thickness 0.1524)
				)
			)
		)
		(duplicate_pad_numbers_are_jumpers no)
		(fp_rect
			(start -0.4318 0.9525)
			(end 0.4318 -0.9525)
			(stroke
				(width 0)
				(type default)
			)
			(fill no)
			(layer "F.CrtYd")
		)
		(fp_rect
			(start -0.4318 0.9525)
			(end 0.4318 -0.9525)
			(stroke
				(width 0)
				(type default)
			)
			(fill no)
			(layer "F.Fab")
		)
		(pad "1" smd custom
			(at 0 -0.4445 90)
			(size 0.1524 0.1524)
			(layers "F.Cu" "F.Mask" "F.Paste")
			(net "P3V3_STBY")
			(options
				(clearance outline)
				(anchor circle)
			)
			(primitives
				(gr_poly
					(pts
						(arc
							(start 0.3048 -0.2032)
							(mid 0.275042 -0.275042)
							(end 0.2032 -0.3048)
						)
						(arc
							(start -0.2032 -0.3048)
							(mid -0.275042 -0.275042)
							(end -0.3048 -0.2032)
						)
						(arc
							(start -0.3048 0.2032)
							(mid -0.275042 0.275042)
							(end -0.2032 0.3048)
						)
						(arc
							(start 0.2032 0.3048)
							(mid 0.275042 0.275042)
							(end 0.3048 0.2032)
						)
					)
					(width 0)
					(fill yes)
				)
			)
		)
		(pad "2" smd custom
			(at 0 0.4445 90)
			(size 0.1524 0.1524)
			(layers "F.Cu" "F.Mask" "F.Paste")
			(net "GND")
			(options
				(clearance outline)
				(anchor circle)
			)
			(primitives
				(gr_poly
					(pts
						(arc
							(start 0.3048 -0.2032)
							(mid 0.275042 -0.275042)
							(end 0.2032 -0.3048)
						)
						(arc
							(start -0.2032 -0.3048)
							(mid -0.275042 -0.275042)
							(end -0.3048 -0.2032)
						)
						(arc
							(start -0.3048 0.2032)
							(mid -0.275042 0.275042)
							(end -0.2032 0.3048)
						)
						(arc
							(start 0.2032 0.3048)
							(mid 0.275042 0.275042)
							(end 0.3048 0.2032)
						)
					)
					(width 0)
					(fill yes)
				)
			)
		)
	)
	(footprint ""
		(layer "F.Cu")
		(at 336.68462 -36.705286 180)
		(property "Reference" "Q28"
			(at 0 0 180)
			(layer "F.SilkS")
			(hide yes)
			(effects
				(font
					(size 1.27 1.27)
				)
			)
		)
		(property "Value" "2N7002K-1-GP"
			(at 0.127 -8.9662 180)
			(unlocked yes)
			(layer "F.Fab")
			(hide yes)
			(effects
				(font
					(size 1.016 1.016)
					(thickness 0.1524)
				)
			)
		)
		(property "Device Type" "SOT23DGS2D4H44"
			(at 0.127 -10.4902 180)
			(unlocked yes)
			(layer "F.Fab")
			(hide yes)
			(effects
				(font
					(size 1.016 1.016)
					(thickness 0.1524)
				)
			)
		)
		(duplicate_pad_numbers_are_jumpers no)
		(fp_line
			(start 1.651 1.778)
			(end 1.651 -1.778)
			(stroke
				(width 0.1524)
				(type default)
			)
			(layer "F.SilkS")
		)
		(fp_line
			(start 1.651 -1.778)
			(end -1.651 -1.778)
			(stroke
				(width 0.1524)
				(type default)
			)
			(layer "F.SilkS")
		)
		(fp_line
			(start -1.651 1.778)
			(end 1.651 1.778)
			(stroke
				(width 0.1524)
				(type default)
			)
			(layer "F.SilkS")
		)
		(fp_line
			(start -1.651 -1.778)
			(end -1.651 1.778)
			(stroke
				(width 0.1524)
				(type default)
			)
			(layer "F.SilkS")
		)
		(fp_poly
			(pts
				(xy -1.778 1.8796) (xy -1.778 -1.8796) (xy 1.778 -1.8796) (xy 1.778 1.8796)
			)
			(stroke
				(width 0)
				(type default)
			)
			(fill no)
			(layer "F.CrtYd")
		)
		(fp_poly
			(pts
				(xy -1.778 1.8796) (xy -1.778 -1.8796) (xy 1.778 -1.8796) (xy 1.778 1.8796)
			)
			(stroke
				(width 0)
				(type default)
			)
			(fill no)
			(layer "F.Fab")
		)
		(pad "D" smd custom
			(at 0 -0.9525 180)
			(size 0.1905 0.1905)
			(layers "F.Cu" "F.Mask" "F.Paste")
			(net "LED_Q_7")
			(options
				(clearance outline)
				(anchor circle)
			)
			(primitives
				(gr_poly
					(pts
						(arc
							(start -0.1778 0.5715)
							(mid -0.321484 0.511984)
							(end -0.381 0.3683)
						)
						(arc
							(start -0.381 -0.3683)
							(mid -0.321484 -0.511984)
							(end -0.1778 -0.5715)
						)
						(arc
							(start 0.1778 -0.5715)
							(mid 0.321484 -0.511984)
							(end 0.381 -0.3683)
						)
						(arc
							(start 0.381 0.3683)
							(mid 0.321484 0.511984)
							(end 0.1778 0.5715)
						)
					)
					(width 0)
					(fill yes)
				)
			)
		)
		(pad "G" smd custom
			(at -0.98425 0.9525 180)
			(size 0.1905 0.1905)
			(layers "F.Cu" "F.Mask" "F.Paste")
			(net "UPLINK7_R")
			(options
				(clearance outline)
				(anchor circle)
			)
			(primitives
				(gr_poly
					(pts
						(arc
							(start -0.1778 0.5715)
							(mid -0.321484 0.511984)
							(end -0.381 0.3683)
						)
						(arc
							(start -0.381 -0.3683)
							(mid -0.321484 -0.511984)
							(end -0.1778 -0.5715)
						)
						(arc
							(start 0.1778 -0.5715)
							(mid 0.321484 -0.511984)
							(end 0.381 -0.3683)
						)
						(arc
							(start 0.381 0.3683)
							(mid 0.321484 0.511984)
							(end 0.1778 0.5715)
						)
					)
					(width 0)
					(fill yes)
				)
			)
		)
		(pad "S" smd custom
			(at 0.98425 0.9525 180)
			(size 0.1905 0.1905)
			(layers "F.Cu" "F.Mask" "F.Paste")
			(net "GND")
			(options
				(clearance outline)
				(anchor circle)
			)
			(primitives
				(gr_poly
					(pts
						(arc
							(start -0.1778 0.5715)
							(mid -0.321484 0.511984)
							(end -0.381 0.3683)
						)
						(arc
							(start -0.381 -0.3683)
							(mid -0.321484 -0.511984)
							(end -0.1778 -0.5715)
						)
						(arc
							(start 0.1778 -0.5715)
							(mid 0.321484 -0.511984)
							(end 0.381 -0.3683)
						)
						(arc
							(start 0.381 0.3683)
							(mid 0.321484 0.511984)
							(end 0.1778 0.5715)
						)
					)
					(width 0)
					(fill yes)
				)
			)
		)
	)
	(footprint ""
		(layer "F.Cu")
		(at 125.960124 -196.443092)
		(property "Reference" "R7921"
			(at 0 0 0)
			(layer "F.SilkS")
			(hide yes)
			(effects
				(font
					(size 1.27 1.27)
				)
			)
		)
		(property "Value" "0R2J-2-GP"
			(at 0.064008 -3.993896 0)
			(unlocked yes)
			(layer "F.Fab")
			(hide yes)
			(effects
				(font
					(size 1.016 1.016)
					(thickness 0.1524)
				)
			)
		)
		(property "Device Type" "R402H16"
			(at 0.064008 -5.517896 0)
			(unlocked yes)
			(layer "F.Fab")
			(hide yes)
			(effects
				(font
					(size 1.016 1.016)
					(thickness 0.1524)
				)
			)
		)
		(duplicate_pad_numbers_are_jumpers no)
		(fp_line
			(start -0.508 -0.9398)
			(end -0.508 0.9398)
			(stroke
				(width 0.1524)
				(type default)
			)
			(layer "F.SilkS")
		)
		(fp_line
			(start 0.508 -0.9398)
			(end -0.508 -0.9398)
			(stroke
				(width 0.1524)
				(type default)
			)
			(layer "F.SilkS")
		)
		(fp_rect
			(start -0.508 0.9398)
			(end 0.508 -0.9398)
			(stroke
				(width 0)
				(type default)
			)
			(fill no)
			(layer "F.CrtYd")
		)
		(fp_rect
			(start -0.508 0.9398)
			(end 0.508 -0.9398)
			(stroke
				(width 0)
				(type default)
			)
			(fill no)
			(layer "F.Fab")
		)
		(pad "1" smd custom
			(at 0 -0.4445)
			(size 0.1397 0.1397)
			(layers "F.Cu" "F.Mask" "F.Paste")
			(net "SSD_PRSNT#1")
			(options
				(clearance outline)
				(anchor circle)
			)
			(primitives
				(gr_poly
					(pts
						(arc
							(start -0.1778 -0.2794)
							(mid -0.249642 -0.249642)
							(end -0.2794 -0.1778)
						)
						(arc
							(start -0.2794 0.1778)
							(mid -0.249642 0.249642)
							(end -0.1778 0.2794)
						)
						(arc
							(start 0.1778 0.2794)
							(mid 0.249642 0.249642)
							(end 0.2794 0.1778)
						)
						(arc
							(start 0.2794 -0.1778)
							(mid 0.249642 -0.249642)
							(end 0.1778 -0.2794)
						)
					)
					(width 0)
					(fill yes)
				)
			)
		)
		(pad "2" smd custom
			(at 0 0.4445)
			(size 0.1397 0.1397)
			(layers "F.Cu" "F.Mask" "F.Paste")
			(net "SSD_PRSNT#1_R")
			(options
				(clearance outline)
				(anchor circle)
			)
			(primitives
				(gr_poly
					(pts
						(arc
							(start -0.1778 -0.2794)
							(mid -0.249642 -0.249642)
							(end -0.2794 -0.1778)
						)
						(arc
							(start -0.2794 0.1778)
							(mid -0.249642 0.249642)
							(end -0.1778 0.2794)
						)
						(arc
							(start 0.1778 0.2794)
							(mid 0.249642 0.249642)
							(end 0.2794 0.1778)
						)
						(arc
							(start 0.2794 -0.1778)
							(mid 0.249642 -0.249642)
							(end 0.1778 -0.2794)
						)
					)
					(width 0)
					(fill yes)
				)
			)
		)
	)
	(footprint ""
		(layer "F.Cu")
		(at 38.433756 -81.858358 -90)
		(property "Reference" "R631"
			(at 0 0 270)
			(layer "F.SilkS")
			(hide yes)
			(effects
				(font
					(size 1.27 1.27)
				)
			)
		)
		(property "Value" "47KR2F-GP"
			(at 0.064008 -3.993896 270)
			(unlocked yes)
			(layer "F.Fab")
			(hide yes)
			(effects
				(font
					(size 1.016 1.016)
					(thickness 0.1524)
				)
			)
		)
		(property "Device Type" "R402H16"
			(at 0.064008 -5.517896 270)
			(unlocked yes)
			(layer "F.Fab")
			(hide yes)
			(effects
				(font
					(size 1.016 1.016)
					(thickness 0.1524)
				)
			)
		)
		(duplicate_pad_numbers_are_jumpers no)
		(fp_line
			(start -0.508 -0.9398)
			(end -0.508 0.9398)
			(stroke
				(width 0.1524)
				(type default)
			)
			(layer "F.SilkS")
		)
		(fp_line
			(start 0.508 -0.9398)
			(end -0.508 -0.9398)
			(stroke
				(width 0.1524)
				(type default)
			)
			(layer "F.SilkS")
		)
		(fp_rect
			(start -0.508 0.9398)
			(end 0.508 -0.9398)
			(stroke
				(width 0)
				(type default)
			)
			(fill no)
			(layer "F.CrtYd")
		)
		(fp_rect
			(start -0.508 0.9398)
			(end 0.508 -0.9398)
			(stroke
				(width 0)
				(type default)
			)
			(fill no)
			(layer "F.Fab")
		)
		(pad "1" smd custom
			(at 0 -0.4445 270)
			(size 0.1397 0.1397)
			(layers "F.Cu" "F.Mask" "F.Paste")
			(net "P12V_PCIE")
			(options
				(clearance outline)
				(anchor circle)
			)
			(primitives
				(gr_poly
					(pts
						(arc
							(start -0.1778 -0.2794)
							(mid -0.249642 -0.249642)
							(end -0.2794 -0.1778)
						)
						(arc
							(start -0.2794 0.1778)
							(mid -0.249642 0.249642)
							(end -0.1778 0.2794)
						)
						(arc
							(start 0.1778 0.2794)
							(mid 0.249642 0.249642)
							(end 0.2794 0.1778)
						)
						(arc
							(start 0.2794 -0.1778)
							(mid 0.249642 -0.249642)
							(end 0.1778 -0.2794)
						)
					)
					(width 0)
					(fill yes)
				)
			)
		)
		(pad "2" smd custom
			(at 0 0.4445 270)
			(size 0.1397 0.1397)
			(layers "F.Cu" "F.Mask" "F.Paste")
			(net "Q45_D")
			(options
				(clearance outline)
				(anchor circle)
			)
			(primitives
				(gr_poly
					(pts
						(arc
							(start -0.1778 -0.2794)
							(mid -0.249642 -0.249642)
							(end -0.2794 -0.1778)
						)
						(arc
							(start -0.2794 0.1778)
							(mid -0.249642 0.249642)
							(end -0.1778 0.2794)
						)
						(arc
							(start 0.1778 0.2794)
							(mid 0.249642 0.249642)
							(end 0.2794 0.1778)
						)
						(arc
							(start 0.2794 -0.1778)
							(mid 0.249642 -0.249642)
							(end 0.1778 -0.2794)
						)
					)
					(width 0)
					(fill yes)
				)
			)
		)
	)
	(footprint ""
		(layer "F.Cu")
		(at 310.007 -60.9346)
		(property "Reference" "PG59"
			(at 0 0 0)
			(layer "F.SilkS")
			(hide yes)
			(effects
				(font
					(size 1.27 1.27)
				)
			)
		)
		(property "Value" "GAP-CLOSE-PWR-3-GP"
			(at 0.0254 -6.5786 0)
			(unlocked yes)
			(layer "F.Fab")
			(hide yes)
			(effects
				(font
					(size 1.016 1.016)
					(thickness 0.1524)
				)
			)
		)
		(property "Device Type" "GAP-CLOSE-PWR-3"
			(at 0.0254 -8.255 0)
			(unlocked yes)
			(layer "F.Fab")
			(hide yes)
			(effects
				(font
					(size 1.016 1.016)
					(thickness 0.1524)
				)
			)
		)
		(duplicate_pad_numbers_are_jumpers no)
		(fp_rect
			(start -0.7112 0.4572)
			(end 0.7112 -0.4572)
			(stroke
				(width 0)
				(type default)
			)
			(fill no)
			(layer "F.CrtYd")
		)
		(fp_poly
			(pts
				(xy -0.7112 -0.4572) (xy 0.7112 -0.4572) (xy 0.7112 0.4572) (xy -0.7112 0.4572)
			)
			(stroke
				(width 0)
				(type default)
			)
			(fill no)
			(layer "F.Fab")
		)
		(pad "1" smd rect
			(at -0.3048 0)
			(size 0.6604 0.762)
			(layers "F.Cu" "F.Mask" "F.Paste")
			(net "DUT_VDD")
		)
		(pad "2" smd rect
			(at 0.3048 0)
			(size 0.6604 0.762)
			(layers "F.Cu" "F.Mask" "F.Paste")
			(net "P0V9_E")
		)
	)
	(footprint ""
		(layer "F.Cu")
		(at 32.6136 -210.058 -90)
		(property "Reference" "D37"
			(at 0 0 270)
			(layer "F.SilkS")
			(hide yes)
			(effects
				(font
					(size 1.27 1.27)
				)
			)
		)
		(property "Value" "SMF15A-GP"
			(at -2.0955 1.2192 270)
			(unlocked yes)
			(layer "F.Fab")
			(hide yes)
			(effects
				(font
					(size 1.016 1.016)
					(thickness 0.1524)
				)
			)
		)
		(property "Device Type" "SOD123AK-2H43"
			(at -2.0955 -0.3048 270)
			(unlocked yes)
			(layer "F.Fab")
			(hide yes)
			(effects
				(font
					(size 1.016 1.016)
					(thickness 0.1524)
				)
			)
		)
		(duplicate_pad_numbers_are_jumpers no)
		(fp_line
			(start 1.1557 2.921)
			(end -1.1557 2.921)
			(stroke
				(width 0.508)
				(type default)
			)
			(layer "F.SilkS")
		)
		(fp_line
			(start -1.1557 2.7686)
			(end 1.1557 2.7686)
			(stroke
				(width 0.1524)
				(type default)
			)
			(layer "F.SilkS")
		)
		(fp_line
			(start 1.1557 2.7686)
			(end 1.1557 -2.7686)
			(stroke
				(width 0.1524)
				(type default)
			)
			(layer "F.SilkS")
		)
		(fp_line
			(start -1.1557 -2.7686)
			(end -1.1557 2.7686)
			(stroke
				(width 0.1524)
				(type default)
			)
			(layer "F.SilkS")
		)
		(fp_line
			(start 1.1557 -2.7686)
			(end -1.1557 -2.7686)
			(stroke
				(width 0.1524)
				(type default)
			)
			(layer "F.SilkS")
		)
		(fp_poly
			(pts
				(xy -0.4572 1.8669) (xy -0.4572 1.397) (xy -0.9017 1.397) (xy -0.9017 -1.397) (xy -0.4572 -1.397)
				(xy -0.4572 -1.8669) (xy 0.4572 -1.8669) (xy 0.4572 -1.397) (xy 0.9017 -1.397) (xy 0.9017 1.397)
				(xy 0.4572 1.397) (xy 0.4572 1.8669)
			)
			(stroke
				(width 0)
				(type default)
			)
			(fill no)
			(layer "F.CrtYd")
		)
		(fp_poly
			(pts
				(xy -1.4097 2.8448) (xy -1.4097 -2.8448) (xy 1.4097 -2.8448) (xy 1.4097 1.3716) (xy 0.9017 1.3716)
				(xy 0.9017 -1.397) (xy 0.4572 -1.397) (xy 0.4572 -1.8669) (xy -0.4572 -1.8669) (xy -0.4572 -1.397)
				(xy -0.9017 -1.397) (xy -0.9017 1.397) (xy -0.4572 1.397) (xy -0.4572 1.8669) (xy 0.4572 1.8669)
				(xy 0.4572 1.397) (xy 0.9017 1.397) (xy 0.9017 1.3843) (xy 1.4097 1.3843) (xy 1.4097 2.8448)
			)
			(stroke
				(width 0)
				(type default)
			)
			(fill no)
			(layer "F.CrtYd")
		)
		(fp_rect
			(start -1.4097 2.8448)
			(end 1.4097 -2.8448)
			(stroke
				(width 0)
				(type default)
			)
			(fill no)
			(layer "F.Fab")
		)
		(pad "A" smd rect
			(at 0 -1.75768 270)
			(size 1.143 1.4986)
			(layers "F.Cu" "F.Mask" "F.Paste")
			(net "GND")
		)
		(pad "K" smd rect
			(at 0 1.75768 270)
			(size 1.143 1.4986)
			(layers "F.Cu" "F.Mask" "F.Paste")
			(net "P12V_PCIE")
		)
	)
	(footprint ""
		(layer "F.Cu")
		(at 350.046036 -44.503086)
		(property "Reference" "R689"
			(at 0 0 0)
			(layer "F.SilkS")
			(hide yes)
			(effects
				(font
					(size 1.27 1.27)
				)
			)
		)
		(property "Value" "4K7R2F-GP"
			(at 0.064008 -3.993896 0)
			(unlocked yes)
			(layer "F.Fab")
			(hide yes)
			(effects
				(font
					(size 1.016 1.016)
					(thickness 0.1524)
				)
			)
		)
		(property "Device Type" "R402H16"
			(at 0.064008 -5.517896 0)
			(unlocked yes)
			(layer "F.Fab")
			(hide yes)
			(effects
				(font
					(size 1.016 1.016)
					(thickness 0.1524)
				)
			)
		)
		(duplicate_pad_numbers_are_jumpers no)
		(fp_line
			(start -0.508 -0.9398)
			(end -0.508 0.9398)
			(stroke
				(width 0.1524)
				(type default)
			)
			(layer "F.SilkS")
		)
		(fp_line
			(start 0.508 -0.9398)
			(end -0.508 -0.9398)
			(stroke
				(width 0.1524)
				(type default)
			)
			(layer "F.SilkS")
		)
		(fp_rect
			(start -0.508 0.9398)
			(end 0.508 -0.9398)
			(stroke
				(width 0)
				(type default)
			)
			(fill no)
			(layer "F.CrtYd")
		)
		(fp_rect
			(start -0.508 0.9398)
			(end 0.508 -0.9398)
			(stroke
				(width 0)
				(type default)
			)
			(fill no)
			(layer "F.Fab")
		)
		(pad "1" smd custom
			(at 0 -0.4445)
			(size 0.1397 0.1397)
			(layers "F.Cu" "F.Mask" "F.Paste")
			(net "PE1_PERST#_R")
			(options
				(clearance outline)
				(anchor circle)
			)
			(primitives
				(gr_poly
					(pts
						(arc
							(start -0.1778 -0.2794)
							(mid -0.249642 -0.249642)
							(end -0.2794 -0.1778)
						)
						(arc
							(start -0.2794 0.1778)
							(mid -0.249642 0.249642)
							(end -0.1778 0.2794)
						)
						(arc
							(start 0.1778 0.2794)
							(mid 0.249642 0.249642)
							(end 0.2794 0.1778)
						)
						(arc
							(start 0.2794 -0.1778)
							(mid 0.249642 -0.249642)
							(end 0.1778 -0.2794)
						)
					)
					(width 0)
					(fill yes)
				)
			)
		)
		(pad "2" smd custom
			(at 0 0.4445)
			(size 0.1397 0.1397)
			(layers "F.Cu" "F.Mask" "F.Paste")
			(net "P3V3_STBY")
			(options
				(clearance outline)
				(anchor circle)
			)
			(primitives
				(gr_poly
					(pts
						(arc
							(start -0.1778 -0.2794)
							(mid -0.249642 -0.249642)
							(end -0.2794 -0.1778)
						)
						(arc
							(start -0.2794 0.1778)
							(mid -0.249642 0.249642)
							(end -0.1778 0.2794)
						)
						(arc
							(start 0.1778 0.2794)
							(mid 0.249642 0.249642)
							(end 0.2794 0.1778)
						)
						(arc
							(start 0.2794 -0.1778)
							(mid 0.249642 -0.249642)
							(end 0.1778 -0.2794)
						)
					)
					(width 0)
					(fill yes)
				)
			)
		)
	)
	(footprint ""
		(layer "F.Cu")
		(at 6.35 -109.855 180)
		(property "Reference" "PR69"
			(at 0 0 180)
			(layer "F.SilkS")
			(hide yes)
			(effects
				(font
					(size 1.27 1.27)
				)
			)
		)
		(property "Value" "0R3J-0-U-GP"
			(at -0.0254 -2.5146 180)
			(unlocked yes)
			(layer "F.Fab")
			(hide yes)
			(effects
				(font
					(size 1.016 1.016)
					(thickness 0.1524)
				)
			)
		)
		(property "Device Type" "R603H22"
			(at -0.0254 -4.0386 180)
			(unlocked yes)
			(layer "F.Fab")
			(hide yes)
			(effects
				(font
					(size 1.016 1.016)
					(thickness 0.1524)
				)
			)
		)
		(duplicate_pad_numbers_are_jumpers no)
		(fp_line
			(start 0.2032 0)
			(end 0.4826 0)
			(stroke
				(width 0.2032)
				(type default)
			)
			(layer "F.SilkS")
		)
		(fp_line
			(start -0.4826 0)
			(end -0.2032 0)
			(stroke
				(width 0.2032)
				(type default)
			)
			(layer "F.SilkS")
		)
		(fp_rect
			(start -0.5842 1.3335)
			(end 0.5842 -1.3335)
			(stroke
				(width 0)
				(type default)
			)
			(fill no)
			(layer "F.CrtYd")
		)
		(fp_rect
			(start -0.5842 1.3335)
			(end 0.5842 -1.3335)
			(stroke
				(width 0)
				(type default)
			)
			(fill no)
			(layer "F.Fab")
		)
		(pad "1" smd custom
			(at 0 -0.762 180)
			(size 0.2159 0.2159)
			(layers "F.Cu" "F.Mask" "F.Paste")
			(net "P3V3_STBY")
			(options
				(clearance outline)
				(anchor circle)
			)
			(primitives
				(gr_poly
					(pts
						(arc
							(start -0.3302 -0.4318)
							(mid -0.402042 -0.402042)
							(end -0.4318 -0.3302)
						)
						(arc
							(start -0.4318 0.3302)
							(mid -0.402042 0.402042)
							(end -0.3302 0.4318)
						)
						(arc
							(start 0.3302 0.4318)
							(mid 0.402042 0.402042)
							(end 0.4318 0.3302)
						)
						(arc
							(start 0.4318 -0.3302)
							(mid 0.402042 -0.402042)
							(end 0.3302 -0.4318)
						)
					)
					(width 0)
					(fill yes)
				)
			)
		)
		(pad "2" smd custom
			(at 0 0.762 180)
			(size 0.2159 0.2159)
			(layers "F.Cu" "F.Mask" "F.Paste")
			(net "VR_P1V26_STBY_IN")
			(options
				(clearance outline)
				(anchor circle)
			)
			(primitives
				(gr_poly
					(pts
						(arc
							(start -0.3302 -0.4318)
							(mid -0.402042 -0.402042)
							(end -0.4318 -0.3302)
						)
						(arc
							(start -0.4318 0.3302)
							(mid -0.402042 0.402042)
							(end -0.3302 0.4318)
						)
						(arc
							(start 0.3302 0.4318)
							(mid 0.402042 0.402042)
							(end 0.4318 0.3302)
						)
						(arc
							(start 0.4318 -0.3302)
							(mid 0.402042 -0.402042)
							(end 0.3302 -0.4318)
						)
					)
					(width 0)
					(fill yes)
				)
			)
		)
	)
	(footprint ""
		(layer "F.Cu")
		(at 331.216 -15.621)
		(property "Reference" "SR715"
			(at 0 0 0)
			(layer "F.SilkS")
			(hide yes)
			(effects
				(font
					(size 1.27 1.27)
				)
			)
		)
		(property "Value" "150R2F-1-GP"
			(at 0.064008 -3.993896 0)
			(unlocked yes)
			(layer "F.Fab")
			(hide yes)
			(effects
				(font
					(size 1.016 1.016)
					(thickness 0.1524)
				)
			)
		)
		(property "Device Type" "R402H16"
			(at 0.064008 -5.517896 0)
			(unlocked yes)
			(layer "F.Fab")
			(hide yes)
			(effects
				(font
					(size 1.016 1.016)
					(thickness 0.1524)
				)
			)
		)
		(duplicate_pad_numbers_are_jumpers no)
		(fp_line
			(start -0.508 -0.9398)
			(end -0.508 0.9398)
			(stroke
				(width 0.1524)
				(type default)
			)
			(layer "F.SilkS")
		)
		(fp_line
			(start 0.508 -0.9398)
			(end -0.508 -0.9398)
			(stroke
				(width 0.1524)
				(type default)
			)
			(layer "F.SilkS")
		)
		(fp_rect
			(start -0.508 0.9398)
			(end 0.508 -0.9398)
			(stroke
				(width 0)
				(type default)
			)
			(fill no)
			(layer "F.CrtYd")
		)
		(fp_rect
			(start -0.508 0.9398)
			(end 0.508 -0.9398)
			(stroke
				(width 0)
				(type default)
			)
			(fill no)
			(layer "F.Fab")
		)
		(pad "1" smd custom
			(at 0 -0.4445)
			(size 0.1397 0.1397)
			(layers "F.Cu" "F.Mask" "F.Paste")
			(net "P3V3_STBY")
			(options
				(clearance outline)
				(anchor circle)
			)
			(primitives
				(gr_poly
					(pts
						(arc
							(start -0.1778 -0.2794)
							(mid -0.249642 -0.249642)
							(end -0.2794 -0.1778)
						)
						(arc
							(start -0.2794 0.1778)
							(mid -0.249642 0.249642)
							(end -0.1778 0.2794)
						)
						(arc
							(start 0.1778 0.2794)
							(mid 0.249642 0.249642)
							(end 0.2794 0.1778)
						)
						(arc
							(start 0.2794 -0.1778)
							(mid 0.249642 -0.249642)
							(end 0.1778 -0.2794)
						)
					)
					(width 0)
					(fill yes)
				)
			)
		)
		(pad "2" smd custom
			(at 0 0.4445)
			(size 0.1397 0.1397)
			(layers "F.Cu" "F.Mask" "F.Paste")
			(net "LED_R_6")
			(options
				(clearance outline)
				(anchor circle)
			)
			(primitives
				(gr_poly
					(pts
						(arc
							(start -0.1778 -0.2794)
							(mid -0.249642 -0.249642)
							(end -0.2794 -0.1778)
						)
						(arc
							(start -0.2794 0.1778)
							(mid -0.249642 0.249642)
							(end -0.1778 0.2794)
						)
						(arc
							(start 0.1778 0.2794)
							(mid 0.249642 0.249642)
							(end 0.2794 0.1778)
						)
						(arc
							(start 0.2794 -0.1778)
							(mid 0.249642 -0.249642)
							(end 0.1778 -0.2794)
						)
					)
					(width 0)
					(fill yes)
				)
			)
		)
	)
	(footprint ""
		(layer "F.Cu")
		(at 11.684 -74.1934 -90)
		(property "Reference" "TP152"
			(at 0 0 270)
			(layer "F.SilkS")
			(hide yes)
			(effects
				(font
					(size 1.27 1.27)
				)
			)
		)
		(property "Value" "TPAD28-2-GP"
			(at -0.0127 -1.6637 270)
			(unlocked yes)
			(layer "F.Fab")
			(hide yes)
			(effects
				(font
					(size 1.016 1.016)
					(thickness 0.1524)
				)
			)
		)
		(property "Device Type" "TPAD28"
			(at -0.0127 -3.1877 270)
			(unlocked yes)
			(layer "F.Fab")
			(hide yes)
			(effects
				(font
					(size 1.016 1.016)
					(thickness 0.1524)
				)
			)
		)
		(duplicate_pad_numbers_are_jumpers no)
		(fp_poly
			(pts
				(arc
					(start 0 -0.3556)
					(mid 0 0.3556)
					(end 0 -0.3556)
				)
			)
			(stroke
				(width 0)
				(type default)
			)
			(fill no)
			(layer "F.CrtYd")
		)
		(fp_poly
			(pts
				(arc
					(start 0 -0.6096)
					(mid 0 0.6096)
					(end 0 -0.6096)
				)
			)
			(stroke
				(width 0)
				(type default)
			)
			(fill no)
			(layer "F.Fab")
		)
		(pad "1" smd circle
			(at 0 0 270)
			(size 0.7112 0.7112)
			(layers "F.Cu" "F.Mask" "F.Paste")
			(net "NCSI_ARB_IN")
		)
	)
	(footprint ""
		(layer "F.Cu")
		(at 23.876 -132.715 90)
		(property "Reference" "R347"
			(at 0 0 90)
			(layer "F.SilkS")
			(hide yes)
			(effects
				(font
					(size 1.27 1.27)
				)
			)
		)
		(property "Value" "3K3R2F-2-GP"
			(at 0.064008 -3.993896 90)
			(unlocked yes)
			(layer "F.Fab")
			(hide yes)
			(effects
				(font
					(size 1.016 1.016)
					(thickness 0.1524)
				)
			)
		)
		(property "Device Type" "R402H16"
			(at 0.064008 -5.517896 90)
			(unlocked yes)
			(layer "F.Fab")
			(hide yes)
			(effects
				(font
					(size 1.016 1.016)
					(thickness 0.1524)
				)
			)
		)
		(duplicate_pad_numbers_are_jumpers no)
		(fp_line
			(start 0.508 -0.9398)
			(end -0.508 -0.9398)
			(stroke
				(width 0.1524)
				(type default)
			)
			(layer "F.SilkS")
		)
		(fp_line
			(start -0.508 -0.9398)
			(end -0.508 0.9398)
			(stroke
				(width 0.1524)
				(type default)
			)
			(layer "F.SilkS")
		)
		(fp_rect
			(start -0.508 0.9398)
			(end 0.508 -0.9398)
			(stroke
				(width 0)
				(type default)
			)
			(fill no)
			(layer "F.CrtYd")
		)
		(fp_rect
			(start -0.508 0.9398)
			(end 0.508 -0.9398)
			(stroke
				(width 0)
				(type default)
			)
			(fill no)
			(layer "F.Fab")
		)
		(pad "1" smd custom
			(at 0 -0.4445 90)
			(size 0.1397 0.1397)
			(layers "F.Cu" "F.Mask" "F.Paste")
			(net "P3V3_STBY")
			(options
				(clearance outline)
				(anchor circle)
			)
			(primitives
				(gr_poly
					(pts
						(arc
							(start -0.1778 -0.2794)
							(mid -0.249642 -0.249642)
							(end -0.2794 -0.1778)
						)
						(arc
							(start -0.2794 0.1778)
							(mid -0.249642 0.249642)
							(end -0.1778 0.2794)
						)
						(arc
							(start 0.1778 0.2794)
							(mid 0.249642 0.249642)
							(end 0.2794 0.1778)
						)
						(arc
							(start 0.2794 -0.1778)
							(mid 0.249642 -0.249642)
							(end 0.1778 -0.2794)
						)
					)
					(width 0)
					(fill yes)
				)
			)
		)
		(pad "2" smd custom
			(at 0 0.4445 90)
			(size 0.1397 0.1397)
			(layers "F.Cu" "F.Mask" "F.Paste")
			(net "ROMA2")
			(options
				(clearance outline)
				(anchor circle)
			)
			(primitives
				(gr_poly
					(pts
						(arc
							(start -0.1778 -0.2794)
							(mid -0.249642 -0.249642)
							(end -0.2794 -0.1778)
						)
						(arc
							(start -0.2794 0.1778)
							(mid -0.249642 0.249642)
							(end -0.1778 0.2794)
						)
						(arc
							(start 0.1778 0.2794)
							(mid 0.249642 0.249642)
							(end 0.2794 0.1778)
						)
						(arc
							(start 0.2794 -0.1778)
							(mid 0.249642 -0.249642)
							(end 0.1778 -0.2794)
						)
					)
					(width 0)
					(fill yes)
				)
			)
		)
	)
	(footprint ""
		(layer "F.Cu")
		(at 63.591948 -212.420454 180)
		(property "Reference" "C357"
			(at 0 0 180)
			(layer "F.SilkS")
			(hide yes)
			(effects
				(font
					(size 1.27 1.27)
				)
			)
		)
		(property "Value" "SCD22U10V2KX-1GP"
			(at 1.1811 -2.7051 180)
			(unlocked yes)
			(layer "F.Fab")
			(hide yes)
			(effects
				(font
					(size 1.016 1.016)
					(thickness 0.1524)
				)
			)
		)
		(property "Device Type" "C402H22"
			(at 1.1811 -4.2291 180)
			(unlocked yes)
			(layer "F.Fab")
			(hide yes)
			(effects
				(font
					(size 1.016 1.016)
					(thickness 0.1524)
				)
			)
		)
		(duplicate_pad_numbers_are_jumpers no)
		(fp_rect
			(start -0.4318 0.9525)
			(end 0.4318 -0.9525)
			(stroke
				(width 0)
				(type default)
			)
			(fill no)
			(layer "F.CrtYd")
		)
		(fp_rect
			(start -0.4318 0.9525)
			(end 0.4318 -0.9525)
			(stroke
				(width 0)
				(type default)
			)
			(fill no)
			(layer "F.Fab")
		)
		(pad "1" smd custom
			(at 0 -0.4445 180)
			(size 0.1524 0.1524)
			(layers "F.Cu" "F.Mask" "F.Paste")
			(net "PCIE_TX_CAP_P71")
			(options
				(clearance outline)
				(anchor circle)
			)
			(primitives
				(gr_poly
					(pts
						(arc
							(start 0.3048 -0.2032)
							(mid 0.275042 -0.275042)
							(end 0.2032 -0.3048)
						)
						(arc
							(start -0.2032 -0.3048)
							(mid -0.275042 -0.275042)
							(end -0.3048 -0.2032)
						)
						(arc
							(start -0.3048 0.2032)
							(mid -0.275042 0.275042)
							(end -0.2032 0.3048)
						)
						(arc
							(start 0.2032 0.3048)
							(mid 0.275042 0.275042)
							(end 0.3048 0.2032)
						)
					)
					(width 0)
					(fill yes)
				)
			)
		)
		(pad "2" smd custom
			(at 0 0.4445 180)
			(size 0.1524 0.1524)
			(layers "F.Cu" "F.Mask" "F.Paste")
			(net "PCIE_TX_P71")
			(options
				(clearance outline)
				(anchor circle)
			)
			(primitives
				(gr_poly
					(pts
						(arc
							(start 0.3048 -0.2032)
							(mid 0.275042 -0.275042)
							(end 0.2032 -0.3048)
						)
						(arc
							(start -0.2032 -0.3048)
							(mid -0.275042 -0.275042)
							(end -0.3048 -0.2032)
						)
						(arc
							(start -0.3048 0.2032)
							(mid -0.275042 0.275042)
							(end -0.2032 0.3048)
						)
						(arc
							(start 0.2032 0.3048)
							(mid 0.275042 0.275042)
							(end 0.3048 0.2032)
						)
					)
					(width 0)
					(fill yes)
				)
			)
		)
	)
	(footprint ""
		(layer "F.Cu")
		(at 53.721 -136.779 90)
		(property "Reference" "R154"
			(at 0 0 90)
			(layer "F.SilkS")
			(hide yes)
			(effects
				(font
					(size 1.27 1.27)
				)
			)
		)
		(property "Value" "4K7R2F-GP"
			(at 0.064008 -3.993896 90)
			(unlocked yes)
			(layer "F.Fab")
			(hide yes)
			(effects
				(font
					(size 1.016 1.016)
					(thickness 0.1524)
				)
			)
		)
		(property "Device Type" "R402H16"
			(at 0.064008 -5.517896 90)
			(unlocked yes)
			(layer "F.Fab")
			(hide yes)
			(effects
				(font
					(size 1.016 1.016)
					(thickness 0.1524)
				)
			)
		)
		(duplicate_pad_numbers_are_jumpers no)
		(fp_line
			(start 0.508 -0.9398)
			(end -0.508 -0.9398)
			(stroke
				(width 0.1524)
				(type default)
			)
			(layer "F.SilkS")
		)
		(fp_line
			(start -0.508 -0.9398)
			(end -0.508 0.9398)
			(stroke
				(width 0.1524)
				(type default)
			)
			(layer "F.SilkS")
		)
		(fp_rect
			(start -0.508 0.9398)
			(end 0.508 -0.9398)
			(stroke
				(width 0)
				(type default)
			)
			(fill no)
			(layer "F.CrtYd")
		)
		(fp_rect
			(start -0.508 0.9398)
			(end 0.508 -0.9398)
			(stroke
				(width 0)
				(type default)
			)
			(fill no)
			(layer "F.Fab")
		)
		(pad "1" smd custom
			(at 0 -0.4445 90)
			(size 0.1397 0.1397)
			(layers "F.Cu" "F.Mask" "F.Paste")
			(net "CBL_PRSNT_N_6")
			(options
				(clearance outline)
				(anchor circle)
			)
			(primitives
				(gr_poly
					(pts
						(arc
							(start -0.1778 -0.2794)
							(mid -0.249642 -0.249642)
							(end -0.2794 -0.1778)
						)
						(arc
							(start -0.2794 0.1778)
							(mid -0.249642 0.249642)
							(end -0.1778 0.2794)
						)
						(arc
							(start 0.1778 0.2794)
							(mid 0.249642 0.249642)
							(end 0.2794 0.1778)
						)
						(arc
							(start 0.2794 -0.1778)
							(mid 0.249642 -0.249642)
							(end 0.1778 -0.2794)
						)
					)
					(width 0)
					(fill yes)
				)
			)
		)
		(pad "2" smd custom
			(at 0 0.4445 90)
			(size 0.1397 0.1397)
			(layers "F.Cu" "F.Mask" "F.Paste")
			(net "P3V3_STBY")
			(options
				(clearance outline)
				(anchor circle)
			)
			(primitives
				(gr_poly
					(pts
						(arc
							(start -0.1778 -0.2794)
							(mid -0.249642 -0.249642)
							(end -0.2794 -0.1778)
						)
						(arc
							(start -0.2794 0.1778)
							(mid -0.249642 0.249642)
							(end -0.1778 0.2794)
						)
						(arc
							(start 0.1778 0.2794)
							(mid 0.249642 0.249642)
							(end 0.2794 0.1778)
						)
						(arc
							(start 0.2794 -0.1778)
							(mid 0.249642 -0.249642)
							(end 0.1778 -0.2794)
						)
					)
					(width 0)
					(fill yes)
				)
			)
		)
	)
	(footprint ""
		(layer "F.Cu")
		(at 263.398 -26.289 180)
		(property "Reference" "R779"
			(at 0 0 180)
			(layer "F.SilkS")
			(hide yes)
			(effects
				(font
					(size 1.27 1.27)
				)
			)
		)
		(property "Value" "2KR2F-3-GP"
			(at 0.064008 -3.993896 180)
			(unlocked yes)
			(layer "F.Fab")
			(hide yes)
			(effects
				(font
					(size 1.016 1.016)
					(thickness 0.1524)
				)
			)
		)
		(property "Device Type" "R402H16"
			(at 0.064008 -5.517896 180)
			(unlocked yes)
			(layer "F.Fab")
			(hide yes)
			(effects
				(font
					(size 1.016 1.016)
					(thickness 0.1524)
				)
			)
		)
		(duplicate_pad_numbers_are_jumpers no)
		(fp_line
			(start 0.508 -0.9398)
			(end -0.508 -0.9398)
			(stroke
				(width 0.1524)
				(type default)
			)
			(layer "F.SilkS")
		)
		(fp_line
			(start -0.508 -0.9398)
			(end -0.508 0.9398)
			(stroke
				(width 0.1524)
				(type default)
			)
			(layer "F.SilkS")
		)
		(fp_rect
			(start -0.508 0.9398)
			(end 0.508 -0.9398)
			(stroke
				(width 0)
				(type default)
			)
			(fill no)
			(layer "F.CrtYd")
		)
		(fp_rect
			(start -0.508 0.9398)
			(end 0.508 -0.9398)
			(stroke
				(width 0)
				(type default)
			)
			(fill no)
			(layer "F.Fab")
		)
		(pad "1" smd custom
			(at 0 -0.4445 180)
			(size 0.1397 0.1397)
			(layers "F.Cu" "F.Mask" "F.Paste")
			(net "P3V3_GPIO")
			(options
				(clearance outline)
				(anchor circle)
			)
			(primitives
				(gr_poly
					(pts
						(arc
							(start -0.1778 -0.2794)
							(mid -0.249642 -0.249642)
							(end -0.2794 -0.1778)
						)
						(arc
							(start -0.2794 0.1778)
							(mid -0.249642 0.249642)
							(end -0.1778 0.2794)
						)
						(arc
							(start 0.1778 0.2794)
							(mid 0.249642 0.249642)
							(end 0.2794 0.1778)
						)
						(arc
							(start 0.2794 -0.1778)
							(mid 0.249642 -0.249642)
							(end 0.1778 -0.2794)
						)
					)
					(width 0)
					(fill yes)
				)
			)
		)
		(pad "2" smd custom
			(at 0 0.4445 180)
			(size 0.1397 0.1397)
			(layers "F.Cu" "F.Mask" "F.Paste")
			(net "TWI_SCL3")
			(options
				(clearance outline)
				(anchor circle)
			)
			(primitives
				(gr_poly
					(pts
						(arc
							(start -0.1778 -0.2794)
							(mid -0.249642 -0.249642)
							(end -0.2794 -0.1778)
						)
						(arc
							(start -0.2794 0.1778)
							(mid -0.249642 0.249642)
							(end -0.1778 0.2794)
						)
						(arc
							(start 0.1778 0.2794)
							(mid 0.249642 0.249642)
							(end 0.2794 0.1778)
						)
						(arc
							(start 0.2794 -0.1778)
							(mid 0.249642 -0.249642)
							(end 0.1778 -0.2794)
						)
					)
					(width 0)
					(fill yes)
				)
			)
		)
	)
	(footprint ""
		(layer "F.Cu")
		(at 53.7464 -125.5776 -90)
		(property "Reference" "R803"
			(at 0 0 270)
			(layer "F.SilkS")
			(hide yes)
			(effects
				(font
					(size 1.27 1.27)
				)
			)
		)
		(property "Value" "4K7R2F-GP"
			(at 0.064008 -3.993896 270)
			(unlocked yes)
			(layer "F.Fab")
			(hide yes)
			(effects
				(font
					(size 1.016 1.016)
					(thickness 0.1524)
				)
			)
		)
		(property "Device Type" "R402H16"
			(at 0.064008 -5.517896 270)
			(unlocked yes)
			(layer "F.Fab")
			(hide yes)
			(effects
				(font
					(size 1.016 1.016)
					(thickness 0.1524)
				)
			)
		)
		(duplicate_pad_numbers_are_jumpers no)
		(fp_line
			(start -0.508 -0.9398)
			(end -0.508 0.9398)
			(stroke
				(width 0.1524)
				(type default)
			)
			(layer "F.SilkS")
		)
		(fp_line
			(start 0.508 -0.9398)
			(end -0.508 -0.9398)
			(stroke
				(width 0.1524)
				(type default)
			)
			(layer "F.SilkS")
		)
		(fp_rect
			(start -0.508 0.9398)
			(end 0.508 -0.9398)
			(stroke
				(width 0)
				(type default)
			)
			(fill no)
			(layer "F.CrtYd")
		)
		(fp_rect
			(start -0.508 0.9398)
			(end 0.508 -0.9398)
			(stroke
				(width 0)
				(type default)
			)
			(fill no)
			(layer "F.Fab")
		)
		(pad "1" smd custom
			(at 0 -0.4445 270)
			(size 0.1397 0.1397)
			(layers "F.Cu" "F.Mask" "F.Paste")
			(net "P3V3_STBY")
			(options
				(clearance outline)
				(anchor circle)
			)
			(primitives
				(gr_poly
					(pts
						(arc
							(start -0.1778 -0.2794)
							(mid -0.249642 -0.249642)
							(end -0.2794 -0.1778)
						)
						(arc
							(start -0.2794 0.1778)
							(mid -0.249642 0.249642)
							(end -0.1778 0.2794)
						)
						(arc
							(start 0.1778 0.2794)
							(mid 0.249642 0.249642)
							(end 0.2794 0.1778)
						)
						(arc
							(start 0.2794 -0.1778)
							(mid 0.249642 -0.249642)
							(end 0.1778 -0.2794)
						)
					)
					(width 0)
					(fill yes)
				)
			)
		)
		(pad "2" smd custom
			(at 0 0.4445 270)
			(size 0.1397 0.1397)
			(layers "F.Cu" "F.Mask" "F.Paste")
			(net "JTAG_BMC_TMS")
			(options
				(clearance outline)
				(anchor circle)
			)
			(primitives
				(gr_poly
					(pts
						(arc
							(start -0.1778 -0.2794)
							(mid -0.249642 -0.249642)
							(end -0.2794 -0.1778)
						)
						(arc
							(start -0.2794 0.1778)
							(mid -0.249642 0.249642)
							(end -0.1778 0.2794)
						)
						(arc
							(start 0.1778 0.2794)
							(mid 0.249642 0.249642)
							(end 0.2794 0.1778)
						)
						(arc
							(start 0.2794 -0.1778)
							(mid 0.249642 -0.249642)
							(end 0.1778 -0.2794)
						)
					)
					(width 0)
					(fill yes)
				)
			)
		)
	)
	(footprint ""
		(layer "F.Cu")
		(at 47.117 -145.415 180)
		(property "Reference" "R228"
			(at 0 0 180)
			(layer "F.SilkS")
			(hide yes)
			(effects
				(font
					(size 1.27 1.27)
				)
			)
		)
		(property "Value" "4K7R2F-GP"
			(at 0.064008 -3.993896 180)
			(unlocked yes)
			(layer "F.Fab")
			(hide yes)
			(effects
				(font
					(size 1.016 1.016)
					(thickness 0.1524)
				)
			)
		)
		(property "Device Type" "R402H16"
			(at 0.064008 -5.517896 180)
			(unlocked yes)
			(layer "F.Fab")
			(hide yes)
			(effects
				(font
					(size 1.016 1.016)
					(thickness 0.1524)
				)
			)
		)
		(duplicate_pad_numbers_are_jumpers no)
		(fp_line
			(start 0.508 -0.9398)
			(end -0.508 -0.9398)
			(stroke
				(width 0.1524)
				(type default)
			)
			(layer "F.SilkS")
		)
		(fp_line
			(start -0.508 -0.9398)
			(end -0.508 0.9398)
			(stroke
				(width 0.1524)
				(type default)
			)
			(layer "F.SilkS")
		)
		(fp_rect
			(start -0.508 0.9398)
			(end 0.508 -0.9398)
			(stroke
				(width 0)
				(type default)
			)
			(fill no)
			(layer "F.CrtYd")
		)
		(fp_rect
			(start -0.508 0.9398)
			(end 0.508 -0.9398)
			(stroke
				(width 0)
				(type default)
			)
			(fill no)
			(layer "F.Fab")
		)
		(pad "1" smd custom
			(at 0 -0.4445 180)
			(size 0.1397 0.1397)
			(layers "F.Cu" "F.Mask" "F.Paste")
			(net "PEER_BMC_HB")
			(options
				(clearance outline)
				(anchor circle)
			)
			(primitives
				(gr_poly
					(pts
						(arc
							(start -0.1778 -0.2794)
							(mid -0.249642 -0.249642)
							(end -0.2794 -0.1778)
						)
						(arc
							(start -0.2794 0.1778)
							(mid -0.249642 0.249642)
							(end -0.1778 0.2794)
						)
						(arc
							(start 0.1778 0.2794)
							(mid 0.249642 0.249642)
							(end 0.2794 0.1778)
						)
						(arc
							(start 0.2794 -0.1778)
							(mid 0.249642 -0.249642)
							(end 0.1778 -0.2794)
						)
					)
					(width 0)
					(fill yes)
				)
			)
		)
		(pad "2" smd custom
			(at 0 0.4445 180)
			(size 0.1397 0.1397)
			(layers "F.Cu" "F.Mask" "F.Paste")
			(net "P3V3_STBY")
			(options
				(clearance outline)
				(anchor circle)
			)
			(primitives
				(gr_poly
					(pts
						(arc
							(start -0.1778 -0.2794)
							(mid -0.249642 -0.249642)
							(end -0.2794 -0.1778)
						)
						(arc
							(start -0.2794 0.1778)
							(mid -0.249642 0.249642)
							(end -0.1778 0.2794)
						)
						(arc
							(start 0.1778 0.2794)
							(mid 0.249642 0.249642)
							(end 0.2794 0.1778)
						)
						(arc
							(start 0.2794 -0.1778)
							(mid 0.249642 -0.249642)
							(end 0.1778 -0.2794)
						)
					)
					(width 0)
					(fill yes)
				)
			)
		)
	)
	(footprint ""
		(layer "F.Cu")
		(at 65.4812 -158.0896 90)
		(property "Reference" "PC19"
			(at 0 0 90)
			(layer "F.SilkS")
			(hide yes)
			(effects
				(font
					(size 1.27 1.27)
				)
			)
		)
		(property "Value" "SC22U6D3V5MX-5-GP"
			(at -0.0762 -6.1214 90)
			(unlocked yes)
			(layer "F.Fab")
			(hide yes)
			(effects
				(font
					(size 1.016 1.016)
					(thickness 0.1524)
				)
			)
		)
		(property "Device Type" "C805H56"
			(at -0.0762 -8.1534 90)
			(unlocked yes)
			(layer "F.Fab")
			(hide yes)
			(effects
				(font
					(size 1.016 1.016)
					(thickness 0.1524)
				)
			)
		)
		(duplicate_pad_numbers_are_jumpers no)
		(fp_line
			(start 0.635 0)
			(end -0.635 0)
			(stroke
				(width 0.508)
				(type default)
			)
			(layer "F.SilkS")
		)
		(fp_rect
			(start -0.9652 1.778)
			(end 0.9652 -1.778)
			(stroke
				(width 0)
				(type default)
			)
			(fill no)
			(layer "F.CrtYd")
		)
		(fp_poly
			(pts
				(xy -0.9652 -1.778) (xy 0.9652 -1.778) (xy 0.9652 1.778) (xy -0.9652 1.778)
			)
			(stroke
				(width 0)
				(type default)
			)
			(fill no)
			(layer "F.Fab")
		)
		(pad "1" smd rect
			(at 0 -0.9652 90)
			(size 1.397 1.143)
			(layers "F.Cu" "F.Mask" "F.Paste")
			(net "P1V53_PWR")
		)
		(pad "2" smd rect
			(at 0 0.9652 90)
			(size 1.397 1.143)
			(layers "F.Cu" "F.Mask" "F.Paste")
			(net "GND")
		)
	)
	(footprint ""
		(layer "F.Cu")
		(at 41.7068 -184.8866 -90)
		(property "Reference" "C692"
			(at 0 0 270)
			(layer "F.SilkS")
			(hide yes)
			(effects
				(font
					(size 1.27 1.27)
				)
			)
		)
		(property "Value" "SC220P50V3JN-GP"
			(at 0 -2.8194 270)
			(unlocked yes)
			(layer "F.Fab")
			(hide yes)
			(effects
				(font
					(size 1.016 1.016)
					(thickness 0.1524)
				)
			)
		)
		(property "Device Type" "C603H36"
			(at 0 -4.3434 270)
			(unlocked yes)
			(layer "F.Fab")
			(hide yes)
			(effects
				(font
					(size 1.016 1.016)
					(thickness 0.1524)
				)
			)
		)
		(duplicate_pad_numbers_are_jumpers no)
		(fp_line
			(start 0.508 0)
			(end -0.508 0)
			(stroke
				(width 0.2032)
				(type default)
			)
			(layer "F.SilkS")
		)
		(fp_rect
			(start -0.5842 1.3335)
			(end 0.5842 -1.3335)
			(stroke
				(width 0)
				(type default)
			)
			(fill no)
			(layer "F.CrtYd")
		)
		(fp_rect
			(start -0.5842 1.3335)
			(end 0.5842 -1.3335)
			(stroke
				(width 0)
				(type default)
			)
			(fill no)
			(layer "F.Fab")
		)
		(pad "1" smd custom
			(at 0 -0.762 270)
			(size 0.2159 0.2159)
			(layers "F.Cu" "F.Mask" "F.Paste")
			(net "BMC_I2C9_CLKBUF2_SDA_R")
			(options
				(clearance outline)
				(anchor circle)
			)
			(primitives
				(gr_poly
					(pts
						(arc
							(start -0.3302 -0.4318)
							(mid -0.402042 -0.402042)
							(end -0.4318 -0.3302)
						)
						(arc
							(start -0.4318 0.3302)
							(mid -0.402042 0.402042)
							(end -0.3302 0.4318)
						)
						(arc
							(start 0.3302 0.4318)
							(mid 0.402042 0.402042)
							(end 0.4318 0.3302)
						)
						(arc
							(start 0.4318 -0.3302)
							(mid 0.402042 -0.402042)
							(end 0.3302 -0.4318)
						)
					)
					(width 0)
					(fill yes)
				)
			)
		)
		(pad "2" smd custom
			(at 0 0.762 270)
			(size 0.2159 0.2159)
			(layers "F.Cu" "F.Mask" "F.Paste")
			(net "GND")
			(options
				(clearance outline)
				(anchor circle)
			)
			(primitives
				(gr_poly
					(pts
						(arc
							(start -0.3302 -0.4318)
							(mid -0.402042 -0.402042)
							(end -0.4318 -0.3302)
						)
						(arc
							(start -0.4318 0.3302)
							(mid -0.402042 0.402042)
							(end -0.3302 0.4318)
						)
						(arc
							(start 0.3302 0.4318)
							(mid 0.402042 0.402042)
							(end 0.4318 0.3302)
						)
						(arc
							(start 0.4318 -0.3302)
							(mid 0.402042 -0.402042)
							(end 0.3302 -0.4318)
						)
					)
					(width 0)
					(fill yes)
				)
			)
		)
	)
	(footprint ""
		(layer "F.Cu")
		(at 221.2086 -205.0034 180)
		(property "Reference" "R9042"
			(at 0 0 180)
			(layer "F.SilkS")
			(hide yes)
			(effects
				(font
					(size 1.27 1.27)
				)
			)
		)
		(property "Value" "4K7R2F-GP"
			(at 0.064008 -3.993896 180)
			(unlocked yes)
			(layer "F.Fab")
			(hide yes)
			(effects
				(font
					(size 1.016 1.016)
					(thickness 0.1524)
				)
			)
		)
		(property "Device Type" "R402H16"
			(at 0.064008 -5.517896 180)
			(unlocked yes)
			(layer "F.Fab")
			(hide yes)
			(effects
				(font
					(size 1.016 1.016)
					(thickness 0.1524)
				)
			)
		)
		(duplicate_pad_numbers_are_jumpers no)
		(fp_line
			(start 0.508 -0.9398)
			(end -0.508 -0.9398)
			(stroke
				(width 0.1524)
				(type default)
			)
			(layer "F.SilkS")
		)
		(fp_line
			(start -0.508 -0.9398)
			(end -0.508 0.9398)
			(stroke
				(width 0.1524)
				(type default)
			)
			(layer "F.SilkS")
		)
		(fp_rect
			(start -0.508 0.9398)
			(end 0.508 -0.9398)
			(stroke
				(width 0)
				(type default)
			)
			(fill no)
			(layer "F.CrtYd")
		)
		(fp_rect
			(start -0.508 0.9398)
			(end 0.508 -0.9398)
			(stroke
				(width 0)
				(type default)
			)
			(fill no)
			(layer "F.Fab")
		)
		(pad "1" smd custom
			(at 0 -0.4445 180)
			(size 0.1397 0.1397)
			(layers "F.Cu" "F.Mask" "F.Paste")
			(net "SSD_PERST#13")
			(options
				(clearance outline)
				(anchor circle)
			)
			(primitives
				(gr_poly
					(pts
						(arc
							(start -0.1778 -0.2794)
							(mid -0.249642 -0.249642)
							(end -0.2794 -0.1778)
						)
						(arc
							(start -0.2794 0.1778)
							(mid -0.249642 0.249642)
							(end -0.1778 0.2794)
						)
						(arc
							(start 0.1778 0.2794)
							(mid 0.249642 0.249642)
							(end 0.2794 0.1778)
						)
						(arc
							(start 0.2794 -0.1778)
							(mid 0.249642 -0.249642)
							(end 0.1778 -0.2794)
						)
					)
					(width 0)
					(fill yes)
				)
			)
		)
		(pad "2" smd custom
			(at 0 0.4445 180)
			(size 0.1397 0.1397)
			(layers "F.Cu" "F.Mask" "F.Paste")
			(net "GND")
			(options
				(clearance outline)
				(anchor circle)
			)
			(primitives
				(gr_poly
					(pts
						(arc
							(start -0.1778 -0.2794)
							(mid -0.249642 -0.249642)
							(end -0.2794 -0.1778)
						)
						(arc
							(start -0.2794 0.1778)
							(mid -0.249642 0.249642)
							(end -0.1778 0.2794)
						)
						(arc
							(start 0.1778 0.2794)
							(mid 0.249642 0.249642)
							(end 0.2794 0.1778)
						)
						(arc
							(start 0.2794 -0.1778)
							(mid 0.249642 -0.249642)
							(end 0.1778 -0.2794)
						)
					)
					(width 0)
					(fill yes)
				)
			)
		)
	)
	(footprint ""
		(layer "F.Cu")
		(at 21.6662 -183.2356 90)
		(property "Reference" "PQ33"
			(at 0 0 90)
			(layer "F.SilkS")
			(hide yes)
			(effects
				(font
					(size 1.27 1.27)
				)
			)
		)
		(property "Value" "MMBT3904FN3-GP-U"
			(at -1.5748 -0.2032 90)
			(unlocked yes)
			(layer "F.Fab")
			(hide yes)
			(effects
				(font
					(size 1.016 1.016)
					(thickness 0.1524)
				)
			)
		)
		(property "Device Type" "SOT883CBE1D0-2U1H22"
			(at -1.5748 -1.7272 90)
			(unlocked yes)
			(layer "F.Fab")
			(hide yes)
			(effects
				(font
					(size 1.016 1.016)
					(thickness 0.1524)
				)
			)
		)
		(duplicate_pad_numbers_are_jumpers no)
		(fp_line
			(start 0.5588 -0.762)
			(end 0.5588 0.762)
			(stroke
				(width 0.1524)
				(type default)
			)
			(layer "F.SilkS")
		)
		(fp_line
			(start -0.5588 -0.762)
			(end 0.5588 -0.762)
			(stroke
				(width 0.1524)
				(type default)
			)
			(layer "F.SilkS")
		)
		(fp_line
			(start 0.5588 0.762)
			(end -0.5588 0.762)
			(stroke
				(width 0.1524)
				(type default)
			)
			(layer "F.SilkS")
		)
		(fp_line
			(start -0.5588 0.762)
			(end -0.5588 -0.762)
			(stroke
				(width 0.1524)
				(type default)
			)
			(layer "F.SilkS")
		)
		(fp_poly
			(pts
				(arc
					(start 0.005842 -0.839978)
					(mid 0.005842 -1.347978)
					(end 0.005842 -0.839978)
				)
			)
			(stroke
				(width 0)
				(type default)
			)
			(fill yes)
			(layer "F.SilkS")
		)
		(fp_rect
			(start -0.2921 0.4953)
			(end 0.2921 -0.4953)
			(stroke
				(width 0)
				(type default)
			)
			(fill no)
			(layer "F.CrtYd")
		)
		(fp_poly
			(pts
				(xy 0.8128 -1.016) (xy 0.8128 1.016) (xy -0.8128 1.016) (xy -0.8128 0.00635) (xy -0.2921 0.00635)
				(xy -0.2921 0.4953) (xy 0.2921 0.4953) (xy 0.2921 -0.4953) (xy -0.2921 -0.4953) (xy -0.2921 -0.00635)
				(xy -0.8128 -0.00635) (xy -0.8128 -1.016)
			)
			(stroke
				(width 0)
				(type default)
			)
			(fill no)
			(layer "F.CrtYd")
		)
		(fp_rect
			(start -0.8128 1.016)
			(end 0.8128 -1.016)
			(stroke
				(width 0)
				(type default)
			)
			(fill no)
			(layer "F.Fab")
		)
		(pad "B" smd rect
			(at -0.2032 0.350012 90)
			(size 0.2032 0.3048)
			(layers "F.Cu" "F.Mask" "F.Paste")
			(net "MB0_TEMP_C")
		)
		(pad "C" smd rect
			(at 0 -0.350012 90)
			(size 0.5588 0.3048)
			(layers "F.Cu" "F.Mask" "F.Paste")
			(net "MB0_TEMP_C")
		)
		(pad "E" smd rect
			(at 0.2032 0.350012 90)
			(size 0.2032 0.3048)
			(layers "F.Cu" "F.Mask" "F.Paste")
			(net "MB0_TEMP_E")
		)
	)
	(footprint ""
		(layer "F.Cu")
		(at 48.811942 -118.38305)
		(property "Reference" "TP154"
			(at 0 0 0)
			(layer "F.SilkS")
			(hide yes)
			(effects
				(font
					(size 1.27 1.27)
				)
			)
		)
		(property "Value" "TPAD28-2-GP"
			(at -0.0127 -1.6637 0)
			(unlocked yes)
			(layer "F.Fab")
			(hide yes)
			(effects
				(font
					(size 1.016 1.016)
					(thickness 0.1524)
				)
			)
		)
		(property "Device Type" "TPAD28"
			(at -0.0127 -3.1877 0)
			(unlocked yes)
			(layer "F.Fab")
			(hide yes)
			(effects
				(font
					(size 1.016 1.016)
					(thickness 0.1524)
				)
			)
		)
		(duplicate_pad_numbers_are_jumpers no)
		(fp_poly
			(pts
				(arc
					(start 0.3556 0)
					(mid -0.3556 0)
					(end 0.3556 0)
				)
			)
			(stroke
				(width 0)
				(type default)
			)
			(fill no)
			(layer "F.CrtYd")
		)
		(fp_poly
			(pts
				(arc
					(start 0.6096 0)
					(mid -0.6096 0)
					(end 0.6096 0)
				)
			)
			(stroke
				(width 0)
				(type default)
			)
			(fill no)
			(layer "F.Fab")
		)
		(pad "1" smd circle
			(at 0 0)
			(size 0.7112 0.7112)
			(layers "F.Cu" "F.Mask" "F.Paste")
			(net "TP_GPIOA6")
		)
	)
	(footprint ""
		(layer "F.Cu")
		(at 187.10402 -16.23314 -90)
		(property "Reference" "SR719"
			(at 0 0 270)
			(layer "F.SilkS")
			(hide yes)
			(effects
				(font
					(size 1.27 1.27)
				)
			)
		)
		(property "Value" "150R2F-1-GP"
			(at 0.064008 -3.993896 270)
			(unlocked yes)
			(layer "F.Fab")
			(hide yes)
			(effects
				(font
					(size 1.016 1.016)
					(thickness 0.1524)
				)
			)
		)
		(property "Device Type" "R402H16"
			(at 0.064008 -5.517896 270)
			(unlocked yes)
			(layer "F.Fab")
			(hide yes)
			(effects
				(font
					(size 1.016 1.016)
					(thickness 0.1524)
				)
			)
		)
		(duplicate_pad_numbers_are_jumpers no)
		(fp_line
			(start -0.508 -0.9398)
			(end -0.508 0.9398)
			(stroke
				(width 0.1524)
				(type default)
			)
			(layer "F.SilkS")
		)
		(fp_line
			(start 0.508 -0.9398)
			(end -0.508 -0.9398)
			(stroke
				(width 0.1524)
				(type default)
			)
			(layer "F.SilkS")
		)
		(fp_rect
			(start -0.508 0.9398)
			(end 0.508 -0.9398)
			(stroke
				(width 0)
				(type default)
			)
			(fill no)
			(layer "F.CrtYd")
		)
		(fp_rect
			(start -0.508 0.9398)
			(end 0.508 -0.9398)
			(stroke
				(width 0)
				(type default)
			)
			(fill no)
			(layer "F.Fab")
		)
		(pad "1" smd custom
			(at 0 -0.4445 270)
			(size 0.1397 0.1397)
			(layers "F.Cu" "F.Mask" "F.Paste")
			(net "P3V3_STBY")
			(options
				(clearance outline)
				(anchor circle)
			)
			(primitives
				(gr_poly
					(pts
						(arc
							(start -0.1778 -0.2794)
							(mid -0.249642 -0.249642)
							(end -0.2794 -0.1778)
						)
						(arc
							(start -0.2794 0.1778)
							(mid -0.249642 0.249642)
							(end -0.1778 0.2794)
						)
						(arc
							(start 0.1778 0.2794)
							(mid 0.249642 0.249642)
							(end 0.2794 0.1778)
						)
						(arc
							(start 0.2794 -0.1778)
							(mid 0.249642 -0.249642)
							(end 0.1778 -0.2794)
						)
					)
					(width 0)
					(fill yes)
				)
			)
		)
		(pad "2" smd custom
			(at 0 0.4445 270)
			(size 0.1397 0.1397)
			(layers "F.Cu" "F.Mask" "F.Paste")
			(net "LED_R_10")
			(options
				(clearance outline)
				(anchor circle)
			)
			(primitives
				(gr_poly
					(pts
						(arc
							(start -0.1778 -0.2794)
							(mid -0.249642 -0.249642)
							(end -0.2794 -0.1778)
						)
						(arc
							(start -0.2794 0.1778)
							(mid -0.249642 0.249642)
							(end -0.1778 0.2794)
						)
						(arc
							(start 0.1778 0.2794)
							(mid 0.249642 0.249642)
							(end 0.2794 0.1778)
						)
						(arc
							(start 0.2794 -0.1778)
							(mid 0.249642 -0.249642)
							(end 0.1778 -0.2794)
						)
					)
					(width 0)
					(fill yes)
				)
			)
		)
	)
	(footprint ""
		(layer "F.Cu")
		(at 9.4996 -100.1014 -90)
		(property "Reference" "R400"
			(at 0 0 270)
			(layer "F.SilkS")
			(hide yes)
			(effects
				(font
					(size 1.27 1.27)
				)
			)
		)
		(property "Value" "10KR2F-2-GP"
			(at 0.064008 -3.993896 270)
			(unlocked yes)
			(layer "F.Fab")
			(hide yes)
			(effects
				(font
					(size 1.016 1.016)
					(thickness 0.1524)
				)
			)
		)
		(property "Device Type" "R402H16"
			(at 0.064008 -5.517896 270)
			(unlocked yes)
			(layer "F.Fab")
			(hide yes)
			(effects
				(font
					(size 1.016 1.016)
					(thickness 0.1524)
				)
			)
		)
		(duplicate_pad_numbers_are_jumpers no)
		(fp_line
			(start -0.508 -0.9398)
			(end -0.508 0.9398)
			(stroke
				(width 0.1524)
				(type default)
			)
			(layer "F.SilkS")
		)
		(fp_line
			(start 0.508 -0.9398)
			(end -0.508 -0.9398)
			(stroke
				(width 0.1524)
				(type default)
			)
			(layer "F.SilkS")
		)
		(fp_rect
			(start -0.508 0.9398)
			(end 0.508 -0.9398)
			(stroke
				(width 0)
				(type default)
			)
			(fill no)
			(layer "F.CrtYd")
		)
		(fp_rect
			(start -0.508 0.9398)
			(end 0.508 -0.9398)
			(stroke
				(width 0)
				(type default)
			)
			(fill no)
			(layer "F.Fab")
		)
		(pad "1" smd custom
			(at 0 -0.4445 270)
			(size 0.1397 0.1397)
			(layers "F.Cu" "F.Mask" "F.Paste")
			(net "P3V3_STBY")
			(options
				(clearance outline)
				(anchor circle)
			)
			(primitives
				(gr_poly
					(pts
						(arc
							(start -0.1778 -0.2794)
							(mid -0.249642 -0.249642)
							(end -0.2794 -0.1778)
						)
						(arc
							(start -0.2794 0.1778)
							(mid -0.249642 0.249642)
							(end -0.1778 0.2794)
						)
						(arc
							(start 0.1778 0.2794)
							(mid 0.249642 0.249642)
							(end 0.2794 0.1778)
						)
						(arc
							(start 0.2794 -0.1778)
							(mid 0.249642 -0.249642)
							(end 0.1778 -0.2794)
						)
					)
					(width 0)
					(fill yes)
				)
			)
		)
		(pad "2" smd custom
			(at 0 0.4445 270)
			(size 0.1397 0.1397)
			(layers "F.Cu" "F.Mask" "F.Paste")
			(net "50M_CLK_OE")
			(options
				(clearance outline)
				(anchor circle)
			)
			(primitives
				(gr_poly
					(pts
						(arc
							(start -0.1778 -0.2794)
							(mid -0.249642 -0.249642)
							(end -0.2794 -0.1778)
						)
						(arc
							(start -0.2794 0.1778)
							(mid -0.249642 0.249642)
							(end -0.1778 0.2794)
						)
						(arc
							(start 0.1778 0.2794)
							(mid 0.249642 0.249642)
							(end 0.2794 0.1778)
						)
						(arc
							(start 0.2794 -0.1778)
							(mid 0.249642 -0.249642)
							(end 0.1778 -0.2794)
						)
					)
					(width 0)
					(fill yes)
				)
			)
		)
	)
	(footprint ""
		(layer "F.Cu")
		(at 35.768026 -153.97988 -90)
		(property "Reference" "U18"
			(at 0 0 270)
			(layer "F.SilkS")
			(hide yes)
			(effects
				(font
					(size 1.27 1.27)
				)
			)
		)
		(property "Value" "K4B2G1646F-BCK0-GP-U"
			(at -7.925054 0.6858 270)
			(unlocked yes)
			(layer "F.Fab")
			(hide yes)
			(effects
				(font
					(size 1.016 1.016)
					(thickness 0.1524)
				)
			)
		)
		(property "Device Type" "BGA96D075133H48"
			(at -7.925054 -0.8382 270)
			(unlocked yes)
			(layer "F.Fab")
			(hide yes)
			(effects
				(font
					(size 1.016 1.016)
					(thickness 0.1524)
				)
			)
		)
		(duplicate_pad_numbers_are_jumpers no)
		(fp_line
			(start -3.750056 6.649974)
			(end 3.750056 6.649974)
			(stroke
				(width 0.1524)
				(type default)
			)
			(layer "F.SilkS")
		)
		(fp_line
			(start 3.750056 6.649974)
			(end 3.750056 -6.649974)
			(stroke
				(width 0.1524)
				(type default)
			)
			(layer "F.SilkS")
		)
		(fp_line
			(start -4.080256 -5.379974)
			(end -4.080256 -6.980174)
			(stroke
				(width 0.508)
				(type default)
			)
			(layer "F.SilkS")
		)
		(fp_line
			(start -3.750056 -6.649974)
			(end -3.750056 6.649974)
			(stroke
				(width 0.1524)
				(type default)
			)
			(layer "F.SilkS")
		)
		(fp_line
			(start 3.750056 -6.649974)
			(end -3.750056 -6.649974)
			(stroke
				(width 0.1524)
				(type default)
			)
			(layer "F.SilkS")
		)
		(fp_line
			(start -4.080256 -6.980174)
			(end -2.480056 -6.980174)
			(stroke
				(width 0.508)
				(type default)
			)
			(layer "F.SilkS")
		)
		(fp_rect
			(start -3.750056 6.649974)
			(end 3.750056 -6.649974)
			(stroke
				(width 0)
				(type default)
			)
			(fill no)
			(layer "F.CrtYd")
		)
		(fp_poly
			(pts
				(xy -4.750054 7.649972) (xy -4.750054 -7.649972) (xy 4.750054 -7.649972) (xy 4.750054 0.4699) (xy 3.750056 0.4699)
				(xy 3.750056 -6.649974) (xy -3.750056 -6.649974) (xy -3.750056 6.649974) (xy 3.750056 6.649974)
				(xy 3.750056 0.4826) (xy 4.750054 0.4826) (xy 4.750054 7.649972)
			)
			(stroke
				(width 0)
				(type default)
			)
			(fill no)
			(layer "F.CrtYd")
		)
		(fp_rect
			(start -5.750052 8.64997)
			(end 5.750052 -8.64997)
			(stroke
				(width 0)
				(type default)
			)
			(fill no)
			(layer "F.Fab")
		)
		(pad "A1" smd circle
			(at -3.199892 -5.999988 270)
			(size 0.3556 0.3556)
			(layers "F.Cu" "F.Mask" "F.Paste")
			(net "P1V53_STBY")
		)
		(pad "A2" smd circle
			(at -2.400046 -5.999988 270)
			(size 0.3556 0.3556)
			(layers "F.Cu" "F.Mask" "F.Paste")
			(net "MEMDQ_15")
		)
		(pad "A3" smd circle
			(at -1.599946 -5.999988 270)
			(size 0.3556 0.3556)
			(layers "F.Cu" "F.Mask" "F.Paste")
			(net "MEMDQ_14")
		)
		(pad "A7" smd circle
			(at 1.599946 -5.999988 270)
			(size 0.3556 0.3556)
			(layers "F.Cu" "F.Mask" "F.Paste")
			(net "MEMDQ_10")
		)
		(pad "A8" smd circle
			(at 2.400046 -5.999988 270)
			(size 0.3556 0.3556)
			(layers "F.Cu" "F.Mask" "F.Paste")
			(net "P1V53_STBY")
		)
		(pad "A9" smd circle
			(at 3.199892 -5.999988 270)
			(size 0.3556 0.3556)
			(layers "F.Cu" "F.Mask" "F.Paste")
			(net "GND")
		)
		(pad "B1" smd circle
			(at -3.199892 -5.199888 270)
			(size 0.3556 0.3556)
			(layers "F.Cu" "F.Mask" "F.Paste")
			(net "GND")
		)
		(pad "B2" smd circle
			(at -2.400046 -5.199888 270)
			(size 0.3556 0.3556)
			(layers "F.Cu" "F.Mask" "F.Paste")
			(net "P1V53_STBY")
		)
		(pad "B3" smd circle
			(at -1.599946 -5.199888 270)
			(size 0.3556 0.3556)
			(layers "F.Cu" "F.Mask" "F.Paste")
			(net "GND")
		)
		(pad "B7" smd circle
			(at 1.599946 -5.199888 270)
			(size 0.3556 0.3556)
			(layers "F.Cu" "F.Mask" "F.Paste")
			(net "MEMDQS_N1")
		)
		(pad "B8" smd circle
			(at 2.400046 -5.199888 270)
			(size 0.3556 0.3556)
			(layers "F.Cu" "F.Mask" "F.Paste")
			(net "MEMDQ_9")
		)
		(pad "B9" smd circle
			(at 3.199892 -5.199888 270)
			(size 0.3556 0.3556)
			(layers "F.Cu" "F.Mask" "F.Paste")
			(net "GND")
		)
		(pad "C1" smd circle
			(at -3.199892 -4.400042 270)
			(size 0.3556 0.3556)
			(layers "F.Cu" "F.Mask" "F.Paste")
			(net "P1V53_STBY")
		)
		(pad "C2" smd circle
			(at -2.400046 -4.400042 270)
			(size 0.3556 0.3556)
			(layers "F.Cu" "F.Mask" "F.Paste")
			(net "MEMDQ_12")
		)
		(pad "C3" smd circle
			(at -1.599946 -4.400042 270)
			(size 0.3556 0.3556)
			(layers "F.Cu" "F.Mask" "F.Paste")
			(net "MEMDQ_11")
		)
		(pad "C7" smd circle
			(at 1.599946 -4.400042 270)
			(size 0.3556 0.3556)
			(layers "F.Cu" "F.Mask" "F.Paste")
			(net "MEMDQS_P1")
		)
		(pad "C8" smd circle
			(at 2.400046 -4.400042 270)
			(size 0.3556 0.3556)
			(layers "F.Cu" "F.Mask" "F.Paste")
			(net "MEMDQ_13")
		)
		(pad "C9" smd circle
			(at 3.199892 -4.400042 270)
			(size 0.3556 0.3556)
			(layers "F.Cu" "F.Mask" "F.Paste")
			(net "P1V53_STBY")
		)
		(pad "D1" smd circle
			(at -3.199892 -3.599942 270)
			(size 0.3556 0.3556)
			(layers "F.Cu" "F.Mask" "F.Paste")
			(net "GND")
		)
		(pad "D2" smd circle
			(at -2.400046 -3.599942 270)
			(size 0.3556 0.3556)
			(layers "F.Cu" "F.Mask" "F.Paste")
			(net "P1V53_STBY")
		)
		(pad "D3" smd circle
			(at -1.599946 -3.599942 270)
			(size 0.3556 0.3556)
			(layers "F.Cu" "F.Mask" "F.Paste")
			(net "MEMDM_1")
		)
		(pad "D7" smd circle
			(at 1.599946 -3.599942 270)
			(size 0.3556 0.3556)
			(layers "F.Cu" "F.Mask" "F.Paste")
			(net "MEMDQ_8")
		)
		(pad "D8" smd circle
			(at 2.400046 -3.599942 270)
			(size 0.3556 0.3556)
			(layers "F.Cu" "F.Mask" "F.Paste")
			(net "GND")
		)
		(pad "D9" smd circle
			(at 3.199892 -3.599942 270)
			(size 0.3556 0.3556)
			(layers "F.Cu" "F.Mask" "F.Paste")
			(net "P1V53_STBY")
		)
		(pad "E1" smd circle
			(at -3.199892 -2.800096 270)
			(size 0.3556 0.3556)
			(layers "F.Cu" "F.Mask" "F.Paste")
			(net "GND")
		)
		(pad "E2" smd circle
			(at -2.400046 -2.800096 270)
			(size 0.3556 0.3556)
			(layers "F.Cu" "F.Mask" "F.Paste")
			(net "GND")
		)
		(pad "E3" smd circle
			(at -1.599946 -2.800096 270)
			(size 0.3556 0.3556)
			(layers "F.Cu" "F.Mask" "F.Paste")
			(net "MEMDQ_7")
		)
		(pad "E7" smd circle
			(at 1.599946 -2.800096 270)
			(size 0.3556 0.3556)
			(layers "F.Cu" "F.Mask" "F.Paste")
			(net "MEMDM_0")
		)
		(pad "E8" smd circle
			(at 2.400046 -2.800096 270)
			(size 0.3556 0.3556)
			(layers "F.Cu" "F.Mask" "F.Paste")
			(net "GND")
		)
		(pad "E9" smd circle
			(at 3.199892 -2.800096 270)
			(size 0.3556 0.3556)
			(layers "F.Cu" "F.Mask" "F.Paste")
			(net "P1V53_STBY")
		)
		(pad "F1" smd circle
			(at -3.199892 -1.999996 270)
			(size 0.3556 0.3556)
			(layers "F.Cu" "F.Mask" "F.Paste")
			(net "P1V53_STBY")
		)
		(pad "F2" smd circle
			(at -2.400046 -1.999996 270)
			(size 0.3556 0.3556)
			(layers "F.Cu" "F.Mask" "F.Paste")
			(net "MEMDQ_4")
		)
		(pad "F3" smd circle
			(at -1.599946 -1.999996 270)
			(size 0.3556 0.3556)
			(layers "F.Cu" "F.Mask" "F.Paste")
			(net "MEMDQS_P0")
		)
		(pad "F7" smd circle
			(at 1.599946 -1.999996 270)
			(size 0.3556 0.3556)
			(layers "F.Cu" "F.Mask" "F.Paste")
			(net "MEMDQ_3")
		)
		(pad "F8" smd circle
			(at 2.400046 -1.999996 270)
			(size 0.3556 0.3556)
			(layers "F.Cu" "F.Mask" "F.Paste")
			(net "MEMDQ_2")
		)
		(pad "F9" smd circle
			(at 3.199892 -1.999996 270)
			(size 0.3556 0.3556)
			(layers "F.Cu" "F.Mask" "F.Paste")
			(net "GND")
		)
		(pad "G1" smd circle
			(at -3.199892 -1.199896 270)
			(size 0.3556 0.3556)
			(layers "F.Cu" "F.Mask" "F.Paste")
			(net "GND")
		)
		(pad "G2" smd circle
			(at -2.400046 -1.199896 270)
			(size 0.3556 0.3556)
			(layers "F.Cu" "F.Mask" "F.Paste")
			(net "MEMDQ_5")
		)
		(pad "G3" smd circle
			(at -1.599946 -1.199896 270)
			(size 0.3556 0.3556)
			(layers "F.Cu" "F.Mask" "F.Paste")
			(net "MEMDQS_N0")
		)
		(pad "G7" smd circle
			(at 1.599946 -1.199896 270)
			(size 0.3556 0.3556)
			(layers "F.Cu" "F.Mask" "F.Paste")
			(net "P1V53_STBY")
		)
		(pad "G8" smd circle
			(at 2.400046 -1.199896 270)
			(size 0.3556 0.3556)
			(layers "F.Cu" "F.Mask" "F.Paste")
			(net "GND")
		)
		(pad "G9" smd circle
			(at 3.199892 -1.199896 270)
			(size 0.3556 0.3556)
			(layers "F.Cu" "F.Mask" "F.Paste")
			(net "GND")
		)
		(pad "H1" smd circle
			(at -3.199892 -0.40005 270)
			(size 0.3556 0.3556)
			(layers "F.Cu" "F.Mask" "F.Paste")
			(net "DDR_VREF")
		)
		(pad "H2" smd circle
			(at -2.400046 -0.40005 270)
			(size 0.3556 0.3556)
			(layers "F.Cu" "F.Mask" "F.Paste")
			(net "P1V53_STBY")
		)
		(pad "H3" smd circle
			(at -1.599946 -0.40005 270)
			(size 0.3556 0.3556)
			(layers "F.Cu" "F.Mask" "F.Paste")
			(net "MEMDQ_1")
		)
		(pad "H7" smd circle
			(at 1.599946 -0.40005 270)
			(size 0.3556 0.3556)
			(layers "F.Cu" "F.Mask" "F.Paste")
			(net "MEMDQ_0")
		)
		(pad "H8" smd circle
			(at 2.400046 -0.40005 270)
			(size 0.3556 0.3556)
			(layers "F.Cu" "F.Mask" "F.Paste")
			(net "MEMDQ_6")
		)
		(pad "H9" smd circle
			(at 3.199892 -0.40005 270)
			(size 0.3556 0.3556)
			(layers "F.Cu" "F.Mask" "F.Paste")
			(net "P1V53_STBY")
		)
		(pad "J1" smd circle
			(at -3.199892 0.40005 270)
			(size 0.3556 0.3556)
			(layers "F.Cu" "F.Mask" "F.Paste")
			(net "Net_187")
		)
		(pad "J2" smd circle
			(at -2.400046 0.40005 270)
			(size 0.3556 0.3556)
			(layers "F.Cu" "F.Mask" "F.Paste")
			(net "GND")
		)
		(pad "J3" smd circle
			(at -1.599946 0.40005 270)
			(size 0.3556 0.3556)
			(layers "F.Cu" "F.Mask" "F.Paste")
			(net "MEMRASN")
		)
		(pad "J7" smd circle
			(at 1.599946 0.40005 270)
			(size 0.3556 0.3556)
			(layers "F.Cu" "F.Mask" "F.Paste")
			(net "MEMCK_P")
		)
		(pad "J8" smd circle
			(at 2.400046 0.40005 270)
			(size 0.3556 0.3556)
			(layers "F.Cu" "F.Mask" "F.Paste")
			(net "GND")
		)
		(pad "J9" smd circle
			(at 3.199892 0.40005 270)
			(size 0.3556 0.3556)
			(layers "F.Cu" "F.Mask" "F.Paste")
			(net "Net_184")
		)
		(pad "K1" smd circle
			(at -3.199892 1.199896 270)
			(size 0.3556 0.3556)
			(layers "F.Cu" "F.Mask" "F.Paste")
			(net "MEMODT")
		)
		(pad "K2" smd circle
			(at -2.400046 1.199896 270)
			(size 0.3556 0.3556)
			(layers "F.Cu" "F.Mask" "F.Paste")
			(net "P1V53_STBY")
		)
		(pad "K3" smd circle
			(at -1.599946 1.199896 270)
			(size 0.3556 0.3556)
			(layers "F.Cu" "F.Mask" "F.Paste")
			(net "MEMCASN")
		)
		(pad "K7" smd circle
			(at 1.599946 1.199896 270)
			(size 0.3556 0.3556)
			(layers "F.Cu" "F.Mask" "F.Paste")
			(net "MEMCK_N")
		)
		(pad "K8" smd circle
			(at 2.400046 1.199896 270)
			(size 0.3556 0.3556)
			(layers "F.Cu" "F.Mask" "F.Paste")
			(net "P1V53_STBY")
		)
		(pad "K9" smd circle
			(at 3.199892 1.199896 270)
			(size 0.3556 0.3556)
			(layers "F.Cu" "F.Mask" "F.Paste")
			(net "MEMCKE")
		)
		(pad "L1" smd circle
			(at -3.199892 1.999996 270)
			(size 0.3556 0.3556)
			(layers "F.Cu" "F.Mask" "F.Paste")
			(net "Net_188")
		)
		(pad "L2" smd circle
			(at -2.400046 1.999996 270)
			(size 0.3556 0.3556)
			(layers "F.Cu" "F.Mask" "F.Paste")
			(net "MEMCSN")
		)
		(pad "L3" smd circle
			(at -1.599946 1.999996 270)
			(size 0.3556 0.3556)
			(layers "F.Cu" "F.Mask" "F.Paste")
			(net "MEMWEN")
		)
		(pad "L7" smd circle
			(at 1.599946 1.999996 270)
			(size 0.3556 0.3556)
			(layers "F.Cu" "F.Mask" "F.Paste")
			(net "MEMA_10")
		)
		(pad "L8" smd circle
			(at 2.400046 1.999996 270)
			(size 0.3556 0.3556)
			(layers "F.Cu" "F.Mask" "F.Paste")
			(net "PD_ZQ")
		)
		(pad "L9" smd circle
			(at 3.199892 1.999996 270)
			(size 0.3556 0.3556)
			(layers "F.Cu" "F.Mask" "F.Paste")
			(net "Net_186")
		)
		(pad "M1" smd circle
			(at -3.199892 2.800096 270)
			(size 0.3556 0.3556)
			(layers "F.Cu" "F.Mask" "F.Paste")
			(net "GND")
		)
		(pad "M2" smd circle
			(at -2.400046 2.800096 270)
			(size 0.3556 0.3556)
			(layers "F.Cu" "F.Mask" "F.Paste")
			(net "MEMBA_0")
		)
		(pad "M3" smd circle
			(at -1.599946 2.800096 270)
			(size 0.3556 0.3556)
			(layers "F.Cu" "F.Mask" "F.Paste")
			(net "MEMBA_2")
		)
		(pad "M7" smd circle
			(at 1.599946 2.800096 270)
			(size 0.3556 0.3556)
			(layers "F.Cu" "F.Mask" "F.Paste")
			(net "Net_185")
		)
		(pad "M8" smd circle
			(at 2.400046 2.800096 270)
			(size 0.3556 0.3556)
			(layers "F.Cu" "F.Mask" "F.Paste")
			(net "DDR_VREF")
		)
		(pad "M9" smd circle
			(at 3.199892 2.800096 270)
			(size 0.3556 0.3556)
			(layers "F.Cu" "F.Mask" "F.Paste")
			(net "GND")
		)
		(pad "N1" smd circle
			(at -3.199892 3.599942 270)
			(size 0.3556 0.3556)
			(layers "F.Cu" "F.Mask" "F.Paste")
			(net "P1V53_STBY")
		)
		(pad "N2" smd circle
			(at -2.400046 3.599942 270)
			(size 0.3556 0.3556)
			(layers "F.Cu" "F.Mask" "F.Paste")
			(net "MEMA_3")
		)
		(pad "N3" smd circle
			(at -1.599946 3.599942 270)
			(size 0.3556 0.3556)
			(layers "F.Cu" "F.Mask" "F.Paste")
			(net "MEMA_0")
		)
		(pad "N7" smd circle
			(at 1.599946 3.599942 270)
			(size 0.3556 0.3556)
			(layers "F.Cu" "F.Mask" "F.Paste")
			(net "MEMA_12")
		)
		(pad "N8" smd circle
			(at 2.400046 3.599942 270)
			(size 0.3556 0.3556)
			(layers "F.Cu" "F.Mask" "F.Paste")
			(net "MEMBA_1")
		)
		(pad "N9" smd circle
			(at 3.199892 3.599942 270)
			(size 0.3556 0.3556)
			(layers "F.Cu" "F.Mask" "F.Paste")
			(net "P1V53_STBY")
		)
		(pad "P1" smd circle
			(at -3.199892 4.400042 270)
			(size 0.3556 0.3556)
			(layers "F.Cu" "F.Mask" "F.Paste")
			(net "GND")
		)
		(pad "P2" smd circle
			(at -2.400046 4.400042 270)
			(size 0.3556 0.3556)
			(layers "F.Cu" "F.Mask" "F.Paste")
			(net "MEMA_5")
		)
		(pad "P3" smd circle
			(at -1.599946 4.400042 270)
			(size 0.3556 0.3556)
			(layers "F.Cu" "F.Mask" "F.Paste")
			(net "MEMA_2")
		)
		(pad "P7" smd circle
			(at 1.599946 4.400042 270)
			(size 0.3556 0.3556)
			(layers "F.Cu" "F.Mask" "F.Paste")
			(net "MEMA_1")
		)
		(pad "P8" smd circle
			(at 2.400046 4.400042 270)
			(size 0.3556 0.3556)
			(layers "F.Cu" "F.Mask" "F.Paste")
			(net "MEMA_4")
		)
		(pad "P9" smd circle
			(at 3.199892 4.400042 270)
			(size 0.3556 0.3556)
			(layers "F.Cu" "F.Mask" "F.Paste")
			(net "GND")
		)
		(pad "R1" smd circle
			(at -3.199892 5.199888 270)
			(size 0.3556 0.3556)
			(layers "F.Cu" "F.Mask" "F.Paste")
			(net "P1V53_STBY")
		)
		(pad "R2" smd circle
			(at -2.400046 5.199888 270)
			(size 0.3556 0.3556)
			(layers "F.Cu" "F.Mask" "F.Paste")
			(net "MEMA_7")
		)
		(pad "R3" smd circle
			(at -1.599946 5.199888 270)
			(size 0.3556 0.3556)
			(layers "F.Cu" "F.Mask" "F.Paste")
			(net "MEMA_9")
		)
		(pad "R7" smd circle
			(at 1.599946 5.199888 270)
			(size 0.3556 0.3556)
			(layers "F.Cu" "F.Mask" "F.Paste")
			(net "MEMA_11")
		)
		(pad "R8" smd circle
			(at 2.400046 5.199888 270)
			(size 0.3556 0.3556)
			(layers "F.Cu" "F.Mask" "F.Paste")
			(net "MEMA_6")
		)
		(pad "R9" smd circle
			(at 3.199892 5.199888 270)
			(size 0.3556 0.3556)
			(layers "F.Cu" "F.Mask" "F.Paste")
			(net "P1V53_STBY")
		)
		(pad "T1" smd circle
			(at -3.199892 5.999988 270)
			(size 0.3556 0.3556)
			(layers "F.Cu" "F.Mask" "F.Paste")
			(net "GND")
		)
		(pad "T2" smd circle
			(at -2.400046 5.999988 270)
			(size 0.3556 0.3556)
			(layers "F.Cu" "F.Mask" "F.Paste")
			(net "BMC_DDR3_RST_N")
		)
		(pad "T3" smd circle
			(at -1.599946 5.999988 270)
			(size 0.3556 0.3556)
			(layers "F.Cu" "F.Mask" "F.Paste")
			(net "MEMA_13")
		)
		(pad "T7" smd circle
			(at 1.599946 5.999988 270)
			(size 0.3556 0.3556)
			(layers "F.Cu" "F.Mask" "F.Paste")
			(net "MEMA_14")
		)
		(pad "T8" smd circle
			(at 2.400046 5.999988 270)
			(size 0.3556 0.3556)
			(layers "F.Cu" "F.Mask" "F.Paste")
			(net "MEMA_8")
		)
		(pad "T9" smd circle
			(at 3.199892 5.999988 270)
			(size 0.3556 0.3556)
			(layers "F.Cu" "F.Mask" "F.Paste")
			(net "GND")
		)
	)
	(footprint ""
		(layer "F.Cu")
		(at 65.405 -114.106452)
		(property "Reference" "R488"
			(at 0 0 0)
			(layer "F.SilkS")
			(hide yes)
			(effects
				(font
					(size 1.27 1.27)
				)
			)
		)
		(property "Value" "0R2J-2-GP"
			(at 0.064008 -3.993896 0)
			(unlocked yes)
			(layer "F.Fab")
			(hide yes)
			(effects
				(font
					(size 1.016 1.016)
					(thickness 0.1524)
				)
			)
		)
		(property "Device Type" "R402H16"
			(at 0.064008 -5.517896 0)
			(unlocked yes)
			(layer "F.Fab")
			(hide yes)
			(effects
				(font
					(size 1.016 1.016)
					(thickness 0.1524)
				)
			)
		)
		(duplicate_pad_numbers_are_jumpers no)
		(fp_line
			(start -0.508 -0.9398)
			(end -0.508 0.9398)
			(stroke
				(width 0.1524)
				(type default)
			)
			(layer "F.SilkS")
		)
		(fp_line
			(start 0.508 -0.9398)
			(end -0.508 -0.9398)
			(stroke
				(width 0.1524)
				(type default)
			)
			(layer "F.SilkS")
		)
		(fp_rect
			(start -0.508 0.9398)
			(end 0.508 -0.9398)
			(stroke
				(width 0)
				(type default)
			)
			(fill no)
			(layer "F.CrtYd")
		)
		(fp_rect
			(start -0.508 0.9398)
			(end 0.508 -0.9398)
			(stroke
				(width 0)
				(type default)
			)
			(fill no)
			(layer "F.Fab")
		)
		(pad "1" smd custom
			(at 0 -0.4445)
			(size 0.1397 0.1397)
			(layers "F.Cu" "F.Mask" "F.Paste")
			(net "BMC0_SCL11_R")
			(options
				(clearance outline)
				(anchor circle)
			)
			(primitives
				(gr_poly
					(pts
						(arc
							(start -0.1778 -0.2794)
							(mid -0.249642 -0.249642)
							(end -0.2794 -0.1778)
						)
						(arc
							(start -0.2794 0.1778)
							(mid -0.249642 0.249642)
							(end -0.1778 0.2794)
						)
						(arc
							(start 0.1778 0.2794)
							(mid 0.249642 0.249642)
							(end 0.2794 0.1778)
						)
						(arc
							(start 0.2794 -0.1778)
							(mid 0.249642 -0.249642)
							(end 0.1778 -0.2794)
						)
					)
					(width 0)
					(fill yes)
				)
			)
		)
		(pad "2" smd custom
			(at 0 0.4445)
			(size 0.1397 0.1397)
			(layers "F.Cu" "F.Mask" "F.Paste")
			(net "BMC_I2C11_MINI5_SCL_S")
			(options
				(clearance outline)
				(anchor circle)
			)
			(primitives
				(gr_poly
					(pts
						(arc
							(start -0.1778 -0.2794)
							(mid -0.249642 -0.249642)
							(end -0.2794 -0.1778)
						)
						(arc
							(start -0.2794 0.1778)
							(mid -0.249642 0.249642)
							(end -0.1778 0.2794)
						)
						(arc
							(start 0.1778 0.2794)
							(mid 0.249642 0.249642)
							(end 0.2794 0.1778)
						)
						(arc
							(start 0.2794 -0.1778)
							(mid 0.249642 -0.249642)
							(end 0.1778 -0.2794)
						)
					)
					(width 0)
					(fill yes)
				)
			)
		)
	)
	(footprint ""
		(layer "F.Cu")
		(at 54.792118 -212.420454 180)
		(property "Reference" "C361"
			(at 0 0 180)
			(layer "F.SilkS")
			(hide yes)
			(effects
				(font
					(size 1.27 1.27)
				)
			)
		)
		(property "Value" "SCD22U10V2KX-1GP"
			(at 1.1811 -2.7051 180)
			(unlocked yes)
			(layer "F.Fab")
			(hide yes)
			(effects
				(font
					(size 1.016 1.016)
					(thickness 0.1524)
				)
			)
		)
		(property "Device Type" "C402H22"
			(at 1.1811 -4.2291 180)
			(unlocked yes)
			(layer "F.Fab")
			(hide yes)
			(effects
				(font
					(size 1.016 1.016)
					(thickness 0.1524)
				)
			)
		)
		(duplicate_pad_numbers_are_jumpers no)
		(fp_rect
			(start -0.4318 0.9525)
			(end 0.4318 -0.9525)
			(stroke
				(width 0)
				(type default)
			)
			(fill no)
			(layer "F.CrtYd")
		)
		(fp_rect
			(start -0.4318 0.9525)
			(end 0.4318 -0.9525)
			(stroke
				(width 0)
				(type default)
			)
			(fill no)
			(layer "F.Fab")
		)
		(pad "1" smd custom
			(at 0 -0.4445 180)
			(size 0.1524 0.1524)
			(layers "F.Cu" "F.Mask" "F.Paste")
			(net "PCIE_TX_CAP_P73")
			(options
				(clearance outline)
				(anchor circle)
			)
			(primitives
				(gr_poly
					(pts
						(arc
							(start 0.3048 -0.2032)
							(mid 0.275042 -0.275042)
							(end 0.2032 -0.3048)
						)
						(arc
							(start -0.2032 -0.3048)
							(mid -0.275042 -0.275042)
							(end -0.3048 -0.2032)
						)
						(arc
							(start -0.3048 0.2032)
							(mid -0.275042 0.275042)
							(end -0.2032 0.3048)
						)
						(arc
							(start 0.2032 0.3048)
							(mid 0.275042 0.275042)
							(end 0.3048 0.2032)
						)
					)
					(width 0)
					(fill yes)
				)
			)
		)
		(pad "2" smd custom
			(at 0 0.4445 180)
			(size 0.1524 0.1524)
			(layers "F.Cu" "F.Mask" "F.Paste")
			(net "PCIE_TX_P73")
			(options
				(clearance outline)
				(anchor circle)
			)
			(primitives
				(gr_poly
					(pts
						(arc
							(start 0.3048 -0.2032)
							(mid 0.275042 -0.275042)
							(end 0.2032 -0.3048)
						)
						(arc
							(start -0.2032 -0.3048)
							(mid -0.275042 -0.275042)
							(end -0.3048 -0.2032)
						)
						(arc
							(start -0.3048 0.2032)
							(mid -0.275042 0.275042)
							(end -0.2032 0.3048)
						)
						(arc
							(start 0.2032 0.3048)
							(mid 0.275042 0.275042)
							(end 0.3048 0.2032)
						)
					)
					(width 0)
					(fill yes)
				)
			)
		)
	)
	(footprint ""
		(layer "F.Cu")
		(at 331.216 -9.652)
		(property "Reference" "SR712"
			(at 0 0 0)
			(layer "F.SilkS")
			(hide yes)
			(effects
				(font
					(size 1.27 1.27)
				)
			)
		)
		(property "Value" "150R2F-1-GP"
			(at 0.064008 -3.993896 0)
			(unlocked yes)
			(layer "F.Fab")
			(hide yes)
			(effects
				(font
					(size 1.016 1.016)
					(thickness 0.1524)
				)
			)
		)
		(property "Device Type" "R402H16"
			(at 0.064008 -5.517896 0)
			(unlocked yes)
			(layer "F.Fab")
			(hide yes)
			(effects
				(font
					(size 1.016 1.016)
					(thickness 0.1524)
				)
			)
		)
		(duplicate_pad_numbers_are_jumpers no)
		(fp_line
			(start -0.508 -0.9398)
			(end -0.508 0.9398)
			(stroke
				(width 0.1524)
				(type default)
			)
			(layer "F.SilkS")
		)
		(fp_line
			(start 0.508 -0.9398)
			(end -0.508 -0.9398)
			(stroke
				(width 0.1524)
				(type default)
			)
			(layer "F.SilkS")
		)
		(fp_rect
			(start -0.508 0.9398)
			(end 0.508 -0.9398)
			(stroke
				(width 0)
				(type default)
			)
			(fill no)
			(layer "F.CrtYd")
		)
		(fp_rect
			(start -0.508 0.9398)
			(end 0.508 -0.9398)
			(stroke
				(width 0)
				(type default)
			)
			(fill no)
			(layer "F.Fab")
		)
		(pad "1" smd custom
			(at 0 -0.4445)
			(size 0.1397 0.1397)
			(layers "F.Cu" "F.Mask" "F.Paste")
			(net "P3V3_STBY")
			(options
				(clearance outline)
				(anchor circle)
			)
			(primitives
				(gr_poly
					(pts
						(arc
							(start -0.1778 -0.2794)
							(mid -0.249642 -0.249642)
							(end -0.2794 -0.1778)
						)
						(arc
							(start -0.2794 0.1778)
							(mid -0.249642 0.249642)
							(end -0.1778 0.2794)
						)
						(arc
							(start 0.1778 0.2794)
							(mid 0.249642 0.249642)
							(end 0.2794 0.1778)
						)
						(arc
							(start 0.2794 -0.1778)
							(mid 0.249642 -0.249642)
							(end 0.1778 -0.2794)
						)
					)
					(width 0)
					(fill yes)
				)
			)
		)
		(pad "2" smd custom
			(at 0 0.4445)
			(size 0.1397 0.1397)
			(layers "F.Cu" "F.Mask" "F.Paste")
			(net "LED_R_7")
			(options
				(clearance outline)
				(anchor circle)
			)
			(primitives
				(gr_poly
					(pts
						(arc
							(start -0.1778 -0.2794)
							(mid -0.249642 -0.249642)
							(end -0.2794 -0.1778)
						)
						(arc
							(start -0.2794 0.1778)
							(mid -0.249642 0.249642)
							(end -0.1778 0.2794)
						)
						(arc
							(start 0.1778 0.2794)
							(mid 0.249642 0.249642)
							(end 0.2794 0.1778)
						)
						(arc
							(start 0.2794 -0.1778)
							(mid 0.249642 -0.249642)
							(end 0.1778 -0.2794)
						)
					)
					(width 0)
					(fill yes)
				)
			)
		)
	)
	(footprint ""
		(layer "F.Cu")
		(at 229.997 -84.582 180)
		(property "Reference" "C328"
			(at 0 0 180)
			(layer "F.SilkS")
			(hide yes)
			(effects
				(font
					(size 1.27 1.27)
				)
			)
		)
		(property "Value" "SCD1U16V2KX-3GP"
			(at 1.1811 -2.7051 180)
			(unlocked yes)
			(layer "F.Fab")
			(hide yes)
			(effects
				(font
					(size 1.016 1.016)
					(thickness 0.1524)
				)
			)
		)
		(property "Device Type" "C402H22"
			(at 1.1811 -4.2291 180)
			(unlocked yes)
			(layer "F.Fab")
			(hide yes)
			(effects
				(font
					(size 1.016 1.016)
					(thickness 0.1524)
				)
			)
		)
		(duplicate_pad_numbers_are_jumpers no)
		(fp_rect
			(start -0.4318 0.9525)
			(end 0.4318 -0.9525)
			(stroke
				(width 0)
				(type default)
			)
			(fill no)
			(layer "F.CrtYd")
		)
		(fp_rect
			(start -0.4318 0.9525)
			(end 0.4318 -0.9525)
			(stroke
				(width 0)
				(type default)
			)
			(fill no)
			(layer "F.Fab")
		)
		(pad "1" smd custom
			(at 0 -0.4445 180)
			(size 0.1524 0.1524)
			(layers "F.Cu" "F.Mask" "F.Paste")
			(net "P3V3_STBY")
			(options
				(clearance outline)
				(anchor circle)
			)
			(primitives
				(gr_poly
					(pts
						(arc
							(start 0.3048 -0.2032)
							(mid 0.275042 -0.275042)
							(end 0.2032 -0.3048)
						)
						(arc
							(start -0.2032 -0.3048)
							(mid -0.275042 -0.275042)
							(end -0.3048 -0.2032)
						)
						(arc
							(start -0.3048 0.2032)
							(mid -0.275042 0.275042)
							(end -0.2032 0.3048)
						)
						(arc
							(start 0.2032 0.3048)
							(mid 0.275042 0.275042)
							(end 0.3048 0.2032)
						)
					)
					(width 0)
					(fill yes)
				)
			)
		)
		(pad "2" smd custom
			(at 0 0.4445 180)
			(size 0.1524 0.1524)
			(layers "F.Cu" "F.Mask" "F.Paste")
			(net "GND")
			(options
				(clearance outline)
				(anchor circle)
			)
			(primitives
				(gr_poly
					(pts
						(arc
							(start 0.3048 -0.2032)
							(mid 0.275042 -0.275042)
							(end 0.2032 -0.3048)
						)
						(arc
							(start -0.2032 -0.3048)
							(mid -0.275042 -0.275042)
							(end -0.3048 -0.2032)
						)
						(arc
							(start -0.3048 0.2032)
							(mid -0.275042 0.275042)
							(end -0.2032 0.3048)
						)
						(arc
							(start 0.2032 0.3048)
							(mid 0.275042 0.275042)
							(end 0.3048 0.2032)
						)
					)
					(width 0)
					(fill yes)
				)
			)
		)
	)
	(footprint ""
		(layer "F.Cu")
		(at 24.218646 -121.219214 90)
		(property "Reference" "R541"
			(at 0 0 90)
			(layer "F.SilkS")
			(hide yes)
			(effects
				(font
					(size 1.27 1.27)
				)
			)
		)
		(property "Value" "0R2J-2-GP"
			(at 0.064008 -3.993896 90)
			(unlocked yes)
			(layer "F.Fab")
			(hide yes)
			(effects
				(font
					(size 1.016 1.016)
					(thickness 0.1524)
				)
			)
		)
		(property "Device Type" "R402H16"
			(at 0.064008 -5.517896 90)
			(unlocked yes)
			(layer "F.Fab")
			(hide yes)
			(effects
				(font
					(size 1.016 1.016)
					(thickness 0.1524)
				)
			)
		)
		(duplicate_pad_numbers_are_jumpers no)
		(fp_line
			(start 0.508 -0.9398)
			(end -0.508 -0.9398)
			(stroke
				(width 0.1524)
				(type default)
			)
			(layer "F.SilkS")
		)
		(fp_line
			(start -0.508 -0.9398)
			(end -0.508 0.9398)
			(stroke
				(width 0.1524)
				(type default)
			)
			(layer "F.SilkS")
		)
		(fp_rect
			(start -0.508 0.9398)
			(end 0.508 -0.9398)
			(stroke
				(width 0)
				(type default)
			)
			(fill no)
			(layer "F.CrtYd")
		)
		(fp_rect
			(start -0.508 0.9398)
			(end 0.508 -0.9398)
			(stroke
				(width 0)
				(type default)
			)
			(fill no)
			(layer "F.Fab")
		)
		(pad "1" smd custom
			(at 0 -0.4445 90)
			(size 0.1397 0.1397)
			(layers "F.Cu" "F.Mask" "F.Paste")
			(net "P0V9_E_PG")
			(options
				(clearance outline)
				(anchor circle)
			)
			(primitives
				(gr_poly
					(pts
						(arc
							(start -0.1778 -0.2794)
							(mid -0.249642 -0.249642)
							(end -0.2794 -0.1778)
						)
						(arc
							(start -0.2794 0.1778)
							(mid -0.249642 0.249642)
							(end -0.1778 0.2794)
						)
						(arc
							(start 0.1778 0.2794)
							(mid 0.249642 0.249642)
							(end 0.2794 0.1778)
						)
						(arc
							(start 0.2794 -0.1778)
							(mid 0.249642 -0.249642)
							(end 0.1778 -0.2794)
						)
					)
					(width 0)
					(fill yes)
				)
			)
		)
		(pad "2" smd custom
			(at 0 0.4445 90)
			(size 0.1397 0.1397)
			(layers "F.Cu" "F.Mask" "F.Paste")
			(net "PWGD_P0V9_E_PG_R")
			(options
				(clearance outline)
				(anchor circle)
			)
			(primitives
				(gr_poly
					(pts
						(arc
							(start -0.1778 -0.2794)
							(mid -0.249642 -0.249642)
							(end -0.2794 -0.1778)
						)
						(arc
							(start -0.2794 0.1778)
							(mid -0.249642 0.249642)
							(end -0.1778 0.2794)
						)
						(arc
							(start 0.1778 0.2794)
							(mid 0.249642 0.249642)
							(end 0.2794 0.1778)
						)
						(arc
							(start 0.2794 -0.1778)
							(mid 0.249642 -0.249642)
							(end 0.1778 -0.2794)
						)
					)
					(width 0)
					(fill yes)
				)
			)
		)
	)
	(footprint ""
		(layer "F.Cu")
		(at 64.389 -133.985)
		(property "Reference" "R5762"
			(at 0 0 0)
			(layer "F.SilkS")
			(hide yes)
			(effects
				(font
					(size 1.27 1.27)
				)
			)
		)
		(property "Value" "1KR2F-3-GP"
			(at 0.064008 -3.993896 0)
			(unlocked yes)
			(layer "F.Fab")
			(hide yes)
			(effects
				(font
					(size 1.016 1.016)
					(thickness 0.1524)
				)
			)
		)
		(property "Device Type" "R402H16"
			(at 0.064008 -5.517896 0)
			(unlocked yes)
			(layer "F.Fab")
			(hide yes)
			(effects
				(font
					(size 1.016 1.016)
					(thickness 0.1524)
				)
			)
		)
		(duplicate_pad_numbers_are_jumpers no)
		(fp_line
			(start -0.508 -0.9398)
			(end -0.508 0.9398)
			(stroke
				(width 0.1524)
				(type default)
			)
			(layer "F.SilkS")
		)
		(fp_line
			(start 0.508 -0.9398)
			(end -0.508 -0.9398)
			(stroke
				(width 0.1524)
				(type default)
			)
			(layer "F.SilkS")
		)
		(fp_rect
			(start -0.508 0.9398)
			(end 0.508 -0.9398)
			(stroke
				(width 0)
				(type default)
			)
			(fill no)
			(layer "F.CrtYd")
		)
		(fp_rect
			(start -0.508 0.9398)
			(end 0.508 -0.9398)
			(stroke
				(width 0)
				(type default)
			)
			(fill no)
			(layer "F.Fab")
		)
		(pad "1" smd custom
			(at 0 -0.4445)
			(size 0.1397 0.1397)
			(layers "F.Cu" "F.Mask" "F.Paste")
			(net "ADC_P0V9")
			(options
				(clearance outline)
				(anchor circle)
			)
			(primitives
				(gr_poly
					(pts
						(arc
							(start -0.1778 -0.2794)
							(mid -0.249642 -0.249642)
							(end -0.2794 -0.1778)
						)
						(arc
							(start -0.2794 0.1778)
							(mid -0.249642 0.249642)
							(end -0.1778 0.2794)
						)
						(arc
							(start 0.1778 0.2794)
							(mid 0.249642 0.249642)
							(end 0.2794 0.1778)
						)
						(arc
							(start 0.2794 -0.1778)
							(mid 0.249642 -0.249642)
							(end 0.1778 -0.2794)
						)
					)
					(width 0)
					(fill yes)
				)
			)
		)
		(pad "2" smd custom
			(at 0 0.4445)
			(size 0.1397 0.1397)
			(layers "F.Cu" "F.Mask" "F.Paste")
			(net "GND")
			(options
				(clearance outline)
				(anchor circle)
			)
			(primitives
				(gr_poly
					(pts
						(arc
							(start -0.1778 -0.2794)
							(mid -0.249642 -0.249642)
							(end -0.2794 -0.1778)
						)
						(arc
							(start -0.2794 0.1778)
							(mid -0.249642 0.249642)
							(end -0.1778 0.2794)
						)
						(arc
							(start 0.1778 0.2794)
							(mid 0.249642 0.249642)
							(end 0.2794 0.1778)
						)
						(arc
							(start 0.2794 -0.1778)
							(mid 0.249642 -0.249642)
							(end 0.1778 -0.2794)
						)
					)
					(width 0)
					(fill yes)
				)
			)
		)
	)
	(footprint ""
		(layer "F.Cu")
		(at 24.5618 -173.2026 -90)
		(property "Reference" "R617"
			(at 0 0 270)
			(layer "F.SilkS")
			(hide yes)
			(effects
				(font
					(size 1.27 1.27)
				)
			)
		)
		(property "Value" "27KR2F-L-GP"
			(at 0.064008 -3.993896 270)
			(unlocked yes)
			(layer "F.Fab")
			(hide yes)
			(effects
				(font
					(size 1.016 1.016)
					(thickness 0.1524)
				)
			)
		)
		(property "Device Type" "R402H16"
			(at 0.064008 -5.517896 270)
			(unlocked yes)
			(layer "F.Fab")
			(hide yes)
			(effects
				(font
					(size 1.016 1.016)
					(thickness 0.1524)
				)
			)
		)
		(duplicate_pad_numbers_are_jumpers no)
		(fp_line
			(start -0.508 -0.9398)
			(end -0.508 0.9398)
			(stroke
				(width 0.1524)
				(type default)
			)
			(layer "F.SilkS")
		)
		(fp_line
			(start 0.508 -0.9398)
			(end -0.508 -0.9398)
			(stroke
				(width 0.1524)
				(type default)
			)
			(layer "F.SilkS")
		)
		(fp_rect
			(start -0.508 0.9398)
			(end 0.508 -0.9398)
			(stroke
				(width 0)
				(type default)
			)
			(fill no)
			(layer "F.CrtYd")
		)
		(fp_rect
			(start -0.508 0.9398)
			(end 0.508 -0.9398)
			(stroke
				(width 0)
				(type default)
			)
			(fill no)
			(layer "F.Fab")
		)
		(pad "1" smd custom
			(at 0 -0.4445 270)
			(size 0.1397 0.1397)
			(layers "F.Cu" "F.Mask" "F.Paste")
			(net "PCIE_MATED#_A")
			(options
				(clearance outline)
				(anchor circle)
			)
			(primitives
				(gr_poly
					(pts
						(arc
							(start -0.1778 -0.2794)
							(mid -0.249642 -0.249642)
							(end -0.2794 -0.1778)
						)
						(arc
							(start -0.2794 0.1778)
							(mid -0.249642 0.249642)
							(end -0.1778 0.2794)
						)
						(arc
							(start 0.1778 0.2794)
							(mid 0.249642 0.249642)
							(end 0.2794 0.1778)
						)
						(arc
							(start 0.2794 -0.1778)
							(mid 0.249642 -0.249642)
							(end 0.1778 -0.2794)
						)
					)
					(width 0)
					(fill yes)
				)
			)
		)
		(pad "2" smd custom
			(at 0 0.4445 270)
			(size 0.1397 0.1397)
			(layers "F.Cu" "F.Mask" "F.Paste")
			(net "P12V_PCIE")
			(options
				(clearance outline)
				(anchor circle)
			)
			(primitives
				(gr_poly
					(pts
						(arc
							(start -0.1778 -0.2794)
							(mid -0.249642 -0.249642)
							(end -0.2794 -0.1778)
						)
						(arc
							(start -0.2794 0.1778)
							(mid -0.249642 0.249642)
							(end -0.1778 0.2794)
						)
						(arc
							(start 0.1778 0.2794)
							(mid 0.249642 0.249642)
							(end 0.2794 0.1778)
						)
						(arc
							(start 0.2794 -0.1778)
							(mid 0.249642 -0.249642)
							(end 0.1778 -0.2794)
						)
					)
					(width 0)
					(fill yes)
				)
			)
		)
	)
	(footprint ""
		(layer "F.Cu")
		(at 222.758 -4.699 -90)
		(property "Reference" "Q19"
			(at 0 0 270)
			(layer "F.SilkS")
			(hide yes)
			(effects
				(font
					(size 1.27 1.27)
				)
			)
		)
		(property "Value" "2N7002K-1-GP"
			(at 0.127 -8.9662 270)
			(unlocked yes)
			(layer "F.Fab")
			(hide yes)
			(effects
				(font
					(size 1.016 1.016)
					(thickness 0.1524)
				)
			)
		)
		(property "Device Type" "SOT23DGS2D4H44"
			(at 0.127 -10.4902 270)
			(unlocked yes)
			(layer "F.Fab")
			(hide yes)
			(effects
				(font
					(size 1.016 1.016)
					(thickness 0.1524)
				)
			)
		)
		(duplicate_pad_numbers_are_jumpers no)
		(fp_line
			(start -1.651 1.778)
			(end 1.651 1.778)
			(stroke
				(width 0.1524)
				(type default)
			)
			(layer "F.SilkS")
		)
		(fp_line
			(start 1.651 1.778)
			(end 1.651 -1.778)
			(stroke
				(width 0.1524)
				(type default)
			)
			(layer "F.SilkS")
		)
		(fp_line
			(start -1.651 -1.778)
			(end -1.651 1.778)
			(stroke
				(width 0.1524)
				(type default)
			)
			(layer "F.SilkS")
		)
		(fp_line
			(start 1.651 -1.778)
			(end -1.651 -1.778)
			(stroke
				(width 0.1524)
				(type default)
			)
			(layer "F.SilkS")
		)
		(fp_poly
			(pts
				(xy -1.778 1.8796) (xy -1.778 -1.8796) (xy 1.778 -1.8796) (xy 1.778 1.8796)
			)
			(stroke
				(width 0)
				(type default)
			)
			(fill no)
			(layer "F.CrtYd")
		)
		(fp_poly
			(pts
				(xy -1.778 1.8796) (xy -1.778 -1.8796) (xy 1.778 -1.8796) (xy 1.778 1.8796)
			)
			(stroke
				(width 0)
				(type default)
			)
			(fill no)
			(layer "F.Fab")
		)
		(pad "D" smd custom
			(at 0 -0.9525 270)
			(size 0.1905 0.1905)
			(layers "F.Cu" "F.Mask" "F.Paste")
			(net "DEBUG_CONSOLE_LED_0")
			(options
				(clearance outline)
				(anchor circle)
			)
			(primitives
				(gr_poly
					(pts
						(arc
							(start -0.1778 0.5715)
							(mid -0.321484 0.511984)
							(end -0.381 0.3683)
						)
						(arc
							(start -0.381 -0.3683)
							(mid -0.321484 -0.511984)
							(end -0.1778 -0.5715)
						)
						(arc
							(start 0.1778 -0.5715)
							(mid 0.321484 -0.511984)
							(end 0.381 -0.3683)
						)
						(arc
							(start 0.381 0.3683)
							(mid 0.321484 0.511984)
							(end 0.1778 0.5715)
						)
					)
					(width 0)
					(fill yes)
				)
			)
		)
		(pad "G" smd custom
			(at -0.98425 0.9525 270)
			(size 0.1905 0.1905)
			(layers "F.Cu" "F.Mask" "F.Paste")
			(net "BMC_CONSOLE_LED0_R")
			(options
				(clearance outline)
				(anchor circle)
			)
			(primitives
				(gr_poly
					(pts
						(arc
							(start -0.1778 0.5715)
							(mid -0.321484 0.511984)
							(end -0.381 0.3683)
						)
						(arc
							(start -0.381 -0.3683)
							(mid -0.321484 -0.511984)
							(end -0.1778 -0.5715)
						)
						(arc
							(start 0.1778 -0.5715)
							(mid 0.321484 -0.511984)
							(end 0.381 -0.3683)
						)
						(arc
							(start 0.381 0.3683)
							(mid 0.321484 0.511984)
							(end 0.1778 0.5715)
						)
					)
					(width 0)
					(fill yes)
				)
			)
		)
		(pad "S" smd custom
			(at 0.98425 0.9525 270)
			(size 0.1905 0.1905)
			(layers "F.Cu" "F.Mask" "F.Paste")
			(net "GND")
			(options
				(clearance outline)
				(anchor circle)
			)
			(primitives
				(gr_poly
					(pts
						(arc
							(start -0.1778 0.5715)
							(mid -0.321484 0.511984)
							(end -0.381 0.3683)
						)
						(arc
							(start -0.381 -0.3683)
							(mid -0.321484 -0.511984)
							(end -0.1778 -0.5715)
						)
						(arc
							(start 0.1778 -0.5715)
							(mid 0.321484 -0.511984)
							(end 0.381 -0.3683)
						)
						(arc
							(start 0.381 0.3683)
							(mid 0.321484 0.511984)
							(end 0.1778 0.5715)
						)
					)
					(width 0)
					(fill yes)
				)
			)
		)
	)
	(footprint ""
		(layer "F.Cu")
		(at 138.4173 -33.54324)
		(property "Reference" "C386"
			(at 0 0 0)
			(layer "F.SilkS")
			(hide yes)
			(effects
				(font
					(size 1.27 1.27)
				)
			)
		)
		(property "Value" "SCD22U10V2KX-1GP"
			(at 1.1811 -2.7051 0)
			(unlocked yes)
			(layer "F.Fab")
			(hide yes)
			(effects
				(font
					(size 1.016 1.016)
					(thickness 0.1524)
				)
			)
		)
		(property "Device Type" "C402H22"
			(at 1.1811 -4.2291 0)
			(unlocked yes)
			(layer "F.Fab")
			(hide yes)
			(effects
				(font
					(size 1.016 1.016)
					(thickness 0.1524)
				)
			)
		)
		(duplicate_pad_numbers_are_jumpers no)
		(fp_rect
			(start -0.4318 0.9525)
			(end 0.4318 -0.9525)
			(stroke
				(width 0)
				(type default)
			)
			(fill no)
			(layer "F.CrtYd")
		)
		(fp_rect
			(start -0.4318 0.9525)
			(end 0.4318 -0.9525)
			(stroke
				(width 0)
				(type default)
			)
			(fill no)
			(layer "F.Fab")
		)
		(pad "1" smd custom
			(at 0 -0.4445)
			(size 0.1524 0.1524)
			(layers "F.Cu" "F.Mask" "F.Paste")
			(net "PCIE_TX_CAP_N83")
			(options
				(clearance outline)
				(anchor circle)
			)
			(primitives
				(gr_poly
					(pts
						(arc
							(start 0.3048 -0.2032)
							(mid 0.275042 -0.275042)
							(end 0.2032 -0.3048)
						)
						(arc
							(start -0.2032 -0.3048)
							(mid -0.275042 -0.275042)
							(end -0.3048 -0.2032)
						)
						(arc
							(start -0.3048 0.2032)
							(mid -0.275042 0.275042)
							(end -0.2032 0.3048)
						)
						(arc
							(start 0.2032 0.3048)
							(mid 0.275042 0.275042)
							(end 0.3048 0.2032)
						)
					)
					(width 0)
					(fill yes)
				)
			)
		)
		(pad "2" smd custom
			(at 0 0.4445)
			(size 0.1524 0.1524)
			(layers "F.Cu" "F.Mask" "F.Paste")
			(net "PCIE_TX_N83")
			(options
				(clearance outline)
				(anchor circle)
			)
			(primitives
				(gr_poly
					(pts
						(arc
							(start 0.3048 -0.2032)
							(mid 0.275042 -0.275042)
							(end 0.2032 -0.3048)
						)
						(arc
							(start -0.2032 -0.3048)
							(mid -0.275042 -0.275042)
							(end -0.3048 -0.2032)
						)
						(arc
							(start -0.3048 0.2032)
							(mid -0.275042 0.275042)
							(end -0.2032 0.3048)
						)
						(arc
							(start 0.2032 0.3048)
							(mid 0.275042 0.275042)
							(end 0.3048 0.2032)
						)
					)
					(width 0)
					(fill yes)
				)
			)
		)
	)
	(footprint ""
		(layer "F.Cu")
		(at 48.133 -145.415 180)
		(property "Reference" "R229"
			(at 0 0 180)
			(layer "F.SilkS")
			(hide yes)
			(effects
				(font
					(size 1.27 1.27)
				)
			)
		)
		(property "Value" "4K7R2F-GP"
			(at 0.064008 -3.993896 180)
			(unlocked yes)
			(layer "F.Fab")
			(hide yes)
			(effects
				(font
					(size 1.016 1.016)
					(thickness 0.1524)
				)
			)
		)
		(property "Device Type" "R402H16"
			(at 0.064008 -5.517896 180)
			(unlocked yes)
			(layer "F.Fab")
			(hide yes)
			(effects
				(font
					(size 1.016 1.016)
					(thickness 0.1524)
				)
			)
		)
		(duplicate_pad_numbers_are_jumpers no)
		(fp_line
			(start 0.508 -0.9398)
			(end -0.508 -0.9398)
			(stroke
				(width 0.1524)
				(type default)
			)
			(layer "F.SilkS")
		)
		(fp_line
			(start -0.508 -0.9398)
			(end -0.508 0.9398)
			(stroke
				(width 0.1524)
				(type default)
			)
			(layer "F.SilkS")
		)
		(fp_rect
			(start -0.508 0.9398)
			(end 0.508 -0.9398)
			(stroke
				(width 0)
				(type default)
			)
			(fill no)
			(layer "F.CrtYd")
		)
		(fp_rect
			(start -0.508 0.9398)
			(end 0.508 -0.9398)
			(stroke
				(width 0)
				(type default)
			)
			(fill no)
			(layer "F.Fab")
		)
		(pad "1" smd custom
			(at 0 -0.4445 180)
			(size 0.1397 0.1397)
			(layers "F.Cu" "F.Mask" "F.Paste")
			(net "HB_OUT_BMC")
			(options
				(clearance outline)
				(anchor circle)
			)
			(primitives
				(gr_poly
					(pts
						(arc
							(start -0.1778 -0.2794)
							(mid -0.249642 -0.249642)
							(end -0.2794 -0.1778)
						)
						(arc
							(start -0.2794 0.1778)
							(mid -0.249642 0.249642)
							(end -0.1778 0.2794)
						)
						(arc
							(start 0.1778 0.2794)
							(mid 0.249642 0.249642)
							(end 0.2794 0.1778)
						)
						(arc
							(start 0.2794 -0.1778)
							(mid 0.249642 -0.249642)
							(end 0.1778 -0.2794)
						)
					)
					(width 0)
					(fill yes)
				)
			)
		)
		(pad "2" smd custom
			(at 0 0.4445 180)
			(size 0.1397 0.1397)
			(layers "F.Cu" "F.Mask" "F.Paste")
			(net "P3V3_STBY")
			(options
				(clearance outline)
				(anchor circle)
			)
			(primitives
				(gr_poly
					(pts
						(arc
							(start -0.1778 -0.2794)
							(mid -0.249642 -0.249642)
							(end -0.2794 -0.1778)
						)
						(arc
							(start -0.2794 0.1778)
							(mid -0.249642 0.249642)
							(end -0.1778 0.2794)
						)
						(arc
							(start 0.1778 0.2794)
							(mid 0.249642 0.249642)
							(end 0.2794 0.1778)
						)
						(arc
							(start 0.2794 -0.1778)
							(mid 0.249642 -0.249642)
							(end 0.1778 -0.2794)
						)
					)
					(width 0)
					(fill yes)
				)
			)
		)
	)
	(footprint ""
		(layer "F.Cu")
		(at 75.300078 -226.70008 180)
		(property "Reference" "GF8"
			(at 0 0 180)
			(layer "F.SilkS")
			(hide yes)
			(effects
				(font
					(size 1.27 1.27)
				)
			)
		)
		(property "Value" "GF-200P-8-GP-U1"
			(at -43.1673 -7.6327 180)
			(unlocked yes)
			(layer "F.Fab")
			(hide yes)
			(effects
				(font
					(size 1.016 1.016)
					(thickness 0.1524)
				)
			)
		)
		(property "Device Type" "GF-200P-8-U1"
			(at -43.1673 -9.1567 180)
			(unlocked yes)
			(layer "F.Fab")
			(hide yes)
			(effects
				(font
					(size 1.016 1.016)
					(thickness 0.1524)
				)
			)
		)
		(duplicate_pad_numbers_are_jumpers no)
		(fp_rect
			(start -38.7096 2.032)
			(end 48.3108 -4.3434)
			(stroke
				(width 0)
				(type default)
			)
			(fill no)
			(layer "B.CrtYd")
		)
		(fp_rect
			(start -38.7096 2.032)
			(end 48.3108 -4.3434)
			(stroke
				(width 0)
				(type default)
			)
			(fill no)
			(layer "F.CrtYd")
		)
		(fp_rect
			(start -38.7096 2.032)
			(end 48.3108 -4.3434)
			(stroke
				(width 0)
				(type default)
			)
			(fill no)
			(layer "B.Fab")
		)
		(fp_rect
			(start -38.7096 2.032)
			(end 48.3108 -4.3434)
			(stroke
				(width 0)
				(type default)
			)
			(fill no)
			(layer "F.Fab")
		)
		(fp_text user "02 Do not mirror"
			(at -7.62 4.1148 180)
			(unlocked yes)
			(layer "F.Fab")
			(effects
				(font
					(size 1.016 1.016)
					(thickness 0.1524)
				)
				(justify left)
			)
		)
		(pad "A1" smd rect
			(at -36.399978 -1.1557 180)
			(size 0.5588 2.3114)
			(layers "F.Cu" "F.Mask" "F.Paste")
			(net "GND")
		)
		(pad "A2" smd rect
			(at -35.599878 -1.1557 180)
			(size 0.5588 2.3114)
			(layers "F.Cu" "F.Mask" "F.Paste")
			(net "PCIE_REFCLK_S1_N")
		)
		(pad "A3" smd rect
			(at -34.800032 -1.1557 180)
			(size 0.5588 2.3114)
			(layers "F.Cu" "F.Mask" "F.Paste")
			(net "PCIE_REFCLK_S1_P")
		)
		(pad "A4" smd rect
			(at -33.999932 -1.1557 180)
			(size 0.5588 2.3114)
			(layers "F.Cu" "F.Mask" "F.Paste")
			(net "GND")
		)
		(pad "A5" smd rect
			(at -33.200086 -1.1557 180)
			(size 0.5588 2.3114)
			(layers "F.Cu" "F.Mask" "F.Paste")
			(net "PCIE_TX_N60")
		)
		(pad "A6" smd rect
			(at -32.399986 -1.1557 180)
			(size 0.5588 2.3114)
			(layers "F.Cu" "F.Mask" "F.Paste")
			(net "PCIE_TX_P60")
		)
		(pad "A7" smd rect
			(at -31.599886 -1.1557 180)
			(size 0.5588 2.3114)
			(layers "F.Cu" "F.Mask" "F.Paste")
			(net "GND")
		)
		(pad "A8" smd rect
			(at -30.80004 -1.1557 180)
			(size 0.5588 2.3114)
			(layers "F.Cu" "F.Mask" "F.Paste")
			(net "GND")
		)
		(pad "A9" smd rect
			(at -29.99994 -1.1557 180)
			(size 0.5588 2.3114)
			(layers "F.Cu" "F.Mask" "F.Paste")
			(net "PCIE_TX_N61")
		)
		(pad "A10" smd rect
			(at -29.200094 -1.1557 180)
			(size 0.5588 2.3114)
			(layers "F.Cu" "F.Mask" "F.Paste")
			(net "PCIE_TX_P61")
		)
		(pad "A11" smd rect
			(at -28.399994 -1.1557 180)
			(size 0.5588 2.3114)
			(layers "F.Cu" "F.Mask" "F.Paste")
			(net "GND")
		)
		(pad "A12" smd rect
			(at -27.599894 -1.1557 180)
			(size 0.5588 2.3114)
			(layers "F.Cu" "F.Mask" "F.Paste")
			(net "GND")
		)
		(pad "A13" smd rect
			(at -26.800048 -1.1557 180)
			(size 0.5588 2.3114)
			(layers "F.Cu" "F.Mask" "F.Paste")
			(net "PCIE_TX_N62")
		)
		(pad "A14" smd rect
			(at -25.999948 -1.1557 180)
			(size 0.5588 2.3114)
			(layers "F.Cu" "F.Mask" "F.Paste")
			(net "PCIE_TX_P62")
		)
		(pad "A15" smd rect
			(at -25.200102 -1.1557 180)
			(size 0.5588 2.3114)
			(layers "F.Cu" "F.Mask" "F.Paste")
			(net "GND")
		)
		(pad "A16" smd rect
			(at -24.400002 -1.1557 180)
			(size 0.5588 2.3114)
			(layers "F.Cu" "F.Mask" "F.Paste")
			(net "GND")
		)
		(pad "A17" smd rect
			(at -23.599902 -1.1557 180)
			(size 0.5588 2.3114)
			(layers "F.Cu" "F.Mask" "F.Paste")
			(net "PCIE_TX_N63")
		)
		(pad "A18" smd rect
			(at -22.800056 -1.1557 180)
			(size 0.5588 2.3114)
			(layers "F.Cu" "F.Mask" "F.Paste")
			(net "PCIE_TX_P63")
		)
		(pad "A19" smd rect
			(at -21.999956 -1.1557 180)
			(size 0.5588 2.3114)
			(layers "F.Cu" "F.Mask" "F.Paste")
			(net "GND")
		)
		(pad "A20" smd rect
			(at -21.20011 -1.1557 180)
			(size 0.5588 2.3114)
			(layers "F.Cu" "F.Mask" "F.Paste")
			(net "SSD_PRSNT#1_R")
		)
		(pad "A21" smd rect
			(at -20.40001 -1.1557 180)
			(size 0.5588 2.3114)
			(layers "F.Cu" "F.Mask" "F.Paste")
			(net "SSD_ATNLED#1_R")
		)
		(pad "A22" smd rect
			(at -19.59991 -1.1557 180)
			(size 0.5588 2.3114)
			(layers "F.Cu" "F.Mask" "F.Paste")
			(net "SSD_PWREN1_R")
		)
		(pad "A23" smd rect
			(at -18.800064 -1.1557 180)
			(size 0.5588 2.3114)
			(layers "F.Cu" "F.Mask" "F.Paste")
			(net "GND")
		)
		(pad "A24" smd rect
			(at -17.999964 -1.1557 180)
			(size 0.5588 2.3114)
			(layers "F.Cu" "F.Mask" "F.Paste")
			(net "PCIE_TX_N64")
		)
		(pad "A25" smd rect
			(at -17.200118 -1.1557 180)
			(size 0.5588 2.3114)
			(layers "F.Cu" "F.Mask" "F.Paste")
			(net "PCIE_TX_P64")
		)
		(pad "A26" smd rect
			(at -16.400018 -1.1557 180)
			(size 0.5588 2.3114)
			(layers "F.Cu" "F.Mask" "F.Paste")
			(net "GND")
		)
		(pad "A27" smd rect
			(at -15.599918 -1.1557 180)
			(size 0.5588 2.3114)
			(layers "F.Cu" "F.Mask" "F.Paste")
			(net "GND")
		)
		(pad "A28" smd rect
			(at -14.800072 -1.1557 180)
			(size 0.5588 2.3114)
			(layers "F.Cu" "F.Mask" "F.Paste")
			(net "PCIE_TX_N65")
		)
		(pad "A29" smd rect
			(at -13.999972 -1.1557 180)
			(size 0.5588 2.3114)
			(layers "F.Cu" "F.Mask" "F.Paste")
			(net "PCIE_TX_P65")
		)
		(pad "A30" smd rect
			(at -13.200126 -1.1557 180)
			(size 0.5588 2.3114)
			(layers "F.Cu" "F.Mask" "F.Paste")
			(net "GND")
		)
		(pad "A31" smd rect
			(at -12.400026 -1.1557 180)
			(size 0.5588 2.3114)
			(layers "F.Cu" "F.Mask" "F.Paste")
			(net "GND")
		)
		(pad "A32" smd rect
			(at -11.599926 -1.1557 180)
			(size 0.5588 2.3114)
			(layers "F.Cu" "F.Mask" "F.Paste")
			(net "PCIE_TX_N66")
		)
		(pad "A33" smd rect
			(at -10.80008 -1.1557 180)
			(size 0.5588 2.3114)
			(layers "F.Cu" "F.Mask" "F.Paste")
			(net "PCIE_TX_P66")
		)
		(pad "A34" smd rect
			(at -9.99998 -1.1557 180)
			(size 0.5588 2.3114)
			(layers "F.Cu" "F.Mask" "F.Paste")
			(net "GND")
		)
		(pad "A35" smd rect
			(at -9.19988 -1.1557 180)
			(size 0.5588 2.3114)
			(layers "F.Cu" "F.Mask" "F.Paste")
			(net "GND")
		)
		(pad "A36" smd rect
			(at -8.400034 -1.1557 180)
			(size 0.5588 2.3114)
			(layers "F.Cu" "F.Mask" "F.Paste")
			(net "PCIE_TX_N67")
		)
		(pad "A37" smd rect
			(at -7.599934 -1.1557 180)
			(size 0.5588 2.3114)
			(layers "F.Cu" "F.Mask" "F.Paste")
			(net "PCIE_TX_P67")
		)
		(pad "A38" smd rect
			(at -6.800088 -1.1557 180)
			(size 0.5588 2.3114)
			(layers "F.Cu" "F.Mask" "F.Paste")
			(net "GND")
		)
		(pad "A39" smd rect
			(at -5.999988 -1.1557 180)
			(size 0.5588 2.3114)
			(layers "F.Cu" "F.Mask" "F.Paste")
			(net "GND")
		)
		(pad "A40" smd rect
			(at -5.199888 -1.1557 180)
			(size 0.5588 2.3114)
			(layers "F.Cu" "F.Mask" "F.Paste")
			(net "PCIE_TX_N68")
		)
		(pad "A41" smd rect
			(at -4.400042 -1.1557 180)
			(size 0.5588 2.3114)
			(layers "F.Cu" "F.Mask" "F.Paste")
			(net "PCIE_TX_P68")
		)
		(pad "A42" smd rect
			(at -3.599942 -1.1557 180)
			(size 0.5588 2.3114)
			(layers "F.Cu" "F.Mask" "F.Paste")
			(net "GND")
		)
		(pad "A43" smd rect
			(at -2.800096 -1.1557 180)
			(size 0.5588 2.3114)
			(layers "F.Cu" "F.Mask" "F.Paste")
			(net "SSD_PERST#1_R")
		)
		(pad "A44" smd rect
			(at -1.999996 -1.1557 180)
			(size 0.5588 2.3114)
			(layers "F.Cu" "F.Mask" "F.Paste")
			(net "SSD_PERST#0_R")
		)
		(pad "A45" smd rect
			(at 1.999996 -1.1557 180)
			(size 0.5588 2.3114)
			(layers "F.Cu" "F.Mask" "F.Paste")
			(net "PWM_EXP_A")
		)
		(pad "A46" smd rect
			(at 2.800096 -1.1557 180)
			(size 0.5588 1.8796)
			(drill
				(offset 0 -0.2159)
			)
			(layers "F.Cu" "F.Mask" "F.Paste")
			(net "PCIE_MATED#_A")
		)
		(pad "A47" smd rect
			(at 3.599942 -1.1557 180)
			(size 0.5588 2.3114)
			(layers "F.Cu" "F.Mask" "F.Paste")
			(net "GND")
		)
		(pad "A48" smd rect
			(at 4.400042 -1.1557 180)
			(size 0.5588 2.3114)
			(layers "F.Cu" "F.Mask" "F.Paste")
			(net "PCIE_TX_N69")
		)
		(pad "A49" smd rect
			(at 5.199888 -1.1557 180)
			(size 0.5588 2.3114)
			(layers "F.Cu" "F.Mask" "F.Paste")
			(net "PCIE_TX_P69")
		)
		(pad "A50" smd rect
			(at 5.999988 -1.1557 180)
			(size 0.5588 2.3114)
			(layers "F.Cu" "F.Mask" "F.Paste")
			(net "GND")
		)
		(pad "A51" smd rect
			(at 6.800088 -1.1557 180)
			(size 0.5588 2.3114)
			(layers "F.Cu" "F.Mask" "F.Paste")
			(net "GND")
		)
		(pad "A52" smd rect
			(at 7.599934 -1.1557 180)
			(size 0.5588 2.3114)
			(layers "F.Cu" "F.Mask" "F.Paste")
			(net "PCIE_TX_N70")
		)
		(pad "A53" smd rect
			(at 8.400034 -1.1557 180)
			(size 0.5588 2.3114)
			(layers "F.Cu" "F.Mask" "F.Paste")
			(net "PCIE_TX_P70")
		)
		(pad "A54" smd rect
			(at 9.19988 -1.1557 180)
			(size 0.5588 2.3114)
			(layers "F.Cu" "F.Mask" "F.Paste")
			(net "GND")
		)
		(pad "A55" smd rect
			(at 9.99998 -1.1557 180)
			(size 0.5588 2.3114)
			(layers "F.Cu" "F.Mask" "F.Paste")
			(net "GND")
		)
		(pad "A56" smd rect
			(at 10.80008 -1.1557 180)
			(size 0.5588 2.3114)
			(layers "F.Cu" "F.Mask" "F.Paste")
			(net "PCIE_TX_N71")
		)
		(pad "A57" smd rect
			(at 11.599926 -1.1557 180)
			(size 0.5588 2.3114)
			(layers "F.Cu" "F.Mask" "F.Paste")
			(net "PCIE_TX_P71")
		)
		(pad "A58" smd rect
			(at 12.400026 -1.1557 180)
			(size 0.5588 2.3114)
			(layers "F.Cu" "F.Mask" "F.Paste")
			(net "GND")
		)
		(pad "A59" smd rect
			(at 13.200126 -1.1557 180)
			(size 0.5588 2.3114)
			(layers "F.Cu" "F.Mask" "F.Paste")
			(net "SSD_PWREN0_R")
		)
		(pad "A60" smd rect
			(at 13.999972 -1.1557 180)
			(size 0.5588 2.3114)
			(layers "F.Cu" "F.Mask" "F.Paste")
			(net "SSD_ATNLED#0_R")
		)
		(pad "A61" smd rect
			(at 14.800072 -1.1557 180)
			(size 0.5588 2.3114)
			(layers "F.Cu" "F.Mask" "F.Paste")
			(net "SSD_PRSNT#0_R")
		)
		(pad "A62" smd rect
			(at 15.599918 -1.1557 180)
			(size 0.5588 2.3114)
			(layers "F.Cu" "F.Mask" "F.Paste")
			(net "GND")
		)
		(pad "A63" smd rect
			(at 16.400018 -1.1557 180)
			(size 0.5588 2.3114)
			(layers "F.Cu" "F.Mask" "F.Paste")
			(net "PCIE_TX_N72")
		)
		(pad "A64" smd rect
			(at 17.200118 -1.1557 180)
			(size 0.5588 2.3114)
			(layers "F.Cu" "F.Mask" "F.Paste")
			(net "PCIE_TX_P72")
		)
		(pad "A65" smd rect
			(at 17.999964 -1.1557 180)
			(size 0.5588 2.3114)
			(layers "F.Cu" "F.Mask" "F.Paste")
			(net "GND")
		)
		(pad "A66" smd rect
			(at 18.800064 -1.1557 180)
			(size 0.5588 2.3114)
			(layers "F.Cu" "F.Mask" "F.Paste")
			(net "GND")
		)
		(pad "A67" smd rect
			(at 19.59991 -1.1557 180)
			(size 0.5588 2.3114)
			(layers "F.Cu" "F.Mask" "F.Paste")
			(net "PCIE_TX_N73")
		)
		(pad "A68" smd rect
			(at 20.40001 -1.1557 180)
			(size 0.5588 2.3114)
			(layers "F.Cu" "F.Mask" "F.Paste")
			(net "PCIE_TX_P73")
		)
		(pad "A69" smd rect
			(at 21.20011 -1.1557 180)
			(size 0.5588 2.3114)
			(layers "F.Cu" "F.Mask" "F.Paste")
			(net "GND")
		)
		(pad "A70" smd rect
			(at 21.999956 -1.1557 180)
			(size 0.5588 2.3114)
			(layers "F.Cu" "F.Mask" "F.Paste")
			(net "GND")
		)
		(pad "A71" smd rect
			(at 22.800056 -1.1557 180)
			(size 0.5588 2.3114)
			(layers "F.Cu" "F.Mask" "F.Paste")
			(net "PCIE_TX_N74")
		)
		(pad "A72" smd rect
			(at 23.599902 -1.1557 180)
			(size 0.5588 2.3114)
			(layers "F.Cu" "F.Mask" "F.Paste")
			(net "PCIE_TX_P74")
		)
		(pad "A73" smd rect
			(at 24.400002 -1.1557 180)
			(size 0.5588 2.3114)
			(layers "F.Cu" "F.Mask" "F.Paste")
			(net "GND")
		)
		(pad "A74" smd rect
			(at 25.200102 -1.1557 180)
			(size 0.5588 2.3114)
			(layers "F.Cu" "F.Mask" "F.Paste")
			(net "GND")
		)
		(pad "A75" smd rect
			(at 25.999948 -1.1557 180)
			(size 0.5588 2.3114)
			(layers "F.Cu" "F.Mask" "F.Paste")
			(net "PCIE_TX_N75")
		)
		(pad "A76" smd rect
			(at 26.800048 -1.1557 180)
			(size 0.5588 2.3114)
			(layers "F.Cu" "F.Mask" "F.Paste")
			(net "PCIE_TX_P75")
		)
		(pad "A77" smd rect
			(at 27.599894 -1.1557 180)
			(size 0.5588 2.3114)
			(layers "F.Cu" "F.Mask" "F.Paste")
			(net "GND")
		)
		(pad "A78" smd rect
			(at 28.399994 -1.1557 180)
			(size 0.5588 2.3114)
			(layers "F.Cu" "F.Mask" "F.Paste")
			(net "PCIE_REFCLK_S4_P")
		)
		(pad "A79" smd rect
			(at 29.200094 -1.1557 180)
			(size 0.5588 2.3114)
			(layers "F.Cu" "F.Mask" "F.Paste")
			(net "PCIE_REFCLK_S4_N")
		)
		(pad "A80" smd rect
			(at 29.99994 -1.1557 180)
			(size 0.5588 2.3114)
			(layers "F.Cu" "F.Mask" "F.Paste")
			(net "GND")
		)
		(pad "A81" smd rect
			(at 30.80004 -1.1557 180)
			(size 0.5588 2.3114)
			(layers "F.Cu" "F.Mask" "F.Paste")
			(net "BUF_I2C7_B_DBP_SCL")
		)
		(pad "A82" smd rect
			(at 31.599886 -1.1557 180)
			(size 0.5588 2.3114)
			(layers "F.Cu" "F.Mask" "F.Paste")
			(net "BUF_I2C7_B_DPB_SDA")
		)
		(pad "A83" smd rect
			(at 32.399986 -1.1557 180)
			(size 0.5588 2.3114)
			(layers "F.Cu" "F.Mask" "F.Paste")
			(net "GND")
		)
		(pad "A84" smd rect
			(at 33.200086 -1.1557 180)
			(size 0.5588 2.3114)
			(layers "F.Cu" "F.Mask" "F.Paste")
			(net "BUF_I2C9_CLKBUF2_SCL")
		)
		(pad "A85" smd rect
			(at 33.999932 -1.1557 180)
			(size 0.5588 2.3114)
			(layers "F.Cu" "F.Mask" "F.Paste")
			(net "BUF_I2C9_CLKBUF2_SDA")
		)
		(pad "A86" smd rect
			(at 34.800032 -1.1557 180)
			(size 0.5588 2.3114)
			(layers "F.Cu" "F.Mask" "F.Paste")
			(net "GND")
		)
		(pad "A87" smd rect
			(at 35.599878 -1.1557 180)
			(size 0.5588 2.3114)
			(layers "F.Cu" "F.Mask" "F.Paste")
			(net "BUF_I2C6_C_FCB_SCL")
		)
		(pad "A88" smd rect
			(at 36.399978 -1.1557 180)
			(size 0.5588 2.3114)
			(layers "F.Cu" "F.Mask" "F.Paste")
			(net "BUF_I2C6_C_FCB_SDA")
		)
		(pad "A89" smd rect
			(at 37.200078 -1.1557 180)
			(size 0.5588 2.3114)
			(layers "F.Cu" "F.Mask" "F.Paste")
			(net "GND")
		)
		(pad "A90" smd rect
			(at 37.999924 -1.1557 180)
			(size 0.5588 2.3114)
			(layers "F.Cu" "F.Mask" "F.Paste")
			(net "GND")
		)
		(pad "A91" smd rect
			(at 38.800024 -1.1557 180)
			(size 0.5588 2.3114)
			(layers "F.Cu" "F.Mask" "F.Paste")
			(net "GND")
		)
		(pad "A92" smd rect
			(at 39.600124 -1.1557 180)
			(size 0.5588 2.3114)
			(layers "F.Cu" "F.Mask" "F.Paste")
			(net "GND")
		)
		(pad "A93" smd rect
			(at 40.39997 -1.1557 180)
			(size 0.5588 2.3114)
			(layers "F.Cu" "F.Mask" "F.Paste")
			(net "GND")
		)
		(pad "A94" smd rect
			(at 41.20007 -1.1557 180)
			(size 0.5588 2.3114)
			(layers "F.Cu" "F.Mask" "F.Paste")
			(net "GND")
		)
		(pad "A95" smd rect
			(at 41.999916 -1.1557 180)
			(size 0.5588 2.3114)
			(layers "F.Cu" "F.Mask" "F.Paste")
			(net "P12V_PCIE")
		)
		(pad "A96" smd rect
			(at 42.800016 -1.1557 180)
			(size 0.5588 2.3114)
			(layers "F.Cu" "F.Mask" "F.Paste")
			(net "P12V_PCIE")
		)
		(pad "A97" smd rect
			(at 43.600116 -1.1557 180)
			(size 0.5588 2.3114)
			(layers "F.Cu" "F.Mask" "F.Paste")
			(net "P12V_PCIE")
		)
		(pad "A98" smd rect
			(at 44.399962 -1.1557 180)
			(size 0.5588 2.3114)
			(layers "F.Cu" "F.Mask" "F.Paste")
			(net "P12V_PCIE")
		)
		(pad "A99" smd rect
			(at 45.200062 -1.1557 180)
			(size 0.5588 2.3114)
			(layers "F.Cu" "F.Mask" "F.Paste")
			(net "P12V_PCIE")
		)
		(pad "A100" smd rect
			(at 45.999908 -1.1557 180)
			(size 0.5588 1.8796)
			(drill
				(offset 0 -0.2159)
			)
			(layers "F.Cu" "F.Mask" "F.Paste")
			(net "P12V_PCIE")
		)
		(pad "B1" smd rect
			(at -36.399978 -0.7747 180)
			(size 0.5588 2.3114)
			(drill
				(offset 0 -0.381)
			)
			(layers "F.Cu" "F.Mask" "F.Paste")
			(net "GND")
		)
		(pad "B2" smd rect
			(at -35.599878 -0.7747 180)
			(size 0.5588 2.3114)
			(drill
				(offset 0 -0.381)
			)
			(layers "F.Cu" "F.Mask" "F.Paste")
			(net "PCIE_REFCLK_S2_P")
		)
		(pad "B3" smd rect
			(at -34.800032 -0.7747 180)
			(size 0.5588 2.3114)
			(drill
				(offset 0 -0.381)
			)
			(layers "F.Cu" "F.Mask" "F.Paste")
			(net "PCIE_REFCLK_S2_N")
		)
		(pad "B4" smd rect
			(at -33.999932 -0.7747 180)
			(size 0.5588 2.3114)
			(drill
				(offset 0 -0.381)
			)
			(layers "F.Cu" "F.Mask" "F.Paste")
			(net "GND")
		)
		(pad "B5" smd rect
			(at -33.200086 -0.7747 180)
			(size 0.5588 2.3114)
			(drill
				(offset 0 -0.381)
			)
			(layers "F.Cu" "F.Mask" "F.Paste")
			(net "SSD_PERST#10_R")
		)
		(pad "B6" smd rect
			(at -32.399986 -0.7747 180)
			(size 0.5588 2.3114)
			(drill
				(offset 0 -0.381)
			)
			(layers "F.Cu" "F.Mask" "F.Paste")
			(net "GND")
		)
		(pad "B7" smd rect
			(at -31.599886 -0.7747 180)
			(size 0.5588 2.3114)
			(drill
				(offset 0 -0.381)
			)
			(layers "F.Cu" "F.Mask" "F.Paste")
			(net "PCIE_RX_N60")
		)
		(pad "B8" smd rect
			(at -30.80004 -0.7747 180)
			(size 0.5588 2.3114)
			(drill
				(offset 0 -0.381)
			)
			(layers "F.Cu" "F.Mask" "F.Paste")
			(net "PCIE_RX_P60")
		)
		(pad "B9" smd rect
			(at -29.99994 -0.7747 180)
			(size 0.5588 2.3114)
			(drill
				(offset 0 -0.381)
			)
			(layers "F.Cu" "F.Mask" "F.Paste")
			(net "GND")
		)
		(pad "B10" smd rect
			(at -29.200094 -0.7747 180)
			(size 0.5588 2.3114)
			(drill
				(offset 0 -0.381)
			)
			(layers "F.Cu" "F.Mask" "F.Paste")
			(net "GND")
		)
		(pad "B11" smd rect
			(at -28.399994 -0.7747 180)
			(size 0.5588 2.3114)
			(drill
				(offset 0 -0.381)
			)
			(layers "F.Cu" "F.Mask" "F.Paste")
			(net "PCIE_RX_N61")
		)
		(pad "B12" smd rect
			(at -27.599894 -0.7747 180)
			(size 0.5588 2.3114)
			(drill
				(offset 0 -0.381)
			)
			(layers "F.Cu" "F.Mask" "F.Paste")
			(net "PCIE_RX_P61")
		)
		(pad "B13" smd rect
			(at -26.800048 -0.7747 180)
			(size 0.5588 2.3114)
			(drill
				(offset 0 -0.381)
			)
			(layers "F.Cu" "F.Mask" "F.Paste")
			(net "GND")
		)
		(pad "B14" smd rect
			(at -25.999948 -0.7747 180)
			(size 0.5588 2.3114)
			(drill
				(offset 0 -0.381)
			)
			(layers "F.Cu" "F.Mask" "F.Paste")
			(net "GND")
		)
		(pad "B15" smd rect
			(at -25.200102 -0.7747 180)
			(size 0.5588 2.3114)
			(drill
				(offset 0 -0.381)
			)
			(layers "F.Cu" "F.Mask" "F.Paste")
			(net "PCIE_RX_N62")
		)
		(pad "B16" smd rect
			(at -24.400002 -0.7747 180)
			(size 0.5588 2.3114)
			(drill
				(offset 0 -0.381)
			)
			(layers "F.Cu" "F.Mask" "F.Paste")
			(net "PCIE_RX_P62")
		)
		(pad "B17" smd rect
			(at -23.599902 -0.7747 180)
			(size 0.5588 2.3114)
			(drill
				(offset 0 -0.381)
			)
			(layers "F.Cu" "F.Mask" "F.Paste")
			(net "GND")
		)
		(pad "B18" smd rect
			(at -22.800056 -0.7747 180)
			(size 0.5588 2.3114)
			(drill
				(offset 0 -0.381)
			)
			(layers "F.Cu" "F.Mask" "F.Paste")
			(net "GND")
		)
		(pad "B19" smd rect
			(at -21.999956 -0.7747 180)
			(size 0.5588 2.3114)
			(drill
				(offset 0 -0.381)
			)
			(layers "F.Cu" "F.Mask" "F.Paste")
			(net "PCIE_RX_N63")
		)
		(pad "B20" smd rect
			(at -21.20011 -0.7747 180)
			(size 0.5588 2.3114)
			(drill
				(offset 0 -0.381)
			)
			(layers "F.Cu" "F.Mask" "F.Paste")
			(net "PCIE_RX_P63")
		)
		(pad "B21" smd rect
			(at -20.40001 -0.7747 180)
			(size 0.5588 2.3114)
			(drill
				(offset 0 -0.381)
			)
			(layers "F.Cu" "F.Mask" "F.Paste")
			(net "GND")
		)
		(pad "B22" smd rect
			(at -19.59991 -0.7747 180)
			(size 0.5588 2.3114)
			(drill
				(offset 0 -0.381)
			)
			(layers "F.Cu" "F.Mask" "F.Paste")
			(net "SSD_PWREN10_R")
		)
		(pad "B23" smd rect
			(at -18.800064 -0.7747 180)
			(size 0.5588 2.3114)
			(drill
				(offset 0 -0.381)
			)
			(layers "F.Cu" "F.Mask" "F.Paste")
			(net "SSD_ATNLED#10_R")
		)
		(pad "B24" smd rect
			(at -17.999964 -0.7747 180)
			(size 0.5588 2.3114)
			(drill
				(offset 0 -0.381)
			)
			(layers "F.Cu" "F.Mask" "F.Paste")
			(net "SSD_PRSNT#10_R")
		)
		(pad "B25" smd rect
			(at -17.200118 -0.7747 180)
			(size 0.5588 2.3114)
			(drill
				(offset 0 -0.381)
			)
			(layers "F.Cu" "F.Mask" "F.Paste")
			(net "GND")
		)
		(pad "B26" smd rect
			(at -16.400018 -0.7747 180)
			(size 0.5588 2.3114)
			(drill
				(offset 0 -0.381)
			)
			(layers "F.Cu" "F.Mask" "F.Paste")
			(net "PCIE_RX_N64")
		)
		(pad "B27" smd rect
			(at -15.599918 -0.7747 180)
			(size 0.5588 2.3114)
			(drill
				(offset 0 -0.381)
			)
			(layers "F.Cu" "F.Mask" "F.Paste")
			(net "PCIE_RX_P64")
		)
		(pad "B28" smd rect
			(at -14.800072 -0.7747 180)
			(size 0.5588 2.3114)
			(drill
				(offset 0 -0.381)
			)
			(layers "F.Cu" "F.Mask" "F.Paste")
			(net "GND")
		)
		(pad "B29" smd rect
			(at -13.999972 -0.7747 180)
			(size 0.5588 2.3114)
			(drill
				(offset 0 -0.381)
			)
			(layers "F.Cu" "F.Mask" "F.Paste")
			(net "GND")
		)
		(pad "B30" smd rect
			(at -13.200126 -0.7747 180)
			(size 0.5588 2.3114)
			(drill
				(offset 0 -0.381)
			)
			(layers "F.Cu" "F.Mask" "F.Paste")
			(net "PCIE_RX_N65")
		)
		(pad "B31" smd rect
			(at -12.400026 -0.7747 180)
			(size 0.5588 2.3114)
			(drill
				(offset 0 -0.381)
			)
			(layers "F.Cu" "F.Mask" "F.Paste")
			(net "PCIE_RX_P65")
		)
		(pad "B32" smd rect
			(at -11.599926 -0.7747 180)
			(size 0.5588 2.3114)
			(drill
				(offset 0 -0.381)
			)
			(layers "F.Cu" "F.Mask" "F.Paste")
			(net "GND")
		)
		(pad "B33" smd rect
			(at -10.80008 -0.7747 180)
			(size 0.5588 2.3114)
			(drill
				(offset 0 -0.381)
			)
			(layers "F.Cu" "F.Mask" "F.Paste")
			(net "GND")
		)
		(pad "B34" smd rect
			(at -9.99998 -0.7747 180)
			(size 0.5588 2.3114)
			(drill
				(offset 0 -0.381)
			)
			(layers "F.Cu" "F.Mask" "F.Paste")
			(net "PCIE_RX_N66")
		)
		(pad "B35" smd rect
			(at -9.19988 -0.7747 180)
			(size 0.5588 2.3114)
			(drill
				(offset 0 -0.381)
			)
			(layers "F.Cu" "F.Mask" "F.Paste")
			(net "PCIE_RX_P66")
		)
		(pad "B36" smd rect
			(at -8.400034 -0.7747 180)
			(size 0.5588 2.3114)
			(drill
				(offset 0 -0.381)
			)
			(layers "F.Cu" "F.Mask" "F.Paste")
			(net "GND")
		)
		(pad "B37" smd rect
			(at -7.599934 -0.7747 180)
			(size 0.5588 2.3114)
			(drill
				(offset 0 -0.381)
			)
			(layers "F.Cu" "F.Mask" "F.Paste")
			(net "GND")
		)
		(pad "B38" smd rect
			(at -6.800088 -0.7747 180)
			(size 0.5588 2.3114)
			(drill
				(offset 0 -0.381)
			)
			(layers "F.Cu" "F.Mask" "F.Paste")
			(net "PCIE_RX_N67")
		)
		(pad "B39" smd rect
			(at -5.999988 -0.7747 180)
			(size 0.5588 2.3114)
			(drill
				(offset 0 -0.381)
			)
			(layers "F.Cu" "F.Mask" "F.Paste")
			(net "PCIE_RX_P67")
		)
		(pad "B40" smd rect
			(at -5.199888 -0.7747 180)
			(size 0.5588 2.3114)
			(drill
				(offset 0 -0.381)
			)
			(layers "F.Cu" "F.Mask" "F.Paste")
			(net "GND")
		)
		(pad "B41" smd rect
			(at -4.400042 -0.7747 180)
			(size 0.5588 2.3114)
			(drill
				(offset 0 -0.381)
			)
			(layers "F.Cu" "F.Mask" "F.Paste")
			(net "GND")
		)
		(pad "B42" smd rect
			(at -3.599942 -0.7747 180)
			(size 0.5588 2.3114)
			(drill
				(offset 0 -0.381)
			)
			(layers "F.Cu" "F.Mask" "F.Paste")
			(net "PCIE_RX_N68")
		)
		(pad "B43" smd rect
			(at -2.800096 -0.7747 180)
			(size 0.5588 2.3114)
			(drill
				(offset 0 -0.381)
			)
			(layers "F.Cu" "F.Mask" "F.Paste")
			(net "PCIE_RX_P68")
		)
		(pad "B44" smd rect
			(at -1.999996 -0.7747 180)
			(size 0.5588 2.3114)
			(drill
				(offset 0 -0.381)
			)
			(layers "F.Cu" "F.Mask" "F.Paste")
			(net "GND")
		)
		(pad "B45" smd rect
			(at 1.999996 -0.7747 180)
			(size 0.5588 2.3114)
			(drill
				(offset 0 -0.381)
			)
			(layers "F.Cu" "F.Mask" "F.Paste")
			(net "GND")
		)
		(pad "B46" smd rect
			(at 2.800096 -0.7747 180)
			(size 0.5588 2.3114)
			(drill
				(offset 0 -0.381)
			)
			(layers "F.Cu" "F.Mask" "F.Paste")
			(net "PCIE_RX_N69")
		)
		(pad "B47" smd rect
			(at 3.599942 -0.7747 180)
			(size 0.5588 2.3114)
			(drill
				(offset 0 -0.381)
			)
			(layers "F.Cu" "F.Mask" "F.Paste")
			(net "PCIE_RX_P69")
		)
		(pad "B48" smd rect
			(at 4.400042 -0.7747 180)
			(size 0.5588 2.3114)
			(drill
				(offset 0 -0.381)
			)
			(layers "F.Cu" "F.Mask" "F.Paste")
			(net "GND")
		)
		(pad "B49" smd rect
			(at 5.199888 -0.7747 180)
			(size 0.5588 2.3114)
			(drill
				(offset 0 -0.381)
			)
			(layers "F.Cu" "F.Mask" "F.Paste")
			(net "GND")
		)
		(pad "B50" smd rect
			(at 5.999988 -0.7747 180)
			(size 0.5588 2.3114)
			(drill
				(offset 0 -0.381)
			)
			(layers "F.Cu" "F.Mask" "F.Paste")
			(net "PCIE_RX_N70")
		)
		(pad "B51" smd rect
			(at 6.800088 -0.7747 180)
			(size 0.5588 2.3114)
			(drill
				(offset 0 -0.381)
			)
			(layers "F.Cu" "F.Mask" "F.Paste")
			(net "PCIE_RX_P70")
		)
		(pad "B52" smd rect
			(at 7.599934 -0.7747 180)
			(size 0.5588 2.3114)
			(drill
				(offset 0 -0.381)
			)
			(layers "F.Cu" "F.Mask" "F.Paste")
			(net "GND")
		)
		(pad "B53" smd rect
			(at 8.400034 -0.7747 180)
			(size 0.5588 2.3114)
			(drill
				(offset 0 -0.381)
			)
			(layers "F.Cu" "F.Mask" "F.Paste")
			(net "GND")
		)
		(pad "B54" smd rect
			(at 9.19988 -0.7747 180)
			(size 0.5588 2.3114)
			(drill
				(offset 0 -0.381)
			)
			(layers "F.Cu" "F.Mask" "F.Paste")
			(net "PCIE_RX_N71")
		)
		(pad "B55" smd rect
			(at 9.99998 -0.7747 180)
			(size 0.5588 2.3114)
			(drill
				(offset 0 -0.381)
			)
			(layers "F.Cu" "F.Mask" "F.Paste")
			(net "PCIE_RX_P71")
		)
		(pad "B56" smd rect
			(at 10.80008 -0.7747 180)
			(size 0.5588 2.3114)
			(drill
				(offset 0 -0.381)
			)
			(layers "F.Cu" "F.Mask" "F.Paste")
			(net "GND")
		)
		(pad "B57" smd rect
			(at 11.599926 -0.7747 180)
			(size 0.5588 2.3114)
			(drill
				(offset 0 -0.381)
			)
			(layers "F.Cu" "F.Mask" "F.Paste")
			(net "SSD_PRSNT#5_R")
		)
		(pad "B58" smd rect
			(at 12.400026 -0.7747 180)
			(size 0.5588 2.3114)
			(drill
				(offset 0 -0.381)
			)
			(layers "F.Cu" "F.Mask" "F.Paste")
			(net "SSD_ATNLED#5_R")
		)
		(pad "B59" smd rect
			(at 13.200126 -0.7747 180)
			(size 0.5588 2.3114)
			(drill
				(offset 0 -0.381)
			)
			(layers "F.Cu" "F.Mask" "F.Paste")
			(net "SSD_PWREN5_R")
		)
		(pad "B60" smd rect
			(at 13.999972 -0.7747 180)
			(size 0.5588 2.3114)
			(drill
				(offset 0 -0.381)
			)
			(layers "F.Cu" "F.Mask" "F.Paste")
			(net "GND")
		)
		(pad "B61" smd rect
			(at 14.800072 -0.7747 180)
			(size 0.5588 2.3114)
			(drill
				(offset 0 -0.381)
			)
			(layers "F.Cu" "F.Mask" "F.Paste")
			(net "PCIE_RX_N72")
		)
		(pad "B62" smd rect
			(at 15.599918 -0.7747 180)
			(size 0.5588 2.3114)
			(drill
				(offset 0 -0.381)
			)
			(layers "F.Cu" "F.Mask" "F.Paste")
			(net "PCIE_RX_P72")
		)
		(pad "B63" smd rect
			(at 16.400018 -0.7747 180)
			(size 0.5588 2.3114)
			(drill
				(offset 0 -0.381)
			)
			(layers "F.Cu" "F.Mask" "F.Paste")
			(net "GND")
		)
		(pad "B64" smd rect
			(at 17.200118 -0.7747 180)
			(size 0.5588 2.3114)
			(drill
				(offset 0 -0.381)
			)
			(layers "F.Cu" "F.Mask" "F.Paste")
			(net "GND")
		)
		(pad "B65" smd rect
			(at 17.999964 -0.7747 180)
			(size 0.5588 2.3114)
			(drill
				(offset 0 -0.381)
			)
			(layers "F.Cu" "F.Mask" "F.Paste")
			(net "PCIE_RX_N73")
		)
		(pad "B66" smd rect
			(at 18.800064 -0.7747 180)
			(size 0.5588 2.3114)
			(drill
				(offset 0 -0.381)
			)
			(layers "F.Cu" "F.Mask" "F.Paste")
			(net "PCIE_RX_P73")
		)
		(pad "B67" smd rect
			(at 19.59991 -0.7747 180)
			(size 0.5588 2.3114)
			(drill
				(offset 0 -0.381)
			)
			(layers "F.Cu" "F.Mask" "F.Paste")
			(net "GND")
		)
		(pad "B68" smd rect
			(at 20.40001 -0.7747 180)
			(size 0.5588 2.3114)
			(drill
				(offset 0 -0.381)
			)
			(layers "F.Cu" "F.Mask" "F.Paste")
			(net "GND")
		)
		(pad "B69" smd rect
			(at 21.20011 -0.7747 180)
			(size 0.5588 2.3114)
			(drill
				(offset 0 -0.381)
			)
			(layers "F.Cu" "F.Mask" "F.Paste")
			(net "PCIE_RX_N74")
		)
		(pad "B70" smd rect
			(at 21.999956 -0.7747 180)
			(size 0.5588 2.3114)
			(drill
				(offset 0 -0.381)
			)
			(layers "F.Cu" "F.Mask" "F.Paste")
			(net "PCIE_RX_P74")
		)
		(pad "B71" smd rect
			(at 22.800056 -0.7747 180)
			(size 0.5588 2.3114)
			(drill
				(offset 0 -0.381)
			)
			(layers "F.Cu" "F.Mask" "F.Paste")
			(net "GND")
		)
		(pad "B72" smd rect
			(at 23.599902 -0.7747 180)
			(size 0.5588 2.3114)
			(drill
				(offset 0 -0.381)
			)
			(layers "F.Cu" "F.Mask" "F.Paste")
			(net "GND")
		)
		(pad "B73" smd rect
			(at 24.400002 -0.7747 180)
			(size 0.5588 2.3114)
			(drill
				(offset 0 -0.381)
			)
			(layers "F.Cu" "F.Mask" "F.Paste")
			(net "PCIE_RX_N75")
		)
		(pad "B74" smd rect
			(at 25.200102 -0.7747 180)
			(size 0.5588 2.3114)
			(drill
				(offset 0 -0.381)
			)
			(layers "F.Cu" "F.Mask" "F.Paste")
			(net "PCIE_RX_P75")
		)
		(pad "B75" smd rect
			(at 25.999948 -0.7747 180)
			(size 0.5588 2.3114)
			(drill
				(offset 0 -0.381)
			)
			(layers "F.Cu" "F.Mask" "F.Paste")
			(net "GND")
		)
		(pad "B76" smd rect
			(at 26.800048 -0.7747 180)
			(size 0.5588 2.3114)
			(drill
				(offset 0 -0.381)
			)
			(layers "F.Cu" "F.Mask" "F.Paste")
			(net "PCIE_REFCLK_S3_P")
		)
		(pad "B77" smd rect
			(at 27.599894 -0.7747 180)
			(size 0.5588 2.3114)
			(drill
				(offset 0 -0.381)
			)
			(layers "F.Cu" "F.Mask" "F.Paste")
			(net "PCIE_REFCLK_S3_N")
		)
		(pad "B78" smd rect
			(at 28.399994 -0.7747 180)
			(size 0.5588 2.3114)
			(drill
				(offset 0 -0.381)
			)
			(layers "F.Cu" "F.Mask" "F.Paste")
			(net "GND")
		)
		(pad "B79" smd rect
			(at 29.200094 -0.7747 180)
			(size 0.5588 2.3114)
			(drill
				(offset 0 -0.381)
			)
			(layers "F.Cu" "F.Mask" "F.Paste")
			(net "BUF_I2C8_CLKBUF1_SCL")
		)
		(pad "B80" smd rect
			(at 29.99994 -0.7747 180)
			(size 0.5588 2.3114)
			(drill
				(offset 0 -0.381)
			)
			(layers "F.Cu" "F.Mask" "F.Paste")
			(net "BUF_I2C8_CLKBUF1_SDA")
		)
		(pad "B81" smd rect
			(at 30.80004 -0.7747 180)
			(size 0.5588 2.3114)
			(drill
				(offset 0 -0.381)
			)
			(layers "F.Cu" "F.Mask" "F.Paste")
			(net "GND")
		)
		(pad "B82" smd rect
			(at 31.599886 -0.7747 180)
			(size 0.5588 2.3114)
			(drill
				(offset 0 -0.381)
			)
			(layers "F.Cu" "F.Mask" "F.Paste")
			(net "SSD_PERST#5_R")
		)
		(pad "B83" smd rect
			(at 32.399986 -0.7747 180)
			(size 0.5588 2.3114)
			(drill
				(offset 0 -0.381)
			)
			(layers "F.Cu" "F.Mask" "F.Paste")
			(net "PEER_BMC_HB")
		)
		(pad "B84" smd rect
			(at 33.200086 -0.7747 180)
			(size 0.5588 2.3114)
			(drill
				(offset 0 -0.381)
			)
			(layers "F.Cu" "F.Mask" "F.Paste")
			(net "HB_OUT")
		)
		(pad "B85" smd rect
			(at 33.999932 -0.7747 180)
			(size 0.5588 2.3114)
			(drill
				(offset 0 -0.381)
			)
			(layers "F.Cu" "F.Mask" "F.Paste")
			(net "FCB_HW_REVISION")
		)
		(pad "B86" smd rect
			(at 34.800032 -0.7747 180)
			(size 0.5588 2.3114)
			(drill
				(offset 0 -0.381)
			)
			(layers "F.Cu" "F.Mask" "F.Paste")
			(net "DPB_HW_REVISION")
		)
		(pad "B87" smd rect
			(at 35.599878 -0.7747 180)
			(size 0.5588 2.3114)
			(drill
				(offset 0 -0.381)
			)
			(layers "F.Cu" "F.Mask" "F.Paste")
			(net "BMC_SELF_TRAY")
		)
		(pad "B88" smd rect
			(at 36.399978 -0.7747 180)
			(size 0.5588 2.3114)
			(drill
				(offset 0 -0.381)
			)
			(layers "F.Cu" "F.Mask" "F.Paste")
			(net "PEER_TRAY_R")
		)
		(pad "B89" smd rect
			(at 37.200078 -0.7747 180)
			(size 0.5588 2.3114)
			(drill
				(offset 0 -0.381)
			)
			(layers "F.Cu" "F.Mask" "F.Paste")
			(net "GND")
		)
		(pad "B90" smd rect
			(at 37.999924 -0.7747 180)
			(size 0.5588 2.3114)
			(drill
				(offset 0 -0.381)
			)
			(layers "F.Cu" "F.Mask" "F.Paste")
			(net "GND")
		)
		(pad "B91" smd rect
			(at 38.800024 -0.7747 180)
			(size 0.5588 2.3114)
			(drill
				(offset 0 -0.381)
			)
			(layers "F.Cu" "F.Mask" "F.Paste")
			(net "GND")
		)
		(pad "B92" smd rect
			(at 39.600124 -0.7747 180)
			(size 0.5588 2.3114)
			(drill
				(offset 0 -0.381)
			)
			(layers "F.Cu" "F.Mask" "F.Paste")
			(net "GND")
		)
		(pad "B93" smd rect
			(at 40.39997 -0.7747 180)
			(size 0.5588 2.3114)
			(drill
				(offset 0 -0.381)
			)
			(layers "F.Cu" "F.Mask" "F.Paste")
			(net "GND")
		)
		(pad "B94" smd rect
			(at 41.20007 -0.7747 180)
			(size 0.5588 2.3114)
			(drill
				(offset 0 -0.381)
			)
			(layers "F.Cu" "F.Mask" "F.Paste")
			(net "GND")
		)
		(pad "B95" smd rect
			(at 41.999916 -0.7747 180)
			(size 0.5588 2.3114)
			(drill
				(offset 0 -0.381)
			)
			(layers "F.Cu" "F.Mask" "F.Paste")
			(net "P12V_PCIE")
		)
		(pad "B96" smd rect
			(at 42.800016 -0.7747 180)
			(size 0.5588 2.3114)
			(drill
				(offset 0 -0.381)
			)
			(layers "F.Cu" "F.Mask" "F.Paste")
			(net "P12V_PCIE")
		)
		(pad "B97" smd rect
			(at 43.600116 -0.7747 180)
			(size 0.5588 2.3114)
			(drill
				(offset 0 -0.381)
			)
			(layers "F.Cu" "F.Mask" "F.Paste")
			(net "P12V_PCIE")
		)
		(pad "B98" smd rect
			(at 44.399962 -0.7747 180)
			(size 0.5588 2.3114)
			(drill
				(offset 0 -0.381)
			)
			(layers "F.Cu" "F.Mask" "F.Paste")
			(net "P12V_PCIE")
		)
		(pad "B99" smd rect
			(at 45.200062 -0.7747 180)
			(size 0.5588 2.3114)
			(drill
				(offset 0 -0.381)
			)
			(layers "F.Cu" "F.Mask" "F.Paste")
			(net "P12V_PCIE")
		)
		(pad "B100" smd rect
			(at 45.999908 -0.7747 180)
			(size 0.5588 2.3114)
			(drill
				(offset 0 -0.381)
			)
			(layers "F.Cu" "F.Mask" "F.Paste")
			(net "P12V_PCIE")
		)
		(zone
			(layer "F.Cu")
			(hatch none 0.5)
			(connect_pads
				(clearance 0)
			)
			(min_thickness 0.25)
			(keepout
				(tracks not_allowed)
				(vias allowed)
				(pads allowed)
				(copperpour not_allowed)
				(footprints allowed)
			)
			(placement
				(enabled no)
				(sheetname "")
			)
			(fill
				(thermal_gap 0.5)
				(thermal_bridge_width 0.5)
				(island_removal_mode 0)
			)
			(polygon
				(pts
					(xy 112.993678 -227.71608) (xy 28.005278 -227.71608) (xy 28.005278 -226.70008) (xy 112.993678 -226.70008)
				)
			)
		)
		(zone
			(layer "F.Cu")
			(hatch none 0.5)
			(connect_pads
				(clearance 0)
			)
			(min_thickness 0.25)
			(keepout
				(tracks allowed)
				(vias not_allowed)
				(pads allowed)
				(copperpour not_allowed)
				(footprints allowed)
			)
			(placement
				(enabled no)
				(sheetname "")
			)
			(fill
				(thermal_gap 0.5)
				(thermal_bridge_width 0.5)
				(island_removal_mode 0)
			)
			(polygon
				(pts
					(xy 112.993678 -227.71608) (xy 28.005278 -227.71608) (xy 28.005278 -223.37268) (xy 112.993678 -223.37268)
				)
			)
		)
		(zone
			(layer "B.Cu")
			(hatch none 0.5)
			(connect_pads
				(clearance 0)
			)
			(min_thickness 0.25)
			(keepout
				(tracks not_allowed)
				(vias allowed)
				(pads allowed)
				(copperpour not_allowed)
				(footprints allowed)
			)
			(placement
				(enabled no)
				(sheetname "")
			)
			(fill
				(thermal_gap 0.5)
				(thermal_bridge_width 0.5)
				(island_removal_mode 0)
			)
			(polygon
				(pts
					(xy 112.993678 -227.71608) (xy 28.005278 -227.71608) (xy 28.005278 -226.70008) (xy 112.993678 -226.70008)
				)
			)
		)
		(zone
			(layer "B.Cu")
			(hatch none 0.5)
			(connect_pads
				(clearance 0)
			)
			(min_thickness 0.25)
			(keepout
				(tracks allowed)
				(vias not_allowed)
				(pads allowed)
				(copperpour not_allowed)
				(footprints allowed)
			)
			(placement
				(enabled no)
				(sheetname "")
			)
			(fill
				(thermal_gap 0.5)
				(thermal_bridge_width 0.5)
				(island_removal_mode 0)
			)
			(polygon
				(pts
					(xy 112.993678 -227.71608) (xy 28.005278 -227.71608) (xy 28.005278 -223.37268) (xy 112.993678 -223.37268)
				)
			)
		)
	)
	(footprint ""
		(layer "F.Cu")
		(at 64.135 -43.668188 90)
		(property "Reference" "PC25"
			(at 0 0 90)
			(layer "F.SilkS")
			(hide yes)
			(effects
				(font
					(size 1.27 1.27)
				)
			)
		)
		(property "Value" "SC10U25V5KX-GP"
			(at -0.0762 -6.1214 90)
			(unlocked yes)
			(layer "F.Fab")
			(hide yes)
			(effects
				(font
					(size 1.016 1.016)
					(thickness 0.1524)
				)
			)
		)
		(property "Device Type" "C805H56"
			(at -0.0762 -8.1534 90)
			(unlocked yes)
			(layer "F.Fab")
			(hide yes)
			(effects
				(font
					(size 1.016 1.016)
					(thickness 0.1524)
				)
			)
		)
		(duplicate_pad_numbers_are_jumpers no)
		(fp_line
			(start 0.635 0)
			(end -0.635 0)
			(stroke
				(width 0.508)
				(type default)
			)
			(layer "F.SilkS")
		)
		(fp_rect
			(start -0.9652 1.778)
			(end 0.9652 -1.778)
			(stroke
				(width 0)
				(type default)
			)
			(fill no)
			(layer "F.CrtYd")
		)
		(fp_poly
			(pts
				(xy -0.9652 -1.778) (xy 0.9652 -1.778) (xy 0.9652 1.778) (xy -0.9652 1.778)
			)
			(stroke
				(width 0)
				(type default)
			)
			(fill no)
			(layer "F.Fab")
		)
		(pad "1" smd rect
			(at 0 -0.9652 90)
			(size 1.397 1.143)
			(layers "F.Cu" "F.Mask" "F.Paste")
			(net "P3V3_STBY_VIN")
		)
		(pad "2" smd rect
			(at 0 0.9652 90)
			(size 1.397 1.143)
			(layers "F.Cu" "F.Mask" "F.Paste")
			(net "GND")
		)
	)
	(footprint ""
		(layer "F.Cu")
		(at 192.659 -11.303 90)
		(property "Reference" "Q9"
			(at 0 0 90)
			(layer "F.SilkS")
			(hide yes)
			(effects
				(font
					(size 1.27 1.27)
				)
			)
		)
		(property "Value" "2N7002K-1-GP"
			(at 0.127 -8.9662 90)
			(unlocked yes)
			(layer "F.Fab")
			(hide yes)
			(effects
				(font
					(size 1.016 1.016)
					(thickness 0.1524)
				)
			)
		)
		(property "Device Type" "SOT23DGS2D4H44"
			(at 0.127 -10.4902 90)
			(unlocked yes)
			(layer "F.Fab")
			(hide yes)
			(effects
				(font
					(size 1.016 1.016)
					(thickness 0.1524)
				)
			)
		)
		(duplicate_pad_numbers_are_jumpers no)
		(fp_line
			(start 1.651 -1.778)
			(end -1.651 -1.778)
			(stroke
				(width 0.1524)
				(type default)
			)
			(layer "F.SilkS")
		)
		(fp_line
			(start -1.651 -1.778)
			(end -1.651 1.778)
			(stroke
				(width 0.1524)
				(type default)
			)
			(layer "F.SilkS")
		)
		(fp_line
			(start 1.651 1.778)
			(end 1.651 -1.778)
			(stroke
				(width 0.1524)
				(type default)
			)
			(layer "F.SilkS")
		)
		(fp_line
			(start -1.651 1.778)
			(end 1.651 1.778)
			(stroke
				(width 0.1524)
				(type default)
			)
			(layer "F.SilkS")
		)
		(fp_poly
			(pts
				(xy -1.778 1.8796) (xy -1.778 -1.8796) (xy 1.778 -1.8796) (xy 1.778 1.8796)
			)
			(stroke
				(width 0)
				(type default)
			)
			(fill no)
			(layer "F.CrtYd")
		)
		(fp_poly
			(pts
				(xy -1.778 1.8796) (xy -1.778 -1.8796) (xy 1.778 -1.8796) (xy 1.778 1.8796)
			)
			(stroke
				(width 0)
				(type default)
			)
			(fill no)
			(layer "F.Fab")
		)
		(pad "D" smd custom
			(at 0 -0.9525 90)
			(size 0.1905 0.1905)
			(layers "F.Cu" "F.Mask" "F.Paste")
			(net "ENCLO_LED_RED_D")
			(options
				(clearance outline)
				(anchor circle)
			)
			(primitives
				(gr_poly
					(pts
						(arc
							(start -0.1778 0.5715)
							(mid -0.321484 0.511984)
							(end -0.381 0.3683)
						)
						(arc
							(start -0.381 -0.3683)
							(mid -0.321484 -0.511984)
							(end -0.1778 -0.5715)
						)
						(arc
							(start 0.1778 -0.5715)
							(mid 0.321484 -0.511984)
							(end 0.381 -0.3683)
						)
						(arc
							(start 0.381 0.3683)
							(mid 0.321484 0.511984)
							(end 0.1778 0.5715)
						)
					)
					(width 0)
					(fill yes)
				)
			)
		)
		(pad "G" smd custom
			(at -0.98425 0.9525 90)
			(size 0.1905 0.1905)
			(layers "F.Cu" "F.Mask" "F.Paste")
			(net "ENCLO_LED_RED_G")
			(options
				(clearance outline)
				(anchor circle)
			)
			(primitives
				(gr_poly
					(pts
						(arc
							(start -0.1778 0.5715)
							(mid -0.321484 0.511984)
							(end -0.381 0.3683)
						)
						(arc
							(start -0.381 -0.3683)
							(mid -0.321484 -0.511984)
							(end -0.1778 -0.5715)
						)
						(arc
							(start 0.1778 -0.5715)
							(mid 0.321484 -0.511984)
							(end 0.381 -0.3683)
						)
						(arc
							(start 0.381 0.3683)
							(mid 0.321484 0.511984)
							(end 0.1778 0.5715)
						)
					)
					(width 0)
					(fill yes)
				)
			)
		)
		(pad "S" smd custom
			(at 0.98425 0.9525 90)
			(size 0.1905 0.1905)
			(layers "F.Cu" "F.Mask" "F.Paste")
			(net "GND")
			(options
				(clearance outline)
				(anchor circle)
			)
			(primitives
				(gr_poly
					(pts
						(arc
							(start -0.1778 0.5715)
							(mid -0.321484 0.511984)
							(end -0.381 0.3683)
						)
						(arc
							(start -0.381 -0.3683)
							(mid -0.321484 -0.511984)
							(end -0.1778 -0.5715)
						)
						(arc
							(start 0.1778 -0.5715)
							(mid 0.321484 -0.511984)
							(end 0.381 -0.3683)
						)
						(arc
							(start 0.381 0.3683)
							(mid 0.321484 0.511984)
							(end 0.1778 0.5715)
						)
					)
					(width 0)
					(fill yes)
				)
			)
		)
	)
	(footprint ""
		(layer "F.Cu")
		(at 235.966 -23.241)
		(property "Reference" "R812"
			(at 0 0 0)
			(layer "F.SilkS")
			(hide yes)
			(effects
				(font
					(size 1.27 1.27)
				)
			)
		)
		(property "Value" "4K7R2F-GP"
			(at 0.064008 -3.993896 0)
			(unlocked yes)
			(layer "F.Fab")
			(hide yes)
			(effects
				(font
					(size 1.016 1.016)
					(thickness 0.1524)
				)
			)
		)
		(property "Device Type" "R402H16"
			(at 0.064008 -5.517896 0)
			(unlocked yes)
			(layer "F.Fab")
			(hide yes)
			(effects
				(font
					(size 1.016 1.016)
					(thickness 0.1524)
				)
			)
		)
		(duplicate_pad_numbers_are_jumpers no)
		(fp_line
			(start -0.508 -0.9398)
			(end -0.508 0.9398)
			(stroke
				(width 0.1524)
				(type default)
			)
			(layer "F.SilkS")
		)
		(fp_line
			(start 0.508 -0.9398)
			(end -0.508 -0.9398)
			(stroke
				(width 0.1524)
				(type default)
			)
			(layer "F.SilkS")
		)
		(fp_rect
			(start -0.508 0.9398)
			(end 0.508 -0.9398)
			(stroke
				(width 0)
				(type default)
			)
			(fill no)
			(layer "F.CrtYd")
		)
		(fp_rect
			(start -0.508 0.9398)
			(end 0.508 -0.9398)
			(stroke
				(width 0)
				(type default)
			)
			(fill no)
			(layer "F.Fab")
		)
		(pad "1" smd custom
			(at 0 -0.4445)
			(size 0.1397 0.1397)
			(layers "F.Cu" "F.Mask" "F.Paste")
			(net "GND")
			(options
				(clearance outline)
				(anchor circle)
			)
			(primitives
				(gr_poly
					(pts
						(arc
							(start -0.1778 -0.2794)
							(mid -0.249642 -0.249642)
							(end -0.2794 -0.1778)
						)
						(arc
							(start -0.2794 0.1778)
							(mid -0.249642 0.249642)
							(end -0.1778 0.2794)
						)
						(arc
							(start 0.1778 0.2794)
							(mid 0.249642 0.249642)
							(end 0.2794 0.1778)
						)
						(arc
							(start 0.2794 -0.1778)
							(mid 0.249642 -0.249642)
							(end 0.1778 -0.2794)
						)
					)
					(width 0)
					(fill yes)
				)
			)
		)
		(pad "2" smd custom
			(at 0 0.4445)
			(size 0.1397 0.1397)
			(layers "F.Cu" "F.Mask" "F.Paste")
			(net "BOOTSTRAP6")
			(options
				(clearance outline)
				(anchor circle)
			)
			(primitives
				(gr_poly
					(pts
						(arc
							(start -0.1778 -0.2794)
							(mid -0.249642 -0.249642)
							(end -0.2794 -0.1778)
						)
						(arc
							(start -0.2794 0.1778)
							(mid -0.249642 0.249642)
							(end -0.1778 0.2794)
						)
						(arc
							(start 0.1778 0.2794)
							(mid 0.249642 0.249642)
							(end 0.2794 0.1778)
						)
						(arc
							(start 0.2794 -0.1778)
							(mid 0.249642 -0.249642)
							(end 0.1778 -0.2794)
						)
					)
					(width 0)
					(fill yes)
				)
			)
		)
	)
	(footprint ""
		(layer "F.Cu")
		(at 212.792056 -212.420454 180)
		(property "Reference" "C111"
			(at 0 0 180)
			(layer "F.SilkS")
			(hide yes)
			(effects
				(font
					(size 1.27 1.27)
				)
			)
		)
		(property "Value" "SCD22U10V2KX-1GP"
			(at 1.1811 -2.7051 180)
			(unlocked yes)
			(layer "F.Fab")
			(hide yes)
			(effects
				(font
					(size 1.016 1.016)
					(thickness 0.1524)
				)
			)
		)
		(property "Device Type" "C402H22"
			(at 1.1811 -4.2291 180)
			(unlocked yes)
			(layer "F.Fab")
			(hide yes)
			(effects
				(font
					(size 1.016 1.016)
					(thickness 0.1524)
				)
			)
		)
		(duplicate_pad_numbers_are_jumpers no)
		(fp_rect
			(start -0.4318 0.9525)
			(end 0.4318 -0.9525)
			(stroke
				(width 0)
				(type default)
			)
			(fill no)
			(layer "F.CrtYd")
		)
		(fp_rect
			(start -0.4318 0.9525)
			(end 0.4318 -0.9525)
			(stroke
				(width 0)
				(type default)
			)
			(fill no)
			(layer "F.Fab")
		)
		(pad "1" smd custom
			(at 0 -0.4445 180)
			(size 0.1524 0.1524)
			(layers "F.Cu" "F.Mask" "F.Paste")
			(net "PCIE_TX_CAP_P39")
			(options
				(clearance outline)
				(anchor circle)
			)
			(primitives
				(gr_poly
					(pts
						(arc
							(start 0.3048 -0.2032)
							(mid 0.275042 -0.275042)
							(end 0.2032 -0.3048)
						)
						(arc
							(start -0.2032 -0.3048)
							(mid -0.275042 -0.275042)
							(end -0.3048 -0.2032)
						)
						(arc
							(start -0.3048 0.2032)
							(mid -0.275042 0.275042)
							(end -0.2032 0.3048)
						)
						(arc
							(start 0.2032 0.3048)
							(mid 0.275042 0.275042)
							(end 0.3048 0.2032)
						)
					)
					(width 0)
					(fill yes)
				)
			)
		)
		(pad "2" smd custom
			(at 0 0.4445 180)
			(size 0.1524 0.1524)
			(layers "F.Cu" "F.Mask" "F.Paste")
			(net "PCIE_TX_P39")
			(options
				(clearance outline)
				(anchor circle)
			)
			(primitives
				(gr_poly
					(pts
						(arc
							(start 0.3048 -0.2032)
							(mid 0.275042 -0.275042)
							(end 0.2032 -0.3048)
						)
						(arc
							(start -0.2032 -0.3048)
							(mid -0.275042 -0.275042)
							(end -0.3048 -0.2032)
						)
						(arc
							(start -0.3048 0.2032)
							(mid -0.275042 0.275042)
							(end -0.2032 0.3048)
						)
						(arc
							(start 0.2032 0.3048)
							(mid 0.275042 0.275042)
							(end 0.3048 0.2032)
						)
					)
					(width 0)
					(fill yes)
				)
			)
		)
	)
	(footprint ""
		(layer "F.Cu")
		(at 27.5336 -99.1108)
		(property "Reference" "C276"
			(at 0 0 0)
			(layer "F.SilkS")
			(hide yes)
			(effects
				(font
					(size 1.27 1.27)
				)
			)
		)
		(property "Value" "SCD1U16V2KX-3GP"
			(at 1.1811 -2.7051 0)
			(unlocked yes)
			(layer "F.Fab")
			(hide yes)
			(effects
				(font
					(size 1.016 1.016)
					(thickness 0.1524)
				)
			)
		)
		(property "Device Type" "C402H22"
			(at 1.1811 -4.2291 0)
			(unlocked yes)
			(layer "F.Fab")
			(hide yes)
			(effects
				(font
					(size 1.016 1.016)
					(thickness 0.1524)
				)
			)
		)
		(duplicate_pad_numbers_are_jumpers no)
		(fp_rect
			(start -0.4318 0.9525)
			(end 0.4318 -0.9525)
			(stroke
				(width 0)
				(type default)
			)
			(fill no)
			(layer "F.CrtYd")
		)
		(fp_rect
			(start -0.4318 0.9525)
			(end 0.4318 -0.9525)
			(stroke
				(width 0)
				(type default)
			)
			(fill no)
			(layer "F.Fab")
		)
		(pad "1" smd custom
			(at 0 -0.4445)
			(size 0.1524 0.1524)
			(layers "F.Cu" "F.Mask" "F.Paste")
			(net "P3V3_STBY")
			(options
				(clearance outline)
				(anchor circle)
			)
			(primitives
				(gr_poly
					(pts
						(arc
							(start 0.3048 -0.2032)
							(mid 0.275042 -0.275042)
							(end 0.2032 -0.3048)
						)
						(arc
							(start -0.2032 -0.3048)
							(mid -0.275042 -0.275042)
							(end -0.3048 -0.2032)
						)
						(arc
							(start -0.3048 0.2032)
							(mid -0.275042 0.275042)
							(end -0.2032 0.3048)
						)
						(arc
							(start 0.2032 0.3048)
							(mid 0.275042 0.275042)
							(end 0.3048 0.2032)
						)
					)
					(width 0)
					(fill yes)
				)
			)
		)
		(pad "2" smd custom
			(at 0 0.4445)
			(size 0.1524 0.1524)
			(layers "F.Cu" "F.Mask" "F.Paste")
			(net "GND")
			(options
				(clearance outline)
				(anchor circle)
			)
			(primitives
				(gr_poly
					(pts
						(arc
							(start 0.3048 -0.2032)
							(mid 0.275042 -0.275042)
							(end 0.2032 -0.3048)
						)
						(arc
							(start -0.2032 -0.3048)
							(mid -0.275042 -0.275042)
							(end -0.3048 -0.2032)
						)
						(arc
							(start -0.3048 0.2032)
							(mid -0.275042 0.275042)
							(end -0.2032 0.3048)
						)
						(arc
							(start 0.2032 0.3048)
							(mid 0.275042 0.275042)
							(end 0.3048 0.2032)
						)
					)
					(width 0)
					(fill yes)
				)
			)
		)
	)
	(footprint ""
		(layer "F.Cu")
		(at 22.8854 -67.6656 -90)
		(property "Reference" "TP148"
			(at 0 0 270)
			(layer "F.SilkS")
			(hide yes)
			(effects
				(font
					(size 1.27 1.27)
				)
			)
		)
		(property "Value" "TPAD28-2-GP"
			(at -0.0127 -1.6637 270)
			(unlocked yes)
			(layer "F.Fab")
			(hide yes)
			(effects
				(font
					(size 1.016 1.016)
					(thickness 0.1524)
				)
			)
		)
		(property "Device Type" "TPAD28"
			(at -0.0127 -3.1877 270)
			(unlocked yes)
			(layer "F.Fab")
			(hide yes)
			(effects
				(font
					(size 1.016 1.016)
					(thickness 0.1524)
				)
			)
		)
		(duplicate_pad_numbers_are_jumpers no)
		(fp_poly
			(pts
				(arc
					(start 0 -0.3556)
					(mid 0 0.3556)
					(end 0 -0.3556)
				)
			)
			(stroke
				(width 0)
				(type default)
			)
			(fill no)
			(layer "F.CrtYd")
		)
		(fp_poly
			(pts
				(arc
					(start 0 -0.6096)
					(mid 0 0.6096)
					(end 0 -0.6096)
				)
			)
			(stroke
				(width 0)
				(type default)
			)
			(fill no)
			(layer "F.Fab")
		)
		(pad "1" smd circle
			(at 0 0 270)
			(size 0.7112 0.7112)
			(layers "F.Cu" "F.Mask" "F.Paste")
			(net "TP_SDP0")
		)
	)
	(footprint ""
		(layer "F.Cu")
		(at 328.676 -61.849 -90)
		(property "Reference" "PL9"
			(at 0 0 270)
			(layer "F.SilkS")
			(hide yes)
			(effects
				(font
					(size 1.27 1.27)
				)
			)
		)
		(property "Value" "IND-320NH-4-GP"
			(at 7.6454 -3.1115 270)
			(unlocked yes)
			(layer "F.Fab")
			(hide yes)
			(effects
				(font
					(size 1.016 1.016)
					(thickness 0.1524)
				)
			)
		)
		(property "Device Type" "L127126-508254H315"
			(at 7.6454 -4.6355 270)
			(unlocked yes)
			(layer "F.Fab")
			(hide yes)
			(effects
				(font
					(size 1.016 1.016)
					(thickness 0.1524)
				)
			)
		)
		(duplicate_pad_numbers_are_jumpers no)
		(fp_line
			(start -6.604 7.1755)
			(end -6.604 -7.1755)
			(stroke
				(width 0.1524)
				(type default)
			)
			(layer "F.SilkS")
		)
		(fp_line
			(start 6.604 7.1755)
			(end -6.604 7.1755)
			(stroke
				(width 0.1524)
				(type default)
			)
			(layer "F.SilkS")
		)
		(fp_line
			(start -6.604 -7.1755)
			(end 6.604 -7.1755)
			(stroke
				(width 0.1524)
				(type default)
			)
			(layer "F.SilkS")
		)
		(fp_line
			(start 6.604 -7.1755)
			(end 6.604 7.1755)
			(stroke
				(width 0.1524)
				(type default)
			)
			(layer "F.SilkS")
		)
		(fp_rect
			(start -6.35 6.2865)
			(end 6.35 -6.2865)
			(stroke
				(width 0)
				(type default)
			)
			(fill no)
			(layer "F.CrtYd")
		)
		(fp_poly
			(pts
				(xy -6.858 7.2517) (xy -6.858 6.2865) (xy 6.35 6.2865) (xy 6.35 -6.2865) (xy -6.35 -6.2865) (xy -6.35 6.2738)
				(xy -6.858 6.2738) (xy -6.858 -7.2517) (xy 6.858 -7.2517) (xy 6.858 7.2517)
			)
			(stroke
				(width 0)
				(type default)
			)
			(fill no)
			(layer "F.CrtYd")
		)
		(fp_rect
			(start -6.858 7.2517)
			(end 6.858 -7.2517)
			(stroke
				(width 0)
				(type default)
			)
			(fill no)
			(layer "F.Fab")
		)
		(pad "1" smd rect
			(at 0 -5.210556 270)
			(size 5.334 3.429)
			(layers "F.Cu" "F.Mask" "F.Paste")
			(net "P0V9_E_LX")
		)
		(pad "2" smd rect
			(at 0 5.210556 270)
			(size 5.334 3.429)
			(layers "F.Cu" "F.Mask" "F.Paste")
			(net "P0V9_E")
		)
	)
	(footprint ""
		(layer "F.Cu")
		(at 332.772512 -172.432218)
		(property "Reference" "R7924"
			(at 0 0 0)
			(layer "F.SilkS")
			(hide yes)
			(effects
				(font
					(size 1.27 1.27)
				)
			)
		)
		(property "Value" "0R2J-2-GP"
			(at 0.064008 -3.993896 0)
			(unlocked yes)
			(layer "F.Fab")
			(hide yes)
			(effects
				(font
					(size 1.016 1.016)
					(thickness 0.1524)
				)
			)
		)
		(property "Device Type" "R402H16"
			(at 0.064008 -5.517896 0)
			(unlocked yes)
			(layer "F.Fab")
			(hide yes)
			(effects
				(font
					(size 1.016 1.016)
					(thickness 0.1524)
				)
			)
		)
		(duplicate_pad_numbers_are_jumpers no)
		(fp_line
			(start -0.508 -0.9398)
			(end -0.508 0.9398)
			(stroke
				(width 0.1524)
				(type default)
			)
			(layer "F.SilkS")
		)
		(fp_line
			(start 0.508 -0.9398)
			(end -0.508 -0.9398)
			(stroke
				(width 0.1524)
				(type default)
			)
			(layer "F.SilkS")
		)
		(fp_rect
			(start -0.508 0.9398)
			(end 0.508 -0.9398)
			(stroke
				(width 0)
				(type default)
			)
			(fill no)
			(layer "F.CrtYd")
		)
		(fp_rect
			(start -0.508 0.9398)
			(end 0.508 -0.9398)
			(stroke
				(width 0)
				(type default)
			)
			(fill no)
			(layer "F.Fab")
		)
		(pad "1" smd custom
			(at 0 -0.4445)
			(size 0.1397 0.1397)
			(layers "F.Cu" "F.Mask" "F.Paste")
			(net "SSD_PRSNT#4")
			(options
				(clearance outline)
				(anchor circle)
			)
			(primitives
				(gr_poly
					(pts
						(arc
							(start -0.1778 -0.2794)
							(mid -0.249642 -0.249642)
							(end -0.2794 -0.1778)
						)
						(arc
							(start -0.2794 0.1778)
							(mid -0.249642 0.249642)
							(end -0.1778 0.2794)
						)
						(arc
							(start 0.1778 0.2794)
							(mid 0.249642 0.249642)
							(end 0.2794 0.1778)
						)
						(arc
							(start 0.2794 -0.1778)
							(mid 0.249642 -0.249642)
							(end 0.1778 -0.2794)
						)
					)
					(width 0)
					(fill yes)
				)
			)
		)
		(pad "2" smd custom
			(at 0 0.4445)
			(size 0.1397 0.1397)
			(layers "F.Cu" "F.Mask" "F.Paste")
			(net "SSD_PRSNT#4_R")
			(options
				(clearance outline)
				(anchor circle)
			)
			(primitives
				(gr_poly
					(pts
						(arc
							(start -0.1778 -0.2794)
							(mid -0.249642 -0.249642)
							(end -0.2794 -0.1778)
						)
						(arc
							(start -0.2794 0.1778)
							(mid -0.249642 0.249642)
							(end -0.1778 0.2794)
						)
						(arc
							(start 0.1778 0.2794)
							(mid 0.249642 0.249642)
							(end 0.2794 0.1778)
						)
						(arc
							(start 0.2794 -0.1778)
							(mid 0.249642 -0.249642)
							(end 0.1778 -0.2794)
						)
					)
					(width 0)
					(fill yes)
				)
			)
		)
	)
	(footprint ""
		(layer "F.Cu")
		(at 276.40915 -3.600958 90)
		(property "Reference" "R278"
			(at 0 0 90)
			(layer "F.SilkS")
			(hide yes)
			(effects
				(font
					(size 1.27 1.27)
				)
			)
		)
		(property "Value" "0R2J-2-GP"
			(at 0.064008 -3.993896 90)
			(unlocked yes)
			(layer "F.Fab")
			(hide yes)
			(effects
				(font
					(size 1.016 1.016)
					(thickness 0.1524)
				)
			)
		)
		(property "Device Type" "R402H16"
			(at 0.064008 -5.517896 90)
			(unlocked yes)
			(layer "F.Fab")
			(hide yes)
			(effects
				(font
					(size 1.016 1.016)
					(thickness 0.1524)
				)
			)
		)
		(duplicate_pad_numbers_are_jumpers no)
		(fp_line
			(start 0.508 -0.9398)
			(end -0.508 -0.9398)
			(stroke
				(width 0.1524)
				(type default)
			)
			(layer "F.SilkS")
		)
		(fp_line
			(start -0.508 -0.9398)
			(end -0.508 0.9398)
			(stroke
				(width 0.1524)
				(type default)
			)
			(layer "F.SilkS")
		)
		(fp_rect
			(start -0.508 0.9398)
			(end 0.508 -0.9398)
			(stroke
				(width 0)
				(type default)
			)
			(fill no)
			(layer "F.CrtYd")
		)
		(fp_rect
			(start -0.508 0.9398)
			(end 0.508 -0.9398)
			(stroke
				(width 0)
				(type default)
			)
			(fill no)
			(layer "F.Fab")
		)
		(pad "1" smd custom
			(at 0 -0.4445 90)
			(size 0.1397 0.1397)
			(layers "F.Cu" "F.Mask" "F.Paste")
			(net "MINISAS_CN16_B_I2C_INT#")
			(options
				(clearance outline)
				(anchor circle)
			)
			(primitives
				(gr_poly
					(pts
						(arc
							(start -0.1778 -0.2794)
							(mid -0.249642 -0.249642)
							(end -0.2794 -0.1778)
						)
						(arc
							(start -0.2794 0.1778)
							(mid -0.249642 0.249642)
							(end -0.1778 0.2794)
						)
						(arc
							(start 0.1778 0.2794)
							(mid 0.249642 0.249642)
							(end 0.2794 0.1778)
						)
						(arc
							(start 0.2794 -0.1778)
							(mid 0.249642 -0.249642)
							(end 0.1778 -0.2794)
						)
					)
					(width 0)
					(fill yes)
				)
			)
		)
		(pad "2" smd custom
			(at 0 0.4445 90)
			(size 0.1397 0.1397)
			(layers "F.Cu" "F.Mask" "F.Paste")
			(net "CLK_N_6")
			(options
				(clearance outline)
				(anchor circle)
			)
			(primitives
				(gr_poly
					(pts
						(arc
							(start -0.1778 -0.2794)
							(mid -0.249642 -0.249642)
							(end -0.2794 -0.1778)
						)
						(arc
							(start -0.2794 0.1778)
							(mid -0.249642 0.249642)
							(end -0.1778 0.2794)
						)
						(arc
							(start 0.1778 0.2794)
							(mid 0.249642 0.249642)
							(end 0.2794 0.1778)
						)
						(arc
							(start 0.2794 -0.1778)
							(mid 0.249642 -0.249642)
							(end 0.1778 -0.2794)
						)
					)
					(width 0)
					(fill yes)
				)
			)
		)
	)
	(footprint ""
		(layer "F.Cu")
		(at 31.369 -44.958 -90)
		(property "Reference" "C336"
			(at 0 0 270)
			(layer "F.SilkS")
			(hide yes)
			(effects
				(font
					(size 1.27 1.27)
				)
			)
		)
		(property "Value" "SC1U10V2KX-4-GP"
			(at 1.1811 -2.7051 270)
			(unlocked yes)
			(layer "F.Fab")
			(hide yes)
			(effects
				(font
					(size 1.016 1.016)
					(thickness 0.1524)
				)
			)
		)
		(property "Device Type" "C402H22"
			(at 1.1811 -4.2291 270)
			(unlocked yes)
			(layer "F.Fab")
			(hide yes)
			(effects
				(font
					(size 1.016 1.016)
					(thickness 0.1524)
				)
			)
		)
		(duplicate_pad_numbers_are_jumpers no)
		(fp_rect
			(start -0.4318 0.9525)
			(end 0.4318 -0.9525)
			(stroke
				(width 0)
				(type default)
			)
			(fill no)
			(layer "F.CrtYd")
		)
		(fp_rect
			(start -0.4318 0.9525)
			(end 0.4318 -0.9525)
			(stroke
				(width 0)
				(type default)
			)
			(fill no)
			(layer "F.Fab")
		)
		(pad "1" smd custom
			(at 0 -0.4445 270)
			(size 0.1524 0.1524)
			(layers "F.Cu" "F.Mask" "F.Paste")
			(net "P5V_USB")
			(options
				(clearance outline)
				(anchor circle)
			)
			(primitives
				(gr_poly
					(pts
						(arc
							(start 0.3048 -0.2032)
							(mid 0.275042 -0.275042)
							(end 0.2032 -0.3048)
						)
						(arc
							(start -0.2032 -0.3048)
							(mid -0.275042 -0.275042)
							(end -0.3048 -0.2032)
						)
						(arc
							(start -0.3048 0.2032)
							(mid -0.275042 0.275042)
							(end -0.2032 0.3048)
						)
						(arc
							(start 0.2032 0.3048)
							(mid 0.275042 0.275042)
							(end 0.3048 0.2032)
						)
					)
					(width 0)
					(fill yes)
				)
			)
		)
		(pad "2" smd custom
			(at 0 0.4445 270)
			(size 0.1524 0.1524)
			(layers "F.Cu" "F.Mask" "F.Paste")
			(net "GND")
			(options
				(clearance outline)
				(anchor circle)
			)
			(primitives
				(gr_poly
					(pts
						(arc
							(start 0.3048 -0.2032)
							(mid 0.275042 -0.275042)
							(end 0.2032 -0.3048)
						)
						(arc
							(start -0.2032 -0.3048)
							(mid -0.275042 -0.275042)
							(end -0.3048 -0.2032)
						)
						(arc
							(start -0.3048 0.2032)
							(mid -0.275042 0.275042)
							(end -0.2032 0.3048)
						)
						(arc
							(start 0.2032 0.3048)
							(mid 0.275042 0.275042)
							(end 0.3048 0.2032)
						)
					)
					(width 0)
					(fill yes)
				)
			)
		)
	)
	(footprint ""
		(layer "F.Cu")
		(at 66.860166 -86.01456 -90)
		(property "Reference" "C304"
			(at 0 0 270)
			(layer "F.SilkS")
			(hide yes)
			(effects
				(font
					(size 1.27 1.27)
				)
			)
		)
		(property "Value" "SC1U10V2KX-4-GP"
			(at 1.1811 -2.7051 270)
			(unlocked yes)
			(layer "F.Fab")
			(hide yes)
			(effects
				(font
					(size 1.016 1.016)
					(thickness 0.1524)
				)
			)
		)
		(property "Device Type" "C402H22"
			(at 1.1811 -4.2291 270)
			(unlocked yes)
			(layer "F.Fab")
			(hide yes)
			(effects
				(font
					(size 1.016 1.016)
					(thickness 0.1524)
				)
			)
		)
		(duplicate_pad_numbers_are_jumpers no)
		(fp_rect
			(start -0.4318 0.9525)
			(end 0.4318 -0.9525)
			(stroke
				(width 0)
				(type default)
			)
			(fill no)
			(layer "F.CrtYd")
		)
		(fp_rect
			(start -0.4318 0.9525)
			(end 0.4318 -0.9525)
			(stroke
				(width 0)
				(type default)
			)
			(fill no)
			(layer "F.Fab")
		)
		(pad "1" smd custom
			(at 0 -0.4445 270)
			(size 0.1524 0.1524)
			(layers "F.Cu" "F.Mask" "F.Paste")
			(net "HB_A_IN")
			(options
				(clearance outline)
				(anchor circle)
			)
			(primitives
				(gr_poly
					(pts
						(arc
							(start 0.3048 -0.2032)
							(mid 0.275042 -0.275042)
							(end 0.2032 -0.3048)
						)
						(arc
							(start -0.2032 -0.3048)
							(mid -0.275042 -0.275042)
							(end -0.3048 -0.2032)
						)
						(arc
							(start -0.3048 0.2032)
							(mid -0.275042 0.275042)
							(end -0.2032 0.3048)
						)
						(arc
							(start 0.2032 0.3048)
							(mid 0.275042 0.275042)
							(end 0.3048 0.2032)
						)
					)
					(width 0)
					(fill yes)
				)
			)
		)
		(pad "2" smd custom
			(at 0 0.4445 270)
			(size 0.1524 0.1524)
			(layers "F.Cu" "F.Mask" "F.Paste")
			(net "GND")
			(options
				(clearance outline)
				(anchor circle)
			)
			(primitives
				(gr_poly
					(pts
						(arc
							(start 0.3048 -0.2032)
							(mid 0.275042 -0.275042)
							(end 0.2032 -0.3048)
						)
						(arc
							(start -0.2032 -0.3048)
							(mid -0.275042 -0.275042)
							(end -0.3048 -0.2032)
						)
						(arc
							(start -0.3048 0.2032)
							(mid -0.275042 0.275042)
							(end -0.2032 0.3048)
						)
						(arc
							(start 0.2032 0.3048)
							(mid 0.275042 0.275042)
							(end 0.3048 0.2032)
						)
					)
					(width 0)
					(fill yes)
				)
			)
		)
	)
	(footprint ""
		(layer "F.Cu")
		(at 128.078992 -33.5915)
		(property "Reference" "R2933"
			(at 0 0 0)
			(layer "F.SilkS")
			(hide yes)
			(effects
				(font
					(size 1.27 1.27)
				)
			)
		)
		(property "Value" "0R2J-2-GP"
			(at 0.064008 -3.993896 0)
			(unlocked yes)
			(layer "F.Fab")
			(hide yes)
			(effects
				(font
					(size 1.016 1.016)
					(thickness 0.1524)
				)
			)
		)
		(property "Device Type" "R402H16"
			(at 0.064008 -5.517896 0)
			(unlocked yes)
			(layer "F.Fab")
			(hide yes)
			(effects
				(font
					(size 1.016 1.016)
					(thickness 0.1524)
				)
			)
		)
		(duplicate_pad_numbers_are_jumpers no)
		(fp_line
			(start -0.508 -0.9398)
			(end -0.508 0.9398)
			(stroke
				(width 0.1524)
				(type default)
			)
			(layer "F.SilkS")
		)
		(fp_line
			(start 0.508 -0.9398)
			(end -0.508 -0.9398)
			(stroke
				(width 0.1524)
				(type default)
			)
			(layer "F.SilkS")
		)
		(fp_rect
			(start -0.508 0.9398)
			(end 0.508 -0.9398)
			(stroke
				(width 0)
				(type default)
			)
			(fill no)
			(layer "F.CrtYd")
		)
		(fp_rect
			(start -0.508 0.9398)
			(end 0.508 -0.9398)
			(stroke
				(width 0)
				(type default)
			)
			(fill no)
			(layer "F.Fab")
		)
		(pad "1" smd custom
			(at 0 -0.4445)
			(size 0.1397 0.1397)
			(layers "F.Cu" "F.Mask" "F.Paste")
			(net "USB2_BMC_DP")
			(options
				(clearance outline)
				(anchor circle)
			)
			(primitives
				(gr_poly
					(pts
						(arc
							(start -0.1778 -0.2794)
							(mid -0.249642 -0.249642)
							(end -0.2794 -0.1778)
						)
						(arc
							(start -0.2794 0.1778)
							(mid -0.249642 0.249642)
							(end -0.1778 0.2794)
						)
						(arc
							(start 0.1778 0.2794)
							(mid 0.249642 0.249642)
							(end 0.2794 0.1778)
						)
						(arc
							(start 0.2794 -0.1778)
							(mid 0.249642 -0.249642)
							(end 0.1778 -0.2794)
						)
					)
					(width 0)
					(fill yes)
				)
			)
		)
		(pad "2" smd custom
			(at 0 0.4445)
			(size 0.1397 0.1397)
			(layers "F.Cu" "F.Mask" "F.Paste")
			(net "8644_USB_DP1")
			(options
				(clearance outline)
				(anchor circle)
			)
			(primitives
				(gr_poly
					(pts
						(arc
							(start -0.1778 -0.2794)
							(mid -0.249642 -0.249642)
							(end -0.2794 -0.1778)
						)
						(arc
							(start -0.2794 0.1778)
							(mid -0.249642 0.249642)
							(end -0.1778 0.2794)
						)
						(arc
							(start 0.1778 0.2794)
							(mid 0.249642 0.249642)
							(end 0.2794 0.1778)
						)
						(arc
							(start 0.2794 -0.1778)
							(mid 0.249642 -0.249642)
							(end 0.1778 -0.2794)
						)
					)
					(width 0)
					(fill yes)
				)
			)
		)
	)
	(footprint ""
		(layer "F.Cu")
		(at 128.119124 -208.889092 180)
		(property "Reference" "R7970"
			(at 0 0 180)
			(layer "F.SilkS")
			(hide yes)
			(effects
				(font
					(size 1.27 1.27)
				)
			)
		)
		(property "Value" "0R2J-2-GP"
			(at 0.064008 -3.993896 180)
			(unlocked yes)
			(layer "F.Fab")
			(hide yes)
			(effects
				(font
					(size 1.016 1.016)
					(thickness 0.1524)
				)
			)
		)
		(property "Device Type" "R402H16"
			(at 0.064008 -5.517896 180)
			(unlocked yes)
			(layer "F.Fab")
			(hide yes)
			(effects
				(font
					(size 1.016 1.016)
					(thickness 0.1524)
				)
			)
		)
		(duplicate_pad_numbers_are_jumpers no)
		(fp_line
			(start 0.508 -0.9398)
			(end -0.508 -0.9398)
			(stroke
				(width 0.1524)
				(type default)
			)
			(layer "F.SilkS")
		)
		(fp_line
			(start -0.508 -0.9398)
			(end -0.508 0.9398)
			(stroke
				(width 0.1524)
				(type default)
			)
			(layer "F.SilkS")
		)
		(fp_rect
			(start -0.508 0.9398)
			(end 0.508 -0.9398)
			(stroke
				(width 0)
				(type default)
			)
			(fill no)
			(layer "F.CrtYd")
		)
		(fp_rect
			(start -0.508 0.9398)
			(end 0.508 -0.9398)
			(stroke
				(width 0)
				(type default)
			)
			(fill no)
			(layer "F.Fab")
		)
		(pad "1" smd custom
			(at 0 -0.4445 180)
			(size 0.1397 0.1397)
			(layers "F.Cu" "F.Mask" "F.Paste")
			(net "SSD_PERST#7")
			(options
				(clearance outline)
				(anchor circle)
			)
			(primitives
				(gr_poly
					(pts
						(arc
							(start -0.1778 -0.2794)
							(mid -0.249642 -0.249642)
							(end -0.2794 -0.1778)
						)
						(arc
							(start -0.2794 0.1778)
							(mid -0.249642 0.249642)
							(end -0.1778 0.2794)
						)
						(arc
							(start 0.1778 0.2794)
							(mid 0.249642 0.249642)
							(end 0.2794 0.1778)
						)
						(arc
							(start 0.2794 -0.1778)
							(mid 0.249642 -0.249642)
							(end 0.1778 -0.2794)
						)
					)
					(width 0)
					(fill yes)
				)
			)
		)
		(pad "2" smd custom
			(at 0 0.4445 180)
			(size 0.1397 0.1397)
			(layers "F.Cu" "F.Mask" "F.Paste")
			(net "SSD_PERST#7_R")
			(options
				(clearance outline)
				(anchor circle)
			)
			(primitives
				(gr_poly
					(pts
						(arc
							(start -0.1778 -0.2794)
							(mid -0.249642 -0.249642)
							(end -0.2794 -0.1778)
						)
						(arc
							(start -0.2794 0.1778)
							(mid -0.249642 0.249642)
							(end -0.1778 0.2794)
						)
						(arc
							(start 0.1778 0.2794)
							(mid 0.249642 0.249642)
							(end 0.2794 0.1778)
						)
						(arc
							(start 0.2794 -0.1778)
							(mid 0.249642 -0.249642)
							(end 0.1778 -0.2794)
						)
					)
					(width 0)
					(fill yes)
				)
			)
		)
	)
	(footprint ""
		(layer "F.Cu")
		(at 123.928124 -208.889092)
		(property "Reference" "R7915"
			(at 0 0 0)
			(layer "F.SilkS")
			(hide yes)
			(effects
				(font
					(size 1.27 1.27)
				)
			)
		)
		(property "Value" "0R2J-2-GP"
			(at 0.064008 -3.993896 0)
			(unlocked yes)
			(layer "F.Fab")
			(hide yes)
			(effects
				(font
					(size 1.016 1.016)
					(thickness 0.1524)
				)
			)
		)
		(property "Device Type" "R402H16"
			(at 0.064008 -5.517896 0)
			(unlocked yes)
			(layer "F.Fab")
			(hide yes)
			(effects
				(font
					(size 1.016 1.016)
					(thickness 0.1524)
				)
			)
		)
		(duplicate_pad_numbers_are_jumpers no)
		(fp_line
			(start -0.508 -0.9398)
			(end -0.508 0.9398)
			(stroke
				(width 0.1524)
				(type default)
			)
			(layer "F.SilkS")
		)
		(fp_line
			(start 0.508 -0.9398)
			(end -0.508 -0.9398)
			(stroke
				(width 0.1524)
				(type default)
			)
			(layer "F.SilkS")
		)
		(fp_rect
			(start -0.508 0.9398)
			(end 0.508 -0.9398)
			(stroke
				(width 0)
				(type default)
			)
			(fill no)
			(layer "F.CrtYd")
		)
		(fp_rect
			(start -0.508 0.9398)
			(end 0.508 -0.9398)
			(stroke
				(width 0)
				(type default)
			)
			(fill no)
			(layer "F.Fab")
		)
		(pad "1" smd custom
			(at 0 -0.4445)
			(size 0.1397 0.1397)
			(layers "F.Cu" "F.Mask" "F.Paste")
			(net "TWI_SDA1")
			(options
				(clearance outline)
				(anchor circle)
			)
			(primitives
				(gr_poly
					(pts
						(arc
							(start -0.1778 -0.2794)
							(mid -0.249642 -0.249642)
							(end -0.2794 -0.1778)
						)
						(arc
							(start -0.2794 0.1778)
							(mid -0.249642 0.249642)
							(end -0.1778 0.2794)
						)
						(arc
							(start 0.1778 0.2794)
							(mid 0.249642 0.249642)
							(end 0.2794 0.1778)
						)
						(arc
							(start 0.2794 -0.1778)
							(mid 0.249642 -0.249642)
							(end 0.1778 -0.2794)
						)
					)
					(width 0)
					(fill yes)
				)
			)
		)
		(pad "2" smd custom
			(at 0 0.4445)
			(size 0.1397 0.1397)
			(layers "F.Cu" "F.Mask" "F.Paste")
			(net "I2C_GPIO_SDA_2")
			(options
				(clearance outline)
				(anchor circle)
			)
			(primitives
				(gr_poly
					(pts
						(arc
							(start -0.1778 -0.2794)
							(mid -0.249642 -0.249642)
							(end -0.2794 -0.1778)
						)
						(arc
							(start -0.2794 0.1778)
							(mid -0.249642 0.249642)
							(end -0.1778 0.2794)
						)
						(arc
							(start 0.1778 0.2794)
							(mid 0.249642 0.249642)
							(end 0.2794 0.1778)
						)
						(arc
							(start 0.2794 -0.1778)
							(mid 0.249642 -0.249642)
							(end 0.1778 -0.2794)
						)
					)
					(width 0)
					(fill yes)
				)
			)
		)
	)
	(footprint ""
		(layer "F.Cu")
		(at 322.79209 -212.420454 180)
		(property "Reference" "C64"
			(at 0 0 180)
			(layer "F.SilkS")
			(hide yes)
			(effects
				(font
					(size 1.27 1.27)
				)
			)
		)
		(property "Value" "SCD22U10V2KX-1GP"
			(at 1.1811 -2.7051 180)
			(unlocked yes)
			(layer "F.Fab")
			(hide yes)
			(effects
				(font
					(size 1.016 1.016)
					(thickness 0.1524)
				)
			)
		)
		(property "Device Type" "C402H22"
			(at 1.1811 -4.2291 180)
			(unlocked yes)
			(layer "F.Fab")
			(hide yes)
			(effects
				(font
					(size 1.016 1.016)
					(thickness 0.1524)
				)
			)
		)
		(duplicate_pad_numbers_are_jumpers no)
		(fp_rect
			(start -0.4318 0.9525)
			(end 0.4318 -0.9525)
			(stroke
				(width 0)
				(type default)
			)
			(fill no)
			(layer "F.CrtYd")
		)
		(fp_rect
			(start -0.4318 0.9525)
			(end 0.4318 -0.9525)
			(stroke
				(width 0)
				(type default)
			)
			(fill no)
			(layer "F.Fab")
		)
		(pad "1" smd custom
			(at 0 -0.4445 180)
			(size 0.1524 0.1524)
			(layers "F.Cu" "F.Mask" "F.Paste")
			(net "PCIE_TX_CAP_P21")
			(options
				(clearance outline)
				(anchor circle)
			)
			(primitives
				(gr_poly
					(pts
						(arc
							(start 0.3048 -0.2032)
							(mid 0.275042 -0.275042)
							(end 0.2032 -0.3048)
						)
						(arc
							(start -0.2032 -0.3048)
							(mid -0.275042 -0.275042)
							(end -0.3048 -0.2032)
						)
						(arc
							(start -0.3048 0.2032)
							(mid -0.275042 0.275042)
							(end -0.2032 0.3048)
						)
						(arc
							(start 0.2032 0.3048)
							(mid 0.275042 0.275042)
							(end 0.3048 0.2032)
						)
					)
					(width 0)
					(fill yes)
				)
			)
		)
		(pad "2" smd custom
			(at 0 0.4445 180)
			(size 0.1524 0.1524)
			(layers "F.Cu" "F.Mask" "F.Paste")
			(net "PCIE_TX_P21")
			(options
				(clearance outline)
				(anchor circle)
			)
			(primitives
				(gr_poly
					(pts
						(arc
							(start 0.3048 -0.2032)
							(mid 0.275042 -0.275042)
							(end 0.2032 -0.3048)
						)
						(arc
							(start -0.2032 -0.3048)
							(mid -0.275042 -0.275042)
							(end -0.3048 -0.2032)
						)
						(arc
							(start -0.3048 0.2032)
							(mid -0.275042 0.275042)
							(end -0.2032 0.3048)
						)
						(arc
							(start 0.2032 0.3048)
							(mid 0.275042 0.275042)
							(end 0.3048 0.2032)
						)
					)
					(width 0)
					(fill yes)
				)
			)
		)
	)
	(footprint ""
		(layer "F.Cu")
		(at 273.939 -12.7 90)
		(property "Reference" "C1"
			(at 0 0 90)
			(layer "F.SilkS")
			(hide yes)
			(effects
				(font
					(size 1.27 1.27)
				)
			)
		)
		(property "Value" "SCD22U10V2KX-1GP"
			(at 1.1811 -2.7051 90)
			(unlocked yes)
			(layer "F.Fab")
			(hide yes)
			(effects
				(font
					(size 1.016 1.016)
					(thickness 0.1524)
				)
			)
		)
		(property "Device Type" "C402H22"
			(at 1.1811 -4.2291 90)
			(unlocked yes)
			(layer "F.Fab")
			(hide yes)
			(effects
				(font
					(size 1.016 1.016)
					(thickness 0.1524)
				)
			)
		)
		(duplicate_pad_numbers_are_jumpers no)
		(fp_rect
			(start -0.4318 0.9525)
			(end 0.4318 -0.9525)
			(stroke
				(width 0)
				(type default)
			)
			(fill no)
			(layer "F.CrtYd")
		)
		(fp_rect
			(start -0.4318 0.9525)
			(end 0.4318 -0.9525)
			(stroke
				(width 0)
				(type default)
			)
			(fill no)
			(layer "F.Fab")
		)
		(pad "1" smd custom
			(at 0 -0.4445 90)
			(size 0.1524 0.1524)
			(layers "F.Cu" "F.Mask" "F.Paste")
			(net "PCIE_TX_CAP_N0")
			(options
				(clearance outline)
				(anchor circle)
			)
			(primitives
				(gr_poly
					(pts
						(arc
							(start 0.3048 -0.2032)
							(mid 0.275042 -0.275042)
							(end 0.2032 -0.3048)
						)
						(arc
							(start -0.2032 -0.3048)
							(mid -0.275042 -0.275042)
							(end -0.3048 -0.2032)
						)
						(arc
							(start -0.3048 0.2032)
							(mid -0.275042 0.275042)
							(end -0.2032 0.3048)
						)
						(arc
							(start 0.2032 0.3048)
							(mid 0.275042 0.275042)
							(end 0.3048 0.2032)
						)
					)
					(width 0)
					(fill yes)
				)
			)
		)
		(pad "2" smd custom
			(at 0 0.4445 90)
			(size 0.1524 0.1524)
			(layers "F.Cu" "F.Mask" "F.Paste")
			(net "PCIE_TX_N0")
			(options
				(clearance outline)
				(anchor circle)
			)
			(primitives
				(gr_poly
					(pts
						(arc
							(start 0.3048 -0.2032)
							(mid 0.275042 -0.275042)
							(end 0.2032 -0.3048)
						)
						(arc
							(start -0.2032 -0.3048)
							(mid -0.275042 -0.275042)
							(end -0.3048 -0.2032)
						)
						(arc
							(start -0.3048 0.2032)
							(mid -0.275042 0.275042)
							(end -0.2032 0.3048)
						)
						(arc
							(start 0.2032 0.3048)
							(mid 0.275042 0.275042)
							(end 0.3048 0.2032)
						)
					)
					(width 0)
					(fill yes)
				)
			)
		)
	)
	(footprint ""
		(layer "F.Cu")
		(at 236.3724 -19.9644 -90)
		(property "Reference" "SR720"
			(at 0 0 270)
			(layer "F.SilkS")
			(hide yes)
			(effects
				(font
					(size 1.27 1.27)
				)
			)
		)
		(property "Value" "150R2F-1-GP"
			(at 0.064008 -3.993896 270)
			(unlocked yes)
			(layer "F.Fab")
			(hide yes)
			(effects
				(font
					(size 1.016 1.016)
					(thickness 0.1524)
				)
			)
		)
		(property "Device Type" "R402H16"
			(at 0.064008 -5.517896 270)
			(unlocked yes)
			(layer "F.Fab")
			(hide yes)
			(effects
				(font
					(size 1.016 1.016)
					(thickness 0.1524)
				)
			)
		)
		(duplicate_pad_numbers_are_jumpers no)
		(fp_line
			(start -0.508 -0.9398)
			(end -0.508 0.9398)
			(stroke
				(width 0.1524)
				(type default)
			)
			(layer "F.SilkS")
		)
		(fp_line
			(start 0.508 -0.9398)
			(end -0.508 -0.9398)
			(stroke
				(width 0.1524)
				(type default)
			)
			(layer "F.SilkS")
		)
		(fp_rect
			(start -0.508 0.9398)
			(end 0.508 -0.9398)
			(stroke
				(width 0)
				(type default)
			)
			(fill no)
			(layer "F.CrtYd")
		)
		(fp_rect
			(start -0.508 0.9398)
			(end 0.508 -0.9398)
			(stroke
				(width 0)
				(type default)
			)
			(fill no)
			(layer "F.Fab")
		)
		(pad "1" smd custom
			(at 0 -0.4445 270)
			(size 0.1397 0.1397)
			(layers "F.Cu" "F.Mask" "F.Paste")
			(net "P3V3_STBY")
			(options
				(clearance outline)
				(anchor circle)
			)
			(primitives
				(gr_poly
					(pts
						(arc
							(start -0.1778 -0.2794)
							(mid -0.249642 -0.249642)
							(end -0.2794 -0.1778)
						)
						(arc
							(start -0.2794 0.1778)
							(mid -0.249642 0.249642)
							(end -0.1778 0.2794)
						)
						(arc
							(start 0.1778 0.2794)
							(mid 0.249642 0.249642)
							(end 0.2794 0.1778)
						)
						(arc
							(start 0.2794 -0.1778)
							(mid 0.249642 -0.249642)
							(end 0.1778 -0.2794)
						)
					)
					(width 0)
					(fill yes)
				)
			)
		)
		(pad "2" smd custom
			(at 0 0.4445 270)
			(size 0.1397 0.1397)
			(layers "F.Cu" "F.Mask" "F.Paste")
			(net "SLED29_A")
			(options
				(clearance outline)
				(anchor circle)
			)
			(primitives
				(gr_poly
					(pts
						(arc
							(start -0.1778 -0.2794)
							(mid -0.249642 -0.249642)
							(end -0.2794 -0.1778)
						)
						(arc
							(start -0.2794 0.1778)
							(mid -0.249642 0.249642)
							(end -0.1778 0.2794)
						)
						(arc
							(start 0.1778 0.2794)
							(mid 0.249642 0.249642)
							(end 0.2794 0.1778)
						)
						(arc
							(start 0.2794 -0.1778)
							(mid 0.249642 -0.249642)
							(end 0.1778 -0.2794)
						)
					)
					(width 0)
					(fill yes)
				)
			)
		)
	)
	(footprint ""
		(layer "F.Cu")
		(at 191.408304 -212.420454 180)
		(property "Reference" "C122"
			(at 0 0 180)
			(layer "F.SilkS")
			(hide yes)
			(effects
				(font
					(size 1.27 1.27)
				)
			)
		)
		(property "Value" "SCD22U10V2KX-1GP"
			(at 1.1811 -2.7051 180)
			(unlocked yes)
			(layer "F.Fab")
			(hide yes)
			(effects
				(font
					(size 1.016 1.016)
					(thickness 0.1524)
				)
			)
		)
		(property "Device Type" "C402H22"
			(at 1.1811 -4.2291 180)
			(unlocked yes)
			(layer "F.Fab")
			(hide yes)
			(effects
				(font
					(size 1.016 1.016)
					(thickness 0.1524)
				)
			)
		)
		(duplicate_pad_numbers_are_jumpers no)
		(fp_rect
			(start -0.4318 0.9525)
			(end 0.4318 -0.9525)
			(stroke
				(width 0)
				(type default)
			)
			(fill no)
			(layer "F.CrtYd")
		)
		(fp_rect
			(start -0.4318 0.9525)
			(end 0.4318 -0.9525)
			(stroke
				(width 0)
				(type default)
			)
			(fill no)
			(layer "F.Fab")
		)
		(pad "1" smd custom
			(at 0 -0.4445 180)
			(size 0.1524 0.1524)
			(layers "F.Cu" "F.Mask" "F.Paste")
			(net "PCIE_TX_CAP_N45")
			(options
				(clearance outline)
				(anchor circle)
			)
			(primitives
				(gr_poly
					(pts
						(arc
							(start 0.3048 -0.2032)
							(mid 0.275042 -0.275042)
							(end 0.2032 -0.3048)
						)
						(arc
							(start -0.2032 -0.3048)
							(mid -0.275042 -0.275042)
							(end -0.3048 -0.2032)
						)
						(arc
							(start -0.3048 0.2032)
							(mid -0.275042 0.275042)
							(end -0.2032 0.3048)
						)
						(arc
							(start 0.2032 0.3048)
							(mid 0.275042 0.275042)
							(end 0.3048 0.2032)
						)
					)
					(width 0)
					(fill yes)
				)
			)
		)
		(pad "2" smd custom
			(at 0 0.4445 180)
			(size 0.1524 0.1524)
			(layers "F.Cu" "F.Mask" "F.Paste")
			(net "PCIE_TX_N45")
			(options
				(clearance outline)
				(anchor circle)
			)
			(primitives
				(gr_poly
					(pts
						(arc
							(start 0.3048 -0.2032)
							(mid 0.275042 -0.275042)
							(end 0.2032 -0.3048)
						)
						(arc
							(start -0.2032 -0.3048)
							(mid -0.275042 -0.275042)
							(end -0.3048 -0.2032)
						)
						(arc
							(start -0.3048 0.2032)
							(mid -0.275042 0.275042)
							(end -0.2032 0.3048)
						)
						(arc
							(start 0.2032 0.3048)
							(mid 0.275042 0.275042)
							(end 0.3048 0.2032)
						)
					)
					(width 0)
					(fill yes)
				)
			)
		)
	)
	(footprint ""
		(layer "F.Cu")
		(at 178.1048 -63.881 180)
		(property "Reference" "PG21"
			(at 0 0 180)
			(layer "F.SilkS")
			(hide yes)
			(effects
				(font
					(size 1.27 1.27)
				)
			)
		)
		(property "Value" "GAP-CLOSE-PWR-3-GP"
			(at 0.0254 -6.5786 180)
			(unlocked yes)
			(layer "F.Fab")
			(hide yes)
			(effects
				(font
					(size 1.016 1.016)
					(thickness 0.1524)
				)
			)
		)
		(property "Device Type" "GAP-CLOSE-PWR-3"
			(at 0.0254 -8.255 180)
			(unlocked yes)
			(layer "F.Fab")
			(hide yes)
			(effects
				(font
					(size 1.016 1.016)
					(thickness 0.1524)
				)
			)
		)
		(duplicate_pad_numbers_are_jumpers no)
		(fp_rect
			(start -0.7112 0.4572)
			(end 0.7112 -0.4572)
			(stroke
				(width 0)
				(type default)
			)
			(fill no)
			(layer "F.CrtYd")
		)
		(fp_poly
			(pts
				(xy -0.7112 -0.4572) (xy 0.7112 -0.4572) (xy 0.7112 0.4572) (xy -0.7112 0.4572)
			)
			(stroke
				(width 0)
				(type default)
			)
			(fill no)
			(layer "F.Fab")
		)
		(pad "1" smd rect
			(at -0.3048 0 180)
			(size 0.6604 0.762)
			(layers "F.Cu" "F.Mask" "F.Paste")
			(net "DUT_AVD_PCIE")
		)
		(pad "2" smd rect
			(at 0.3048 0 180)
			(size 0.6604 0.762)
			(layers "F.Cu" "F.Mask" "F.Paste")
			(net "P0V9")
		)
	)
	(footprint ""
		(layer "F.Cu")
		(at 228.195124 -203.047092 180)
		(property "Reference" "R7932"
			(at 0 0 180)
			(layer "F.SilkS")
			(hide yes)
			(effects
				(font
					(size 1.27 1.27)
				)
			)
		)
		(property "Value" "0R2J-2-GP"
			(at 0.064008 -3.993896 180)
			(unlocked yes)
			(layer "F.Fab")
			(hide yes)
			(effects
				(font
					(size 1.016 1.016)
					(thickness 0.1524)
				)
			)
		)
		(property "Device Type" "R402H16"
			(at 0.064008 -5.517896 180)
			(unlocked yes)
			(layer "F.Fab")
			(hide yes)
			(effects
				(font
					(size 1.016 1.016)
					(thickness 0.1524)
				)
			)
		)
		(duplicate_pad_numbers_are_jumpers no)
		(fp_line
			(start 0.508 -0.9398)
			(end -0.508 -0.9398)
			(stroke
				(width 0.1524)
				(type default)
			)
			(layer "F.SilkS")
		)
		(fp_line
			(start -0.508 -0.9398)
			(end -0.508 0.9398)
			(stroke
				(width 0.1524)
				(type default)
			)
			(layer "F.SilkS")
		)
		(fp_rect
			(start -0.508 0.9398)
			(end 0.508 -0.9398)
			(stroke
				(width 0)
				(type default)
			)
			(fill no)
			(layer "F.CrtYd")
		)
		(fp_rect
			(start -0.508 0.9398)
			(end 0.508 -0.9398)
			(stroke
				(width 0)
				(type default)
			)
			(fill no)
			(layer "F.Fab")
		)
		(pad "1" smd custom
			(at 0 -0.4445 180)
			(size 0.1397 0.1397)
			(layers "F.Cu" "F.Mask" "F.Paste")
			(net "SSD_PRSNT#12")
			(options
				(clearance outline)
				(anchor circle)
			)
			(primitives
				(gr_poly
					(pts
						(arc
							(start -0.1778 -0.2794)
							(mid -0.249642 -0.249642)
							(end -0.2794 -0.1778)
						)
						(arc
							(start -0.2794 0.1778)
							(mid -0.249642 0.249642)
							(end -0.1778 0.2794)
						)
						(arc
							(start 0.1778 0.2794)
							(mid 0.249642 0.249642)
							(end 0.2794 0.1778)
						)
						(arc
							(start 0.2794 -0.1778)
							(mid 0.249642 -0.249642)
							(end 0.1778 -0.2794)
						)
					)
					(width 0)
					(fill yes)
				)
			)
		)
		(pad "2" smd custom
			(at 0 0.4445 180)
			(size 0.1397 0.1397)
			(layers "F.Cu" "F.Mask" "F.Paste")
			(net "SSD_PRSNT#12_R")
			(options
				(clearance outline)
				(anchor circle)
			)
			(primitives
				(gr_poly
					(pts
						(arc
							(start -0.1778 -0.2794)
							(mid -0.249642 -0.249642)
							(end -0.2794 -0.1778)
						)
						(arc
							(start -0.2794 0.1778)
							(mid -0.249642 0.249642)
							(end -0.1778 0.2794)
						)
						(arc
							(start 0.1778 0.2794)
							(mid 0.249642 0.249642)
							(end 0.2794 0.1778)
						)
						(arc
							(start 0.2794 -0.1778)
							(mid 0.249642 -0.249642)
							(end 0.1778 -0.2794)
						)
					)
					(width 0)
					(fill yes)
				)
			)
		)
	)
	(footprint ""
		(layer "F.Cu")
		(at 80.428084 -74.99985)
		(property "Reference" "R732"
			(at 0 0 0)
			(layer "F.SilkS")
			(hide yes)
			(effects
				(font
					(size 1.27 1.27)
				)
			)
		)
		(property "Value" "0R2J-2-GP"
			(at 0.064008 -3.993896 0)
			(unlocked yes)
			(layer "F.Fab")
			(hide yes)
			(effects
				(font
					(size 1.016 1.016)
					(thickness 0.1524)
				)
			)
		)
		(property "Device Type" "R402H16"
			(at 0.064008 -5.517896 0)
			(unlocked yes)
			(layer "F.Fab")
			(hide yes)
			(effects
				(font
					(size 1.016 1.016)
					(thickness 0.1524)
				)
			)
		)
		(duplicate_pad_numbers_are_jumpers no)
		(fp_line
			(start -0.508 -0.9398)
			(end -0.508 0.9398)
			(stroke
				(width 0.1524)
				(type default)
			)
			(layer "F.SilkS")
		)
		(fp_line
			(start 0.508 -0.9398)
			(end -0.508 -0.9398)
			(stroke
				(width 0.1524)
				(type default)
			)
			(layer "F.SilkS")
		)
		(fp_rect
			(start -0.508 0.9398)
			(end 0.508 -0.9398)
			(stroke
				(width 0)
				(type default)
			)
			(fill no)
			(layer "F.CrtYd")
		)
		(fp_rect
			(start -0.508 0.9398)
			(end 0.508 -0.9398)
			(stroke
				(width 0)
				(type default)
			)
			(fill no)
			(layer "F.Fab")
		)
		(pad "1" smd custom
			(at 0 -0.4445)
			(size 0.1397 0.1397)
			(layers "F.Cu" "F.Mask" "F.Paste")
			(net "FM_BMC_RESET_N")
			(options
				(clearance outline)
				(anchor circle)
			)
			(primitives
				(gr_poly
					(pts
						(arc
							(start -0.1778 -0.2794)
							(mid -0.249642 -0.249642)
							(end -0.2794 -0.1778)
						)
						(arc
							(start -0.2794 0.1778)
							(mid -0.249642 0.249642)
							(end -0.1778 0.2794)
						)
						(arc
							(start 0.1778 0.2794)
							(mid 0.249642 0.249642)
							(end 0.2794 0.1778)
						)
						(arc
							(start 0.2794 -0.1778)
							(mid 0.249642 -0.249642)
							(end 0.1778 -0.2794)
						)
					)
					(width 0)
					(fill yes)
				)
			)
		)
		(pad "2" smd custom
			(at 0 0.4445)
			(size 0.1397 0.1397)
			(layers "F.Cu" "F.Mask" "F.Paste")
			(net "SEC_RST_N_R")
			(options
				(clearance outline)
				(anchor circle)
			)
			(primitives
				(gr_poly
					(pts
						(arc
							(start -0.1778 -0.2794)
							(mid -0.249642 -0.249642)
							(end -0.2794 -0.1778)
						)
						(arc
							(start -0.2794 0.1778)
							(mid -0.249642 0.249642)
							(end -0.1778 0.2794)
						)
						(arc
							(start 0.1778 0.2794)
							(mid 0.249642 0.249642)
							(end 0.2794 0.1778)
						)
						(arc
							(start 0.2794 -0.1778)
							(mid 0.249642 -0.249642)
							(end 0.1778 -0.2794)
						)
					)
					(width 0)
					(fill yes)
				)
			)
		)
	)
	(footprint ""
		(layer "F.Cu")
		(at 39.5478 -103.632 180)
		(property "Reference" "R658"
			(at 0 0 180)
			(layer "F.SilkS")
			(hide yes)
			(effects
				(font
					(size 1.27 1.27)
				)
			)
		)
		(property "Value" "4K7R2F-GP"
			(at 0.064008 -3.993896 180)
			(unlocked yes)
			(layer "F.Fab")
			(hide yes)
			(effects
				(font
					(size 1.016 1.016)
					(thickness 0.1524)
				)
			)
		)
		(property "Device Type" "R402H16"
			(at 0.064008 -5.517896 180)
			(unlocked yes)
			(layer "F.Fab")
			(hide yes)
			(effects
				(font
					(size 1.016 1.016)
					(thickness 0.1524)
				)
			)
		)
		(duplicate_pad_numbers_are_jumpers no)
		(fp_line
			(start 0.508 -0.9398)
			(end -0.508 -0.9398)
			(stroke
				(width 0.1524)
				(type default)
			)
			(layer "F.SilkS")
		)
		(fp_line
			(start -0.508 -0.9398)
			(end -0.508 0.9398)
			(stroke
				(width 0.1524)
				(type default)
			)
			(layer "F.SilkS")
		)
		(fp_rect
			(start -0.508 0.9398)
			(end 0.508 -0.9398)
			(stroke
				(width 0)
				(type default)
			)
			(fill no)
			(layer "F.CrtYd")
		)
		(fp_rect
			(start -0.508 0.9398)
			(end 0.508 -0.9398)
			(stroke
				(width 0)
				(type default)
			)
			(fill no)
			(layer "F.Fab")
		)
		(pad "1" smd custom
			(at 0 -0.4445 180)
			(size 0.1397 0.1397)
			(layers "F.Cu" "F.Mask" "F.Paste")
			(net "GND")
			(options
				(clearance outline)
				(anchor circle)
			)
			(primitives
				(gr_poly
					(pts
						(arc
							(start -0.1778 -0.2794)
							(mid -0.249642 -0.249642)
							(end -0.2794 -0.1778)
						)
						(arc
							(start -0.2794 0.1778)
							(mid -0.249642 0.249642)
							(end -0.1778 0.2794)
						)
						(arc
							(start 0.1778 0.2794)
							(mid 0.249642 0.249642)
							(end 0.2794 0.1778)
						)
						(arc
							(start 0.2794 -0.1778)
							(mid 0.249642 -0.249642)
							(end 0.1778 -0.2794)
						)
					)
					(width 0)
					(fill yes)
				)
			)
		)
		(pad "2" smd custom
			(at 0 0.4445 180)
			(size 0.1397 0.1397)
			(layers "F.Cu" "F.Mask" "F.Paste")
			(net "SPI_FLASH_SELECT")
			(options
				(clearance outline)
				(anchor circle)
			)
			(primitives
				(gr_poly
					(pts
						(arc
							(start -0.1778 -0.2794)
							(mid -0.249642 -0.249642)
							(end -0.2794 -0.1778)
						)
						(arc
							(start -0.2794 0.1778)
							(mid -0.249642 0.249642)
							(end -0.1778 0.2794)
						)
						(arc
							(start 0.1778 0.2794)
							(mid 0.249642 0.249642)
							(end 0.2794 0.1778)
						)
						(arc
							(start 0.2794 -0.1778)
							(mid 0.249642 -0.249642)
							(end 0.1778 -0.2794)
						)
					)
					(width 0)
					(fill yes)
				)
			)
		)
	)
	(footprint ""
		(layer "F.Cu")
		(at 157.826202 -55.272432 -90)
		(property "Reference" "PR168"
			(at 0 0 270)
			(layer "F.SilkS")
			(hide yes)
			(effects
				(font
					(size 1.27 1.27)
				)
			)
		)
		(property "Value" "4K53R2F-1-GP"
			(at 0.064008 -3.993896 270)
			(unlocked yes)
			(layer "F.Fab")
			(hide yes)
			(effects
				(font
					(size 1.016 1.016)
					(thickness 0.1524)
				)
			)
		)
		(property "Device Type" "R402H16"
			(at 0.064008 -5.517896 270)
			(unlocked yes)
			(layer "F.Fab")
			(hide yes)
			(effects
				(font
					(size 1.016 1.016)
					(thickness 0.1524)
				)
			)
		)
		(duplicate_pad_numbers_are_jumpers no)
		(fp_line
			(start -0.508 -0.9398)
			(end -0.508 0.9398)
			(stroke
				(width 0.1524)
				(type default)
			)
			(layer "F.SilkS")
		)
		(fp_line
			(start 0.508 -0.9398)
			(end -0.508 -0.9398)
			(stroke
				(width 0.1524)
				(type default)
			)
			(layer "F.SilkS")
		)
		(fp_rect
			(start -0.508 0.9398)
			(end 0.508 -0.9398)
			(stroke
				(width 0)
				(type default)
			)
			(fill no)
			(layer "F.CrtYd")
		)
		(fp_rect
			(start -0.508 0.9398)
			(end 0.508 -0.9398)
			(stroke
				(width 0)
				(type default)
			)
			(fill no)
			(layer "F.Fab")
		)
		(pad "1" smd custom
			(at 0 -0.4445 270)
			(size 0.1397 0.1397)
			(layers "F.Cu" "F.Mask" "F.Paste")
			(net "P0V9_VFB_R")
			(options
				(clearance outline)
				(anchor circle)
			)
			(primitives
				(gr_poly
					(pts
						(arc
							(start -0.1778 -0.2794)
							(mid -0.249642 -0.249642)
							(end -0.2794 -0.1778)
						)
						(arc
							(start -0.2794 0.1778)
							(mid -0.249642 0.249642)
							(end -0.1778 0.2794)
						)
						(arc
							(start 0.1778 0.2794)
							(mid 0.249642 0.249642)
							(end 0.2794 0.1778)
						)
						(arc
							(start 0.2794 -0.1778)
							(mid 0.249642 -0.249642)
							(end 0.1778 -0.2794)
						)
					)
					(width 0)
					(fill yes)
				)
			)
		)
		(pad "2" smd custom
			(at 0 0.4445 270)
			(size 0.1397 0.1397)
			(layers "F.Cu" "F.Mask" "F.Paste")
			(net "P0V9_VFB")
			(options
				(clearance outline)
				(anchor circle)
			)
			(primitives
				(gr_poly
					(pts
						(arc
							(start -0.1778 -0.2794)
							(mid -0.249642 -0.249642)
							(end -0.2794 -0.1778)
						)
						(arc
							(start -0.2794 0.1778)
							(mid -0.249642 0.249642)
							(end -0.1778 0.2794)
						)
						(arc
							(start 0.1778 0.2794)
							(mid 0.249642 0.249642)
							(end 0.2794 0.1778)
						)
						(arc
							(start 0.2794 -0.1778)
							(mid 0.249642 -0.249642)
							(end 0.1778 -0.2794)
						)
					)
					(width 0)
					(fill yes)
				)
			)
		)
	)
	(footprint ""
		(layer "F.Cu")
		(at 52.578 -192.913 90)
		(property "Reference" "C704"
			(at 0 0 90)
			(layer "F.SilkS")
			(hide yes)
			(effects
				(font
					(size 1.27 1.27)
				)
			)
		)
		(property "Value" "SC220P50V3JN-GP"
			(at 0 -2.8194 90)
			(unlocked yes)
			(layer "F.Fab")
			(hide yes)
			(effects
				(font
					(size 1.016 1.016)
					(thickness 0.1524)
				)
			)
		)
		(property "Device Type" "C603H36"
			(at 0 -4.3434 90)
			(unlocked yes)
			(layer "F.Fab")
			(hide yes)
			(effects
				(font
					(size 1.016 1.016)
					(thickness 0.1524)
				)
			)
		)
		(duplicate_pad_numbers_are_jumpers no)
		(fp_line
			(start 0.508 0)
			(end -0.508 0)
			(stroke
				(width 0.2032)
				(type default)
			)
			(layer "F.SilkS")
		)
		(fp_rect
			(start -0.5842 1.3335)
			(end 0.5842 -1.3335)
			(stroke
				(width 0)
				(type default)
			)
			(fill no)
			(layer "F.CrtYd")
		)
		(fp_rect
			(start -0.5842 1.3335)
			(end 0.5842 -1.3335)
			(stroke
				(width 0)
				(type default)
			)
			(fill no)
			(layer "F.Fab")
		)
		(pad "1" smd custom
			(at 0 -0.762 90)
			(size 0.2159 0.2159)
			(layers "F.Cu" "F.Mask" "F.Paste")
			(net "BMC_I2C7_B_DBP_SCL_R")
			(options
				(clearance outline)
				(anchor circle)
			)
			(primitives
				(gr_poly
					(pts
						(arc
							(start -0.3302 -0.4318)
							(mid -0.402042 -0.402042)
							(end -0.4318 -0.3302)
						)
						(arc
							(start -0.4318 0.3302)
							(mid -0.402042 0.402042)
							(end -0.3302 0.4318)
						)
						(arc
							(start 0.3302 0.4318)
							(mid 0.402042 0.402042)
							(end 0.4318 0.3302)
						)
						(arc
							(start 0.4318 -0.3302)
							(mid 0.402042 -0.402042)
							(end 0.3302 -0.4318)
						)
					)
					(width 0)
					(fill yes)
				)
			)
		)
		(pad "2" smd custom
			(at 0 0.762 90)
			(size 0.2159 0.2159)
			(layers "F.Cu" "F.Mask" "F.Paste")
			(net "GND")
			(options
				(clearance outline)
				(anchor circle)
			)
			(primitives
				(gr_poly
					(pts
						(arc
							(start -0.3302 -0.4318)
							(mid -0.402042 -0.402042)
							(end -0.4318 -0.3302)
						)
						(arc
							(start -0.4318 0.3302)
							(mid -0.402042 0.402042)
							(end -0.3302 0.4318)
						)
						(arc
							(start 0.3302 0.4318)
							(mid 0.402042 0.402042)
							(end 0.4318 0.3302)
						)
						(arc
							(start 0.4318 -0.3302)
							(mid 0.402042 -0.402042)
							(end 0.3302 -0.4318)
						)
					)
					(width 0)
					(fill yes)
				)
			)
		)
	)
	(footprint ""
		(layer "F.Cu")
		(at 303.53 -68.834 180)
		(property "Reference" "C458"
			(at 0 0 180)
			(layer "F.SilkS")
			(hide yes)
			(effects
				(font
					(size 1.27 1.27)
				)
			)
		)
		(property "Value" "SC10U16V5KX-1-GP"
			(at -0.0762 -6.1214 180)
			(unlocked yes)
			(layer "F.Fab")
			(hide yes)
			(effects
				(font
					(size 1.016 1.016)
					(thickness 0.1524)
				)
			)
		)
		(property "Device Type" "C805H54"
			(at -0.0762 -8.1534 180)
			(unlocked yes)
			(layer "F.Fab")
			(hide yes)
			(effects
				(font
					(size 1.016 1.016)
					(thickness 0.1524)
				)
			)
		)
		(duplicate_pad_numbers_are_jumpers no)
		(fp_line
			(start 0.635 0)
			(end -0.635 0)
			(stroke
				(width 0.508)
				(type default)
			)
			(layer "F.SilkS")
		)
		(fp_rect
			(start -0.9652 1.778)
			(end 0.9652 -1.778)
			(stroke
				(width 0)
				(type default)
			)
			(fill no)
			(layer "F.CrtYd")
		)
		(fp_poly
			(pts
				(xy -0.9652 -1.778) (xy 0.9652 -1.778) (xy 0.9652 1.778) (xy -0.9652 1.778)
			)
			(stroke
				(width 0)
				(type default)
			)
			(fill no)
			(layer "F.Fab")
		)
		(pad "1" smd rect
			(at 0 -0.9652 180)
			(size 1.397 1.143)
			(layers "F.Cu" "F.Mask" "F.Paste")
			(net "DUT_VDD")
		)
		(pad "2" smd rect
			(at 0 0.9652 180)
			(size 1.397 1.143)
			(layers "F.Cu" "F.Mask" "F.Paste")
			(net "GND")
		)
	)
	(footprint ""
		(layer "F.Cu")
		(at 133.453886 -81.925414)
		(property "Reference" "C306"
			(at 0 0 0)
			(layer "F.SilkS")
			(hide yes)
			(effects
				(font
					(size 1.27 1.27)
				)
			)
		)
		(property "Value" "SC3D9P50V2CN-1GP"
			(at 1.1811 -2.7051 0)
			(unlocked yes)
			(layer "F.Fab")
			(hide yes)
			(effects
				(font
					(size 1.016 1.016)
					(thickness 0.1524)
				)
			)
		)
		(property "Device Type" "C402H22"
			(at 1.1811 -4.2291 0)
			(unlocked yes)
			(layer "F.Fab")
			(hide yes)
			(effects
				(font
					(size 1.016 1.016)
					(thickness 0.1524)
				)
			)
		)
		(duplicate_pad_numbers_are_jumpers no)
		(fp_rect
			(start -0.4318 0.9525)
			(end 0.4318 -0.9525)
			(stroke
				(width 0)
				(type default)
			)
			(fill no)
			(layer "F.CrtYd")
		)
		(fp_rect
			(start -0.4318 0.9525)
			(end 0.4318 -0.9525)
			(stroke
				(width 0)
				(type default)
			)
			(fill no)
			(layer "F.Fab")
		)
		(pad "1" smd custom
			(at 0 -0.4445)
			(size 0.1524 0.1524)
			(layers "F.Cu" "F.Mask" "F.Paste")
			(net "RTC_OSCI")
			(options
				(clearance outline)
				(anchor circle)
			)
			(primitives
				(gr_poly
					(pts
						(arc
							(start 0.3048 -0.2032)
							(mid 0.275042 -0.275042)
							(end 0.2032 -0.3048)
						)
						(arc
							(start -0.2032 -0.3048)
							(mid -0.275042 -0.275042)
							(end -0.3048 -0.2032)
						)
						(arc
							(start -0.3048 0.2032)
							(mid -0.275042 0.275042)
							(end -0.2032 0.3048)
						)
						(arc
							(start 0.2032 0.3048)
							(mid 0.275042 0.275042)
							(end 0.3048 0.2032)
						)
					)
					(width 0)
					(fill yes)
				)
			)
		)
		(pad "2" smd custom
			(at 0 0.4445)
			(size 0.1524 0.1524)
			(layers "F.Cu" "F.Mask" "F.Paste")
			(net "GND")
			(options
				(clearance outline)
				(anchor circle)
			)
			(primitives
				(gr_poly
					(pts
						(arc
							(start 0.3048 -0.2032)
							(mid 0.275042 -0.275042)
							(end 0.2032 -0.3048)
						)
						(arc
							(start -0.2032 -0.3048)
							(mid -0.275042 -0.275042)
							(end -0.3048 -0.2032)
						)
						(arc
							(start -0.3048 0.2032)
							(mid -0.275042 0.275042)
							(end -0.2032 0.3048)
						)
						(arc
							(start 0.2032 0.3048)
							(mid 0.275042 0.275042)
							(end 0.3048 0.2032)
						)
					)
					(width 0)
					(fill yes)
				)
			)
		)
	)
	(footprint ""
		(layer "F.Cu")
		(at 48.84801 -73.533254 -90)
		(property "Reference" "R942"
			(at 0 0 270)
			(layer "F.SilkS")
			(hide yes)
			(effects
				(font
					(size 1.27 1.27)
				)
			)
		)
		(property "Value" "0R2J-2-GP"
			(at 0.064008 -3.993896 270)
			(unlocked yes)
			(layer "F.Fab")
			(hide yes)
			(effects
				(font
					(size 1.016 1.016)
					(thickness 0.1524)
				)
			)
		)
		(property "Device Type" "R402H16"
			(at 0.064008 -5.517896 270)
			(unlocked yes)
			(layer "F.Fab")
			(hide yes)
			(effects
				(font
					(size 1.016 1.016)
					(thickness 0.1524)
				)
			)
		)
		(duplicate_pad_numbers_are_jumpers no)
		(fp_line
			(start -0.508 -0.9398)
			(end -0.508 0.9398)
			(stroke
				(width 0.1524)
				(type default)
			)
			(layer "F.SilkS")
		)
		(fp_line
			(start 0.508 -0.9398)
			(end -0.508 -0.9398)
			(stroke
				(width 0.1524)
				(type default)
			)
			(layer "F.SilkS")
		)
		(fp_rect
			(start -0.508 0.9398)
			(end 0.508 -0.9398)
			(stroke
				(width 0)
				(type default)
			)
			(fill no)
			(layer "F.CrtYd")
		)
		(fp_rect
			(start -0.508 0.9398)
			(end 0.508 -0.9398)
			(stroke
				(width 0)
				(type default)
			)
			(fill no)
			(layer "F.Fab")
		)
		(pad "1" smd custom
			(at 0 -0.4445 270)
			(size 0.1397 0.1397)
			(layers "F.Cu" "F.Mask" "F.Paste")
			(net "BMC_R_TXD5")
			(options
				(clearance outline)
				(anchor circle)
			)
			(primitives
				(gr_poly
					(pts
						(arc
							(start -0.1778 -0.2794)
							(mid -0.249642 -0.249642)
							(end -0.2794 -0.1778)
						)
						(arc
							(start -0.2794 0.1778)
							(mid -0.249642 0.249642)
							(end -0.1778 0.2794)
						)
						(arc
							(start 0.1778 0.2794)
							(mid 0.249642 0.249642)
							(end 0.2794 0.1778)
						)
						(arc
							(start 0.2794 -0.1778)
							(mid 0.249642 -0.249642)
							(end 0.1778 -0.2794)
						)
					)
					(width 0)
					(fill yes)
				)
			)
		)
		(pad "2" smd custom
			(at 0 0.4445 270)
			(size 0.1397 0.1397)
			(layers "F.Cu" "F.Mask" "F.Paste")
			(net "BMC_TXD5")
			(options
				(clearance outline)
				(anchor circle)
			)
			(primitives
				(gr_poly
					(pts
						(arc
							(start -0.1778 -0.2794)
							(mid -0.249642 -0.249642)
							(end -0.2794 -0.1778)
						)
						(arc
							(start -0.2794 0.1778)
							(mid -0.249642 0.249642)
							(end -0.1778 0.2794)
						)
						(arc
							(start 0.1778 0.2794)
							(mid 0.249642 0.249642)
							(end 0.2794 0.1778)
						)
						(arc
							(start 0.2794 -0.1778)
							(mid 0.249642 -0.249642)
							(end 0.1778 -0.2794)
						)
					)
					(width 0)
					(fill yes)
				)
			)
		)
	)
	(footprint ""
		(layer "F.Cu")
		(at 167.767 -92.0242 90)
		(property "Reference" "TP75"
			(at 0 0 90)
			(layer "F.SilkS")
			(hide yes)
			(effects
				(font
					(size 1.27 1.27)
				)
			)
		)
		(property "Value" "TPAD28-2-GP"
			(at -0.0127 -1.6637 90)
			(unlocked yes)
			(layer "F.Fab")
			(hide yes)
			(effects
				(font
					(size 1.016 1.016)
					(thickness 0.1524)
				)
			)
		)
		(property "Device Type" "TPAD28"
			(at -0.0127 -3.1877 90)
			(unlocked yes)
			(layer "F.Fab")
			(hide yes)
			(effects
				(font
					(size 1.016 1.016)
					(thickness 0.1524)
				)
			)
		)
		(duplicate_pad_numbers_are_jumpers no)
		(fp_poly
			(pts
				(arc
					(start 0 0.3556)
					(mid 0 -0.3556)
					(end 0 0.3556)
				)
			)
			(stroke
				(width 0)
				(type default)
			)
			(fill no)
			(layer "F.CrtYd")
		)
		(fp_poly
			(pts
				(arc
					(start 0 0.6096)
					(mid 0 -0.6096)
					(end 0 0.6096)
				)
			)
			(stroke
				(width 0)
				(type default)
			)
			(fill no)
			(layer "F.Fab")
		)
		(pad "1" smd circle
			(at 0 0 90)
			(size 0.7112 0.7112)
			(layers "F.Cu" "F.Mask" "F.Paste")
			(net "CLKGEN_P2")
		)
	)
	(footprint ""
		(layer "F.Cu")
		(at 224.040446 -203.708 180)
		(property "Reference" "R7934"
			(at 0 0 180)
			(layer "F.SilkS")
			(hide yes)
			(effects
				(font
					(size 1.27 1.27)
				)
			)
		)
		(property "Value" "0R2J-2-GP"
			(at 0.064008 -3.993896 180)
			(unlocked yes)
			(layer "F.Fab")
			(hide yes)
			(effects
				(font
					(size 1.016 1.016)
					(thickness 0.1524)
				)
			)
		)
		(property "Device Type" "R402H16"
			(at 0.064008 -5.517896 180)
			(unlocked yes)
			(layer "F.Fab")
			(hide yes)
			(effects
				(font
					(size 1.016 1.016)
					(thickness 0.1524)
				)
			)
		)
		(duplicate_pad_numbers_are_jumpers no)
		(fp_line
			(start 0.508 -0.9398)
			(end -0.508 -0.9398)
			(stroke
				(width 0.1524)
				(type default)
			)
			(layer "F.SilkS")
		)
		(fp_line
			(start -0.508 -0.9398)
			(end -0.508 0.9398)
			(stroke
				(width 0.1524)
				(type default)
			)
			(layer "F.SilkS")
		)
		(fp_rect
			(start -0.508 0.9398)
			(end 0.508 -0.9398)
			(stroke
				(width 0)
				(type default)
			)
			(fill no)
			(layer "F.CrtYd")
		)
		(fp_rect
			(start -0.508 0.9398)
			(end 0.508 -0.9398)
			(stroke
				(width 0)
				(type default)
			)
			(fill no)
			(layer "F.Fab")
		)
		(pad "1" smd custom
			(at 0 -0.4445 180)
			(size 0.1397 0.1397)
			(layers "F.Cu" "F.Mask" "F.Paste")
			(net "SSD_PRSNT#13")
			(options
				(clearance outline)
				(anchor circle)
			)
			(primitives
				(gr_poly
					(pts
						(arc
							(start -0.1778 -0.2794)
							(mid -0.249642 -0.249642)
							(end -0.2794 -0.1778)
						)
						(arc
							(start -0.2794 0.1778)
							(mid -0.249642 0.249642)
							(end -0.1778 0.2794)
						)
						(arc
							(start 0.1778 0.2794)
							(mid 0.249642 0.249642)
							(end 0.2794 0.1778)
						)
						(arc
							(start 0.2794 -0.1778)
							(mid 0.249642 -0.249642)
							(end 0.1778 -0.2794)
						)
					)
					(width 0)
					(fill yes)
				)
			)
		)
		(pad "2" smd custom
			(at 0 0.4445 180)
			(size 0.1397 0.1397)
			(layers "F.Cu" "F.Mask" "F.Paste")
			(net "SSD_PRSNT#13_R")
			(options
				(clearance outline)
				(anchor circle)
			)
			(primitives
				(gr_poly
					(pts
						(arc
							(start -0.1778 -0.2794)
							(mid -0.249642 -0.249642)
							(end -0.2794 -0.1778)
						)
						(arc
							(start -0.2794 0.1778)
							(mid -0.249642 0.249642)
							(end -0.1778 0.2794)
						)
						(arc
							(start 0.1778 0.2794)
							(mid 0.249642 0.249642)
							(end 0.2794 0.1778)
						)
						(arc
							(start 0.2794 -0.1778)
							(mid 0.249642 -0.249642)
							(end 0.1778 -0.2794)
						)
					)
					(width 0)
					(fill yes)
				)
			)
		)
	)
	(footprint ""
		(layer "F.Cu")
		(at 227.965 -23.241 180)
		(property "Reference" "R3720"
			(at 0 0 180)
			(layer "F.SilkS")
			(hide yes)
			(effects
				(font
					(size 1.27 1.27)
				)
			)
		)
		(property "Value" "4K7R2F-GP"
			(at 0.064008 -3.993896 180)
			(unlocked yes)
			(layer "F.Fab")
			(hide yes)
			(effects
				(font
					(size 1.016 1.016)
					(thickness 0.1524)
				)
			)
		)
		(property "Device Type" "R402H16"
			(at 0.064008 -5.517896 180)
			(unlocked yes)
			(layer "F.Fab")
			(hide yes)
			(effects
				(font
					(size 1.016 1.016)
					(thickness 0.1524)
				)
			)
		)
		(duplicate_pad_numbers_are_jumpers no)
		(fp_line
			(start 0.508 -0.9398)
			(end -0.508 -0.9398)
			(stroke
				(width 0.1524)
				(type default)
			)
			(layer "F.SilkS")
		)
		(fp_line
			(start -0.508 -0.9398)
			(end -0.508 0.9398)
			(stroke
				(width 0.1524)
				(type default)
			)
			(layer "F.SilkS")
		)
		(fp_rect
			(start -0.508 0.9398)
			(end 0.508 -0.9398)
			(stroke
				(width 0)
				(type default)
			)
			(fill no)
			(layer "F.CrtYd")
		)
		(fp_rect
			(start -0.508 0.9398)
			(end 0.508 -0.9398)
			(stroke
				(width 0)
				(type default)
			)
			(fill no)
			(layer "F.Fab")
		)
		(pad "1" smd custom
			(at 0 -0.4445 180)
			(size 0.1397 0.1397)
			(layers "F.Cu" "F.Mask" "F.Paste")
			(net "HOST3_RST_N_LS")
			(options
				(clearance outline)
				(anchor circle)
			)
			(primitives
				(gr_poly
					(pts
						(arc
							(start -0.1778 -0.2794)
							(mid -0.249642 -0.249642)
							(end -0.2794 -0.1778)
						)
						(arc
							(start -0.2794 0.1778)
							(mid -0.249642 0.249642)
							(end -0.1778 0.2794)
						)
						(arc
							(start 0.1778 0.2794)
							(mid 0.249642 0.249642)
							(end 0.2794 0.1778)
						)
						(arc
							(start 0.2794 -0.1778)
							(mid 0.249642 -0.249642)
							(end 0.1778 -0.2794)
						)
					)
					(width 0)
					(fill yes)
				)
			)
		)
		(pad "2" smd custom
			(at 0 0.4445 180)
			(size 0.1397 0.1397)
			(layers "F.Cu" "F.Mask" "F.Paste")
			(net "GND")
			(options
				(clearance outline)
				(anchor circle)
			)
			(primitives
				(gr_poly
					(pts
						(arc
							(start -0.1778 -0.2794)
							(mid -0.249642 -0.249642)
							(end -0.2794 -0.1778)
						)
						(arc
							(start -0.2794 0.1778)
							(mid -0.249642 0.249642)
							(end -0.1778 0.2794)
						)
						(arc
							(start 0.1778 0.2794)
							(mid 0.249642 0.249642)
							(end 0.2794 0.1778)
						)
						(arc
							(start 0.2794 -0.1778)
							(mid 0.249642 -0.249642)
							(end 0.1778 -0.2794)
						)
					)
					(width 0)
					(fill yes)
				)
			)
		)
	)
	(footprint ""
		(layer "F.Cu")
		(at 18.415 -129.667 -90)
		(property "Reference" "R369"
			(at 0 0 270)
			(layer "F.SilkS")
			(hide yes)
			(effects
				(font
					(size 1.27 1.27)
				)
			)
		)
		(property "Value" "3K3R2F-2-GP"
			(at 0.064008 -3.993896 270)
			(unlocked yes)
			(layer "F.Fab")
			(hide yes)
			(effects
				(font
					(size 1.016 1.016)
					(thickness 0.1524)
				)
			)
		)
		(property "Device Type" "R402H16"
			(at 0.064008 -5.517896 270)
			(unlocked yes)
			(layer "F.Fab")
			(hide yes)
			(effects
				(font
					(size 1.016 1.016)
					(thickness 0.1524)
				)
			)
		)
		(duplicate_pad_numbers_are_jumpers no)
		(fp_line
			(start -0.508 -0.9398)
			(end -0.508 0.9398)
			(stroke
				(width 0.1524)
				(type default)
			)
			(layer "F.SilkS")
		)
		(fp_line
			(start 0.508 -0.9398)
			(end -0.508 -0.9398)
			(stroke
				(width 0.1524)
				(type default)
			)
			(layer "F.SilkS")
		)
		(fp_rect
			(start -0.508 0.9398)
			(end 0.508 -0.9398)
			(stroke
				(width 0)
				(type default)
			)
			(fill no)
			(layer "F.CrtYd")
		)
		(fp_rect
			(start -0.508 0.9398)
			(end 0.508 -0.9398)
			(stroke
				(width 0)
				(type default)
			)
			(fill no)
			(layer "F.Fab")
		)
		(pad "1" smd custom
			(at 0 -0.4445 270)
			(size 0.1397 0.1397)
			(layers "F.Cu" "F.Mask" "F.Paste")
			(net "P3V3_STBY")
			(options
				(clearance outline)
				(anchor circle)
			)
			(primitives
				(gr_poly
					(pts
						(arc
							(start -0.1778 -0.2794)
							(mid -0.249642 -0.249642)
							(end -0.2794 -0.1778)
						)
						(arc
							(start -0.2794 0.1778)
							(mid -0.249642 0.249642)
							(end -0.1778 0.2794)
						)
						(arc
							(start 0.1778 0.2794)
							(mid 0.249642 0.249642)
							(end 0.2794 0.1778)
						)
						(arc
							(start 0.2794 -0.1778)
							(mid 0.249642 -0.249642)
							(end 0.1778 -0.2794)
						)
					)
					(width 0)
					(fill yes)
				)
			)
		)
		(pad "2" smd custom
			(at 0 0.4445 270)
			(size 0.1397 0.1397)
			(layers "F.Cu" "F.Mask" "F.Paste")
			(net "ROMA23")
			(options
				(clearance outline)
				(anchor circle)
			)
			(primitives
				(gr_poly
					(pts
						(arc
							(start -0.1778 -0.2794)
							(mid -0.249642 -0.249642)
							(end -0.2794 -0.1778)
						)
						(arc
							(start -0.2794 0.1778)
							(mid -0.249642 0.249642)
							(end -0.1778 0.2794)
						)
						(arc
							(start 0.1778 0.2794)
							(mid 0.249642 0.249642)
							(end 0.2794 0.1778)
						)
						(arc
							(start 0.2794 -0.1778)
							(mid 0.249642 -0.249642)
							(end 0.1778 -0.2794)
						)
					)
					(width 0)
					(fill yes)
				)
			)
		)
	)
	(footprint ""
		(layer "F.Cu")
		(at 53.721 -119.126 -90)
		(property "Reference" "R461"
			(at 0 0 270)
			(layer "F.SilkS")
			(hide yes)
			(effects
				(font
					(size 1.27 1.27)
				)
			)
		)
		(property "Value" "0R2J-2-GP"
			(at 0.064008 -3.993896 270)
			(unlocked yes)
			(layer "F.Fab")
			(hide yes)
			(effects
				(font
					(size 1.016 1.016)
					(thickness 0.1524)
				)
			)
		)
		(property "Device Type" "R402H16"
			(at 0.064008 -5.517896 270)
			(unlocked yes)
			(layer "F.Fab")
			(hide yes)
			(effects
				(font
					(size 1.016 1.016)
					(thickness 0.1524)
				)
			)
		)
		(duplicate_pad_numbers_are_jumpers no)
		(fp_line
			(start -0.508 -0.9398)
			(end -0.508 0.9398)
			(stroke
				(width 0.1524)
				(type default)
			)
			(layer "F.SilkS")
		)
		(fp_line
			(start 0.508 -0.9398)
			(end -0.508 -0.9398)
			(stroke
				(width 0.1524)
				(type default)
			)
			(layer "F.SilkS")
		)
		(fp_rect
			(start -0.508 0.9398)
			(end 0.508 -0.9398)
			(stroke
				(width 0)
				(type default)
			)
			(fill no)
			(layer "F.CrtYd")
		)
		(fp_rect
			(start -0.508 0.9398)
			(end 0.508 -0.9398)
			(stroke
				(width 0)
				(type default)
			)
			(fill no)
			(layer "F.Fab")
		)
		(pad "1" smd custom
			(at 0 -0.4445 270)
			(size 0.1397 0.1397)
			(layers "F.Cu" "F.Mask" "F.Paste")
			(net "BMC_I2C7_B_DBP_SCL")
			(options
				(clearance outline)
				(anchor circle)
			)
			(primitives
				(gr_poly
					(pts
						(arc
							(start -0.1778 -0.2794)
							(mid -0.249642 -0.249642)
							(end -0.2794 -0.1778)
						)
						(arc
							(start -0.2794 0.1778)
							(mid -0.249642 0.249642)
							(end -0.1778 0.2794)
						)
						(arc
							(start 0.1778 0.2794)
							(mid 0.249642 0.249642)
							(end 0.2794 0.1778)
						)
						(arc
							(start 0.2794 -0.1778)
							(mid 0.249642 -0.249642)
							(end 0.1778 -0.2794)
						)
					)
					(width 0)
					(fill yes)
				)
			)
		)
		(pad "2" smd custom
			(at 0 0.4445 270)
			(size 0.1397 0.1397)
			(layers "F.Cu" "F.Mask" "F.Paste")
			(net "BMC0_SMB7_CLK")
			(options
				(clearance outline)
				(anchor circle)
			)
			(primitives
				(gr_poly
					(pts
						(arc
							(start -0.1778 -0.2794)
							(mid -0.249642 -0.249642)
							(end -0.2794 -0.1778)
						)
						(arc
							(start -0.2794 0.1778)
							(mid -0.249642 0.249642)
							(end -0.1778 0.2794)
						)
						(arc
							(start 0.1778 0.2794)
							(mid 0.249642 0.249642)
							(end 0.2794 0.1778)
						)
						(arc
							(start 0.2794 -0.1778)
							(mid 0.249642 -0.249642)
							(end 0.1778 -0.2794)
						)
					)
					(width 0)
					(fill yes)
				)
			)
		)
	)
	(footprint ""
		(layer "F.Cu")
		(at 33.857946 -146.48688 180)
		(property "Reference" "C184"
			(at 0 0 180)
			(layer "F.SilkS")
			(hide yes)
			(effects
				(font
					(size 1.27 1.27)
				)
			)
		)
		(property "Value" "SCD1U16V2KX-3GP"
			(at 1.1811 -2.7051 180)
			(unlocked yes)
			(layer "F.Fab")
			(hide yes)
			(effects
				(font
					(size 1.016 1.016)
					(thickness 0.1524)
				)
			)
		)
		(property "Device Type" "C402H22"
			(at 1.1811 -4.2291 180)
			(unlocked yes)
			(layer "F.Fab")
			(hide yes)
			(effects
				(font
					(size 1.016 1.016)
					(thickness 0.1524)
				)
			)
		)
		(duplicate_pad_numbers_are_jumpers no)
		(fp_rect
			(start -0.4318 0.9525)
			(end 0.4318 -0.9525)
			(stroke
				(width 0)
				(type default)
			)
			(fill no)
			(layer "F.CrtYd")
		)
		(fp_rect
			(start -0.4318 0.9525)
			(end 0.4318 -0.9525)
			(stroke
				(width 0)
				(type default)
			)
			(fill no)
			(layer "F.Fab")
		)
		(pad "1" smd custom
			(at 0 -0.4445 180)
			(size 0.1524 0.1524)
			(layers "F.Cu" "F.Mask" "F.Paste")
			(net "GND")
			(options
				(clearance outline)
				(anchor circle)
			)
			(primitives
				(gr_poly
					(pts
						(arc
							(start 0.3048 -0.2032)
							(mid 0.275042 -0.275042)
							(end 0.2032 -0.3048)
						)
						(arc
							(start -0.2032 -0.3048)
							(mid -0.275042 -0.275042)
							(end -0.3048 -0.2032)
						)
						(arc
							(start -0.3048 0.2032)
							(mid -0.275042 0.275042)
							(end -0.2032 0.3048)
						)
						(arc
							(start 0.2032 0.3048)
							(mid 0.275042 0.275042)
							(end 0.3048 0.2032)
						)
					)
					(width 0)
					(fill yes)
				)
			)
		)
		(pad "2" smd custom
			(at 0 0.4445 180)
			(size 0.1524 0.1524)
			(layers "F.Cu" "F.Mask" "F.Paste")
			(net "DDR_VREF")
			(options
				(clearance outline)
				(anchor circle)
			)
			(primitives
				(gr_poly
					(pts
						(arc
							(start 0.3048 -0.2032)
							(mid 0.275042 -0.275042)
							(end 0.2032 -0.3048)
						)
						(arc
							(start -0.2032 -0.3048)
							(mid -0.275042 -0.275042)
							(end -0.3048 -0.2032)
						)
						(arc
							(start -0.3048 0.2032)
							(mid -0.275042 0.275042)
							(end -0.2032 0.3048)
						)
						(arc
							(start 0.2032 0.3048)
							(mid 0.275042 0.275042)
							(end 0.3048 0.2032)
						)
					)
					(width 0)
					(fill yes)
				)
			)
		)
	)
	(footprint ""
		(layer "F.Cu")
		(at 31.369 -70.4596 -90)
		(property "Reference" "PC72"
			(at 0 0 270)
			(layer "F.SilkS")
			(hide yes)
			(effects
				(font
					(size 1.27 1.27)
				)
			)
		)
		(property "Value" "SC4D7U25V5KX-1-GP"
			(at -0.0762 -6.1214 270)
			(unlocked yes)
			(layer "F.Fab")
			(hide yes)
			(effects
				(font
					(size 1.016 1.016)
					(thickness 0.1524)
				)
			)
		)
		(property "Device Type" "C805H58"
			(at -0.0762 -8.1534 270)
			(unlocked yes)
			(layer "F.Fab")
			(hide yes)
			(effects
				(font
					(size 1.016 1.016)
					(thickness 0.1524)
				)
			)
		)
		(duplicate_pad_numbers_are_jumpers no)
		(fp_line
			(start 0.635 0)
			(end -0.635 0)
			(stroke
				(width 0.508)
				(type default)
			)
			(layer "F.SilkS")
		)
		(fp_rect
			(start -0.9652 1.778)
			(end 0.9652 -1.778)
			(stroke
				(width 0)
				(type default)
			)
			(fill no)
			(layer "F.CrtYd")
		)
		(fp_poly
			(pts
				(xy -0.9652 -1.778) (xy 0.9652 -1.778) (xy 0.9652 1.778) (xy -0.9652 1.778)
			)
			(stroke
				(width 0)
				(type default)
			)
			(fill no)
			(layer "F.Fab")
		)
		(pad "1" smd rect
			(at 0 -0.9652 270)
			(size 1.397 1.143)
			(layers "F.Cu" "F.Mask" "F.Paste")
			(net "P12V")
		)
		(pad "2" smd rect
			(at 0 0.9652 270)
			(size 1.397 1.143)
			(layers "F.Cu" "F.Mask" "F.Paste")
			(net "GND")
		)
	)
	(footprint ""
		(layer "F.Cu")
		(at 24.0538 -85.2424 -90)
		(property "Reference" "TP170"
			(at 0 0 270)
			(layer "F.SilkS")
			(hide yes)
			(effects
				(font
					(size 1.27 1.27)
				)
			)
		)
		(property "Value" "TPAD28-2-GP"
			(at -0.0127 -1.6637 270)
			(unlocked yes)
			(layer "F.Fab")
			(hide yes)
			(effects
				(font
					(size 1.016 1.016)
					(thickness 0.1524)
				)
			)
		)
		(property "Device Type" "TPAD28"
			(at -0.0127 -3.1877 270)
			(unlocked yes)
			(layer "F.Fab")
			(hide yes)
			(effects
				(font
					(size 1.016 1.016)
					(thickness 0.1524)
				)
			)
		)
		(duplicate_pad_numbers_are_jumpers no)
		(fp_poly
			(pts
				(arc
					(start 0 -0.3556)
					(mid 0 0.3556)
					(end 0 -0.3556)
				)
			)
			(stroke
				(width 0)
				(type default)
			)
			(fill no)
			(layer "F.CrtYd")
		)
		(fp_poly
			(pts
				(arc
					(start 0 -0.6096)
					(mid 0 0.6096)
					(end 0 -0.6096)
				)
			)
			(stroke
				(width 0)
				(type default)
			)
			(fill no)
			(layer "F.Fab")
		)
		(pad "1" smd circle
			(at 0 0 270)
			(size 0.7112 0.7112)
			(layers "F.Cu" "F.Mask" "F.Paste")
			(net "NIC_JTMS")
		)
	)
	(footprint ""
		(layer "F.Cu")
		(at 266.9794 -16.2814 -90)
		(property "Reference" "SR717"
			(at 0 0 270)
			(layer "F.SilkS")
			(hide yes)
			(effects
				(font
					(size 1.27 1.27)
				)
			)
		)
		(property "Value" "150R2F-1-GP"
			(at 0.064008 -3.993896 270)
			(unlocked yes)
			(layer "F.Fab")
			(hide yes)
			(effects
				(font
					(size 1.016 1.016)
					(thickness 0.1524)
				)
			)
		)
		(property "Device Type" "R402H16"
			(at 0.064008 -5.517896 270)
			(unlocked yes)
			(layer "F.Fab")
			(hide yes)
			(effects
				(font
					(size 1.016 1.016)
					(thickness 0.1524)
				)
			)
		)
		(duplicate_pad_numbers_are_jumpers no)
		(fp_line
			(start -0.508 -0.9398)
			(end -0.508 0.9398)
			(stroke
				(width 0.1524)
				(type default)
			)
			(layer "F.SilkS")
		)
		(fp_line
			(start 0.508 -0.9398)
			(end -0.508 -0.9398)
			(stroke
				(width 0.1524)
				(type default)
			)
			(layer "F.SilkS")
		)
		(fp_rect
			(start -0.508 0.9398)
			(end 0.508 -0.9398)
			(stroke
				(width 0)
				(type default)
			)
			(fill no)
			(layer "F.CrtYd")
		)
		(fp_rect
			(start -0.508 0.9398)
			(end 0.508 -0.9398)
			(stroke
				(width 0)
				(type default)
			)
			(fill no)
			(layer "F.Fab")
		)
		(pad "1" smd custom
			(at 0 -0.4445 270)
			(size 0.1397 0.1397)
			(layers "F.Cu" "F.Mask" "F.Paste")
			(net "P3V3_STBY")
			(options
				(clearance outline)
				(anchor circle)
			)
			(primitives
				(gr_poly
					(pts
						(arc
							(start -0.1778 -0.2794)
							(mid -0.249642 -0.249642)
							(end -0.2794 -0.1778)
						)
						(arc
							(start -0.2794 0.1778)
							(mid -0.249642 0.249642)
							(end -0.1778 0.2794)
						)
						(arc
							(start 0.1778 0.2794)
							(mid 0.249642 0.249642)
							(end 0.2794 0.1778)
						)
						(arc
							(start 0.2794 -0.1778)
							(mid 0.249642 -0.249642)
							(end 0.1778 -0.2794)
						)
					)
					(width 0)
					(fill yes)
				)
			)
		)
		(pad "2" smd custom
			(at 0 0.4445 270)
			(size 0.1397 0.1397)
			(layers "F.Cu" "F.Mask" "F.Paste")
			(net "LED_R_12")
			(options
				(clearance outline)
				(anchor circle)
			)
			(primitives
				(gr_poly
					(pts
						(arc
							(start -0.1778 -0.2794)
							(mid -0.249642 -0.249642)
							(end -0.2794 -0.1778)
						)
						(arc
							(start -0.2794 0.1778)
							(mid -0.249642 0.249642)
							(end -0.1778 0.2794)
						)
						(arc
							(start 0.1778 0.2794)
							(mid 0.249642 0.249642)
							(end 0.2794 0.1778)
						)
						(arc
							(start 0.2794 -0.1778)
							(mid 0.249642 -0.249642)
							(end 0.1778 -0.2794)
						)
					)
					(width 0)
					(fill yes)
				)
			)
		)
	)
	(footprint ""
		(layer "F.Cu")
		(at 192.9003 -19.2786 -90)
		(property "Reference" "R572"
			(at 0 0 270)
			(layer "F.SilkS")
			(hide yes)
			(effects
				(font
					(size 1.27 1.27)
				)
			)
		)
		(property "Value" "4K7R2F-GP"
			(at 0.064008 -3.993896 270)
			(unlocked yes)
			(layer "F.Fab")
			(hide yes)
			(effects
				(font
					(size 1.016 1.016)
					(thickness 0.1524)
				)
			)
		)
		(property "Device Type" "R402H16"
			(at 0.064008 -5.517896 270)
			(unlocked yes)
			(layer "F.Fab")
			(hide yes)
			(effects
				(font
					(size 1.016 1.016)
					(thickness 0.1524)
				)
			)
		)
		(duplicate_pad_numbers_are_jumpers no)
		(fp_line
			(start -0.508 -0.9398)
			(end -0.508 0.9398)
			(stroke
				(width 0.1524)
				(type default)
			)
			(layer "F.SilkS")
		)
		(fp_line
			(start 0.508 -0.9398)
			(end -0.508 -0.9398)
			(stroke
				(width 0.1524)
				(type default)
			)
			(layer "F.SilkS")
		)
		(fp_rect
			(start -0.508 0.9398)
			(end 0.508 -0.9398)
			(stroke
				(width 0)
				(type default)
			)
			(fill no)
			(layer "F.CrtYd")
		)
		(fp_rect
			(start -0.508 0.9398)
			(end 0.508 -0.9398)
			(stroke
				(width 0)
				(type default)
			)
			(fill no)
			(layer "F.Fab")
		)
		(pad "1" smd custom
			(at 0 -0.4445 270)
			(size 0.1397 0.1397)
			(layers "F.Cu" "F.Mask" "F.Paste")
			(net "MINISAS_CN15_C_I2C_INT#")
			(options
				(clearance outline)
				(anchor circle)
			)
			(primitives
				(gr_poly
					(pts
						(arc
							(start -0.1778 -0.2794)
							(mid -0.249642 -0.249642)
							(end -0.2794 -0.1778)
						)
						(arc
							(start -0.2794 0.1778)
							(mid -0.249642 0.249642)
							(end -0.1778 0.2794)
						)
						(arc
							(start 0.1778 0.2794)
							(mid 0.249642 0.249642)
							(end 0.2794 0.1778)
						)
						(arc
							(start 0.2794 -0.1778)
							(mid 0.249642 -0.249642)
							(end 0.1778 -0.2794)
						)
					)
					(width 0)
					(fill yes)
				)
			)
		)
		(pad "2" smd custom
			(at 0 0.4445 270)
			(size 0.1397 0.1397)
			(layers "F.Cu" "F.Mask" "F.Paste")
			(net "P3V3_STBY")
			(options
				(clearance outline)
				(anchor circle)
			)
			(primitives
				(gr_poly
					(pts
						(arc
							(start -0.1778 -0.2794)
							(mid -0.249642 -0.249642)
							(end -0.2794 -0.1778)
						)
						(arc
							(start -0.2794 0.1778)
							(mid -0.249642 0.249642)
							(end -0.1778 0.2794)
						)
						(arc
							(start 0.1778 0.2794)
							(mid 0.249642 0.249642)
							(end 0.2794 0.1778)
						)
						(arc
							(start 0.2794 -0.1778)
							(mid 0.249642 -0.249642)
							(end 0.1778 -0.2794)
						)
					)
					(width 0)
					(fill yes)
				)
			)
		)
	)
	(footprint ""
		(layer "F.Cu")
		(at 330.099924 -19.99996 -90)
		(property "Reference" "LED12"
			(at 0 0 270)
			(layer "F.SilkS")
			(hide yes)
			(effects
				(font
					(size 1.27 1.27)
				)
			)
		)
		(property "Value" "LED-YG-51-GP"
			(at -2.6924 -1.4224 270)
			(unlocked yes)
			(layer "F.Fab")
			(hide yes)
			(effects
				(font
					(size 1.016 1.016)
					(thickness 0.1524)
				)
			)
		)
		(property "Device Type" "LED1608AKH40"
			(at -2.6924 -2.9464 270)
			(unlocked yes)
			(layer "F.Fab")
			(hide yes)
			(effects
				(font
					(size 1.016 1.016)
					(thickness 0.1524)
				)
			)
		)
		(duplicate_pad_numbers_are_jumpers no)
		(fp_line
			(start -0.7493 1.651)
			(end -0.7493 1.1811)
			(stroke
				(width 0.3302)
				(type default)
			)
			(layer "F.SilkS")
		)
		(fp_line
			(start 0.7493 1.651)
			(end 0.7493 1.1811)
			(stroke
				(width 0.3302)
				(type default)
			)
			(layer "F.SilkS")
		)
		(fp_line
			(start -0.5969 1.5494)
			(end 0.5842 1.5494)
			(stroke
				(width 0.508)
				(type default)
			)
			(layer "F.SilkS")
		)
		(fp_line
			(start -0.6604 1.3716)
			(end -0.6604 -1.3716)
			(stroke
				(width 0.1524)
				(type default)
			)
			(layer "F.SilkS")
		)
		(fp_line
			(start 0.6604 1.3716)
			(end -0.6604 1.3716)
			(stroke
				(width 0.1524)
				(type default)
			)
			(layer "F.SilkS")
		)
		(fp_line
			(start -0.6604 -1.3716)
			(end 0.6604 -1.3716)
			(stroke
				(width 0.1524)
				(type default)
			)
			(layer "F.SilkS")
		)
		(fp_line
			(start 0.6604 -1.3716)
			(end 0.6604 1.3716)
			(stroke
				(width 0.1524)
				(type default)
			)
			(layer "F.SilkS")
		)
		(fp_rect
			(start -0.6223 1.3335)
			(end 0.6223 -1.3335)
			(stroke
				(width 0)
				(type default)
			)
			(fill no)
			(layer "F.CrtYd")
		)
		(fp_rect
			(start -0.6223 1.3335)
			(end 0.6223 -1.3335)
			(stroke
				(width 0)
				(type default)
			)
			(fill no)
			(layer "F.Fab")
		)
		(pad "A" smd custom
			(at 0 -0.762 270)
			(size 0.2159 0.2159)
			(layers "F.Cu" "F.Mask" "F.Paste")
			(net "LED_R_5")
			(options
				(clearance outline)
				(anchor circle)
			)
			(primitives
				(gr_poly
					(pts
						(arc
							(start -0.3302 -0.4318)
							(mid -0.402042 -0.402042)
							(end -0.4318 -0.3302)
						)
						(arc
							(start -0.4318 0.3302)
							(mid -0.402042 0.402042)
							(end -0.3302 0.4318)
						)
						(arc
							(start 0.3302 0.4318)
							(mid 0.402042 0.402042)
							(end 0.4318 0.3302)
						)
						(arc
							(start 0.4318 -0.3302)
							(mid 0.402042 -0.402042)
							(end 0.3302 -0.4318)
						)
					)
					(width 0)
					(fill yes)
				)
			)
		)
		(pad "K" smd custom
			(at 0 0.762 270)
			(size 0.2159 0.2159)
			(layers "F.Cu" "F.Mask" "F.Paste")
			(net "LED_Q_5")
			(options
				(clearance outline)
				(anchor circle)
			)
			(primitives
				(gr_poly
					(pts
						(arc
							(start -0.3302 -0.4318)
							(mid -0.402042 -0.402042)
							(end -0.4318 -0.3302)
						)
						(arc
							(start -0.4318 0.3302)
							(mid -0.402042 0.402042)
							(end -0.3302 0.4318)
						)
						(arc
							(start 0.3302 0.4318)
							(mid 0.402042 0.402042)
							(end 0.4318 0.3302)
						)
						(arc
							(start 0.4318 -0.3302)
							(mid 0.402042 -0.402042)
							(end 0.3302 -0.4318)
						)
					)
					(width 0)
					(fill yes)
				)
			)
		)
	)
	(footprint ""
		(layer "F.Cu")
		(at 221.9579 -203.0476 180)
		(property "Reference" "R7964"
			(at 0 0 180)
			(layer "F.SilkS")
			(hide yes)
			(effects
				(font
					(size 1.27 1.27)
				)
			)
		)
		(property "Value" "0R2J-2-GP"
			(at 0.064008 -3.993896 180)
			(unlocked yes)
			(layer "F.Fab")
			(hide yes)
			(effects
				(font
					(size 1.016 1.016)
					(thickness 0.1524)
				)
			)
		)
		(property "Device Type" "R402H16"
			(at 0.064008 -5.517896 180)
			(unlocked yes)
			(layer "F.Fab")
			(hide yes)
			(effects
				(font
					(size 1.016 1.016)
					(thickness 0.1524)
				)
			)
		)
		(duplicate_pad_numbers_are_jumpers no)
		(fp_line
			(start 0.508 -0.9398)
			(end -0.508 -0.9398)
			(stroke
				(width 0.1524)
				(type default)
			)
			(layer "F.SilkS")
		)
		(fp_line
			(start -0.508 -0.9398)
			(end -0.508 0.9398)
			(stroke
				(width 0.1524)
				(type default)
			)
			(layer "F.SilkS")
		)
		(fp_rect
			(start -0.508 0.9398)
			(end 0.508 -0.9398)
			(stroke
				(width 0)
				(type default)
			)
			(fill no)
			(layer "F.CrtYd")
		)
		(fp_rect
			(start -0.508 0.9398)
			(end 0.508 -0.9398)
			(stroke
				(width 0)
				(type default)
			)
			(fill no)
			(layer "F.Fab")
		)
		(pad "1" smd custom
			(at 0 -0.4445 180)
			(size 0.1397 0.1397)
			(layers "F.Cu" "F.Mask" "F.Paste")
			(net "SSD_PWREN13")
			(options
				(clearance outline)
				(anchor circle)
			)
			(primitives
				(gr_poly
					(pts
						(arc
							(start -0.1778 -0.2794)
							(mid -0.249642 -0.249642)
							(end -0.2794 -0.1778)
						)
						(arc
							(start -0.2794 0.1778)
							(mid -0.249642 0.249642)
							(end -0.1778 0.2794)
						)
						(arc
							(start 0.1778 0.2794)
							(mid 0.249642 0.249642)
							(end 0.2794 0.1778)
						)
						(arc
							(start 0.2794 -0.1778)
							(mid 0.249642 -0.249642)
							(end 0.1778 -0.2794)
						)
					)
					(width 0)
					(fill yes)
				)
			)
		)
		(pad "2" smd custom
			(at 0 0.4445 180)
			(size 0.1397 0.1397)
			(layers "F.Cu" "F.Mask" "F.Paste")
			(net "SSD_PWREN13_R")
			(options
				(clearance outline)
				(anchor circle)
			)
			(primitives
				(gr_poly
					(pts
						(arc
							(start -0.1778 -0.2794)
							(mid -0.249642 -0.249642)
							(end -0.2794 -0.1778)
						)
						(arc
							(start -0.2794 0.1778)
							(mid -0.249642 0.249642)
							(end -0.1778 0.2794)
						)
						(arc
							(start 0.1778 0.2794)
							(mid 0.249642 0.249642)
							(end 0.2794 0.1778)
						)
						(arc
							(start 0.2794 -0.1778)
							(mid 0.249642 -0.249642)
							(end 0.1778 -0.2794)
						)
					)
					(width 0)
					(fill yes)
				)
			)
		)
	)
	(footprint ""
		(layer "F.Cu")
		(at 327.533 -99.568 180)
		(property "Reference" "R4173"
			(at 0 0 180)
			(layer "F.SilkS")
			(hide yes)
			(effects
				(font
					(size 1.27 1.27)
				)
			)
		)
		(property "Value" "4K7R2F-GP"
			(at 0.064008 -3.993896 180)
			(unlocked yes)
			(layer "F.Fab")
			(hide yes)
			(effects
				(font
					(size 1.016 1.016)
					(thickness 0.1524)
				)
			)
		)
		(property "Device Type" "R402H16"
			(at 0.064008 -5.517896 180)
			(unlocked yes)
			(layer "F.Fab")
			(hide yes)
			(effects
				(font
					(size 1.016 1.016)
					(thickness 0.1524)
				)
			)
		)
		(duplicate_pad_numbers_are_jumpers no)
		(fp_line
			(start 0.508 -0.9398)
			(end -0.508 -0.9398)
			(stroke
				(width 0.1524)
				(type default)
			)
			(layer "F.SilkS")
		)
		(fp_line
			(start -0.508 -0.9398)
			(end -0.508 0.9398)
			(stroke
				(width 0.1524)
				(type default)
			)
			(layer "F.SilkS")
		)
		(fp_rect
			(start -0.508 0.9398)
			(end 0.508 -0.9398)
			(stroke
				(width 0)
				(type default)
			)
			(fill no)
			(layer "F.CrtYd")
		)
		(fp_rect
			(start -0.508 0.9398)
			(end 0.508 -0.9398)
			(stroke
				(width 0)
				(type default)
			)
			(fill no)
			(layer "F.Fab")
		)
		(pad "1" smd custom
			(at 0 -0.4445 180)
			(size 0.1397 0.1397)
			(layers "F.Cu" "F.Mask" "F.Paste")
			(net "VS5_LED")
			(options
				(clearance outline)
				(anchor circle)
			)
			(primitives
				(gr_poly
					(pts
						(arc
							(start -0.1778 -0.2794)
							(mid -0.249642 -0.249642)
							(end -0.2794 -0.1778)
						)
						(arc
							(start -0.2794 0.1778)
							(mid -0.249642 0.249642)
							(end -0.1778 0.2794)
						)
						(arc
							(start 0.1778 0.2794)
							(mid 0.249642 0.249642)
							(end 0.2794 0.1778)
						)
						(arc
							(start 0.2794 -0.1778)
							(mid 0.249642 -0.249642)
							(end 0.1778 -0.2794)
						)
					)
					(width 0)
					(fill yes)
				)
			)
		)
		(pad "2" smd custom
			(at 0 0.4445 180)
			(size 0.1397 0.1397)
			(layers "F.Cu" "F.Mask" "F.Paste")
			(net "P3V3_STBY")
			(options
				(clearance outline)
				(anchor circle)
			)
			(primitives
				(gr_poly
					(pts
						(arc
							(start -0.1778 -0.2794)
							(mid -0.249642 -0.249642)
							(end -0.2794 -0.1778)
						)
						(arc
							(start -0.2794 0.1778)
							(mid -0.249642 0.249642)
							(end -0.1778 0.2794)
						)
						(arc
							(start 0.1778 0.2794)
							(mid 0.249642 0.249642)
							(end 0.2794 0.1778)
						)
						(arc
							(start 0.2794 -0.1778)
							(mid 0.249642 -0.249642)
							(end 0.1778 -0.2794)
						)
					)
					(width 0)
					(fill yes)
				)
			)
		)
	)
	(footprint ""
		(layer "F.Cu")
		(at 159.512 -85.2424 180)
		(property "Reference" "R75"
			(at 0 0 180)
			(layer "F.SilkS")
			(hide yes)
			(effects
				(font
					(size 1.27 1.27)
				)
			)
		)
		(property "Value" "0R2J-2-GP"
			(at 0.064008 -3.993896 180)
			(unlocked yes)
			(layer "F.Fab")
			(hide yes)
			(effects
				(font
					(size 1.016 1.016)
					(thickness 0.1524)
				)
			)
		)
		(property "Device Type" "R402H16"
			(at 0.064008 -5.517896 180)
			(unlocked yes)
			(layer "F.Fab")
			(hide yes)
			(effects
				(font
					(size 1.016 1.016)
					(thickness 0.1524)
				)
			)
		)
		(duplicate_pad_numbers_are_jumpers no)
		(fp_line
			(start 0.508 -0.9398)
			(end -0.508 -0.9398)
			(stroke
				(width 0.1524)
				(type default)
			)
			(layer "F.SilkS")
		)
		(fp_line
			(start -0.508 -0.9398)
			(end -0.508 0.9398)
			(stroke
				(width 0.1524)
				(type default)
			)
			(layer "F.SilkS")
		)
		(fp_rect
			(start -0.508 0.9398)
			(end 0.508 -0.9398)
			(stroke
				(width 0)
				(type default)
			)
			(fill no)
			(layer "F.CrtYd")
		)
		(fp_rect
			(start -0.508 0.9398)
			(end 0.508 -0.9398)
			(stroke
				(width 0)
				(type default)
			)
			(fill no)
			(layer "F.Fab")
		)
		(pad "1" smd custom
			(at 0 -0.4445 180)
			(size 0.1397 0.1397)
			(layers "F.Cu" "F.Mask" "F.Paste")
			(net "BMC_I2C5_D_PEB_SDA")
			(options
				(clearance outline)
				(anchor circle)
			)
			(primitives
				(gr_poly
					(pts
						(arc
							(start -0.1778 -0.2794)
							(mid -0.249642 -0.249642)
							(end -0.2794 -0.1778)
						)
						(arc
							(start -0.2794 0.1778)
							(mid -0.249642 0.249642)
							(end -0.1778 0.2794)
						)
						(arc
							(start 0.1778 0.2794)
							(mid 0.249642 0.249642)
							(end 0.2794 0.1778)
						)
						(arc
							(start 0.2794 -0.1778)
							(mid 0.249642 -0.249642)
							(end 0.1778 -0.2794)
						)
					)
					(width 0)
					(fill yes)
				)
			)
		)
		(pad "2" smd custom
			(at 0 0.4445 180)
			(size 0.1397 0.1397)
			(layers "F.Cu" "F.Mask" "F.Paste")
			(net "CLKGEN_SDA")
			(options
				(clearance outline)
				(anchor circle)
			)
			(primitives
				(gr_poly
					(pts
						(arc
							(start -0.1778 -0.2794)
							(mid -0.249642 -0.249642)
							(end -0.2794 -0.1778)
						)
						(arc
							(start -0.2794 0.1778)
							(mid -0.249642 0.249642)
							(end -0.1778 0.2794)
						)
						(arc
							(start 0.1778 0.2794)
							(mid 0.249642 0.249642)
							(end 0.2794 0.1778)
						)
						(arc
							(start 0.2794 -0.1778)
							(mid 0.249642 -0.249642)
							(end 0.1778 -0.2794)
						)
					)
					(width 0)
					(fill yes)
				)
			)
		)
	)
	(footprint ""
		(layer "F.Cu")
		(at 24.5618 -119.7356)
		(property "Reference" "R684"
			(at 0 0 0)
			(layer "F.SilkS")
			(hide yes)
			(effects
				(font
					(size 1.27 1.27)
				)
			)
		)
		(property "Value" "0R2J-2-GP"
			(at 0.064008 -3.993896 0)
			(unlocked yes)
			(layer "F.Fab")
			(hide yes)
			(effects
				(font
					(size 1.016 1.016)
					(thickness 0.1524)
				)
			)
		)
		(property "Device Type" "R402H16"
			(at 0.064008 -5.517896 0)
			(unlocked yes)
			(layer "F.Fab")
			(hide yes)
			(effects
				(font
					(size 1.016 1.016)
					(thickness 0.1524)
				)
			)
		)
		(duplicate_pad_numbers_are_jumpers no)
		(fp_line
			(start -0.508 -0.9398)
			(end -0.508 0.9398)
			(stroke
				(width 0.1524)
				(type default)
			)
			(layer "F.SilkS")
		)
		(fp_line
			(start 0.508 -0.9398)
			(end -0.508 -0.9398)
			(stroke
				(width 0.1524)
				(type default)
			)
			(layer "F.SilkS")
		)
		(fp_rect
			(start -0.508 0.9398)
			(end 0.508 -0.9398)
			(stroke
				(width 0)
				(type default)
			)
			(fill no)
			(layer "F.CrtYd")
		)
		(fp_rect
			(start -0.508 0.9398)
			(end 0.508 -0.9398)
			(stroke
				(width 0)
				(type default)
			)
			(fill no)
			(layer "F.Fab")
		)
		(pad "1" smd custom
			(at 0 -0.4445)
			(size 0.1397 0.1397)
			(layers "F.Cu" "F.Mask" "F.Paste")
			(net "SPICS0_N_R")
			(options
				(clearance outline)
				(anchor circle)
			)
			(primitives
				(gr_poly
					(pts
						(arc
							(start -0.1778 -0.2794)
							(mid -0.249642 -0.249642)
							(end -0.2794 -0.1778)
						)
						(arc
							(start -0.2794 0.1778)
							(mid -0.249642 0.249642)
							(end -0.1778 0.2794)
						)
						(arc
							(start 0.1778 0.2794)
							(mid 0.249642 0.249642)
							(end 0.2794 0.1778)
						)
						(arc
							(start 0.2794 -0.1778)
							(mid 0.249642 -0.249642)
							(end 0.1778 -0.2794)
						)
					)
					(width 0)
					(fill yes)
				)
			)
		)
		(pad "2" smd custom
			(at 0 0.4445)
			(size 0.1397 0.1397)
			(layers "F.Cu" "F.Mask" "F.Paste")
			(net "SPICS0_N")
			(options
				(clearance outline)
				(anchor circle)
			)
			(primitives
				(gr_poly
					(pts
						(arc
							(start -0.1778 -0.2794)
							(mid -0.249642 -0.249642)
							(end -0.2794 -0.1778)
						)
						(arc
							(start -0.2794 0.1778)
							(mid -0.249642 0.249642)
							(end -0.1778 0.2794)
						)
						(arc
							(start 0.1778 0.2794)
							(mid 0.249642 0.249642)
							(end 0.2794 0.1778)
						)
						(arc
							(start 0.2794 -0.1778)
							(mid 0.249642 -0.249642)
							(end 0.1778 -0.2794)
						)
					)
					(width 0)
					(fill yes)
				)
			)
		)
	)
	(footprint ""
		(layer "F.Cu")
		(at 276.607016 -9.241282 90)
		(property "Reference" "R2909"
			(at 0 0 90)
			(layer "F.SilkS")
			(hide yes)
			(effects
				(font
					(size 1.27 1.27)
				)
			)
		)
		(property "Value" "0R2J-2-GP"
			(at 0.064008 -3.993896 90)
			(unlocked yes)
			(layer "F.Fab")
			(hide yes)
			(effects
				(font
					(size 1.016 1.016)
					(thickness 0.1524)
				)
			)
		)
		(property "Device Type" "R402H16"
			(at 0.064008 -5.517896 90)
			(unlocked yes)
			(layer "F.Fab")
			(hide yes)
			(effects
				(font
					(size 1.016 1.016)
					(thickness 0.1524)
				)
			)
		)
		(duplicate_pad_numbers_are_jumpers no)
		(fp_line
			(start 0.508 -0.9398)
			(end -0.508 -0.9398)
			(stroke
				(width 0.1524)
				(type default)
			)
			(layer "F.SilkS")
		)
		(fp_line
			(start -0.508 -0.9398)
			(end -0.508 0.9398)
			(stroke
				(width 0.1524)
				(type default)
			)
			(layer "F.SilkS")
		)
		(fp_rect
			(start -0.508 0.9398)
			(end 0.508 -0.9398)
			(stroke
				(width 0)
				(type default)
			)
			(fill no)
			(layer "F.CrtYd")
		)
		(fp_rect
			(start -0.508 0.9398)
			(end 0.508 -0.9398)
			(stroke
				(width 0)
				(type default)
			)
			(fill no)
			(layer "F.Fab")
		)
		(pad "1" smd custom
			(at 0 -0.4445 90)
			(size 0.1397 0.1397)
			(layers "F.Cu" "F.Mask" "F.Paste")
			(net "BMC_I2C11_MINI5_SDA")
			(options
				(clearance outline)
				(anchor circle)
			)
			(primitives
				(gr_poly
					(pts
						(arc
							(start -0.1778 -0.2794)
							(mid -0.249642 -0.249642)
							(end -0.2794 -0.1778)
						)
						(arc
							(start -0.2794 0.1778)
							(mid -0.249642 0.249642)
							(end -0.1778 0.2794)
						)
						(arc
							(start 0.1778 0.2794)
							(mid 0.249642 0.249642)
							(end 0.2794 0.1778)
						)
						(arc
							(start 0.2794 -0.1778)
							(mid 0.249642 -0.249642)
							(end 0.1778 -0.2794)
						)
					)
					(width 0)
					(fill yes)
				)
			)
		)
		(pad "2" smd custom
			(at 0 0.4445 90)
			(size 0.1397 0.1397)
			(layers "F.Cu" "F.Mask" "F.Paste")
			(net "8644_CBL_PRSNT_R_5")
			(options
				(clearance outline)
				(anchor circle)
			)
			(primitives
				(gr_poly
					(pts
						(arc
							(start -0.1778 -0.2794)
							(mid -0.249642 -0.249642)
							(end -0.2794 -0.1778)
						)
						(arc
							(start -0.2794 0.1778)
							(mid -0.249642 0.249642)
							(end -0.1778 0.2794)
						)
						(arc
							(start 0.1778 0.2794)
							(mid 0.249642 0.249642)
							(end 0.2794 0.1778)
						)
						(arc
							(start 0.2794 -0.1778)
							(mid 0.249642 -0.249642)
							(end 0.1778 -0.2794)
						)
					)
					(width 0)
					(fill yes)
				)
			)
		)
	)
	(footprint ""
		(layer "F.Cu")
		(at 15.642082 -38.509956)
		(property "Reference" "RJ1"
			(at 0 0 0)
			(layer "F.SilkS")
			(hide yes)
			(effects
				(font
					(size 1.27 1.27)
				)
			)
		)
		(property "Value" "RJ45-LED-12P-10-GP"
			(at -2.15773 -12.96797 0)
			(unlocked yes)
			(layer "F.Fab")
			(hide yes)
			(effects
				(font
					(size 1.016 1.016)
					(thickness 0.1524)
				)
			)
		)
		(property "Device Type" "XRJH-01H-D-H71-D81-W"
			(at -2.15773 -14.49197 0)
			(unlocked yes)
			(layer "F.Fab")
			(hide yes)
			(effects
				(font
					(size 1.016 1.016)
					(thickness 0.1524)
				)
			)
		)
		(duplicate_pad_numbers_are_jumpers no)
		(fp_line
			(start -10.033 -1.2446)
			(end -9.144 -1.2446)
			(stroke
				(width 0.1524)
				(type default)
			)
			(layer "F.SilkS")
		)
		(fp_line
			(start -10.033 1.2446)
			(end -10.033 -1.2446)
			(stroke
				(width 0.1524)
				(type default)
			)
			(layer "F.SilkS")
		)
		(fp_line
			(start -9.144 -11.176)
			(end 9.144 -11.176)
			(stroke
				(width 0.1524)
				(type default)
			)
			(layer "F.SilkS")
		)
		(fp_line
			(start -9.144 -1.2446)
			(end -9.144 -11.176)
			(stroke
				(width 0.1524)
				(type default)
			)
			(layer "F.SilkS")
		)
		(fp_line
			(start -9.144 1.2446)
			(end -10.033 1.2446)
			(stroke
				(width 0.1524)
				(type default)
			)
			(layer "F.SilkS")
		)
		(fp_line
			(start -9.144 13.462)
			(end -9.144 1.2446)
			(stroke
				(width 0.1524)
				(type default)
			)
			(layer "F.SilkS")
		)
		(fp_line
			(start 9.144 -11.176)
			(end 9.144 -1.2446)
			(stroke
				(width 0.1524)
				(type default)
			)
			(layer "F.SilkS")
		)
		(fp_line
			(start 9.144 -1.2446)
			(end 10.033 -1.2446)
			(stroke
				(width 0.1524)
				(type default)
			)
			(layer "F.SilkS")
		)
		(fp_line
			(start 9.144 1.2446)
			(end 9.144 13.462)
			(stroke
				(width 0.1524)
				(type default)
			)
			(layer "F.SilkS")
		)
		(fp_line
			(start 9.144 13.462)
			(end -9.144 13.462)
			(stroke
				(width 0.1524)
				(type default)
			)
			(layer "F.SilkS")
		)
		(fp_line
			(start 10.033 -1.2446)
			(end 10.033 1.2446)
			(stroke
				(width 0.1524)
				(type default)
			)
			(layer "F.SilkS")
		)
		(fp_line
			(start 10.033 1.2446)
			(end 9.144 1.2446)
			(stroke
				(width 0.1524)
				(type default)
			)
			(layer "F.SilkS")
		)
		(fp_circle
			(center -8.789924 0)
			(end -7.443724 0)
			(stroke
				(width 0.3048)
				(type default)
			)
			(fill no)
			(layer "F.SilkS")
		)
		(fp_circle
			(center -7.519924 6.35)
			(end -6.326124 6.35)
			(stroke
				(width 0.3048)
				(type default)
			)
			(fill no)
			(layer "F.SilkS")
		)
		(fp_circle
			(center -7.519924 8.89)
			(end -6.326124 8.89)
			(stroke
				(width 0.3048)
				(type default)
			)
			(fill no)
			(layer "F.SilkS")
		)
		(fp_circle
			(center -6.100064 -9.139936)
			(end -5.084064 -9.139936)
			(stroke
				(width 0.3048)
				(type default)
			)
			(fill no)
			(layer "F.SilkS")
		)
		(fp_circle
			(center -5.07492 -6.599936)
			(end -4.05892 -6.599936)
			(stroke
				(width 0.3048)
				(type default)
			)
			(fill no)
			(layer "F.SilkS")
		)
		(fp_circle
			(center -4.070096 -9.139936)
			(end -3.054096 -9.139936)
			(stroke
				(width 0.3048)
				(type default)
			)
			(fill no)
			(layer "F.SilkS")
		)
		(fp_circle
			(center -3.044952 -6.599936)
			(end -2.028952 -6.599936)
			(stroke
				(width 0.3048)
				(type default)
			)
			(fill no)
			(layer "F.SilkS")
		)
		(fp_circle
			(center -2.040128 -9.139936)
			(end -1.024128 -9.139936)
			(stroke
				(width 0.3048)
				(type default)
			)
			(fill no)
			(layer "F.SilkS")
		)
		(fp_circle
			(center -1.014984 -6.599936)
			(end 0.001016 -6.599936)
			(stroke
				(width 0.3048)
				(type default)
			)
			(fill no)
			(layer "F.SilkS")
		)
		(fp_circle
			(center 1.014984 -6.599936)
			(end 2.030984 -6.599936)
			(stroke
				(width 0.3048)
				(type default)
			)
			(fill no)
			(layer "F.SilkS")
		)
		(fp_circle
			(center 2.040128 -9.139936)
			(end 3.056128 -9.139936)
			(stroke
				(width 0.3048)
				(type default)
			)
			(fill no)
			(layer "F.SilkS")
		)
		(fp_circle
			(center 3.044952 -6.599936)
			(end 4.060952 -6.599936)
			(stroke
				(width 0.3048)
				(type default)
			)
			(fill no)
			(layer "F.SilkS")
		)
		(fp_circle
			(center 4.070096 -9.139936)
			(end 5.086096 -9.139936)
			(stroke
				(width 0.3048)
				(type default)
			)
			(fill no)
			(layer "F.SilkS")
		)
		(fp_circle
			(center 5.07492 -6.599936)
			(end 6.09092 -6.599936)
			(stroke
				(width 0.3048)
				(type default)
			)
			(fill no)
			(layer "F.SilkS")
		)
		(fp_circle
			(center 6.100064 -9.139936)
			(end 7.116064 -9.139936)
			(stroke
				(width 0.3048)
				(type default)
			)
			(fill no)
			(layer "F.SilkS")
		)
		(fp_circle
			(center 7.519924 3.81)
			(end 8.713724 3.81)
			(stroke
				(width 0.3048)
				(type default)
			)
			(fill no)
			(layer "F.SilkS")
		)
		(fp_circle
			(center 7.519924 6.35)
			(end 8.713724 6.35)
			(stroke
				(width 0.3048)
				(type default)
			)
			(fill no)
			(layer "F.SilkS")
		)
		(fp_circle
			(center 7.519924 8.89)
			(end 8.713724 8.89)
			(stroke
				(width 0.3048)
				(type default)
			)
			(fill no)
			(layer "F.SilkS")
		)
		(fp_circle
			(center 8.789924 0)
			(end 10.136124 0)
			(stroke
				(width 0.3048)
				(type default)
			)
			(fill no)
			(layer "F.SilkS")
		)
		(fp_rect
			(start -8.89 13.208)
			(end 8.89 -10.922)
			(stroke
				(width 0)
				(type default)
			)
			(fill no)
			(layer "F.CrtYd")
		)
		(fp_poly
			(pts
				(xy -9.398 13.716) (xy -9.398 1.4986) (xy -10.287 1.4986) (xy -10.287 -1.4986) (xy -9.398 -1.4986)
				(xy -9.398 -11.43) (xy 9.398 -11.43) (xy 9.398 -1.4986) (xy 10.287 -1.4986) (xy 10.287 -0.00635)
				(xy 8.89 -0.00635) (xy 8.89 -10.922) (xy -8.89 -10.922) (xy -8.89 13.208) (xy 8.89 13.208) (xy 8.89 0.00635)
				(xy 10.287 0.00635) (xy 10.287 1.4986) (xy 9.398 1.4986) (xy 9.398 13.716)
			)
			(stroke
				(width 0)
				(type default)
			)
			(fill no)
			(layer "F.CrtYd")
		)
		(fp_poly
			(pts
				(xy -9.398 13.716) (xy -9.398 1.4986) (xy -10.287 1.4986) (xy -10.287 -1.4986) (xy -9.398 -1.4986)
				(xy -9.398 -11.43) (xy 9.398 -11.43) (xy 9.398 -1.4986) (xy 10.287 -1.4986) (xy 10.287 1.4986) (xy 9.398 1.4986)
				(xy 9.398 13.716)
			)
			(stroke
				(width 0)
				(type default)
			)
			(fill no)
			(layer "F.Fab")
		)
		(pad "" np_thru_hole circle
			(at -4.824984 0)
			(size 0.254 0.254)
			(drill 3.2512)
			(layers "*.Cu" "*.Mask")
			(clearance 1.8542)
			(thermal_gap 1.8542)
		)
		(pad "" np_thru_hole circle
			(at 4.824984 0)
			(size 0.254 0.254)
			(drill 3.2512)
			(layers "*.Cu" "*.Mask")
			(clearance 1.8542)
			(thermal_gap 1.8542)
		)
		(pad "1" thru_hole circle
			(at 5.07492 -6.599936)
			(size 1.3208 1.3208)
			(drill 0.9144)
			(layers "*.Cu" "*.Mask")
			(remove_unused_layers no)
			(net "NIC0_CT_POWER")
			(clearance 0.1524)
			(thermal_gap 0.1524)
		)
		(pad "2" thru_hole circle
			(at 3.044952 -6.599936)
			(size 1.3208 1.3208)
			(drill 0.9144)
			(layers "*.Cu" "*.Mask")
			(remove_unused_layers no)
			(net "NIC0_MDI0_N2_R")
			(clearance 0.1524)
			(thermal_gap 0.1524)
		)
		(pad "3" thru_hole circle
			(at 1.014984 -6.599936)
			(size 1.3208 1.3208)
			(drill 0.9144)
			(layers "*.Cu" "*.Mask")
			(remove_unused_layers no)
			(net "NIC0_MDI0_P2_R")
			(clearance 0.1524)
			(thermal_gap 0.1524)
		)
		(pad "4" thru_hole circle
			(at -1.014984 -6.599936)
			(size 1.3208 1.3208)
			(drill 0.9144)
			(layers "*.Cu" "*.Mask")
			(remove_unused_layers no)
			(net "NIC0_MDI0_P1_R")
			(clearance 0.1524)
			(thermal_gap 0.1524)
		)
		(pad "5" thru_hole circle
			(at -3.044952 -6.599936)
			(size 1.3208 1.3208)
			(drill 0.9144)
			(layers "*.Cu" "*.Mask")
			(remove_unused_layers no)
			(net "NIC0_MDI0_N1_R")
			(clearance 0.1524)
			(thermal_gap 0.1524)
		)
		(pad "6" thru_hole circle
			(at -5.07492 -6.599936)
			(size 1.3208 1.3208)
			(drill 0.9144)
			(layers "*.Cu" "*.Mask")
			(remove_unused_layers no)
			(net "NIC0_CT_POWER")
			(clearance 0.1524)
			(thermal_gap 0.1524)
		)
		(pad "7" thru_hole circle
			(at 6.100064 -9.139936)
			(size 1.3208 1.3208)
			(drill 0.9144)
			(layers "*.Cu" "*.Mask")
			(remove_unused_layers no)
			(net "NIC0_CT_POWER")
			(clearance 0.1524)
			(thermal_gap 0.1524)
		)
		(pad "8" thru_hole circle
			(at 4.070096 -9.139936)
			(size 1.3208 1.3208)
			(drill 0.9144)
			(layers "*.Cu" "*.Mask")
			(remove_unused_layers no)
			(net "NIC0_MDI0_P3_R")
			(clearance 0.1524)
			(thermal_gap 0.1524)
		)
		(pad "9" thru_hole circle
			(at 2.040128 -9.139936)
			(size 1.3208 1.3208)
			(drill 0.9144)
			(layers "*.Cu" "*.Mask")
			(remove_unused_layers no)
			(net "NIC0_MDI0_N3_R")
			(clearance 0.1524)
			(thermal_gap 0.1524)
		)
		(pad "10" thru_hole circle
			(at -2.040128 -9.139936)
			(size 1.3208 1.3208)
			(drill 0.9144)
			(layers "*.Cu" "*.Mask")
			(remove_unused_layers no)
			(net "NIC0_MDI0_N0_R")
			(clearance 0.1524)
			(thermal_gap 0.1524)
		)
		(pad "11" thru_hole circle
			(at -4.070096 -9.139936)
			(size 1.3208 1.3208)
			(drill 0.9144)
			(layers "*.Cu" "*.Mask")
			(remove_unused_layers no)
			(net "NIC0_MDI0_P0_R")
			(clearance 0.1524)
			(thermal_gap 0.1524)
		)
		(pad "12" thru_hole circle
			(at -6.100064 -9.139936)
			(size 1.3208 1.3208)
			(drill 0.9144)
			(layers "*.Cu" "*.Mask")
			(remove_unused_layers no)
			(net "NIC0_CT_POWER")
			(clearance 0.1524)
			(thermal_gap 0.1524)
		)
		(pad "13" thru_hole circle
			(at 8.789924 0)
			(size 1.9812 1.9812)
			(drill 1.5748)
			(layers "*.Cu" "*.Mask")
			(remove_unused_layers no)
			(net "GND")
			(clearance 0.1524)
			(thermal_gap 0.1524)
		)
		(pad "14" thru_hole circle
			(at -8.789924 0)
			(size 1.9812 1.9812)
			(drill 1.5748)
			(layers "*.Cu" "*.Mask")
			(remove_unused_layers no)
			(net "GND")
			(clearance 0.1524)
			(thermal_gap 0.1524)
		)
		(pad "D1" thru_hole circle
			(at -7.519924 6.35)
			(size 1.6764 1.6764)
			(drill 1.27)
			(layers "*.Cu" "*.Mask")
			(remove_unused_layers no)
			(net "LED_MDI0_LINK_N")
			(clearance 0.1524)
			(thermal_gap 0.1524)
		)
		(pad "D2" thru_hole circle
			(at -7.519924 8.89)
			(size 1.6764 1.6764)
			(drill 1.27)
			(layers "*.Cu" "*.Mask")
			(remove_unused_layers no)
			(net "LED_MDI0_ACT")
			(clearance 0.1524)
			(thermal_gap 0.1524)
		)
		(pad "D3" thru_hole circle
			(at 7.519924 3.81)
			(size 1.6764 1.6764)
			(drill 1.27)
			(layers "*.Cu" "*.Mask")
			(remove_unused_layers no)
			(net "LED_MDI0_1G_N_R")
			(clearance 0.1524)
			(thermal_gap 0.1524)
		)
		(pad "D4" thru_hole circle
			(at 7.519924 6.35)
			(size 1.6764 1.6764)
			(drill 1.27)
			(layers "*.Cu" "*.Mask")
			(remove_unused_layers no)
			(net "LED_MDI0_100M_1G_N")
			(clearance 0.1524)
			(thermal_gap 0.1524)
		)
		(pad "D5" thru_hole circle
			(at 7.519924 8.89)
			(size 1.6764 1.6764)
			(drill 1.27)
			(layers "*.Cu" "*.Mask")
			(remove_unused_layers no)
			(net "LED_MDI0_100M_N_R")
			(clearance 0.1524)
			(thermal_gap 0.1524)
		)
		(zone
			(layer "F.Cu")
			(hatch none 0.5)
			(connect_pads
				(clearance 0)
			)
			(min_thickness 0.25)
			(keepout
				(tracks allowed)
				(vias not_allowed)
				(pads allowed)
				(copperpour not_allowed)
				(footprints allowed)
			)
			(placement
				(enabled no)
				(sheetname "")
			)
			(fill
				(thermal_gap 0.5)
				(thermal_bridge_width 0.5)
				(island_removal_mode 0)
			)
			(polygon
				(pts
					(xy 6.452108 -40.099996) (xy 6.452108 -42.69994) (xy 8.55218 -42.69994) (xy 8.55218 -40.099996)
				)
			)
		)
		(zone
			(layer "F.Cu")
			(hatch none 0.5)
			(connect_pads
				(clearance 0)
			)
			(min_thickness 0.25)
			(keepout
				(tracks not_allowed)
				(vias allowed)
				(pads allowed)
				(copperpour not_allowed)
				(footprints allowed)
			)
			(placement
				(enabled no)
				(sheetname "")
			)
			(fill
				(thermal_gap 0.5)
				(thermal_bridge_width 0.5)
				(island_removal_mode 0)
			)
			(polygon
				(pts
					(xy 6.452108 -40.099996) (xy 8.55218 -40.099996) (xy 8.55218 -42.69994) (xy 6.452108 -42.69994)
				)
			)
		)
		(zone
			(layer "F.Cu")
			(hatch none 0.5)
			(connect_pads
				(clearance 0)
			)
			(min_thickness 0.25)
			(keepout
				(tracks not_allowed)
				(vias allowed)
				(pads allowed)
				(copperpour not_allowed)
				(footprints allowed)
			)
			(placement
				(enabled no)
				(sheetname "")
			)
			(fill
				(thermal_gap 0.5)
				(thermal_bridge_width 0.5)
				(island_removal_mode 0)
			)
			(polygon
				(pts
					(xy 22.731984 -40.099996) (xy 24.832056 -40.099996) (xy 24.832056 -42.69994) (xy 22.731984 -42.69994)
				)
			)
		)
		(zone
			(layer "F.Cu")
			(hatch none 0.5)
			(connect_pads
				(clearance 0)
			)
			(min_thickness 0.25)
			(keepout
				(tracks allowed)
				(vias not_allowed)
				(pads allowed)
				(copperpour not_allowed)
				(footprints allowed)
			)
			(placement
				(enabled no)
				(sheetname "")
			)
			(fill
				(thermal_gap 0.5)
				(thermal_bridge_width 0.5)
				(island_removal_mode 0)
			)
			(polygon
				(pts
					(xy 24.832056 -40.099996) (xy 24.832056 -42.69994) (xy 22.731984 -42.69994) (xy 22.731984 -40.099996)
				)
			)
		)
		(zone
			(layer "F.Cu")
			(hatch none 0.5)
			(connect_pads
				(clearance 0)
			)
			(min_thickness 0.25)
			(keepout
				(tracks not_allowed)
				(vias allowed)
				(pads allowed)
				(copperpour not_allowed)
				(footprints allowed)
			)
			(placement
				(enabled no)
				(sheetname "")
			)
			(fill
				(thermal_gap 0.5)
				(thermal_bridge_width 0.5)
				(island_removal_mode 0)
			)
			(polygon
				(pts
					(xy 6.452108 -24.99995) (xy 24.832056 -24.99995) (xy 24.832056 -28.549854) (xy 22.323806 -28.549854)
					(xy 22.323806 -34.500058) (xy 8.960358 -34.500058) (xy 8.960358 -28.549854) (xy 6.452108 -28.549854)
				)
			)
		)
		(zone
			(layer "F.Cu")
			(hatch none 0.5)
			(connect_pads
				(clearance 0)
			)
			(min_thickness 0.25)
			(keepout
				(tracks allowed)
				(vias not_allowed)
				(pads allowed)
				(copperpour not_allowed)
				(footprints allowed)
			)
			(placement
				(enabled no)
				(sheetname "")
			)
			(fill
				(thermal_gap 0.5)
				(thermal_bridge_width 0.5)
				(island_removal_mode 0)
			)
			(polygon
				(pts
					(xy 6.452108 -24.99995) (xy 24.832056 -24.99995) (xy 24.832056 -28.549854) (xy 22.323806 -28.549854)
					(xy 22.323806 -34.500058) (xy 8.960358 -34.500058) (xy 8.960358 -28.549854) (xy 6.452108 -28.549854)
				)
			)
		)
		(zone
			(layers "F.Cu" "B.Cu" "In1.Cu" "In2.Cu" "In3.Cu" "In4.Cu" "In5.Cu" "In6.Cu")
			(hatch none 0.5)
			(connect_pads
				(clearance 0)
			)
			(min_thickness 0.25)
			(keepout
				(tracks not_allowed)
				(vias allowed)
				(pads allowed)
				(copperpour not_allowed)
				(footprints allowed)
			)
			(placement
				(enabled no)
				(sheetname "")
			)
			(fill
				(thermal_gap 0.5)
				(thermal_bridge_width 0.5)
				(island_removal_mode 0)
			)
			(polygon
				(pts
					(arc
						(start 12.747498 -38.509956)
						(mid 8.886698 -38.509956)
						(end 12.747498 -38.509956)
					)
				)
			)
		)
		(zone
			(layers "F.Cu" "B.Cu" "In1.Cu" "In2.Cu" "In3.Cu" "In4.Cu" "In5.Cu" "In6.Cu")
			(hatch none 0.5)
			(connect_pads
				(clearance 0)
			)
			(min_thickness 0.25)
			(keepout
				(tracks not_allowed)
				(vias allowed)
				(pads allowed)
				(copperpour not_allowed)
				(footprints allowed)
			)
			(placement
				(enabled no)
				(sheetname "")
			)
			(fill
				(thermal_gap 0.5)
				(thermal_bridge_width 0.5)
				(island_removal_mode 0)
			)
			(polygon
				(pts
					(arc
						(start 22.397466 -38.509956)
						(mid 18.536666 -38.509956)
						(end 22.397466 -38.509956)
					)
				)
			)
		)
	)
	(footprint ""
		(layer "F.Cu")
		(at 276.606 -1.27 90)
		(property "Reference" "R2905"
			(at 0 0 90)
			(layer "F.SilkS")
			(hide yes)
			(effects
				(font
					(size 1.27 1.27)
				)
			)
		)
		(property "Value" "0R2J-2-GP"
			(at 0.064008 -3.993896 90)
			(unlocked yes)
			(layer "F.Fab")
			(hide yes)
			(effects
				(font
					(size 1.016 1.016)
					(thickness 0.1524)
				)
			)
		)
		(property "Device Type" "R402H16"
			(at 0.064008 -5.517896 90)
			(unlocked yes)
			(layer "F.Fab")
			(hide yes)
			(effects
				(font
					(size 1.016 1.016)
					(thickness 0.1524)
				)
			)
		)
		(duplicate_pad_numbers_are_jumpers no)
		(fp_line
			(start 0.508 -0.9398)
			(end -0.508 -0.9398)
			(stroke
				(width 0.1524)
				(type default)
			)
			(layer "F.SilkS")
		)
		(fp_line
			(start -0.508 -0.9398)
			(end -0.508 0.9398)
			(stroke
				(width 0.1524)
				(type default)
			)
			(layer "F.SilkS")
		)
		(fp_rect
			(start -0.508 0.9398)
			(end 0.508 -0.9398)
			(stroke
				(width 0)
				(type default)
			)
			(fill no)
			(layer "F.CrtYd")
		)
		(fp_rect
			(start -0.508 0.9398)
			(end 0.508 -0.9398)
			(stroke
				(width 0)
				(type default)
			)
			(fill no)
			(layer "F.Fab")
		)
		(pad "1" smd custom
			(at 0 -0.4445 90)
			(size 0.1397 0.1397)
			(layers "F.Cu" "F.Mask" "F.Paste")
			(net "BMC_I2C13_MINI7_SDA")
			(options
				(clearance outline)
				(anchor circle)
			)
			(primitives
				(gr_poly
					(pts
						(arc
							(start -0.1778 -0.2794)
							(mid -0.249642 -0.249642)
							(end -0.2794 -0.1778)
						)
						(arc
							(start -0.2794 0.1778)
							(mid -0.249642 0.249642)
							(end -0.1778 0.2794)
						)
						(arc
							(start 0.1778 0.2794)
							(mid 0.249642 0.249642)
							(end 0.2794 0.1778)
						)
						(arc
							(start 0.2794 -0.1778)
							(mid 0.249642 -0.249642)
							(end 0.1778 -0.2794)
						)
					)
					(width 0)
					(fill yes)
				)
			)
		)
		(pad "2" smd custom
			(at 0 0.4445 90)
			(size 0.1397 0.1397)
			(layers "F.Cu" "F.Mask" "F.Paste")
			(net "8644_SDA_R_7")
			(options
				(clearance outline)
				(anchor circle)
			)
			(primitives
				(gr_poly
					(pts
						(arc
							(start -0.1778 -0.2794)
							(mid -0.249642 -0.249642)
							(end -0.2794 -0.1778)
						)
						(arc
							(start -0.2794 0.1778)
							(mid -0.249642 0.249642)
							(end -0.1778 0.2794)
						)
						(arc
							(start 0.1778 0.2794)
							(mid 0.249642 0.249642)
							(end 0.2794 0.1778)
						)
						(arc
							(start 0.2794 -0.1778)
							(mid 0.249642 -0.249642)
							(end 0.1778 -0.2794)
						)
					)
					(width 0)
					(fill yes)
				)
			)
		)
	)
	(footprint ""
		(layer "F.Cu")
		(at 172.593 -53.848 -90)
		(property "Reference" "R558"
			(at 0 0 270)
			(layer "F.SilkS")
			(hide yes)
			(effects
				(font
					(size 1.27 1.27)
				)
			)
		)
		(property "Value" "0R2J-2-GP"
			(at 0.064008 -3.993896 270)
			(unlocked yes)
			(layer "F.Fab")
			(hide yes)
			(effects
				(font
					(size 1.016 1.016)
					(thickness 0.1524)
				)
			)
		)
		(property "Device Type" "R402H16"
			(at 0.064008 -5.517896 270)
			(unlocked yes)
			(layer "F.Fab")
			(hide yes)
			(effects
				(font
					(size 1.016 1.016)
					(thickness 0.1524)
				)
			)
		)
		(duplicate_pad_numbers_are_jumpers no)
		(fp_line
			(start -0.508 -0.9398)
			(end -0.508 0.9398)
			(stroke
				(width 0.1524)
				(type default)
			)
			(layer "F.SilkS")
		)
		(fp_line
			(start 0.508 -0.9398)
			(end -0.508 -0.9398)
			(stroke
				(width 0.1524)
				(type default)
			)
			(layer "F.SilkS")
		)
		(fp_rect
			(start -0.508 0.9398)
			(end 0.508 -0.9398)
			(stroke
				(width 0)
				(type default)
			)
			(fill no)
			(layer "F.CrtYd")
		)
		(fp_rect
			(start -0.508 0.9398)
			(end 0.508 -0.9398)
			(stroke
				(width 0)
				(type default)
			)
			(fill no)
			(layer "F.Fab")
		)
		(pad "1" smd custom
			(at 0 -0.4445 270)
			(size 0.1397 0.1397)
			(layers "F.Cu" "F.Mask" "F.Paste")
			(net "VS2_LED_R")
			(options
				(clearance outline)
				(anchor circle)
			)
			(primitives
				(gr_poly
					(pts
						(arc
							(start -0.1778 -0.2794)
							(mid -0.249642 -0.249642)
							(end -0.2794 -0.1778)
						)
						(arc
							(start -0.2794 0.1778)
							(mid -0.249642 0.249642)
							(end -0.1778 0.2794)
						)
						(arc
							(start 0.1778 0.2794)
							(mid 0.249642 0.249642)
							(end 0.2794 0.1778)
						)
						(arc
							(start 0.2794 -0.1778)
							(mid 0.249642 -0.249642)
							(end 0.1778 -0.2794)
						)
					)
					(width 0)
					(fill yes)
				)
			)
		)
		(pad "2" smd custom
			(at 0 0.4445 270)
			(size 0.1397 0.1397)
			(layers "F.Cu" "F.Mask" "F.Paste")
			(net "VS2_LED")
			(options
				(clearance outline)
				(anchor circle)
			)
			(primitives
				(gr_poly
					(pts
						(arc
							(start -0.1778 -0.2794)
							(mid -0.249642 -0.249642)
							(end -0.2794 -0.1778)
						)
						(arc
							(start -0.2794 0.1778)
							(mid -0.249642 0.249642)
							(end -0.1778 0.2794)
						)
						(arc
							(start 0.1778 0.2794)
							(mid 0.249642 0.249642)
							(end 0.2794 0.1778)
						)
						(arc
							(start 0.2794 -0.1778)
							(mid 0.249642 -0.249642)
							(end 0.1778 -0.2794)
						)
					)
					(width 0)
					(fill yes)
				)
			)
		)
	)
	(footprint ""
		(layer "F.Cu")
		(at 192.9384 -23.0124 -90)
		(property "Reference" "R838"
			(at 0 0 270)
			(layer "F.SilkS")
			(hide yes)
			(effects
				(font
					(size 1.27 1.27)
				)
			)
		)
		(property "Value" "4K7R2F-GP"
			(at 0.064008 -3.993896 270)
			(unlocked yes)
			(layer "F.Fab")
			(hide yes)
			(effects
				(font
					(size 1.016 1.016)
					(thickness 0.1524)
				)
			)
		)
		(property "Device Type" "R402H16"
			(at 0.064008 -5.517896 270)
			(unlocked yes)
			(layer "F.Fab")
			(hide yes)
			(effects
				(font
					(size 1.016 1.016)
					(thickness 0.1524)
				)
			)
		)
		(duplicate_pad_numbers_are_jumpers no)
		(fp_line
			(start -0.508 -0.9398)
			(end -0.508 0.9398)
			(stroke
				(width 0.1524)
				(type default)
			)
			(layer "F.SilkS")
		)
		(fp_line
			(start 0.508 -0.9398)
			(end -0.508 -0.9398)
			(stroke
				(width 0.1524)
				(type default)
			)
			(layer "F.SilkS")
		)
		(fp_rect
			(start -0.508 0.9398)
			(end 0.508 -0.9398)
			(stroke
				(width 0)
				(type default)
			)
			(fill no)
			(layer "F.CrtYd")
		)
		(fp_rect
			(start -0.508 0.9398)
			(end 0.508 -0.9398)
			(stroke
				(width 0)
				(type default)
			)
			(fill no)
			(layer "F.Fab")
		)
		(pad "1" smd custom
			(at 0 -0.4445 270)
			(size 0.1397 0.1397)
			(layers "F.Cu" "F.Mask" "F.Paste")
			(net "U56_A2")
			(options
				(clearance outline)
				(anchor circle)
			)
			(primitives
				(gr_poly
					(pts
						(arc
							(start -0.1778 -0.2794)
							(mid -0.249642 -0.249642)
							(end -0.2794 -0.1778)
						)
						(arc
							(start -0.2794 0.1778)
							(mid -0.249642 0.249642)
							(end -0.1778 0.2794)
						)
						(arc
							(start 0.1778 0.2794)
							(mid 0.249642 0.249642)
							(end 0.2794 0.1778)
						)
						(arc
							(start 0.2794 -0.1778)
							(mid 0.249642 -0.249642)
							(end 0.1778 -0.2794)
						)
					)
					(width 0)
					(fill yes)
				)
			)
		)
		(pad "2" smd custom
			(at 0 0.4445 270)
			(size 0.1397 0.1397)
			(layers "F.Cu" "F.Mask" "F.Paste")
			(net "P3V3_STBY")
			(options
				(clearance outline)
				(anchor circle)
			)
			(primitives
				(gr_poly
					(pts
						(arc
							(start -0.1778 -0.2794)
							(mid -0.249642 -0.249642)
							(end -0.2794 -0.1778)
						)
						(arc
							(start -0.2794 0.1778)
							(mid -0.249642 0.249642)
							(end -0.1778 0.2794)
						)
						(arc
							(start 0.1778 0.2794)
							(mid 0.249642 0.249642)
							(end 0.2794 0.1778)
						)
						(arc
							(start 0.2794 -0.1778)
							(mid 0.249642 -0.249642)
							(end 0.1778 -0.2794)
						)
					)
					(width 0)
					(fill yes)
				)
			)
		)
	)
	(footprint ""
		(layer "F.Cu")
		(at 21.405596 -101.813614)
		(property "Reference" "R2946"
			(at 0 0 0)
			(layer "F.SilkS")
			(hide yes)
			(effects
				(font
					(size 1.27 1.27)
				)
			)
		)
		(property "Value" "10KR2F-2-GP"
			(at 0.064008 -3.993896 0)
			(unlocked yes)
			(layer "F.Fab")
			(hide yes)
			(effects
				(font
					(size 1.016 1.016)
					(thickness 0.1524)
				)
			)
		)
		(property "Device Type" "R402H16"
			(at 0.064008 -5.517896 0)
			(unlocked yes)
			(layer "F.Fab")
			(hide yes)
			(effects
				(font
					(size 1.016 1.016)
					(thickness 0.1524)
				)
			)
		)
		(duplicate_pad_numbers_are_jumpers no)
		(fp_line
			(start -0.508 -0.9398)
			(end -0.508 0.9398)
			(stroke
				(width 0.1524)
				(type default)
			)
			(layer "F.SilkS")
		)
		(fp_line
			(start 0.508 -0.9398)
			(end -0.508 -0.9398)
			(stroke
				(width 0.1524)
				(type default)
			)
			(layer "F.SilkS")
		)
		(fp_rect
			(start -0.508 0.9398)
			(end 0.508 -0.9398)
			(stroke
				(width 0)
				(type default)
			)
			(fill no)
			(layer "F.CrtYd")
		)
		(fp_rect
			(start -0.508 0.9398)
			(end 0.508 -0.9398)
			(stroke
				(width 0)
				(type default)
			)
			(fill no)
			(layer "F.Fab")
		)
		(pad "1" smd custom
			(at 0 -0.4445)
			(size 0.1397 0.1397)
			(layers "F.Cu" "F.Mask" "F.Paste")
			(net "VREF_2V2")
			(options
				(clearance outline)
				(anchor circle)
			)
			(primitives
				(gr_poly
					(pts
						(arc
							(start -0.1778 -0.2794)
							(mid -0.249642 -0.249642)
							(end -0.2794 -0.1778)
						)
						(arc
							(start -0.2794 0.1778)
							(mid -0.249642 0.249642)
							(end -0.1778 0.2794)
						)
						(arc
							(start 0.1778 0.2794)
							(mid 0.249642 0.249642)
							(end 0.2794 0.1778)
						)
						(arc
							(start 0.2794 -0.1778)
							(mid 0.249642 -0.249642)
							(end 0.1778 -0.2794)
						)
					)
					(width 0)
					(fill yes)
				)
			)
		)
		(pad "2" smd custom
			(at 0 0.4445)
			(size 0.1397 0.1397)
			(layers "F.Cu" "F.Mask" "F.Paste")
			(net "GND")
			(options
				(clearance outline)
				(anchor circle)
			)
			(primitives
				(gr_poly
					(pts
						(arc
							(start -0.1778 -0.2794)
							(mid -0.249642 -0.249642)
							(end -0.2794 -0.1778)
						)
						(arc
							(start -0.2794 0.1778)
							(mid -0.249642 0.249642)
							(end -0.1778 0.2794)
						)
						(arc
							(start 0.1778 0.2794)
							(mid 0.249642 0.249642)
							(end 0.2794 0.1778)
						)
						(arc
							(start 0.2794 -0.1778)
							(mid 0.249642 -0.249642)
							(end 0.1778 -0.2794)
						)
					)
					(width 0)
					(fill yes)
				)
			)
		)
	)
	(footprint ""
		(layer "F.Cu")
		(at 69.2658 -126.6952 -90)
		(property "Reference" "U45"
			(at 0 0 270)
			(layer "F.SilkS")
			(hide yes)
			(effects
				(font
					(size 1.27 1.27)
				)
			)
		)
		(property "Value" "SN74AUP1T97DCKR-GP"
			(at -2.3622 -8.2042 270)
			(unlocked yes)
			(layer "F.Fab")
			(hide yes)
			(effects
				(font
					(size 1.016 1.016)
					(thickness 0.1524)
				)
			)
		)
		(property "Device Type" "SC70-6H44"
			(at -2.3622 -10.1092 270)
			(unlocked yes)
			(layer "F.Fab")
			(hide yes)
			(effects
				(font
					(size 1.016 1.016)
					(thickness 0.1524)
				)
			)
		)
		(duplicate_pad_numbers_are_jumpers no)
		(fp_line
			(start -1.5494 1.7907)
			(end -1.5494 0.8255)
			(stroke
				(width 0.3302)
				(type default)
			)
			(layer "F.SilkS")
		)
		(fp_line
			(start -0.5715 1.7907)
			(end -1.5494 1.7907)
			(stroke
				(width 0.3302)
				(type default)
			)
			(layer "F.SilkS")
		)
		(fp_line
			(start -1.4478 1.7018)
			(end 1.4478 1.7018)
			(stroke
				(width 0.1524)
				(type default)
			)
			(layer "F.SilkS")
		)
		(fp_line
			(start 1.4478 1.7018)
			(end 1.4478 -1.7018)
			(stroke
				(width 0.1524)
				(type default)
			)
			(layer "F.SilkS")
		)
		(fp_line
			(start -1.4478 -1.7018)
			(end -1.4478 1.7018)
			(stroke
				(width 0.1524)
				(type default)
			)
			(layer "F.SilkS")
		)
		(fp_line
			(start 1.4478 -1.7018)
			(end -1.4478 -1.7018)
			(stroke
				(width 0.1524)
				(type default)
			)
			(layer "F.SilkS")
		)
		(fp_poly
			(pts
				(xy -0.6604 1.7272) (xy -1.016 2.0828) (xy -0.3048 2.0828)
			)
			(stroke
				(width 0)
				(type default)
			)
			(fill yes)
			(layer "F.SilkS")
		)
		(fp_poly
			(pts
				(xy -1.524 -1.778) (xy 1.524 -1.778) (xy 1.524 1.778) (xy -1.524 1.778)
			)
			(stroke
				(width 0)
				(type default)
			)
			(fill no)
			(layer "F.CrtYd")
		)
		(fp_poly
			(pts
				(xy -1.524 -1.778) (xy 1.524 -1.778) (xy 1.524 1.778) (xy -1.524 1.778)
			)
			(stroke
				(width 0)
				(type default)
			)
			(fill no)
			(layer "F.Fab")
		)
		(pad "1" smd rect
			(at -0.65024 0.9398 270)
			(size 0.4064 1.016)
			(layers "F.Cu" "F.Mask" "F.Paste")
			(net "BMC_TXD5_R")
		)
		(pad "2" smd rect
			(at 0 0.9398 270)
			(size 0.4064 1.016)
			(layers "F.Cu" "F.Mask" "F.Paste")
			(net "GND")
		)
		(pad "3" smd rect
			(at 0.65024 0.9398 270)
			(size 0.4064 1.016)
			(layers "F.Cu" "F.Mask" "F.Paste")
			(net "GND")
		)
		(pad "4" smd rect
			(at 0.65024 -0.9398 270)
			(size 0.4064 1.016)
			(layers "F.Cu" "F.Mask" "F.Paste")
			(net "MBP_UART_TX")
		)
		(pad "5" smd rect
			(at 0 -0.9398 270)
			(size 0.4064 1.016)
			(layers "F.Cu" "F.Mask" "F.Paste")
			(net "P3V3_STBY")
		)
		(pad "6" smd rect
			(at -0.65024 -0.9398 270)
			(size 0.4064 1.016)
			(layers "F.Cu" "F.Mask" "F.Paste")
			(net "GND")
		)
	)
	(footprint ""
		(layer "F.Cu")
		(at 53.594 -134.62 -90)
		(property "Reference" "R338"
			(at 0 0 270)
			(layer "F.SilkS")
			(hide yes)
			(effects
				(font
					(size 1.27 1.27)
				)
			)
		)
		(property "Value" "2K74R3F-GP"
			(at -0.0254 -2.5146 270)
			(unlocked yes)
			(layer "F.Fab")
			(hide yes)
			(effects
				(font
					(size 1.016 1.016)
					(thickness 0.1524)
				)
			)
		)
		(property "Device Type" "R603H22"
			(at -0.0254 -4.0386 270)
			(unlocked yes)
			(layer "F.Fab")
			(hide yes)
			(effects
				(font
					(size 1.016 1.016)
					(thickness 0.1524)
				)
			)
		)
		(duplicate_pad_numbers_are_jumpers no)
		(fp_line
			(start -0.4826 0)
			(end -0.2032 0)
			(stroke
				(width 0.2032)
				(type default)
			)
			(layer "F.SilkS")
		)
		(fp_line
			(start 0.2032 0)
			(end 0.4826 0)
			(stroke
				(width 0.2032)
				(type default)
			)
			(layer "F.SilkS")
		)
		(fp_rect
			(start -0.5842 1.3335)
			(end 0.5842 -1.3335)
			(stroke
				(width 0)
				(type default)
			)
			(fill no)
			(layer "F.CrtYd")
		)
		(fp_rect
			(start -0.5842 1.3335)
			(end 0.5842 -1.3335)
			(stroke
				(width 0)
				(type default)
			)
			(fill no)
			(layer "F.Fab")
		)
		(pad "1" smd custom
			(at 0 -0.762 270)
			(size 0.2159 0.2159)
			(layers "F.Cu" "F.Mask" "F.Paste")
			(net "GND")
			(options
				(clearance outline)
				(anchor circle)
			)
			(primitives
				(gr_poly
					(pts
						(arc
							(start -0.3302 -0.4318)
							(mid -0.402042 -0.402042)
							(end -0.4318 -0.3302)
						)
						(arc
							(start -0.4318 0.3302)
							(mid -0.402042 0.402042)
							(end -0.3302 0.4318)
						)
						(arc
							(start 0.3302 0.4318)
							(mid 0.402042 0.402042)
							(end 0.4318 0.3302)
						)
						(arc
							(start 0.4318 -0.3302)
							(mid 0.402042 -0.402042)
							(end 0.3302 -0.4318)
						)
					)
					(width 0)
					(fill yes)
				)
			)
		)
		(pad "2" smd custom
			(at 0 0.762 270)
			(size 0.2159 0.2159)
			(layers "F.Cu" "F.Mask" "F.Paste")
			(net "DACRSET")
			(options
				(clearance outline)
				(anchor circle)
			)
			(primitives
				(gr_poly
					(pts
						(arc
							(start -0.3302 -0.4318)
							(mid -0.402042 -0.402042)
							(end -0.4318 -0.3302)
						)
						(arc
							(start -0.4318 0.3302)
							(mid -0.402042 0.402042)
							(end -0.3302 0.4318)
						)
						(arc
							(start 0.3302 0.4318)
							(mid 0.402042 0.402042)
							(end 0.4318 0.3302)
						)
						(arc
							(start 0.4318 -0.3302)
							(mid 0.402042 -0.402042)
							(end 0.3302 -0.4318)
						)
					)
					(width 0)
					(fill yes)
				)
			)
		)
	)
	(footprint ""
		(layer "F.Cu")
		(at 262.382 -17.272 180)
		(property "Reference" "R715"
			(at 0 0 180)
			(layer "F.SilkS")
			(hide yes)
			(effects
				(font
					(size 1.27 1.27)
				)
			)
		)
		(property "Value" "4K7R2F-GP"
			(at 0.064008 -3.993896 180)
			(unlocked yes)
			(layer "F.Fab")
			(hide yes)
			(effects
				(font
					(size 1.016 1.016)
					(thickness 0.1524)
				)
			)
		)
		(property "Device Type" "R402H16"
			(at 0.064008 -5.517896 180)
			(unlocked yes)
			(layer "F.Fab")
			(hide yes)
			(effects
				(font
					(size 1.016 1.016)
					(thickness 0.1524)
				)
			)
		)
		(duplicate_pad_numbers_are_jumpers no)
		(fp_line
			(start 0.508 -0.9398)
			(end -0.508 -0.9398)
			(stroke
				(width 0.1524)
				(type default)
			)
			(layer "F.SilkS")
		)
		(fp_line
			(start -0.508 -0.9398)
			(end -0.508 0.9398)
			(stroke
				(width 0.1524)
				(type default)
			)
			(layer "F.SilkS")
		)
		(fp_rect
			(start -0.508 0.9398)
			(end 0.508 -0.9398)
			(stroke
				(width 0)
				(type default)
			)
			(fill no)
			(layer "F.CrtYd")
		)
		(fp_rect
			(start -0.508 0.9398)
			(end 0.508 -0.9398)
			(stroke
				(width 0)
				(type default)
			)
			(fill no)
			(layer "F.Fab")
		)
		(pad "1" smd custom
			(at 0 -0.4445 180)
			(size 0.1397 0.1397)
			(layers "F.Cu" "F.Mask" "F.Paste")
			(net "Q40_D")
			(options
				(clearance outline)
				(anchor circle)
			)
			(primitives
				(gr_poly
					(pts
						(arc
							(start -0.1778 -0.2794)
							(mid -0.249642 -0.249642)
							(end -0.2794 -0.1778)
						)
						(arc
							(start -0.2794 0.1778)
							(mid -0.249642 0.249642)
							(end -0.1778 0.2794)
						)
						(arc
							(start 0.1778 0.2794)
							(mid 0.249642 0.249642)
							(end 0.2794 0.1778)
						)
						(arc
							(start 0.2794 -0.1778)
							(mid 0.249642 -0.249642)
							(end 0.1778 -0.2794)
						)
					)
					(width 0)
					(fill yes)
				)
			)
		)
		(pad "2" smd custom
			(at 0 0.4445 180)
			(size 0.1397 0.1397)
			(layers "F.Cu" "F.Mask" "F.Paste")
			(net "Q3203_G")
			(options
				(clearance outline)
				(anchor circle)
			)
			(primitives
				(gr_poly
					(pts
						(arc
							(start -0.1778 -0.2794)
							(mid -0.249642 -0.249642)
							(end -0.2794 -0.1778)
						)
						(arc
							(start -0.2794 0.1778)
							(mid -0.249642 0.249642)
							(end -0.1778 0.2794)
						)
						(arc
							(start 0.1778 0.2794)
							(mid 0.249642 0.249642)
							(end 0.2794 0.1778)
						)
						(arc
							(start 0.2794 -0.1778)
							(mid 0.249642 -0.249642)
							(end 0.1778 -0.2794)
						)
					)
					(width 0)
					(fill yes)
				)
			)
		)
	)
	(footprint ""
		(layer "F.Cu")
		(at 120.200674 -64.83223 -90)
		(property "Reference" "BAT1"
			(at 0 0 270)
			(layer "F.SilkS")
			(hide yes)
			(effects
				(font
					(size 1.27 1.27)
				)
			)
		)
		(property "Value" "AAA-BAT-043-K03-GP"
			(at -10.2616 -6.7056 270)
			(unlocked yes)
			(layer "F.Fab")
			(hide yes)
			(effects
				(font
					(size 1.016 1.016)
					(thickness 0.1524)
				)
			)
		)
		(property "Device Type" "AAA-BAT-043-K01"
			(at -10.2616 -8.2296 270)
			(unlocked yes)
			(layer "F.Fab")
			(hide yes)
			(effects
				(font
					(size 1.016 1.016)
					(thickness 0.1524)
				)
			)
		)
		(duplicate_pad_numbers_are_jumpers no)
		(fp_line
			(start -5.38099 2.0574)
			(end -4.61899 2.0574)
			(stroke
				(width 0.1524)
				(type default)
			)
			(layer "F.SilkS")
		)
		(fp_line
			(start 4.61899 2.0574)
			(end 5.38099 2.0574)
			(stroke
				(width 0.1524)
				(type default)
			)
			(layer "F.SilkS")
		)
		(fp_line
			(start -4.99999 1.6764)
			(end -4.99999 2.4384)
			(stroke
				(width 0.1524)
				(type default)
			)
			(layer "F.SilkS")
		)
		(fp_line
			(start 4.99999 1.6764)
			(end 4.99999 2.4384)
			(stroke
				(width 0.1524)
				(type default)
			)
			(layer "F.SilkS")
		)
		(fp_line
			(start 10.7569 1.4732)
			(end 12.0269 1.4732)
			(stroke
				(width 0.4064)
				(type default)
			)
			(layer "F.SilkS")
		)
		(fp_line
			(start 12.0269 1.4732)
			(end 12.0269 0.2032)
			(stroke
				(width 0.4064)
				(type default)
			)
			(layer "F.SilkS")
		)
		(fp_line
			(start -11.8999 1.3462)
			(end -11.8999 -4.953)
			(stroke
				(width 0.1524)
				(type default)
			)
			(layer "F.SilkS")
		)
		(fp_line
			(start 11.8999 1.3462)
			(end -11.8999 1.3462)
			(stroke
				(width 0.1524)
				(type default)
			)
			(layer "F.SilkS")
		)
		(fp_line
			(start -11.8999 -4.953)
			(end 11.8999 -4.953)
			(stroke
				(width 0.1524)
				(type default)
			)
			(layer "F.SilkS")
		)
		(fp_line
			(start 11.8999 -4.953)
			(end 11.8999 1.3462)
			(stroke
				(width 0.1524)
				(type default)
			)
			(layer "F.SilkS")
		)
		(fp_line
			(start -0.381 -5.301234)
			(end 0.381 -5.301234)
			(stroke
				(width 0.1524)
				(type default)
			)
			(layer "F.SilkS")
		)
		(fp_circle
			(center -4.99999 0)
			(end -4.99999 -1.0922)
			(stroke
				(width 0.3048)
				(type default)
			)
			(fill no)
			(layer "F.SilkS")
		)
		(fp_circle
			(center 4.99999 0)
			(end 4.99999 -1.0922)
			(stroke
				(width 0.3048)
				(type default)
			)
			(fill no)
			(layer "F.SilkS")
		)
		(fp_circle
			(center 0 -3.599942)
			(end 0 -4.692142)
			(stroke
				(width 0.3048)
				(type default)
			)
			(fill no)
			(layer "F.SilkS")
		)
		(fp_rect
			(start -11.6459 1.0922)
			(end 11.6459 -4.699)
			(stroke
				(width 0)
				(type default)
			)
			(fill no)
			(layer "F.CrtYd")
		)
		(fp_poly
			(pts
				(xy -0.1016 -5.207) (xy -0.1016 -4.699) (xy 11.6459 -4.699) (xy 11.6459 1.0922) (xy -11.6459 1.0922)
				(xy -11.6459 -4.699) (xy -0.1143 -4.699) (xy -0.1143 -5.207) (xy -12.1539 -5.207) (xy -12.1539 1.6002)
				(xy 12.1539 1.6002) (xy 12.1539 -5.207)
			)
			(stroke
				(width 0)
				(type default)
			)
			(fill no)
			(layer "F.CrtYd")
		)
		(fp_rect
			(start -12.1539 1.6002)
			(end 12.1539 -5.207)
			(stroke
				(width 0)
				(type default)
			)
			(fill no)
			(layer "F.Fab")
		)
		(pad "1" thru_hole circle
			(at 4.99999 0 270)
			(size 1.4732 1.4732)
			(drill 1.0668)
			(layers "*.Cu" "*.Mask")
			(remove_unused_layers no)
			(net "P3V0_BAT")
			(clearance 0.1524)
			(thermal_gap 0.1524)
		)
		(pad "2" thru_hole circle
			(at 0 -3.599942 270)
			(size 1.4732 1.4732)
			(drill 1.0668)
			(layers "*.Cu" "*.Mask")
			(remove_unused_layers no)
			(net "GND")
			(clearance 0.1524)
			(thermal_gap 0.1524)
		)
		(pad "3" thru_hole circle
			(at -4.99999 0 270)
			(size 1.4732 1.4732)
			(drill 1.0668)
			(layers "*.Cu" "*.Mask")
			(remove_unused_layers no)
			(net "P3V0_BAT")
			(clearance 0.1524)
			(thermal_gap 0.1524)
		)
	)
	(footprint ""
		(layer "F.Cu")
		(at 335.026 -71.247)
		(property "Reference" "PC187"
			(at 0 0 0)
			(layer "F.SilkS")
			(hide yes)
			(effects
				(font
					(size 1.27 1.27)
				)
			)
		)
		(property "Value" "SC1U10V2KX-1GP"
			(at 1.1811 -2.7051 0)
			(unlocked yes)
			(layer "F.Fab")
			(hide yes)
			(effects
				(font
					(size 1.016 1.016)
					(thickness 0.1524)
				)
			)
		)
		(property "Device Type" "C402H22"
			(at 1.1811 -4.2291 0)
			(unlocked yes)
			(layer "F.Fab")
			(hide yes)
			(effects
				(font
					(size 1.016 1.016)
					(thickness 0.1524)
				)
			)
		)
		(duplicate_pad_numbers_are_jumpers no)
		(fp_rect
			(start -0.4318 0.9525)
			(end 0.4318 -0.9525)
			(stroke
				(width 0)
				(type default)
			)
			(fill no)
			(layer "F.CrtYd")
		)
		(fp_rect
			(start -0.4318 0.9525)
			(end 0.4318 -0.9525)
			(stroke
				(width 0)
				(type default)
			)
			(fill no)
			(layer "F.Fab")
		)
		(pad "1" smd custom
			(at 0 -0.4445)
			(size 0.1524 0.1524)
			(layers "F.Cu" "F.Mask" "F.Paste")
			(net "GND")
			(options
				(clearance outline)
				(anchor circle)
			)
			(primitives
				(gr_poly
					(pts
						(arc
							(start 0.3048 -0.2032)
							(mid 0.275042 -0.275042)
							(end 0.2032 -0.3048)
						)
						(arc
							(start -0.2032 -0.3048)
							(mid -0.275042 -0.275042)
							(end -0.3048 -0.2032)
						)
						(arc
							(start -0.3048 0.2032)
							(mid -0.275042 0.275042)
							(end -0.2032 0.3048)
						)
						(arc
							(start 0.2032 0.3048)
							(mid 0.275042 0.275042)
							(end 0.3048 0.2032)
						)
					)
					(width 0)
					(fill yes)
				)
			)
		)
		(pad "2" smd custom
			(at 0 0.4445)
			(size 0.1524 0.1524)
			(layers "F.Cu" "F.Mask" "F.Paste")
			(net "P0V9_E_EN")
			(options
				(clearance outline)
				(anchor circle)
			)
			(primitives
				(gr_poly
					(pts
						(arc
							(start 0.3048 -0.2032)
							(mid 0.275042 -0.275042)
							(end 0.2032 -0.3048)
						)
						(arc
							(start -0.2032 -0.3048)
							(mid -0.275042 -0.275042)
							(end -0.3048 -0.2032)
						)
						(arc
							(start -0.3048 0.2032)
							(mid -0.275042 0.275042)
							(end -0.2032 0.3048)
						)
						(arc
							(start 0.2032 0.3048)
							(mid 0.275042 0.275042)
							(end 0.3048 0.2032)
						)
					)
					(width 0)
					(fill yes)
				)
			)
		)
	)
	(footprint ""
		(layer "F.Cu")
		(at 36.528502 -81.8769 -90)
		(property "Reference" "R735"
			(at 0 0 270)
			(layer "F.SilkS")
			(hide yes)
			(effects
				(font
					(size 1.27 1.27)
				)
			)
		)
		(property "Value" "10KR2F-2-GP"
			(at 0.064008 -3.993896 270)
			(unlocked yes)
			(layer "F.Fab")
			(hide yes)
			(effects
				(font
					(size 1.016 1.016)
					(thickness 0.1524)
				)
			)
		)
		(property "Device Type" "R402H16"
			(at 0.064008 -5.517896 270)
			(unlocked yes)
			(layer "F.Fab")
			(hide yes)
			(effects
				(font
					(size 1.016 1.016)
					(thickness 0.1524)
				)
			)
		)
		(duplicate_pad_numbers_are_jumpers no)
		(fp_line
			(start -0.508 -0.9398)
			(end -0.508 0.9398)
			(stroke
				(width 0.1524)
				(type default)
			)
			(layer "F.SilkS")
		)
		(fp_line
			(start 0.508 -0.9398)
			(end -0.508 -0.9398)
			(stroke
				(width 0.1524)
				(type default)
			)
			(layer "F.SilkS")
		)
		(fp_rect
			(start -0.508 0.9398)
			(end 0.508 -0.9398)
			(stroke
				(width 0)
				(type default)
			)
			(fill no)
			(layer "F.CrtYd")
		)
		(fp_rect
			(start -0.508 0.9398)
			(end 0.508 -0.9398)
			(stroke
				(width 0)
				(type default)
			)
			(fill no)
			(layer "F.Fab")
		)
		(pad "1" smd custom
			(at 0 -0.4445 270)
			(size 0.1397 0.1397)
			(layers "F.Cu" "F.Mask" "F.Paste")
			(net "Q45_D")
			(options
				(clearance outline)
				(anchor circle)
			)
			(primitives
				(gr_poly
					(pts
						(arc
							(start -0.1778 -0.2794)
							(mid -0.249642 -0.249642)
							(end -0.2794 -0.1778)
						)
						(arc
							(start -0.2794 0.1778)
							(mid -0.249642 0.249642)
							(end -0.1778 0.2794)
						)
						(arc
							(start 0.1778 0.2794)
							(mid 0.249642 0.249642)
							(end 0.2794 0.1778)
						)
						(arc
							(start 0.2794 -0.1778)
							(mid 0.249642 -0.249642)
							(end 0.1778 -0.2794)
						)
					)
					(width 0)
					(fill yes)
				)
			)
		)
		(pad "2" smd custom
			(at 0 0.4445 270)
			(size 0.1397 0.1397)
			(layers "F.Cu" "F.Mask" "F.Paste")
			(net "Q46_G")
			(options
				(clearance outline)
				(anchor circle)
			)
			(primitives
				(gr_poly
					(pts
						(arc
							(start -0.1778 -0.2794)
							(mid -0.249642 -0.249642)
							(end -0.2794 -0.1778)
						)
						(arc
							(start -0.2794 0.1778)
							(mid -0.249642 0.249642)
							(end -0.1778 0.2794)
						)
						(arc
							(start 0.1778 0.2794)
							(mid 0.249642 0.249642)
							(end 0.2794 0.1778)
						)
						(arc
							(start 0.2794 -0.1778)
							(mid 0.249642 -0.249642)
							(end 0.1778 -0.2794)
						)
					)
					(width 0)
					(fill yes)
				)
			)
		)
	)
	(footprint ""
		(layer "F.Cu")
		(at 120.9548 -91.7702)
		(property "Reference" "R863"
			(at 0 0 0)
			(layer "F.SilkS")
			(hide yes)
			(effects
				(font
					(size 1.27 1.27)
				)
			)
		)
		(property "Value" "0R2J-2-GP"
			(at 0.064008 -3.993896 0)
			(unlocked yes)
			(layer "F.Fab")
			(hide yes)
			(effects
				(font
					(size 1.016 1.016)
					(thickness 0.1524)
				)
			)
		)
		(property "Device Type" "R402H16"
			(at 0.064008 -5.517896 0)
			(unlocked yes)
			(layer "F.Fab")
			(hide yes)
			(effects
				(font
					(size 1.016 1.016)
					(thickness 0.1524)
				)
			)
		)
		(duplicate_pad_numbers_are_jumpers no)
		(fp_line
			(start -0.508 -0.9398)
			(end -0.508 0.9398)
			(stroke
				(width 0.1524)
				(type default)
			)
			(layer "F.SilkS")
		)
		(fp_line
			(start 0.508 -0.9398)
			(end -0.508 -0.9398)
			(stroke
				(width 0.1524)
				(type default)
			)
			(layer "F.SilkS")
		)
		(fp_rect
			(start -0.508 0.9398)
			(end 0.508 -0.9398)
			(stroke
				(width 0)
				(type default)
			)
			(fill no)
			(layer "F.CrtYd")
		)
		(fp_rect
			(start -0.508 0.9398)
			(end 0.508 -0.9398)
			(stroke
				(width 0)
				(type default)
			)
			(fill no)
			(layer "F.Fab")
		)
		(pad "1" smd custom
			(at 0 -0.4445)
			(size 0.1397 0.1397)
			(layers "F.Cu" "F.Mask" "F.Paste")
			(net "BMC_I2C10_8536_SDA_R")
			(options
				(clearance outline)
				(anchor circle)
			)
			(primitives
				(gr_poly
					(pts
						(arc
							(start -0.1778 -0.2794)
							(mid -0.249642 -0.249642)
							(end -0.2794 -0.1778)
						)
						(arc
							(start -0.2794 0.1778)
							(mid -0.249642 0.249642)
							(end -0.1778 0.2794)
						)
						(arc
							(start 0.1778 0.2794)
							(mid 0.249642 0.249642)
							(end 0.2794 0.1778)
						)
						(arc
							(start 0.2794 -0.1778)
							(mid 0.249642 -0.249642)
							(end 0.1778 -0.2794)
						)
					)
					(width 0)
					(fill yes)
				)
			)
		)
		(pad "2" smd custom
			(at 0 0.4445)
			(size 0.1397 0.1397)
			(layers "F.Cu" "F.Mask" "F.Paste")
			(net "BMC_I2C10_8536_SDA")
			(options
				(clearance outline)
				(anchor circle)
			)
			(primitives
				(gr_poly
					(pts
						(arc
							(start -0.1778 -0.2794)
							(mid -0.249642 -0.249642)
							(end -0.2794 -0.1778)
						)
						(arc
							(start -0.2794 0.1778)
							(mid -0.249642 0.249642)
							(end -0.1778 0.2794)
						)
						(arc
							(start 0.1778 0.2794)
							(mid 0.249642 0.249642)
							(end 0.2794 0.1778)
						)
						(arc
							(start 0.2794 -0.1778)
							(mid 0.249642 -0.249642)
							(end 0.1778 -0.2794)
						)
					)
					(width 0)
					(fill yes)
				)
			)
		)
	)
	(footprint ""
		(layer "F.Cu")
		(at 185.008266 -212.420454 180)
		(property "Reference" "C126"
			(at 0 0 180)
			(layer "F.SilkS")
			(hide yes)
			(effects
				(font
					(size 1.27 1.27)
				)
			)
		)
		(property "Value" "SCD22U10V2KX-1GP"
			(at 1.1811 -2.7051 180)
			(unlocked yes)
			(layer "F.Fab")
			(hide yes)
			(effects
				(font
					(size 1.016 1.016)
					(thickness 0.1524)
				)
			)
		)
		(property "Device Type" "C402H22"
			(at 1.1811 -4.2291 180)
			(unlocked yes)
			(layer "F.Fab")
			(hide yes)
			(effects
				(font
					(size 1.016 1.016)
					(thickness 0.1524)
				)
			)
		)
		(duplicate_pad_numbers_are_jumpers no)
		(fp_rect
			(start -0.4318 0.9525)
			(end 0.4318 -0.9525)
			(stroke
				(width 0)
				(type default)
			)
			(fill no)
			(layer "F.CrtYd")
		)
		(fp_rect
			(start -0.4318 0.9525)
			(end 0.4318 -0.9525)
			(stroke
				(width 0)
				(type default)
			)
			(fill no)
			(layer "F.Fab")
		)
		(pad "1" smd custom
			(at 0 -0.4445 180)
			(size 0.1524 0.1524)
			(layers "F.Cu" "F.Mask" "F.Paste")
			(net "PCIE_TX_CAP_N47")
			(options
				(clearance outline)
				(anchor circle)
			)
			(primitives
				(gr_poly
					(pts
						(arc
							(start 0.3048 -0.2032)
							(mid 0.275042 -0.275042)
							(end 0.2032 -0.3048)
						)
						(arc
							(start -0.2032 -0.3048)
							(mid -0.275042 -0.275042)
							(end -0.3048 -0.2032)
						)
						(arc
							(start -0.3048 0.2032)
							(mid -0.275042 0.275042)
							(end -0.2032 0.3048)
						)
						(arc
							(start 0.2032 0.3048)
							(mid 0.275042 0.275042)
							(end 0.3048 0.2032)
						)
					)
					(width 0)
					(fill yes)
				)
			)
		)
		(pad "2" smd custom
			(at 0 0.4445 180)
			(size 0.1524 0.1524)
			(layers "F.Cu" "F.Mask" "F.Paste")
			(net "PCIE_TX_N47")
			(options
				(clearance outline)
				(anchor circle)
			)
			(primitives
				(gr_poly
					(pts
						(arc
							(start 0.3048 -0.2032)
							(mid 0.275042 -0.275042)
							(end 0.2032 -0.3048)
						)
						(arc
							(start -0.2032 -0.3048)
							(mid -0.275042 -0.275042)
							(end -0.3048 -0.2032)
						)
						(arc
							(start -0.3048 0.2032)
							(mid -0.275042 0.275042)
							(end -0.2032 0.3048)
						)
						(arc
							(start 0.2032 0.3048)
							(mid 0.275042 0.275042)
							(end 0.3048 0.2032)
						)
					)
					(width 0)
					(fill yes)
				)
			)
		)
	)
	(footprint ""
		(layer "F.Cu")
		(at 34.3535 -112.26546 180)
		(property "Reference" "R507"
			(at 0 0 180)
			(layer "F.SilkS")
			(hide yes)
			(effects
				(font
					(size 1.27 1.27)
				)
			)
		)
		(property "Value" "0R2J-2-GP"
			(at 0.064008 -3.993896 180)
			(unlocked yes)
			(layer "F.Fab")
			(hide yes)
			(effects
				(font
					(size 1.016 1.016)
					(thickness 0.1524)
				)
			)
		)
		(property "Device Type" "R402H16"
			(at 0.064008 -5.517896 180)
			(unlocked yes)
			(layer "F.Fab")
			(hide yes)
			(effects
				(font
					(size 1.016 1.016)
					(thickness 0.1524)
				)
			)
		)
		(duplicate_pad_numbers_are_jumpers no)
		(fp_line
			(start 0.508 -0.9398)
			(end -0.508 -0.9398)
			(stroke
				(width 0.1524)
				(type default)
			)
			(layer "F.SilkS")
		)
		(fp_line
			(start -0.508 -0.9398)
			(end -0.508 0.9398)
			(stroke
				(width 0.1524)
				(type default)
			)
			(layer "F.SilkS")
		)
		(fp_rect
			(start -0.508 0.9398)
			(end 0.508 -0.9398)
			(stroke
				(width 0)
				(type default)
			)
			(fill no)
			(layer "F.CrtYd")
		)
		(fp_rect
			(start -0.508 0.9398)
			(end 0.508 -0.9398)
			(stroke
				(width 0)
				(type default)
			)
			(fill no)
			(layer "F.Fab")
		)
		(pad "1" smd custom
			(at 0 -0.4445 180)
			(size 0.1397 0.1397)
			(layers "F.Cu" "F.Mask" "F.Paste")
			(net "BMC_ADD1")
			(options
				(clearance outline)
				(anchor circle)
			)
			(primitives
				(gr_poly
					(pts
						(arc
							(start -0.1778 -0.2794)
							(mid -0.249642 -0.249642)
							(end -0.2794 -0.1778)
						)
						(arc
							(start -0.2794 0.1778)
							(mid -0.249642 0.249642)
							(end -0.1778 0.2794)
						)
						(arc
							(start 0.1778 0.2794)
							(mid 0.249642 0.249642)
							(end 0.2794 0.1778)
						)
						(arc
							(start 0.2794 -0.1778)
							(mid 0.249642 -0.249642)
							(end 0.1778 -0.2794)
						)
					)
					(width 0)
					(fill yes)
				)
			)
		)
		(pad "2" smd custom
			(at 0 0.4445 180)
			(size 0.1397 0.1397)
			(layers "F.Cu" "F.Mask" "F.Paste")
			(net "BMC_ADD1_R")
			(options
				(clearance outline)
				(anchor circle)
			)
			(primitives
				(gr_poly
					(pts
						(arc
							(start -0.1778 -0.2794)
							(mid -0.249642 -0.249642)
							(end -0.2794 -0.1778)
						)
						(arc
							(start -0.2794 0.1778)
							(mid -0.249642 0.249642)
							(end -0.1778 0.2794)
						)
						(arc
							(start 0.1778 0.2794)
							(mid 0.249642 0.249642)
							(end 0.2794 0.1778)
						)
						(arc
							(start 0.2794 -0.1778)
							(mid 0.249642 -0.249642)
							(end 0.1778 -0.2794)
						)
					)
					(width 0)
					(fill yes)
				)
			)
		)
	)
	(footprint ""
		(layer "F.Cu")
		(at 139.115546 -73.931526 90)
		(property "Reference" "R959"
			(at 0 0 90)
			(layer "F.SilkS")
			(hide yes)
			(effects
				(font
					(size 1.27 1.27)
				)
			)
		)
		(property "Value" "33R2J-2-GP"
			(at 0.064008 -3.993896 90)
			(unlocked yes)
			(layer "F.Fab")
			(hide yes)
			(effects
				(font
					(size 1.016 1.016)
					(thickness 0.1524)
				)
			)
		)
		(property "Device Type" "R402H16"
			(at 0.064008 -5.517896 90)
			(unlocked yes)
			(layer "F.Fab")
			(hide yes)
			(effects
				(font
					(size 1.016 1.016)
					(thickness 0.1524)
				)
			)
		)
		(duplicate_pad_numbers_are_jumpers no)
		(fp_line
			(start 0.508 -0.9398)
			(end -0.508 -0.9398)
			(stroke
				(width 0.1524)
				(type default)
			)
			(layer "F.SilkS")
		)
		(fp_line
			(start -0.508 -0.9398)
			(end -0.508 0.9398)
			(stroke
				(width 0.1524)
				(type default)
			)
			(layer "F.SilkS")
		)
		(fp_rect
			(start -0.508 0.9398)
			(end 0.508 -0.9398)
			(stroke
				(width 0)
				(type default)
			)
			(fill no)
			(layer "F.CrtYd")
		)
		(fp_rect
			(start -0.508 0.9398)
			(end 0.508 -0.9398)
			(stroke
				(width 0)
				(type default)
			)
			(fill no)
			(layer "F.Fab")
		)
		(pad "1" smd custom
			(at 0 -0.4445 90)
			(size 0.1397 0.1397)
			(layers "F.Cu" "F.Mask" "F.Paste")
			(net "SPI_DATA0_0_R")
			(options
				(clearance outline)
				(anchor circle)
			)
			(primitives
				(gr_poly
					(pts
						(arc
							(start -0.1778 -0.2794)
							(mid -0.249642 -0.249642)
							(end -0.2794 -0.1778)
						)
						(arc
							(start -0.2794 0.1778)
							(mid -0.249642 0.249642)
							(end -0.1778 0.2794)
						)
						(arc
							(start 0.1778 0.2794)
							(mid 0.249642 0.249642)
							(end 0.2794 0.1778)
						)
						(arc
							(start 0.2794 -0.1778)
							(mid 0.249642 -0.249642)
							(end 0.1778 -0.2794)
						)
					)
					(width 0)
					(fill yes)
				)
			)
		)
		(pad "2" smd custom
			(at 0 0.4445 90)
			(size 0.1397 0.1397)
			(layers "F.Cu" "F.Mask" "F.Paste")
			(net "SPI_DATA0_0")
			(options
				(clearance outline)
				(anchor circle)
			)
			(primitives
				(gr_poly
					(pts
						(arc
							(start -0.1778 -0.2794)
							(mid -0.249642 -0.249642)
							(end -0.2794 -0.1778)
						)
						(arc
							(start -0.2794 0.1778)
							(mid -0.249642 0.249642)
							(end -0.1778 0.2794)
						)
						(arc
							(start 0.1778 0.2794)
							(mid 0.249642 0.249642)
							(end 0.2794 0.1778)
						)
						(arc
							(start 0.2794 -0.1778)
							(mid 0.249642 -0.249642)
							(end 0.1778 -0.2794)
						)
					)
					(width 0)
					(fill yes)
				)
			)
		)
	)
	(footprint ""
		(layer "F.Cu")
		(at 46.3804 -73.525888 -90)
		(property "Reference" "SC1308"
			(at 0 0 270)
			(layer "F.SilkS")
			(hide yes)
			(effects
				(font
					(size 1.27 1.27)
				)
			)
		)
		(property "Value" "SCD1U16V2KX-3GP"
			(at 1.1811 -2.7051 270)
			(unlocked yes)
			(layer "F.Fab")
			(hide yes)
			(effects
				(font
					(size 1.016 1.016)
					(thickness 0.1524)
				)
			)
		)
		(property "Device Type" "C402H22"
			(at 1.1811 -4.2291 270)
			(unlocked yes)
			(layer "F.Fab")
			(hide yes)
			(effects
				(font
					(size 1.016 1.016)
					(thickness 0.1524)
				)
			)
		)
		(duplicate_pad_numbers_are_jumpers no)
		(fp_rect
			(start -0.4318 0.9525)
			(end 0.4318 -0.9525)
			(stroke
				(width 0)
				(type default)
			)
			(fill no)
			(layer "F.CrtYd")
		)
		(fp_rect
			(start -0.4318 0.9525)
			(end 0.4318 -0.9525)
			(stroke
				(width 0)
				(type default)
			)
			(fill no)
			(layer "F.Fab")
		)
		(pad "1" smd custom
			(at 0 -0.4445 270)
			(size 0.1524 0.1524)
			(layers "F.Cu" "F.Mask" "F.Paste")
			(net "P5V_STBY")
			(options
				(clearance outline)
				(anchor circle)
			)
			(primitives
				(gr_poly
					(pts
						(arc
							(start 0.3048 -0.2032)
							(mid 0.275042 -0.275042)
							(end 0.2032 -0.3048)
						)
						(arc
							(start -0.2032 -0.3048)
							(mid -0.275042 -0.275042)
							(end -0.3048 -0.2032)
						)
						(arc
							(start -0.3048 0.2032)
							(mid -0.275042 0.275042)
							(end -0.2032 0.3048)
						)
						(arc
							(start 0.2032 0.3048)
							(mid 0.275042 0.275042)
							(end 0.3048 0.2032)
						)
					)
					(width 0)
					(fill yes)
				)
			)
		)
		(pad "2" smd custom
			(at 0 0.4445 270)
			(size 0.1524 0.1524)
			(layers "F.Cu" "F.Mask" "F.Paste")
			(net "GND")
			(options
				(clearance outline)
				(anchor circle)
			)
			(primitives
				(gr_poly
					(pts
						(arc
							(start 0.3048 -0.2032)
							(mid 0.275042 -0.275042)
							(end 0.2032 -0.3048)
						)
						(arc
							(start -0.2032 -0.3048)
							(mid -0.275042 -0.275042)
							(end -0.3048 -0.2032)
						)
						(arc
							(start -0.3048 0.2032)
							(mid -0.275042 0.275042)
							(end -0.2032 0.3048)
						)
						(arc
							(start 0.2032 0.3048)
							(mid 0.275042 0.275042)
							(end 0.3048 0.2032)
						)
					)
					(width 0)
					(fill yes)
				)
			)
		)
	)
	(footprint ""
		(layer "F.Cu")
		(at 53.1876 -114.7572)
		(property "Reference" "R542"
			(at 0 0 0)
			(layer "F.SilkS")
			(hide yes)
			(effects
				(font
					(size 1.27 1.27)
				)
			)
		)
		(property "Value" "0R2J-2-GP"
			(at 0.064008 -3.993896 0)
			(unlocked yes)
			(layer "F.Fab")
			(hide yes)
			(effects
				(font
					(size 1.016 1.016)
					(thickness 0.1524)
				)
			)
		)
		(property "Device Type" "R402H16"
			(at 0.064008 -5.517896 0)
			(unlocked yes)
			(layer "F.Fab")
			(hide yes)
			(effects
				(font
					(size 1.016 1.016)
					(thickness 0.1524)
				)
			)
		)
		(duplicate_pad_numbers_are_jumpers no)
		(fp_line
			(start -0.508 -0.9398)
			(end -0.508 0.9398)
			(stroke
				(width 0.1524)
				(type default)
			)
			(layer "F.SilkS")
		)
		(fp_line
			(start 0.508 -0.9398)
			(end -0.508 -0.9398)
			(stroke
				(width 0.1524)
				(type default)
			)
			(layer "F.SilkS")
		)
		(fp_rect
			(start -0.508 0.9398)
			(end 0.508 -0.9398)
			(stroke
				(width 0)
				(type default)
			)
			(fill no)
			(layer "F.CrtYd")
		)
		(fp_rect
			(start -0.508 0.9398)
			(end 0.508 -0.9398)
			(stroke
				(width 0)
				(type default)
			)
			(fill no)
			(layer "F.Fab")
		)
		(pad "1" smd custom
			(at 0 -0.4445)
			(size 0.1397 0.1397)
			(layers "F.Cu" "F.Mask" "F.Paste")
			(net "BMC0_SDA13_R")
			(options
				(clearance outline)
				(anchor circle)
			)
			(primitives
				(gr_poly
					(pts
						(arc
							(start -0.1778 -0.2794)
							(mid -0.249642 -0.249642)
							(end -0.2794 -0.1778)
						)
						(arc
							(start -0.2794 0.1778)
							(mid -0.249642 0.249642)
							(end -0.1778 0.2794)
						)
						(arc
							(start 0.1778 0.2794)
							(mid 0.249642 0.249642)
							(end 0.2794 0.1778)
						)
						(arc
							(start 0.2794 -0.1778)
							(mid 0.249642 -0.249642)
							(end 0.1778 -0.2794)
						)
					)
					(width 0)
					(fill yes)
				)
			)
		)
		(pad "2" smd custom
			(at 0 0.4445)
			(size 0.1397 0.1397)
			(layers "F.Cu" "F.Mask" "F.Paste")
			(net "BMC_I2C13_MINI7_SDA_S")
			(options
				(clearance outline)
				(anchor circle)
			)
			(primitives
				(gr_poly
					(pts
						(arc
							(start -0.1778 -0.2794)
							(mid -0.249642 -0.249642)
							(end -0.2794 -0.1778)
						)
						(arc
							(start -0.2794 0.1778)
							(mid -0.249642 0.249642)
							(end -0.1778 0.2794)
						)
						(arc
							(start 0.1778 0.2794)
							(mid 0.249642 0.249642)
							(end 0.2794 0.1778)
						)
						(arc
							(start 0.2794 -0.1778)
							(mid 0.249642 -0.249642)
							(end 0.1778 -0.2794)
						)
					)
					(width 0)
					(fill yes)
				)
			)
		)
	)
	(footprint ""
		(layer "F.Cu")
		(at 66.1924 -120.5992 180)
		(property "Reference" "R26"
			(at 0 0 180)
			(layer "F.SilkS")
			(hide yes)
			(effects
				(font
					(size 1.27 1.27)
				)
			)
		)
		(property "Value" "0R2J-2-GP"
			(at 0.064008 -3.993896 180)
			(unlocked yes)
			(layer "F.Fab")
			(hide yes)
			(effects
				(font
					(size 1.016 1.016)
					(thickness 0.1524)
				)
			)
		)
		(property "Device Type" "R402H16"
			(at 0.064008 -5.517896 180)
			(unlocked yes)
			(layer "F.Fab")
			(hide yes)
			(effects
				(font
					(size 1.016 1.016)
					(thickness 0.1524)
				)
			)
		)
		(duplicate_pad_numbers_are_jumpers no)
		(fp_line
			(start 0.508 -0.9398)
			(end -0.508 -0.9398)
			(stroke
				(width 0.1524)
				(type default)
			)
			(layer "F.SilkS")
		)
		(fp_line
			(start -0.508 -0.9398)
			(end -0.508 0.9398)
			(stroke
				(width 0.1524)
				(type default)
			)
			(layer "F.SilkS")
		)
		(fp_rect
			(start -0.508 0.9398)
			(end 0.508 -0.9398)
			(stroke
				(width 0)
				(type default)
			)
			(fill no)
			(layer "F.CrtYd")
		)
		(fp_rect
			(start -0.508 0.9398)
			(end 0.508 -0.9398)
			(stroke
				(width 0)
				(type default)
			)
			(fill no)
			(layer "F.Fab")
		)
		(pad "1" smd custom
			(at 0 -0.4445 180)
			(size 0.1397 0.1397)
			(layers "F.Cu" "F.Mask" "F.Paste")
			(net "BMC_I2C4_MINI4_SCL_S")
			(options
				(clearance outline)
				(anchor circle)
			)
			(primitives
				(gr_poly
					(pts
						(arc
							(start -0.1778 -0.2794)
							(mid -0.249642 -0.249642)
							(end -0.2794 -0.1778)
						)
						(arc
							(start -0.2794 0.1778)
							(mid -0.249642 0.249642)
							(end -0.1778 0.2794)
						)
						(arc
							(start 0.1778 0.2794)
							(mid 0.249642 0.249642)
							(end 0.2794 0.1778)
						)
						(arc
							(start 0.2794 -0.1778)
							(mid 0.249642 -0.249642)
							(end 0.1778 -0.2794)
						)
					)
					(width 0)
					(fill yes)
				)
			)
		)
		(pad "2" smd custom
			(at 0 0.4445 180)
			(size 0.1397 0.1397)
			(layers "F.Cu" "F.Mask" "F.Paste")
			(net "BMC_I2C4_MINI4_SCL")
			(options
				(clearance outline)
				(anchor circle)
			)
			(primitives
				(gr_poly
					(pts
						(arc
							(start -0.1778 -0.2794)
							(mid -0.249642 -0.249642)
							(end -0.2794 -0.1778)
						)
						(arc
							(start -0.2794 0.1778)
							(mid -0.249642 0.249642)
							(end -0.1778 0.2794)
						)
						(arc
							(start 0.1778 0.2794)
							(mid 0.249642 0.249642)
							(end 0.2794 0.1778)
						)
						(arc
							(start 0.2794 -0.1778)
							(mid 0.249642 -0.249642)
							(end 0.1778 -0.2794)
						)
					)
					(width 0)
					(fill yes)
				)
			)
		)
	)
	(footprint ""
		(layer "F.Cu")
		(at 23.867872 -95.239078)
		(property "Reference" "Q36"
			(at 0 0 0)
			(layer "F.SilkS")
			(hide yes)
			(effects
				(font
					(size 1.27 1.27)
				)
			)
		)
		(property "Value" "TMBT3904-GP"
			(at 0.10287 -10.29843 0)
			(unlocked yes)
			(layer "F.Fab")
			(hide yes)
			(effects
				(font
					(size 1.016 1.016)
					(thickness 0.1524)
				)
			)
		)
		(property "Device Type" "SOT23CBE2D4H44"
			(at 0.10287 -12.20343 0)
			(unlocked yes)
			(layer "F.Fab")
			(hide yes)
			(effects
				(font
					(size 1.016 1.016)
					(thickness 0.1524)
				)
			)
		)
		(duplicate_pad_numbers_are_jumpers no)
		(fp_line
			(start -1.651 -1.778)
			(end -1.651 1.778)
			(stroke
				(width 0.1524)
				(type default)
			)
			(layer "F.SilkS")
		)
		(fp_line
			(start -1.651 1.778)
			(end 1.651 1.778)
			(stroke
				(width 0.1524)
				(type default)
			)
			(layer "F.SilkS")
		)
		(fp_line
			(start 1.651 -1.778)
			(end -1.651 -1.778)
			(stroke
				(width 0.1524)
				(type default)
			)
			(layer "F.SilkS")
		)
		(fp_line
			(start 1.651 1.778)
			(end 1.651 -1.778)
			(stroke
				(width 0.1524)
				(type default)
			)
			(layer "F.SilkS")
		)
		(fp_poly
			(pts
				(xy -1.778 1.8796) (xy -1.778 -1.8796) (xy 1.778 -1.8796) (xy 1.778 1.8796)
			)
			(stroke
				(width 0)
				(type default)
			)
			(fill no)
			(layer "F.CrtYd")
		)
		(fp_poly
			(pts
				(xy -1.778 1.8796) (xy -1.778 -1.8796) (xy 1.778 -1.8796) (xy 1.778 1.8796)
			)
			(stroke
				(width 0)
				(type default)
			)
			(fill no)
			(layer "F.Fab")
		)
		(pad "B" smd custom
			(at -0.98425 0.9525)
			(size 0.1905 0.1905)
			(layers "F.Cu" "F.Mask" "F.Paste")
			(net "FM_TPM_PRES_RST_N_R")
			(options
				(clearance outline)
				(anchor circle)
			)
			(primitives
				(gr_poly
					(pts
						(arc
							(start -0.1778 0.5715)
							(mid -0.321484 0.511984)
							(end -0.381 0.3683)
						)
						(arc
							(start -0.381 -0.3683)
							(mid -0.321484 -0.511984)
							(end -0.1778 -0.5715)
						)
						(arc
							(start 0.1778 -0.5715)
							(mid 0.321484 -0.511984)
							(end 0.381 -0.3683)
						)
						(arc
							(start 0.381 0.3683)
							(mid 0.321484 0.511984)
							(end 0.1778 0.5715)
						)
					)
					(width 0)
					(fill yes)
				)
			)
		)
		(pad "C" smd custom
			(at 0 -0.9525)
			(size 0.1905 0.1905)
			(layers "F.Cu" "F.Mask" "F.Paste")
			(net "FM_TPM_PRES_RST")
			(options
				(clearance outline)
				(anchor circle)
			)
			(primitives
				(gr_poly
					(pts
						(arc
							(start -0.1778 0.5715)
							(mid -0.321484 0.511984)
							(end -0.381 0.3683)
						)
						(arc
							(start -0.381 -0.3683)
							(mid -0.321484 -0.511984)
							(end -0.1778 -0.5715)
						)
						(arc
							(start 0.1778 -0.5715)
							(mid 0.321484 -0.511984)
							(end 0.381 -0.3683)
						)
						(arc
							(start 0.381 0.3683)
							(mid 0.321484 0.511984)
							(end 0.1778 0.5715)
						)
					)
					(width 0)
					(fill yes)
				)
			)
		)
		(pad "E" smd custom
			(at 0.98425 0.9525)
			(size 0.1905 0.1905)
			(layers "F.Cu" "F.Mask" "F.Paste")
			(net "GND")
			(options
				(clearance outline)
				(anchor circle)
			)
			(primitives
				(gr_poly
					(pts
						(arc
							(start -0.1778 0.5715)
							(mid -0.321484 0.511984)
							(end -0.381 0.3683)
						)
						(arc
							(start -0.381 -0.3683)
							(mid -0.321484 -0.511984)
							(end -0.1778 -0.5715)
						)
						(arc
							(start 0.1778 -0.5715)
							(mid 0.321484 -0.511984)
							(end 0.381 -0.3683)
						)
						(arc
							(start 0.381 0.3683)
							(mid 0.321484 0.511984)
							(end 0.1778 0.5715)
						)
					)
					(width 0)
					(fill yes)
				)
			)
		)
	)
	(footprint ""
		(layer "F.Cu")
		(at 10.9982 -180.6956)
		(property "Reference" "R2102"
			(at 0 0 0)
			(layer "F.SilkS")
			(hide yes)
			(effects
				(font
					(size 1.27 1.27)
				)
			)
		)
		(property "Value" "26K1R2F-2-GP"
			(at 0.064008 -3.993896 0)
			(unlocked yes)
			(layer "F.Fab")
			(hide yes)
			(effects
				(font
					(size 1.016 1.016)
					(thickness 0.1524)
				)
			)
		)
		(property "Device Type" "R402H16"
			(at 0.064008 -5.517896 0)
			(unlocked yes)
			(layer "F.Fab")
			(hide yes)
			(effects
				(font
					(size 1.016 1.016)
					(thickness 0.1524)
				)
			)
		)
		(duplicate_pad_numbers_are_jumpers no)
		(fp_line
			(start -0.508 -0.9398)
			(end -0.508 0.9398)
			(stroke
				(width 0.1524)
				(type default)
			)
			(layer "F.SilkS")
		)
		(fp_line
			(start 0.508 -0.9398)
			(end -0.508 -0.9398)
			(stroke
				(width 0.1524)
				(type default)
			)
			(layer "F.SilkS")
		)
		(fp_rect
			(start -0.508 0.9398)
			(end 0.508 -0.9398)
			(stroke
				(width 0)
				(type default)
			)
			(fill no)
			(layer "F.CrtYd")
		)
		(fp_rect
			(start -0.508 0.9398)
			(end 0.508 -0.9398)
			(stroke
				(width 0)
				(type default)
			)
			(fill no)
			(layer "F.Fab")
		)
		(pad "1" smd custom
			(at 0 -0.4445)
			(size 0.1397 0.1397)
			(layers "F.Cu" "F.Mask" "F.Paste")
			(net "MB0_P12V_PWRGOOD")
			(options
				(clearance outline)
				(anchor circle)
			)
			(primitives
				(gr_poly
					(pts
						(arc
							(start -0.1778 -0.2794)
							(mid -0.249642 -0.249642)
							(end -0.2794 -0.1778)
						)
						(arc
							(start -0.2794 0.1778)
							(mid -0.249642 0.249642)
							(end -0.1778 0.2794)
						)
						(arc
							(start 0.1778 0.2794)
							(mid 0.249642 0.249642)
							(end 0.2794 0.1778)
						)
						(arc
							(start 0.2794 -0.1778)
							(mid 0.249642 -0.249642)
							(end 0.1778 -0.2794)
						)
					)
					(width 0)
					(fill yes)
				)
			)
		)
		(pad "2" smd custom
			(at 0 0.4445)
			(size 0.1397 0.1397)
			(layers "F.Cu" "F.Mask" "F.Paste")
			(net "AGND_CURRENT_MON")
			(options
				(clearance outline)
				(anchor circle)
			)
			(primitives
				(gr_poly
					(pts
						(arc
							(start -0.1778 -0.2794)
							(mid -0.249642 -0.249642)
							(end -0.2794 -0.1778)
						)
						(arc
							(start -0.2794 0.1778)
							(mid -0.249642 0.249642)
							(end -0.1778 0.2794)
						)
						(arc
							(start 0.1778 0.2794)
							(mid 0.249642 0.249642)
							(end 0.2794 0.1778)
						)
						(arc
							(start 0.2794 -0.1778)
							(mid 0.249642 -0.249642)
							(end 0.1778 -0.2794)
						)
					)
					(width 0)
					(fill yes)
				)
			)
		)
	)
	(footprint ""
		(layer "F.Cu")
		(at 176.723802 -71.071232 -90)
		(property "Reference" "PG30"
			(at 0 0 270)
			(layer "F.SilkS")
			(hide yes)
			(effects
				(font
					(size 1.27 1.27)
				)
			)
		)
		(property "Value" "GAP-CLOSE-PWR-3-GP"
			(at 0.0254 -6.5786 270)
			(unlocked yes)
			(layer "F.Fab")
			(hide yes)
			(effects
				(font
					(size 1.016 1.016)
					(thickness 0.1524)
				)
			)
		)
		(property "Device Type" "GAP-CLOSE-PWR-3"
			(at 0.0254 -8.255 270)
			(unlocked yes)
			(layer "F.Fab")
			(hide yes)
			(effects
				(font
					(size 1.016 1.016)
					(thickness 0.1524)
				)
			)
		)
		(duplicate_pad_numbers_are_jumpers no)
		(fp_rect
			(start -0.7112 0.4572)
			(end 0.7112 -0.4572)
			(stroke
				(width 0)
				(type default)
			)
			(fill no)
			(layer "F.CrtYd")
		)
		(fp_poly
			(pts
				(xy -0.7112 -0.4572) (xy 0.7112 -0.4572) (xy 0.7112 0.4572) (xy -0.7112 0.4572)
			)
			(stroke
				(width 0)
				(type default)
			)
			(fill no)
			(layer "F.Fab")
		)
		(pad "1" smd rect
			(at -0.3048 0 270)
			(size 0.6604 0.762)
			(layers "F.Cu" "F.Mask" "F.Paste")
			(net "DUT_AVD_TX")
		)
		(pad "2" smd rect
			(at 0.3048 0 270)
			(size 0.6604 0.762)
			(layers "F.Cu" "F.Mask" "F.Paste")
			(net "P0V9")
		)
	)
	(footprint ""
		(layer "F.Cu")
		(at 53.721 -123.444 -90)
		(property "Reference" "R802"
			(at 0 0 270)
			(layer "F.SilkS")
			(hide yes)
			(effects
				(font
					(size 1.27 1.27)
				)
			)
		)
		(property "Value" "4K7R2F-GP"
			(at 0.064008 -3.993896 270)
			(unlocked yes)
			(layer "F.Fab")
			(hide yes)
			(effects
				(font
					(size 1.016 1.016)
					(thickness 0.1524)
				)
			)
		)
		(property "Device Type" "R402H16"
			(at 0.064008 -5.517896 270)
			(unlocked yes)
			(layer "F.Fab")
			(hide yes)
			(effects
				(font
					(size 1.016 1.016)
					(thickness 0.1524)
				)
			)
		)
		(duplicate_pad_numbers_are_jumpers no)
		(fp_line
			(start -0.508 -0.9398)
			(end -0.508 0.9398)
			(stroke
				(width 0.1524)
				(type default)
			)
			(layer "F.SilkS")
		)
		(fp_line
			(start 0.508 -0.9398)
			(end -0.508 -0.9398)
			(stroke
				(width 0.1524)
				(type default)
			)
			(layer "F.SilkS")
		)
		(fp_rect
			(start -0.508 0.9398)
			(end 0.508 -0.9398)
			(stroke
				(width 0)
				(type default)
			)
			(fill no)
			(layer "F.CrtYd")
		)
		(fp_rect
			(start -0.508 0.9398)
			(end 0.508 -0.9398)
			(stroke
				(width 0)
				(type default)
			)
			(fill no)
			(layer "F.Fab")
		)
		(pad "1" smd custom
			(at 0 -0.4445 270)
			(size 0.1397 0.1397)
			(layers "F.Cu" "F.Mask" "F.Paste")
			(net "P3V3_STBY")
			(options
				(clearance outline)
				(anchor circle)
			)
			(primitives
				(gr_poly
					(pts
						(arc
							(start -0.1778 -0.2794)
							(mid -0.249642 -0.249642)
							(end -0.2794 -0.1778)
						)
						(arc
							(start -0.2794 0.1778)
							(mid -0.249642 0.249642)
							(end -0.1778 0.2794)
						)
						(arc
							(start 0.1778 0.2794)
							(mid 0.249642 0.249642)
							(end 0.2794 0.1778)
						)
						(arc
							(start 0.2794 -0.1778)
							(mid 0.249642 -0.249642)
							(end 0.1778 -0.2794)
						)
					)
					(width 0)
					(fill yes)
				)
			)
		)
		(pad "2" smd custom
			(at 0 0.4445 270)
			(size 0.1397 0.1397)
			(layers "F.Cu" "F.Mask" "F.Paste")
			(net "JTAG_BMC_TDI")
			(options
				(clearance outline)
				(anchor circle)
			)
			(primitives
				(gr_poly
					(pts
						(arc
							(start -0.1778 -0.2794)
							(mid -0.249642 -0.249642)
							(end -0.2794 -0.1778)
						)
						(arc
							(start -0.2794 0.1778)
							(mid -0.249642 0.249642)
							(end -0.1778 0.2794)
						)
						(arc
							(start 0.1778 0.2794)
							(mid 0.249642 0.249642)
							(end 0.2794 0.1778)
						)
						(arc
							(start 0.2794 -0.1778)
							(mid 0.249642 -0.249642)
							(end 0.1778 -0.2794)
						)
					)
					(width 0)
					(fill yes)
				)
			)
		)
	)
	(footprint ""
		(layer "F.Cu")
		(at 212.594444 -40.19296 -90)
		(property "Reference" "C641"
			(at 0 0 270)
			(layer "F.SilkS")
			(hide yes)
			(effects
				(font
					(size 1.27 1.27)
				)
			)
		)
		(property "Value" "SCD22U10V2KX-1GP"
			(at 1.1811 -2.7051 270)
			(unlocked yes)
			(layer "F.Fab")
			(hide yes)
			(effects
				(font
					(size 1.016 1.016)
					(thickness 0.1524)
				)
			)
		)
		(property "Device Type" "C402H22"
			(at 1.1811 -4.2291 270)
			(unlocked yes)
			(layer "F.Fab")
			(hide yes)
			(effects
				(font
					(size 1.016 1.016)
					(thickness 0.1524)
				)
			)
		)
		(duplicate_pad_numbers_are_jumpers no)
		(fp_rect
			(start -0.4318 0.9525)
			(end 0.4318 -0.9525)
			(stroke
				(width 0)
				(type default)
			)
			(fill no)
			(layer "F.CrtYd")
		)
		(fp_rect
			(start -0.4318 0.9525)
			(end 0.4318 -0.9525)
			(stroke
				(width 0)
				(type default)
			)
			(fill no)
			(layer "F.Fab")
		)
		(pad "1" smd custom
			(at 0 -0.4445 270)
			(size 0.1524 0.1524)
			(layers "F.Cu" "F.Mask" "F.Paste")
			(net "PCIE_TX_CAP_P78")
			(options
				(clearance outline)
				(anchor circle)
			)
			(primitives
				(gr_poly
					(pts
						(arc
							(start 0.3048 -0.2032)
							(mid 0.275042 -0.275042)
							(end 0.2032 -0.3048)
						)
						(arc
							(start -0.2032 -0.3048)
							(mid -0.275042 -0.275042)
							(end -0.3048 -0.2032)
						)
						(arc
							(start -0.3048 0.2032)
							(mid -0.275042 0.275042)
							(end -0.2032 0.3048)
						)
						(arc
							(start 0.2032 0.3048)
							(mid 0.275042 0.275042)
							(end 0.3048 0.2032)
						)
					)
					(width 0)
					(fill yes)
				)
			)
		)
		(pad "2" smd custom
			(at 0 0.4445 270)
			(size 0.1524 0.1524)
			(layers "F.Cu" "F.Mask" "F.Paste")
			(net "PCIE_TX_P78")
			(options
				(clearance outline)
				(anchor circle)
			)
			(primitives
				(gr_poly
					(pts
						(arc
							(start 0.3048 -0.2032)
							(mid 0.275042 -0.275042)
							(end 0.2032 -0.3048)
						)
						(arc
							(start -0.2032 -0.3048)
							(mid -0.275042 -0.275042)
							(end -0.3048 -0.2032)
						)
						(arc
							(start -0.3048 0.2032)
							(mid -0.275042 0.275042)
							(end -0.2032 0.3048)
						)
						(arc
							(start 0.2032 0.3048)
							(mid 0.275042 0.275042)
							(end 0.3048 0.2032)
						)
					)
					(width 0)
					(fill yes)
				)
			)
		)
	)
	(footprint ""
		(layer "F.Cu")
		(at 135.358124 -208.889092 180)
		(property "Reference" "R7926"
			(at 0 0 180)
			(layer "F.SilkS")
			(hide yes)
			(effects
				(font
					(size 1.27 1.27)
				)
			)
		)
		(property "Value" "0R2J-2-GP"
			(at 0.064008 -3.993896 180)
			(unlocked yes)
			(layer "F.Fab")
			(hide yes)
			(effects
				(font
					(size 1.016 1.016)
					(thickness 0.1524)
				)
			)
		)
		(property "Device Type" "R402H16"
			(at 0.064008 -5.517896 180)
			(unlocked yes)
			(layer "F.Fab")
			(hide yes)
			(effects
				(font
					(size 1.016 1.016)
					(thickness 0.1524)
				)
			)
		)
		(duplicate_pad_numbers_are_jumpers no)
		(fp_line
			(start 0.508 -0.9398)
			(end -0.508 -0.9398)
			(stroke
				(width 0.1524)
				(type default)
			)
			(layer "F.SilkS")
		)
		(fp_line
			(start -0.508 -0.9398)
			(end -0.508 0.9398)
			(stroke
				(width 0.1524)
				(type default)
			)
			(layer "F.SilkS")
		)
		(fp_rect
			(start -0.508 0.9398)
			(end 0.508 -0.9398)
			(stroke
				(width 0)
				(type default)
			)
			(fill no)
			(layer "F.CrtYd")
		)
		(fp_rect
			(start -0.508 0.9398)
			(end 0.508 -0.9398)
			(stroke
				(width 0)
				(type default)
			)
			(fill no)
			(layer "F.Fab")
		)
		(pad "1" smd custom
			(at 0 -0.4445 180)
			(size 0.1397 0.1397)
			(layers "F.Cu" "F.Mask" "F.Paste")
			(net "SSD_PRSNT#6")
			(options
				(clearance outline)
				(anchor circle)
			)
			(primitives
				(gr_poly
					(pts
						(arc
							(start -0.1778 -0.2794)
							(mid -0.249642 -0.249642)
							(end -0.2794 -0.1778)
						)
						(arc
							(start -0.2794 0.1778)
							(mid -0.249642 0.249642)
							(end -0.1778 0.2794)
						)
						(arc
							(start 0.1778 0.2794)
							(mid 0.249642 0.249642)
							(end 0.2794 0.1778)
						)
						(arc
							(start 0.2794 -0.1778)
							(mid 0.249642 -0.249642)
							(end 0.1778 -0.2794)
						)
					)
					(width 0)
					(fill yes)
				)
			)
		)
		(pad "2" smd custom
			(at 0 0.4445 180)
			(size 0.1397 0.1397)
			(layers "F.Cu" "F.Mask" "F.Paste")
			(net "SSD_PRSNT#6_R")
			(options
				(clearance outline)
				(anchor circle)
			)
			(primitives
				(gr_poly
					(pts
						(arc
							(start -0.1778 -0.2794)
							(mid -0.249642 -0.249642)
							(end -0.2794 -0.1778)
						)
						(arc
							(start -0.2794 0.1778)
							(mid -0.249642 0.249642)
							(end -0.1778 0.2794)
						)
						(arc
							(start 0.1778 0.2794)
							(mid 0.249642 0.249642)
							(end 0.2794 0.1778)
						)
						(arc
							(start 0.2794 -0.1778)
							(mid 0.249642 -0.249642)
							(end 0.1778 -0.2794)
						)
					)
					(width 0)
					(fill yes)
				)
			)
		)
	)
	(footprint ""
		(layer "F.Cu")
		(at 142.23238 -34.774886 -90)
		(property "Reference" "R214"
			(at 0 0 270)
			(layer "F.SilkS")
			(hide yes)
			(effects
				(font
					(size 1.27 1.27)
				)
			)
		)
		(property "Value" "4K7R2F-GP"
			(at 0.064008 -3.993896 270)
			(unlocked yes)
			(layer "F.Fab")
			(hide yes)
			(effects
				(font
					(size 1.016 1.016)
					(thickness 0.1524)
				)
			)
		)
		(property "Device Type" "R402H16"
			(at 0.064008 -5.517896 270)
			(unlocked yes)
			(layer "F.Fab")
			(hide yes)
			(effects
				(font
					(size 1.016 1.016)
					(thickness 0.1524)
				)
			)
		)
		(duplicate_pad_numbers_are_jumpers no)
		(fp_line
			(start -0.508 -0.9398)
			(end -0.508 0.9398)
			(stroke
				(width 0.1524)
				(type default)
			)
			(layer "F.SilkS")
		)
		(fp_line
			(start 0.508 -0.9398)
			(end -0.508 -0.9398)
			(stroke
				(width 0.1524)
				(type default)
			)
			(layer "F.SilkS")
		)
		(fp_rect
			(start -0.508 0.9398)
			(end 0.508 -0.9398)
			(stroke
				(width 0)
				(type default)
			)
			(fill no)
			(layer "F.CrtYd")
		)
		(fp_rect
			(start -0.508 0.9398)
			(end 0.508 -0.9398)
			(stroke
				(width 0)
				(type default)
			)
			(fill no)
			(layer "F.Fab")
		)
		(pad "1" smd custom
			(at 0 -0.4445 270)
			(size 0.1397 0.1397)
			(layers "F.Cu" "F.Mask" "F.Paste")
			(net "P3V3_STBY")
			(options
				(clearance outline)
				(anchor circle)
			)
			(primitives
				(gr_poly
					(pts
						(arc
							(start -0.1778 -0.2794)
							(mid -0.249642 -0.249642)
							(end -0.2794 -0.1778)
						)
						(arc
							(start -0.2794 0.1778)
							(mid -0.249642 0.249642)
							(end -0.1778 0.2794)
						)
						(arc
							(start 0.1778 0.2794)
							(mid 0.249642 0.249642)
							(end 0.2794 0.1778)
						)
						(arc
							(start 0.2794 -0.1778)
							(mid 0.249642 -0.249642)
							(end 0.1778 -0.2794)
						)
					)
					(width 0)
					(fill yes)
				)
			)
		)
		(pad "2" smd custom
			(at 0 0.4445 270)
			(size 0.1397 0.1397)
			(layers "F.Cu" "F.Mask" "F.Paste")
			(net "CLK_P_2_R")
			(options
				(clearance outline)
				(anchor circle)
			)
			(primitives
				(gr_poly
					(pts
						(arc
							(start -0.1778 -0.2794)
							(mid -0.249642 -0.249642)
							(end -0.2794 -0.1778)
						)
						(arc
							(start -0.2794 0.1778)
							(mid -0.249642 0.249642)
							(end -0.1778 0.2794)
						)
						(arc
							(start 0.1778 0.2794)
							(mid 0.249642 0.249642)
							(end 0.2794 0.1778)
						)
						(arc
							(start 0.2794 -0.1778)
							(mid 0.249642 -0.249642)
							(end 0.1778 -0.2794)
						)
					)
					(width 0)
					(fill yes)
				)
			)
		)
	)
	(footprint ""
		(layer "F.Cu")
		(at 117.5258 -95.0722)
		(property "Reference" "C693"
			(at 0 0 0)
			(layer "F.SilkS")
			(hide yes)
			(effects
				(font
					(size 1.27 1.27)
				)
			)
		)
		(property "Value" "SCD01U50V2KX-1GP"
			(at 1.1811 -2.7051 0)
			(unlocked yes)
			(layer "F.Fab")
			(hide yes)
			(effects
				(font
					(size 1.016 1.016)
					(thickness 0.1524)
				)
			)
		)
		(property "Device Type" "C402H22"
			(at 1.1811 -4.2291 0)
			(unlocked yes)
			(layer "F.Fab")
			(hide yes)
			(effects
				(font
					(size 1.016 1.016)
					(thickness 0.1524)
				)
			)
		)
		(duplicate_pad_numbers_are_jumpers no)
		(fp_rect
			(start -0.4318 0.9525)
			(end 0.4318 -0.9525)
			(stroke
				(width 0)
				(type default)
			)
			(fill no)
			(layer "F.CrtYd")
		)
		(fp_rect
			(start -0.4318 0.9525)
			(end 0.4318 -0.9525)
			(stroke
				(width 0)
				(type default)
			)
			(fill no)
			(layer "F.Fab")
		)
		(pad "1" smd custom
			(at 0 -0.4445)
			(size 0.1524 0.1524)
			(layers "F.Cu" "F.Mask" "F.Paste")
			(net "P3V3_STBY")
			(options
				(clearance outline)
				(anchor circle)
			)
			(primitives
				(gr_poly
					(pts
						(arc
							(start 0.3048 -0.2032)
							(mid 0.275042 -0.275042)
							(end 0.2032 -0.3048)
						)
						(arc
							(start -0.2032 -0.3048)
							(mid -0.275042 -0.275042)
							(end -0.3048 -0.2032)
						)
						(arc
							(start -0.3048 0.2032)
							(mid -0.275042 0.275042)
							(end -0.2032 0.3048)
						)
						(arc
							(start 0.2032 0.3048)
							(mid 0.275042 0.275042)
							(end 0.3048 0.2032)
						)
					)
					(width 0)
					(fill yes)
				)
			)
		)
		(pad "2" smd custom
			(at 0 0.4445)
			(size 0.1524 0.1524)
			(layers "F.Cu" "F.Mask" "F.Paste")
			(net "GND")
			(options
				(clearance outline)
				(anchor circle)
			)
			(primitives
				(gr_poly
					(pts
						(arc
							(start 0.3048 -0.2032)
							(mid 0.275042 -0.275042)
							(end 0.2032 -0.3048)
						)
						(arc
							(start -0.2032 -0.3048)
							(mid -0.275042 -0.275042)
							(end -0.3048 -0.2032)
						)
						(arc
							(start -0.3048 0.2032)
							(mid -0.275042 0.275042)
							(end -0.2032 0.3048)
						)
						(arc
							(start 0.2032 0.3048)
							(mid 0.275042 0.275042)
							(end 0.3048 0.2032)
						)
					)
					(width 0)
					(fill yes)
				)
			)
		)
	)
	(footprint ""
		(layer "F.Cu")
		(at 316.392052 -212.420454 180)
		(property "Reference" "C68"
			(at 0 0 180)
			(layer "F.SilkS")
			(hide yes)
			(effects
				(font
					(size 1.27 1.27)
				)
			)
		)
		(property "Value" "SCD22U10V2KX-1GP"
			(at 1.1811 -2.7051 180)
			(unlocked yes)
			(layer "F.Fab")
			(hide yes)
			(effects
				(font
					(size 1.016 1.016)
					(thickness 0.1524)
				)
			)
		)
		(property "Device Type" "C402H22"
			(at 1.1811 -4.2291 180)
			(unlocked yes)
			(layer "F.Fab")
			(hide yes)
			(effects
				(font
					(size 1.016 1.016)
					(thickness 0.1524)
				)
			)
		)
		(duplicate_pad_numbers_are_jumpers no)
		(fp_rect
			(start -0.4318 0.9525)
			(end 0.4318 -0.9525)
			(stroke
				(width 0)
				(type default)
			)
			(fill no)
			(layer "F.CrtYd")
		)
		(fp_rect
			(start -0.4318 0.9525)
			(end 0.4318 -0.9525)
			(stroke
				(width 0)
				(type default)
			)
			(fill no)
			(layer "F.Fab")
		)
		(pad "1" smd custom
			(at 0 -0.4445 180)
			(size 0.1524 0.1524)
			(layers "F.Cu" "F.Mask" "F.Paste")
			(net "PCIE_TX_CAP_P23")
			(options
				(clearance outline)
				(anchor circle)
			)
			(primitives
				(gr_poly
					(pts
						(arc
							(start 0.3048 -0.2032)
							(mid 0.275042 -0.275042)
							(end 0.2032 -0.3048)
						)
						(arc
							(start -0.2032 -0.3048)
							(mid -0.275042 -0.275042)
							(end -0.3048 -0.2032)
						)
						(arc
							(start -0.3048 0.2032)
							(mid -0.275042 0.275042)
							(end -0.2032 0.3048)
						)
						(arc
							(start 0.2032 0.3048)
							(mid 0.275042 0.275042)
							(end 0.3048 0.2032)
						)
					)
					(width 0)
					(fill yes)
				)
			)
		)
		(pad "2" smd custom
			(at 0 0.4445 180)
			(size 0.1524 0.1524)
			(layers "F.Cu" "F.Mask" "F.Paste")
			(net "PCIE_TX_P23")
			(options
				(clearance outline)
				(anchor circle)
			)
			(primitives
				(gr_poly
					(pts
						(arc
							(start 0.3048 -0.2032)
							(mid 0.275042 -0.275042)
							(end 0.2032 -0.3048)
						)
						(arc
							(start -0.2032 -0.3048)
							(mid -0.275042 -0.275042)
							(end -0.3048 -0.2032)
						)
						(arc
							(start -0.3048 0.2032)
							(mid -0.275042 0.275042)
							(end -0.2032 0.3048)
						)
						(arc
							(start 0.2032 0.3048)
							(mid 0.275042 0.275042)
							(end 0.3048 0.2032)
						)
					)
					(width 0)
					(fill yes)
				)
			)
		)
	)
	(footprint ""
		(layer "F.Cu")
		(at 15.9766 -81.8642 -90)
		(property "Reference" "TP163"
			(at 0 0 270)
			(layer "F.SilkS")
			(hide yes)
			(effects
				(font
					(size 1.27 1.27)
				)
			)
		)
		(property "Value" "TPAD28-2-GP"
			(at -0.0127 -1.6637 270)
			(unlocked yes)
			(layer "F.Fab")
			(hide yes)
			(effects
				(font
					(size 1.016 1.016)
					(thickness 0.1524)
				)
			)
		)
		(property "Device Type" "TPAD28"
			(at -0.0127 -3.1877 270)
			(unlocked yes)
			(layer "F.Fab")
			(hide yes)
			(effects
				(font
					(size 1.016 1.016)
					(thickness 0.1524)
				)
			)
		)
		(duplicate_pad_numbers_are_jumpers no)
		(fp_poly
			(pts
				(arc
					(start 0 -0.3556)
					(mid 0 0.3556)
					(end 0 -0.3556)
				)
			)
			(stroke
				(width 0)
				(type default)
			)
			(fill no)
			(layer "F.CrtYd")
		)
		(fp_poly
			(pts
				(arc
					(start 0 -0.6096)
					(mid 0 0.6096)
					(end 0 -0.6096)
				)
			)
			(stroke
				(width 0)
				(type default)
			)
			(fill no)
			(layer "F.Fab")
		)
		(pad "1" smd circle
			(at 0 0 270)
			(size 0.7112 0.7112)
			(layers "F.Cu" "F.Mask" "F.Paste")
			(net "NIC_JTDI")
		)
	)
	(footprint ""
		(layer "F.Cu")
		(at 77.827124 -183.235092)
		(property "Reference" "R7958"
			(at 0 0 0)
			(layer "F.SilkS")
			(hide yes)
			(effects
				(font
					(size 1.27 1.27)
				)
			)
		)
		(property "Value" "0R2J-2-GP"
			(at 0.064008 -3.993896 0)
			(unlocked yes)
			(layer "F.Fab")
			(hide yes)
			(effects
				(font
					(size 1.016 1.016)
					(thickness 0.1524)
				)
			)
		)
		(property "Device Type" "R402H16"
			(at 0.064008 -5.517896 0)
			(unlocked yes)
			(layer "F.Fab")
			(hide yes)
			(effects
				(font
					(size 1.016 1.016)
					(thickness 0.1524)
				)
			)
		)
		(duplicate_pad_numbers_are_jumpers no)
		(fp_line
			(start -0.508 -0.9398)
			(end -0.508 0.9398)
			(stroke
				(width 0.1524)
				(type default)
			)
			(layer "F.SilkS")
		)
		(fp_line
			(start 0.508 -0.9398)
			(end -0.508 -0.9398)
			(stroke
				(width 0.1524)
				(type default)
			)
			(layer "F.SilkS")
		)
		(fp_rect
			(start -0.508 0.9398)
			(end 0.508 -0.9398)
			(stroke
				(width 0)
				(type default)
			)
			(fill no)
			(layer "F.CrtYd")
		)
		(fp_rect
			(start -0.508 0.9398)
			(end 0.508 -0.9398)
			(stroke
				(width 0)
				(type default)
			)
			(fill no)
			(layer "F.Fab")
		)
		(pad "1" smd custom
			(at 0 -0.4445)
			(size 0.1397 0.1397)
			(layers "F.Cu" "F.Mask" "F.Paste")
			(net "SSD_PWREN5")
			(options
				(clearance outline)
				(anchor circle)
			)
			(primitives
				(gr_poly
					(pts
						(arc
							(start -0.1778 -0.2794)
							(mid -0.249642 -0.249642)
							(end -0.2794 -0.1778)
						)
						(arc
							(start -0.2794 0.1778)
							(mid -0.249642 0.249642)
							(end -0.1778 0.2794)
						)
						(arc
							(start 0.1778 0.2794)
							(mid 0.249642 0.249642)
							(end 0.2794 0.1778)
						)
						(arc
							(start 0.2794 -0.1778)
							(mid 0.249642 -0.249642)
							(end 0.1778 -0.2794)
						)
					)
					(width 0)
					(fill yes)
				)
			)
		)
		(pad "2" smd custom
			(at 0 0.4445)
			(size 0.1397 0.1397)
			(layers "F.Cu" "F.Mask" "F.Paste")
			(net "SSD_PWREN5_R")
			(options
				(clearance outline)
				(anchor circle)
			)
			(primitives
				(gr_poly
					(pts
						(arc
							(start -0.1778 -0.2794)
							(mid -0.249642 -0.249642)
							(end -0.2794 -0.1778)
						)
						(arc
							(start -0.2794 0.1778)
							(mid -0.249642 0.249642)
							(end -0.1778 0.2794)
						)
						(arc
							(start 0.1778 0.2794)
							(mid 0.249642 0.249642)
							(end 0.2794 0.1778)
						)
						(arc
							(start 0.2794 -0.1778)
							(mid 0.249642 -0.249642)
							(end 0.1778 -0.2794)
						)
					)
					(width 0)
					(fill yes)
				)
			)
		)
	)
	(footprint ""
		(layer "F.Cu")
		(at 71.940166 -85.37956 -90)
		(property "Reference" "U41"
			(at 0 0 270)
			(layer "F.SilkS")
			(hide yes)
			(effects
				(font
					(size 1.27 1.27)
				)
			)
		)
		(property "Value" "LM393ADR-1-GP"
			(at -3.707384 -1.5367 270)
			(unlocked yes)
			(layer "F.Fab")
			(hide yes)
			(effects
				(font
					(size 1.016 1.016)
					(thickness 0.1524)
				)
			)
		)
		(property "Device Type" "SOIC8H69"
			(at -3.707384 -3.0607 270)
			(unlocked yes)
			(layer "F.Fab")
			(hide yes)
			(effects
				(font
					(size 1.016 1.016)
					(thickness 0.1524)
				)
			)
		)
		(duplicate_pad_numbers_are_jumpers no)
		(fp_line
			(start -2.6289 3.4417)
			(end -2.6289 1.4732)
			(stroke
				(width 0.381)
				(type default)
			)
			(layer "F.SilkS")
		)
		(fp_line
			(start -2.7432 1.4224)
			(end -2.6416 1.4224)
			(stroke
				(width 0.1524)
				(type default)
			)
			(layer "F.SilkS")
		)
		(fp_line
			(start -2.7432 1.4224)
			(end 2.1336 1.4224)
			(stroke
				(width 0.1524)
				(type default)
			)
			(layer "F.SilkS")
		)
		(fp_line
			(start 2.1336 1.4224)
			(end 2.1336 -1.4224)
			(stroke
				(width 0.1524)
				(type default)
			)
			(layer "F.SilkS")
		)
		(fp_line
			(start -2.1844 -0.0508)
			(end -2.7178 0.508)
			(stroke
				(width 0.1524)
				(type default)
			)
			(layer "F.SilkS")
		)
		(fp_line
			(start -2.7178 -0.508)
			(end -2.1844 -0.0508)
			(stroke
				(width 0.1524)
				(type default)
			)
			(layer "F.SilkS")
		)
		(fp_line
			(start -2.7432 -1.4224)
			(end -2.7432 1.4224)
			(stroke
				(width 0.1524)
				(type default)
			)
			(layer "F.SilkS")
		)
		(fp_line
			(start 2.1336 -1.4224)
			(end -2.7432 -1.4224)
			(stroke
				(width 0.1524)
				(type default)
			)
			(layer "F.SilkS")
		)
		(fp_poly
			(pts
				(xy -2.2098 -1.4224) (xy -2.2098 1.4224) (xy 2.2098 1.4224) (xy 2.2098 -1.4224)
			)
			(stroke
				(width 0)
				(type default)
			)
			(fill yes)
			(layer "F.SilkS")
		)
		(fp_rect
			(start -2.450084 2.999994)
			(end 2.450084 -2.999994)
			(stroke
				(width 0)
				(type default)
			)
			(fill no)
			(layer "F.CrtYd")
		)
		(fp_poly
			(pts
				(xy -2.8194 3.6322) (xy -2.8194 -3.6322) (xy 2.8194 -3.6322) (xy 2.8194 1.18364) (xy 2.450084 1.18364)
				(xy 2.450084 -2.999994) (xy -2.450084 -2.999994) (xy -2.450084 2.999994) (xy 2.450084 2.999994)
				(xy 2.450084 1.18618) (xy 2.8194 1.18618) (xy 2.8194 3.6322)
			)
			(stroke
				(width 0)
				(type default)
			)
			(fill no)
			(layer "F.CrtYd")
		)
		(fp_rect
			(start -2.8194 3.6322)
			(end 2.8194 -3.6322)
			(stroke
				(width 0)
				(type default)
			)
			(fill no)
			(layer "F.Fab")
		)
		(pad "1" smd rect
			(at -1.905 2.54 270)
			(size 0.635 1.651)
			(layers "F.Cu" "F.Mask" "F.Paste")
			(net "HB_A_OUT")
		)
		(pad "2" smd rect
			(at -0.635 2.54 270)
			(size 0.635 1.651)
			(layers "F.Cu" "F.Mask" "F.Paste")
			(net "HB_A_IN")
		)
		(pad "3" smd rect
			(at 0.635 2.54 270)
			(size 0.635 1.651)
			(layers "F.Cu" "F.Mask" "F.Paste")
			(net "DIVIDER_1_IN")
		)
		(pad "4" smd rect
			(at 1.905 2.54 270)
			(size 0.635 1.651)
			(layers "F.Cu" "F.Mask" "F.Paste")
			(net "GND")
		)
		(pad "5" smd rect
			(at 1.905 -2.54 270)
			(size 0.635 1.651)
			(layers "F.Cu" "F.Mask" "F.Paste")
			(net "HB_A_IN")
		)
		(pad "6" smd rect
			(at 0.635 -2.54 270)
			(size 0.635 1.651)
			(layers "F.Cu" "F.Mask" "F.Paste")
			(net "DIVIDER_2_IN")
		)
		(pad "7" smd rect
			(at -0.635 -2.54 270)
			(size 0.635 1.651)
			(layers "F.Cu" "F.Mask" "F.Paste")
			(net "HB_A_OUT")
		)
		(pad "8" smd rect
			(at -1.905 -2.54 270)
			(size 0.635 1.651)
			(layers "F.Cu" "F.Mask" "F.Paste")
			(net "P3V3_STBY")
		)
	)
	(footprint ""
		(layer "F.Cu")
		(at 305.816 -68.834 180)
		(property "Reference" "C459"
			(at 0 0 180)
			(layer "F.SilkS")
			(hide yes)
			(effects
				(font
					(size 1.27 1.27)
				)
			)
		)
		(property "Value" "SC100U4V5MX-1-GP"
			(at -0.0762 -6.1214 180)
			(unlocked yes)
			(layer "F.Fab")
			(hide yes)
			(effects
				(font
					(size 1.016 1.016)
					(thickness 0.1524)
				)
			)
		)
		(property "Device Type" "C805H58"
			(at -0.0762 -8.1534 180)
			(unlocked yes)
			(layer "F.Fab")
			(hide yes)
			(effects
				(font
					(size 1.016 1.016)
					(thickness 0.1524)
				)
			)
		)
		(duplicate_pad_numbers_are_jumpers no)
		(fp_line
			(start 0.635 0)
			(end -0.635 0)
			(stroke
				(width 0.508)
				(type default)
			)
			(layer "F.SilkS")
		)
		(fp_rect
			(start -0.9652 1.778)
			(end 0.9652 -1.778)
			(stroke
				(width 0)
				(type default)
			)
			(fill no)
			(layer "F.CrtYd")
		)
		(fp_poly
			(pts
				(xy -0.9652 -1.778) (xy 0.9652 -1.778) (xy 0.9652 1.778) (xy -0.9652 1.778)
			)
			(stroke
				(width 0)
				(type default)
			)
			(fill no)
			(layer "F.Fab")
		)
		(pad "1" smd rect
			(at 0 -0.9652 180)
			(size 1.397 1.143)
			(layers "F.Cu" "F.Mask" "F.Paste")
			(net "DUT_VDD")
		)
		(pad "2" smd rect
			(at 0 0.9652 180)
			(size 1.397 1.143)
			(layers "F.Cu" "F.Mask" "F.Paste")
			(net "GND")
		)
	)
	(footprint ""
		(layer "F.Cu")
		(at 19.177 -148.844 -90)
		(property "Reference" "R333"
			(at 0 0 270)
			(layer "F.SilkS")
			(hide yes)
			(effects
				(font
					(size 1.27 1.27)
				)
			)
		)
		(property "Value" "47KR2F-GP"
			(at 0.064008 -3.993896 270)
			(unlocked yes)
			(layer "F.Fab")
			(hide yes)
			(effects
				(font
					(size 1.016 1.016)
					(thickness 0.1524)
				)
			)
		)
		(property "Device Type" "R402H16"
			(at 0.064008 -5.517896 270)
			(unlocked yes)
			(layer "F.Fab")
			(hide yes)
			(effects
				(font
					(size 1.016 1.016)
					(thickness 0.1524)
				)
			)
		)
		(duplicate_pad_numbers_are_jumpers no)
		(fp_line
			(start -0.508 -0.9398)
			(end -0.508 0.9398)
			(stroke
				(width 0.1524)
				(type default)
			)
			(layer "F.SilkS")
		)
		(fp_line
			(start 0.508 -0.9398)
			(end -0.508 -0.9398)
			(stroke
				(width 0.1524)
				(type default)
			)
			(layer "F.SilkS")
		)
		(fp_rect
			(start -0.508 0.9398)
			(end 0.508 -0.9398)
			(stroke
				(width 0)
				(type default)
			)
			(fill no)
			(layer "F.CrtYd")
		)
		(fp_rect
			(start -0.508 0.9398)
			(end 0.508 -0.9398)
			(stroke
				(width 0)
				(type default)
			)
			(fill no)
			(layer "F.Fab")
		)
		(pad "1" smd custom
			(at 0 -0.4445 270)
			(size 0.1397 0.1397)
			(layers "F.Cu" "F.Mask" "F.Paste")
			(net "P3V3_STBY")
			(options
				(clearance outline)
				(anchor circle)
			)
			(primitives
				(gr_poly
					(pts
						(arc
							(start -0.1778 -0.2794)
							(mid -0.249642 -0.249642)
							(end -0.2794 -0.1778)
						)
						(arc
							(start -0.2794 0.1778)
							(mid -0.249642 0.249642)
							(end -0.1778 0.2794)
						)
						(arc
							(start 0.1778 0.2794)
							(mid 0.249642 0.249642)
							(end 0.2794 0.1778)
						)
						(arc
							(start 0.2794 -0.1778)
							(mid 0.249642 -0.249642)
							(end 0.1778 -0.2794)
						)
					)
					(width 0)
					(fill yes)
				)
			)
		)
		(pad "2" smd custom
			(at 0 0.4445 270)
			(size 0.1397 0.1397)
			(layers "F.Cu" "F.Mask" "F.Paste")
			(net "FM_BMC_RESET_N")
			(options
				(clearance outline)
				(anchor circle)
			)
			(primitives
				(gr_poly
					(pts
						(arc
							(start -0.1778 -0.2794)
							(mid -0.249642 -0.249642)
							(end -0.2794 -0.1778)
						)
						(arc
							(start -0.2794 0.1778)
							(mid -0.249642 0.249642)
							(end -0.1778 0.2794)
						)
						(arc
							(start 0.1778 0.2794)
							(mid 0.249642 0.249642)
							(end 0.2794 0.1778)
						)
						(arc
							(start 0.2794 -0.1778)
							(mid 0.249642 -0.249642)
							(end 0.1778 -0.2794)
						)
					)
					(width 0)
					(fill yes)
				)
			)
		)
	)
	(footprint ""
		(layer "F.Cu")
		(at 118.17858 -33.929828 180)
		(property "Reference" "Q24"
			(at 0 0 180)
			(layer "F.SilkS")
			(hide yes)
			(effects
				(font
					(size 1.27 1.27)
				)
			)
		)
		(property "Value" "2N7002K-1-GP"
			(at 0.127 -8.9662 180)
			(unlocked yes)
			(layer "F.Fab")
			(hide yes)
			(effects
				(font
					(size 1.016 1.016)
					(thickness 0.1524)
				)
			)
		)
		(property "Device Type" "SOT23DGS2D4H44"
			(at 0.127 -10.4902 180)
			(unlocked yes)
			(layer "F.Fab")
			(hide yes)
			(effects
				(font
					(size 1.016 1.016)
					(thickness 0.1524)
				)
			)
		)
		(duplicate_pad_numbers_are_jumpers no)
		(fp_line
			(start 1.651 1.778)
			(end 1.651 -1.778)
			(stroke
				(width 0.1524)
				(type default)
			)
			(layer "F.SilkS")
		)
		(fp_line
			(start 1.651 -1.778)
			(end -1.651 -1.778)
			(stroke
				(width 0.1524)
				(type default)
			)
			(layer "F.SilkS")
		)
		(fp_line
			(start -1.651 1.778)
			(end 1.651 1.778)
			(stroke
				(width 0.1524)
				(type default)
			)
			(layer "F.SilkS")
		)
		(fp_line
			(start -1.651 -1.778)
			(end -1.651 1.778)
			(stroke
				(width 0.1524)
				(type default)
			)
			(layer "F.SilkS")
		)
		(fp_poly
			(pts
				(xy -1.778 1.8796) (xy -1.778 -1.8796) (xy 1.778 -1.8796) (xy 1.778 1.8796)
			)
			(stroke
				(width 0)
				(type default)
			)
			(fill no)
			(layer "F.CrtYd")
		)
		(fp_poly
			(pts
				(xy -1.778 1.8796) (xy -1.778 -1.8796) (xy 1.778 -1.8796) (xy 1.778 1.8796)
			)
			(stroke
				(width 0)
				(type default)
			)
			(fill no)
			(layer "F.Fab")
		)
		(pad "D" smd custom
			(at 0 -0.9525 180)
			(size 0.1905 0.1905)
			(layers "F.Cu" "F.Mask" "F.Paste")
			(net "LED_Q_1")
			(options
				(clearance outline)
				(anchor circle)
			)
			(primitives
				(gr_poly
					(pts
						(arc
							(start -0.1778 0.5715)
							(mid -0.321484 0.511984)
							(end -0.381 0.3683)
						)
						(arc
							(start -0.381 -0.3683)
							(mid -0.321484 -0.511984)
							(end -0.1778 -0.5715)
						)
						(arc
							(start 0.1778 -0.5715)
							(mid 0.321484 -0.511984)
							(end 0.381 -0.3683)
						)
						(arc
							(start 0.381 0.3683)
							(mid 0.321484 0.511984)
							(end 0.1778 0.5715)
						)
					)
					(width 0)
					(fill yes)
				)
			)
		)
		(pad "G" smd custom
			(at -0.98425 0.9525 180)
			(size 0.1905 0.1905)
			(layers "F.Cu" "F.Mask" "F.Paste")
			(net "UPLINK1_R")
			(options
				(clearance outline)
				(anchor circle)
			)
			(primitives
				(gr_poly
					(pts
						(arc
							(start -0.1778 0.5715)
							(mid -0.321484 0.511984)
							(end -0.381 0.3683)
						)
						(arc
							(start -0.381 -0.3683)
							(mid -0.321484 -0.511984)
							(end -0.1778 -0.5715)
						)
						(arc
							(start 0.1778 -0.5715)
							(mid 0.321484 -0.511984)
							(end 0.381 -0.3683)
						)
						(arc
							(start 0.381 0.3683)
							(mid 0.321484 0.511984)
							(end 0.1778 0.5715)
						)
					)
					(width 0)
					(fill yes)
				)
			)
		)
		(pad "S" smd custom
			(at 0.98425 0.9525 180)
			(size 0.1905 0.1905)
			(layers "F.Cu" "F.Mask" "F.Paste")
			(net "GND")
			(options
				(clearance outline)
				(anchor circle)
			)
			(primitives
				(gr_poly
					(pts
						(arc
							(start -0.1778 0.5715)
							(mid -0.321484 0.511984)
							(end -0.381 0.3683)
						)
						(arc
							(start -0.381 -0.3683)
							(mid -0.321484 -0.511984)
							(end -0.1778 -0.5715)
						)
						(arc
							(start 0.1778 -0.5715)
							(mid 0.321484 -0.511984)
							(end 0.381 -0.3683)
						)
						(arc
							(start 0.381 0.3683)
							(mid 0.321484 0.511984)
							(end 0.1778 0.5715)
						)
					)
					(width 0)
					(fill yes)
				)
			)
		)
	)
	(footprint ""
		(layer "F.Cu")
		(at 43.9928 -191.3636 -90)
		(property "Reference" "R873"
			(at 0 0 270)
			(layer "F.SilkS")
			(hide yes)
			(effects
				(font
					(size 1.27 1.27)
				)
			)
		)
		(property "Value" "2KR2F-3-GP"
			(at 0.064008 -3.993896 270)
			(unlocked yes)
			(layer "F.Fab")
			(hide yes)
			(effects
				(font
					(size 1.016 1.016)
					(thickness 0.1524)
				)
			)
		)
		(property "Device Type" "R402H16"
			(at 0.064008 -5.517896 270)
			(unlocked yes)
			(layer "F.Fab")
			(hide yes)
			(effects
				(font
					(size 1.016 1.016)
					(thickness 0.1524)
				)
			)
		)
		(duplicate_pad_numbers_are_jumpers no)
		(fp_line
			(start -0.508 -0.9398)
			(end -0.508 0.9398)
			(stroke
				(width 0.1524)
				(type default)
			)
			(layer "F.SilkS")
		)
		(fp_line
			(start 0.508 -0.9398)
			(end -0.508 -0.9398)
			(stroke
				(width 0.1524)
				(type default)
			)
			(layer "F.SilkS")
		)
		(fp_rect
			(start -0.508 0.9398)
			(end 0.508 -0.9398)
			(stroke
				(width 0)
				(type default)
			)
			(fill no)
			(layer "F.CrtYd")
		)
		(fp_rect
			(start -0.508 0.9398)
			(end 0.508 -0.9398)
			(stroke
				(width 0)
				(type default)
			)
			(fill no)
			(layer "F.Fab")
		)
		(pad "1" smd custom
			(at 0 -0.4445 270)
			(size 0.1397 0.1397)
			(layers "F.Cu" "F.Mask" "F.Paste")
			(net "P3V3_STBY")
			(options
				(clearance outline)
				(anchor circle)
			)
			(primitives
				(gr_poly
					(pts
						(arc
							(start -0.1778 -0.2794)
							(mid -0.249642 -0.249642)
							(end -0.2794 -0.1778)
						)
						(arc
							(start -0.2794 0.1778)
							(mid -0.249642 0.249642)
							(end -0.1778 0.2794)
						)
						(arc
							(start 0.1778 0.2794)
							(mid 0.249642 0.249642)
							(end 0.2794 0.1778)
						)
						(arc
							(start 0.2794 -0.1778)
							(mid 0.249642 -0.249642)
							(end 0.1778 -0.2794)
						)
					)
					(width 0)
					(fill yes)
				)
			)
		)
		(pad "2" smd custom
			(at 0 0.4445 270)
			(size 0.1397 0.1397)
			(layers "F.Cu" "F.Mask" "F.Paste")
			(net "BUF_I2C9_CLKBUF2_SCL_R")
			(options
				(clearance outline)
				(anchor circle)
			)
			(primitives
				(gr_poly
					(pts
						(arc
							(start -0.1778 -0.2794)
							(mid -0.249642 -0.249642)
							(end -0.2794 -0.1778)
						)
						(arc
							(start -0.2794 0.1778)
							(mid -0.249642 0.249642)
							(end -0.1778 0.2794)
						)
						(arc
							(start 0.1778 0.2794)
							(mid 0.249642 0.249642)
							(end 0.2794 0.1778)
						)
						(arc
							(start 0.2794 -0.1778)
							(mid 0.249642 -0.249642)
							(end 0.1778 -0.2794)
						)
					)
					(width 0)
					(fill yes)
				)
			)
		)
	)
	(footprint ""
		(layer "F.Cu")
		(at 64.4906 -109.3724 90)
		(property "Reference" "U28"
			(at 0 0 90)
			(layer "F.SilkS")
			(hide yes)
			(effects
				(font
					(size 1.27 1.27)
				)
			)
		)
		(property "Value" "2N7002DW-7F-GP"
			(at -2.3622 -8.2042 90)
			(unlocked yes)
			(layer "F.Fab")
			(hide yes)
			(effects
				(font
					(size 1.016 1.016)
					(thickness 0.1524)
				)
			)
		)
		(property "Device Type" "SOT-363H44"
			(at -2.3622 -10.1092 90)
			(unlocked yes)
			(layer "F.Fab")
			(hide yes)
			(effects
				(font
					(size 1.016 1.016)
					(thickness 0.1524)
				)
			)
		)
		(duplicate_pad_numbers_are_jumpers no)
		(fp_line
			(start 1.4478 -1.7018)
			(end -1.4478 -1.7018)
			(stroke
				(width 0.1524)
				(type default)
			)
			(layer "F.SilkS")
		)
		(fp_line
			(start -1.4478 -1.7018)
			(end -1.4478 1.7018)
			(stroke
				(width 0.1524)
				(type default)
			)
			(layer "F.SilkS")
		)
		(fp_line
			(start -1.27 1.524)
			(end -1.27 0.6604)
			(stroke
				(width 0.4826)
				(type default)
			)
			(layer "F.SilkS")
		)
		(fp_line
			(start 1.4478 1.7018)
			(end 1.4478 -1.7018)
			(stroke
				(width 0.1524)
				(type default)
			)
			(layer "F.SilkS")
		)
		(fp_line
			(start -1.4478 1.7018)
			(end 1.4478 1.7018)
			(stroke
				(width 0.1524)
				(type default)
			)
			(layer "F.SilkS")
		)
		(fp_poly
			(pts
				(xy -1.524 -1.778) (xy 1.524 -1.778) (xy 1.524 1.778) (xy -1.524 1.778)
			)
			(stroke
				(width 0)
				(type default)
			)
			(fill no)
			(layer "F.CrtYd")
		)
		(fp_poly
			(pts
				(xy -1.524 -1.778) (xy 1.524 -1.778) (xy 1.524 1.778) (xy -1.524 1.778)
			)
			(stroke
				(width 0)
				(type default)
			)
			(fill no)
			(layer "F.Fab")
		)
		(pad "1" smd rect
			(at -0.65024 0.9398 90)
			(size 0.4064 1.016)
			(layers "F.Cu" "F.Mask" "F.Paste")
			(net "BMC_I2C11_MINI5_SCL_S")
		)
		(pad "2" smd rect
			(at 0 0.9398 90)
			(size 0.4064 1.016)
			(layers "F.Cu" "F.Mask" "F.Paste")
			(net "I2C5_LS_G2")
		)
		(pad "3" smd rect
			(at 0.65024 0.9398 90)
			(size 0.4064 1.016)
			(layers "F.Cu" "F.Mask" "F.Paste")
			(net "BMC_I2C11_MINI5_SDA")
		)
		(pad "4" smd rect
			(at 0.65024 -0.9398 90)
			(size 0.4064 1.016)
			(layers "F.Cu" "F.Mask" "F.Paste")
			(net "BMC_I2C11_MINI5_SDA_S")
		)
		(pad "5" smd rect
			(at 0 -0.9398 90)
			(size 0.4064 1.016)
			(layers "F.Cu" "F.Mask" "F.Paste")
			(net "I2C5_LS_G1")
		)
		(pad "6" smd rect
			(at -0.65024 -0.9398 90)
			(size 0.4064 1.016)
			(layers "F.Cu" "F.Mask" "F.Paste")
			(net "BMC_I2C11_MINI5_SCL")
		)
	)
	(footprint ""
		(layer "F.Cu")
		(at 18.7452 -56.5404 180)
		(property "Reference" "R613"
			(at 0 0 180)
			(layer "F.SilkS")
			(hide yes)
			(effects
				(font
					(size 1.27 1.27)
				)
			)
		)
		(property "Value" "0R2J-2-GP"
			(at 0.064008 -3.993896 180)
			(unlocked yes)
			(layer "F.Fab")
			(hide yes)
			(effects
				(font
					(size 1.016 1.016)
					(thickness 0.1524)
				)
			)
		)
		(property "Device Type" "R402H16"
			(at 0.064008 -5.517896 180)
			(unlocked yes)
			(layer "F.Fab")
			(hide yes)
			(effects
				(font
					(size 1.016 1.016)
					(thickness 0.1524)
				)
			)
		)
		(duplicate_pad_numbers_are_jumpers no)
		(fp_line
			(start 0.508 -0.9398)
			(end -0.508 -0.9398)
			(stroke
				(width 0.1524)
				(type default)
			)
			(layer "F.SilkS")
		)
		(fp_line
			(start -0.508 -0.9398)
			(end -0.508 0.9398)
			(stroke
				(width 0.1524)
				(type default)
			)
			(layer "F.SilkS")
		)
		(fp_rect
			(start -0.508 0.9398)
			(end 0.508 -0.9398)
			(stroke
				(width 0)
				(type default)
			)
			(fill no)
			(layer "F.CrtYd")
		)
		(fp_rect
			(start -0.508 0.9398)
			(end 0.508 -0.9398)
			(stroke
				(width 0)
				(type default)
			)
			(fill no)
			(layer "F.Fab")
		)
		(pad "1" smd custom
			(at 0 -0.4445 180)
			(size 0.1397 0.1397)
			(layers "F.Cu" "F.Mask" "F.Paste")
			(net "NIC0_MDI0_P2")
			(options
				(clearance outline)
				(anchor circle)
			)
			(primitives
				(gr_poly
					(pts
						(arc
							(start -0.1778 -0.2794)
							(mid -0.249642 -0.249642)
							(end -0.2794 -0.1778)
						)
						(arc
							(start -0.2794 0.1778)
							(mid -0.249642 0.249642)
							(end -0.1778 0.2794)
						)
						(arc
							(start 0.1778 0.2794)
							(mid 0.249642 0.249642)
							(end 0.2794 0.1778)
						)
						(arc
							(start 0.2794 -0.1778)
							(mid 0.249642 -0.249642)
							(end 0.1778 -0.2794)
						)
					)
					(width 0)
					(fill yes)
				)
			)
		)
		(pad "2" smd custom
			(at 0 0.4445 180)
			(size 0.1397 0.1397)
			(layers "F.Cu" "F.Mask" "F.Paste")
			(net "MNG_TX_DP")
			(options
				(clearance outline)
				(anchor circle)
			)
			(primitives
				(gr_poly
					(pts
						(arc
							(start -0.1778 -0.2794)
							(mid -0.249642 -0.249642)
							(end -0.2794 -0.1778)
						)
						(arc
							(start -0.2794 0.1778)
							(mid -0.249642 0.249642)
							(end -0.1778 0.2794)
						)
						(arc
							(start 0.1778 0.2794)
							(mid 0.249642 0.249642)
							(end 0.2794 0.1778)
						)
						(arc
							(start 0.2794 -0.1778)
							(mid 0.249642 -0.249642)
							(end 0.1778 -0.2794)
						)
					)
					(width 0)
					(fill yes)
				)
			)
		)
	)
	(footprint ""
		(layer "F.Cu")
		(at 234.823 -23.241)
		(property "Reference" "R808"
			(at 0 0 0)
			(layer "F.SilkS")
			(hide yes)
			(effects
				(font
					(size 1.27 1.27)
				)
			)
		)
		(property "Value" "4K7R2F-GP"
			(at 0.064008 -3.993896 0)
			(unlocked yes)
			(layer "F.Fab")
			(hide yes)
			(effects
				(font
					(size 1.016 1.016)
					(thickness 0.1524)
				)
			)
		)
		(property "Device Type" "R402H16"
			(at 0.064008 -5.517896 0)
			(unlocked yes)
			(layer "F.Fab")
			(hide yes)
			(effects
				(font
					(size 1.016 1.016)
					(thickness 0.1524)
				)
			)
		)
		(duplicate_pad_numbers_are_jumpers no)
		(fp_line
			(start -0.508 -0.9398)
			(end -0.508 0.9398)
			(stroke
				(width 0.1524)
				(type default)
			)
			(layer "F.SilkS")
		)
		(fp_line
			(start 0.508 -0.9398)
			(end -0.508 -0.9398)
			(stroke
				(width 0.1524)
				(type default)
			)
			(layer "F.SilkS")
		)
		(fp_rect
			(start -0.508 0.9398)
			(end 0.508 -0.9398)
			(stroke
				(width 0)
				(type default)
			)
			(fill no)
			(layer "F.CrtYd")
		)
		(fp_rect
			(start -0.508 0.9398)
			(end 0.508 -0.9398)
			(stroke
				(width 0)
				(type default)
			)
			(fill no)
			(layer "F.Fab")
		)
		(pad "1" smd custom
			(at 0 -0.4445)
			(size 0.1397 0.1397)
			(layers "F.Cu" "F.Mask" "F.Paste")
			(net "GND")
			(options
				(clearance outline)
				(anchor circle)
			)
			(primitives
				(gr_poly
					(pts
						(arc
							(start -0.1778 -0.2794)
							(mid -0.249642 -0.249642)
							(end -0.2794 -0.1778)
						)
						(arc
							(start -0.2794 0.1778)
							(mid -0.249642 0.249642)
							(end -0.1778 0.2794)
						)
						(arc
							(start 0.1778 0.2794)
							(mid 0.249642 0.249642)
							(end 0.2794 0.1778)
						)
						(arc
							(start 0.2794 -0.1778)
							(mid 0.249642 -0.249642)
							(end 0.1778 -0.2794)
						)
					)
					(width 0)
					(fill yes)
				)
			)
		)
		(pad "2" smd custom
			(at 0 0.4445)
			(size 0.1397 0.1397)
			(layers "F.Cu" "F.Mask" "F.Paste")
			(net "BOOTSTRAP4")
			(options
				(clearance outline)
				(anchor circle)
			)
			(primitives
				(gr_poly
					(pts
						(arc
							(start -0.1778 -0.2794)
							(mid -0.249642 -0.249642)
							(end -0.2794 -0.1778)
						)
						(arc
							(start -0.2794 0.1778)
							(mid -0.249642 0.249642)
							(end -0.1778 0.2794)
						)
						(arc
							(start 0.1778 0.2794)
							(mid 0.249642 0.249642)
							(end 0.2794 0.1778)
						)
						(arc
							(start 0.2794 -0.1778)
							(mid 0.249642 -0.249642)
							(end 0.1778 -0.2794)
						)
					)
					(width 0)
					(fill yes)
				)
			)
		)
	)
	(footprint ""
		(layer "F.Cu")
		(at 330.48448 -45.362622)
		(property "Reference" "SW5"
			(at 0 0 0)
			(layer "F.SilkS")
			(hide yes)
			(effects
				(font
					(size 1.27 1.27)
				)
			)
		)
		(property "Value" "PUSH-SW132-GP"
			(at -4.9657 -6.1341 0)
			(unlocked yes)
			(layer "F.Fab")
			(hide yes)
			(effects
				(font
					(size 1.016 1.016)
					(thickness 0.1524)
				)
			)
		)
		(property "Device Type" "PTCFGP2-Q-TR"
			(at -4.9657 -7.6581 0)
			(unlocked yes)
			(layer "F.Fab")
			(hide yes)
			(effects
				(font
					(size 1.016 1.016)
					(thickness 0.1524)
				)
			)
		)
		(duplicate_pad_numbers_are_jumpers no)
		(fp_line
			(start -3.6576 -0.6604)
			(end -3.6576 -1.0414)
			(stroke
				(width 0.3302)
				(type default)
			)
			(layer "F.SilkS")
		)
		(fp_line
			(start -3.556 -2.0066)
			(end 3.556 -2.0066)
			(stroke
				(width 0.1524)
				(type default)
			)
			(layer "F.SilkS")
		)
		(fp_line
			(start -3.556 2.0066)
			(end -3.556 -2.0066)
			(stroke
				(width 0.1524)
				(type default)
			)
			(layer "F.SilkS")
		)
		(fp_line
			(start 1.4986 2.0066)
			(end -3.556 2.0066)
			(stroke
				(width 0.1524)
				(type default)
			)
			(layer "F.SilkS")
		)
		(fp_line
			(start 1.4986 2.7686)
			(end 1.4986 2.0066)
			(stroke
				(width 0.1524)
				(type default)
			)
			(layer "F.SilkS")
		)
		(fp_line
			(start 2.7178 1.6002)
			(end 2.7178 2.7686)
			(stroke
				(width 0.1524)
				(type default)
			)
			(layer "F.SilkS")
		)
		(fp_line
			(start 2.7178 2.7686)
			(end 1.4986 2.7686)
			(stroke
				(width 0.1524)
				(type default)
			)
			(layer "F.SilkS")
		)
		(fp_line
			(start 3.556 -2.0066)
			(end 3.556 1.6002)
			(stroke
				(width 0.1524)
				(type default)
			)
			(layer "F.SilkS")
		)
		(fp_line
			(start 3.556 1.6002)
			(end 2.7178 1.6002)
			(stroke
				(width 0.1524)
				(type default)
			)
			(layer "F.SilkS")
		)
		(fp_poly
			(pts
				(xy -4.2545 -0.2159) (xy -4.2545 -1.4859) (xy -3.6195 -0.8509)
			)
			(stroke
				(width 0)
				(type default)
			)
			(fill yes)
			(layer "F.SilkS")
		)
		(fp_poly
			(pts
				(xy 1.7526 2.2606) (xy 1.7526 1.7526) (xy -2.3495 1.7526) (xy -2.3495 1.1049) (xy -2.9464 1.1049)
				(xy -2.9464 -1.1049) (xy -2.3495 -1.1049) (xy -2.3495 -1.7526) (xy 2.3495 -1.7526) (xy 2.3495 -1.1049)
				(xy 2.9464 -1.1049) (xy 2.9464 1.1049) (xy 2.3495 1.1049) (xy 2.3495 2.2606)
			)
			(stroke
				(width 0)
				(type default)
			)
			(fill no)
			(layer "F.CrtYd")
		)
		(fp_poly
			(pts
				(xy 1.2446 3.0226) (xy 1.2446 2.2606) (xy -3.81 2.2606) (xy -3.81 -2.2606) (xy -1.4097 -2.2606)
				(xy -1.4097 -1.752854) (xy -2.349754 -1.752854) (xy -2.349754 -1.105154) (xy -2.946654 -1.105154)
				(xy -2.946654 1.105154) (xy -2.349754 1.105154) (xy -2.349754 1.752854) (xy 1.752346 1.752854) (xy 1.752346 2.2606)
				(xy 2.349754 2.2606) (xy 2.349754 1.105154) (xy 2.946654 1.105154) (xy 2.946654 -1.105154) (xy 2.349754 -1.105154)
				(xy 2.349754 -1.752854) (xy -1.397 -1.752854) (xy -1.397 -2.2606) (xy 3.81 -2.2606) (xy 3.81 1.8542)
				(xy 2.9718 1.8542) (xy 2.9718 3.0226)
			)
			(stroke
				(width 0)
				(type default)
			)
			(fill no)
			(layer "F.CrtYd")
		)
		(fp_poly
			(pts
				(xy 1.2446 3.0226) (xy 1.2446 2.2606) (xy -3.81 2.2606) (xy -3.81 -2.2606) (xy 3.81 -2.2606) (xy 3.81 1.8542)
				(xy 2.9718 1.8542) (xy 2.9718 3.0226)
			)
			(stroke
				(width 0)
				(type default)
			)
			(fill no)
			(layer "F.Fab")
		)
		(pad "" np_thru_hole circle
			(at 0 -1.35001)
			(size 0.254 0.254)
			(drill 0.8128)
			(layers "*.Cu" "*.Mask")
			(clearance 0.635)
			(thermal_gap 0.635)
		)
		(pad "" np_thru_hole circle
			(at 0 1.35001)
			(size 0.254 0.254)
			(drill 0.8128)
			(layers "*.Cu" "*.Mask")
			(clearance 0.635)
			(thermal_gap 0.635)
		)
		(pad "1" smd rect
			(at -2.576068 -0.85471)
			(size 1.4478 0.9906)
			(layers "F.Cu" "F.Mask" "F.Paste")
			(net "GND")
		)
		(pad "2" smd rect
			(at -2.576068 0.85471)
			(size 1.4478 0.9906)
			(layers "F.Cu" "F.Mask" "F.Paste")
			(net "SHUTDOWN_RELEASE")
		)
		(pad "3" smd rect
			(at 2.576068 -0.85471)
			(size 1.4478 0.9906)
			(layers "F.Cu" "F.Mask" "F.Paste")
			(net "GND")
		)
		(pad "4" smd rect
			(at 2.576068 0.85471)
			(size 1.4478 0.9906)
			(layers "F.Cu" "F.Mask" "F.Paste")
			(net "SHUTDOWN_RELEASE")
		)
		(pad "5" smd rect
			(at 2.10566 2.13106)
			(size 0.7112 0.762)
			(layers "F.Cu" "F.Mask" "F.Paste")
			(net "Net_2109")
		)
		(zone
			(layers "F.Cu" "B.Cu" "In1.Cu" "In2.Cu" "In3.Cu" "In4.Cu" "In5.Cu" "In6.Cu")
			(hatch none 0.5)
			(connect_pads
				(clearance 0)
			)
			(min_thickness 0.25)
			(keepout
				(tracks not_allowed)
				(vias allowed)
				(pads allowed)
				(copperpour not_allowed)
				(footprints allowed)
			)
			(placement
				(enabled no)
				(sheetname "")
			)
			(fill
				(thermal_gap 0.5)
				(thermal_bridge_width 0.5)
				(island_removal_mode 0)
			)
			(polygon
				(pts
					(arc
						(start 331.19568 -46.712632)
						(mid 329.77328 -46.712632)
						(end 331.19568 -46.712632)
					)
				)
			)
		)
		(zone
			(layers "F.Cu" "B.Cu" "In1.Cu" "In2.Cu" "In3.Cu" "In4.Cu" "In5.Cu" "In6.Cu")
			(hatch none 0.5)
			(connect_pads
				(clearance 0)
			)
			(min_thickness 0.25)
			(keepout
				(tracks not_allowed)
				(vias allowed)
				(pads allowed)
				(copperpour not_allowed)
				(footprints allowed)
			)
			(placement
				(enabled no)
				(sheetname "")
			)
			(fill
				(thermal_gap 0.5)
				(thermal_bridge_width 0.5)
				(island_removal_mode 0)
			)
			(polygon
				(pts
					(arc
						(start 331.19568 -44.012612)
						(mid 329.77328 -44.012612)
						(end 331.19568 -44.012612)
					)
				)
			)
		)
	)
	(footprint ""
		(layer "F.Cu")
		(at 115.7732 -24.6888 180)
		(property "Reference" "R56"
			(at 0 0 180)
			(layer "F.SilkS")
			(hide yes)
			(effects
				(font
					(size 1.27 1.27)
				)
			)
		)
		(property "Value" "0R2J-2-GP"
			(at 0.064008 -3.993896 180)
			(unlocked yes)
			(layer "F.Fab")
			(hide yes)
			(effects
				(font
					(size 1.016 1.016)
					(thickness 0.1524)
				)
			)
		)
		(property "Device Type" "R402H16"
			(at 0.064008 -5.517896 180)
			(unlocked yes)
			(layer "F.Fab")
			(hide yes)
			(effects
				(font
					(size 1.016 1.016)
					(thickness 0.1524)
				)
			)
		)
		(duplicate_pad_numbers_are_jumpers no)
		(fp_line
			(start 0.508 -0.9398)
			(end -0.508 -0.9398)
			(stroke
				(width 0.1524)
				(type default)
			)
			(layer "F.SilkS")
		)
		(fp_line
			(start -0.508 -0.9398)
			(end -0.508 0.9398)
			(stroke
				(width 0.1524)
				(type default)
			)
			(layer "F.SilkS")
		)
		(fp_rect
			(start -0.508 0.9398)
			(end 0.508 -0.9398)
			(stroke
				(width 0)
				(type default)
			)
			(fill no)
			(layer "F.CrtYd")
		)
		(fp_rect
			(start -0.508 0.9398)
			(end 0.508 -0.9398)
			(stroke
				(width 0)
				(type default)
			)
			(fill no)
			(layer "F.Fab")
		)
		(pad "1" smd custom
			(at 0 -0.4445 180)
			(size 0.1397 0.1397)
			(layers "F.Cu" "F.Mask" "F.Paste")
			(net "U54_P0")
			(options
				(clearance outline)
				(anchor circle)
			)
			(primitives
				(gr_poly
					(pts
						(arc
							(start -0.1778 -0.2794)
							(mid -0.249642 -0.249642)
							(end -0.2794 -0.1778)
						)
						(arc
							(start -0.2794 0.1778)
							(mid -0.249642 0.249642)
							(end -0.1778 0.2794)
						)
						(arc
							(start 0.1778 0.2794)
							(mid 0.249642 0.249642)
							(end 0.2794 0.1778)
						)
						(arc
							(start 0.2794 -0.1778)
							(mid 0.249642 -0.249642)
							(end 0.1778 -0.2794)
						)
					)
					(width 0)
					(fill yes)
				)
			)
		)
		(pad "2" smd custom
			(at 0 0.4445 180)
			(size 0.1397 0.1397)
			(layers "F.Cu" "F.Mask" "F.Paste")
			(net "HOST_I2C_RESET_N")
			(options
				(clearance outline)
				(anchor circle)
			)
			(primitives
				(gr_poly
					(pts
						(arc
							(start -0.1778 -0.2794)
							(mid -0.249642 -0.249642)
							(end -0.2794 -0.1778)
						)
						(arc
							(start -0.2794 0.1778)
							(mid -0.249642 0.249642)
							(end -0.1778 0.2794)
						)
						(arc
							(start 0.1778 0.2794)
							(mid 0.249642 0.249642)
							(end 0.2794 0.1778)
						)
						(arc
							(start 0.2794 -0.1778)
							(mid 0.249642 -0.249642)
							(end 0.1778 -0.2794)
						)
					)
					(width 0)
					(fill yes)
				)
			)
		)
	)
	(footprint ""
		(layer "F.Cu")
		(at 273.678904 -4.639564 90)
		(property "Reference" "R222"
			(at 0 0 90)
			(layer "F.SilkS")
			(hide yes)
			(effects
				(font
					(size 1.27 1.27)
				)
			)
		)
		(property "Value" "4K7R2F-GP"
			(at 0.064008 -3.993896 90)
			(unlocked yes)
			(layer "F.Fab")
			(hide yes)
			(effects
				(font
					(size 1.016 1.016)
					(thickness 0.1524)
				)
			)
		)
		(property "Device Type" "R402H16"
			(at 0.064008 -5.517896 90)
			(unlocked yes)
			(layer "F.Fab")
			(hide yes)
			(effects
				(font
					(size 1.016 1.016)
					(thickness 0.1524)
				)
			)
		)
		(duplicate_pad_numbers_are_jumpers no)
		(fp_line
			(start 0.508 -0.9398)
			(end -0.508 -0.9398)
			(stroke
				(width 0.1524)
				(type default)
			)
			(layer "F.SilkS")
		)
		(fp_line
			(start -0.508 -0.9398)
			(end -0.508 0.9398)
			(stroke
				(width 0.1524)
				(type default)
			)
			(layer "F.SilkS")
		)
		(fp_rect
			(start -0.508 0.9398)
			(end 0.508 -0.9398)
			(stroke
				(width 0)
				(type default)
			)
			(fill no)
			(layer "F.CrtYd")
		)
		(fp_rect
			(start -0.508 0.9398)
			(end 0.508 -0.9398)
			(stroke
				(width 0)
				(type default)
			)
			(fill no)
			(layer "F.Fab")
		)
		(pad "1" smd custom
			(at 0 -0.4445 90)
			(size 0.1397 0.1397)
			(layers "F.Cu" "F.Mask" "F.Paste")
			(net "P3V3_STBY")
			(options
				(clearance outline)
				(anchor circle)
			)
			(primitives
				(gr_poly
					(pts
						(arc
							(start -0.1778 -0.2794)
							(mid -0.249642 -0.249642)
							(end -0.2794 -0.1778)
						)
						(arc
							(start -0.2794 0.1778)
							(mid -0.249642 0.249642)
							(end -0.1778 0.2794)
						)
						(arc
							(start 0.1778 0.2794)
							(mid 0.249642 0.249642)
							(end 0.2794 0.1778)
						)
						(arc
							(start 0.2794 -0.1778)
							(mid 0.249642 -0.249642)
							(end 0.1778 -0.2794)
						)
					)
					(width 0)
					(fill yes)
				)
			)
		)
		(pad "2" smd custom
			(at 0 0.4445 90)
			(size 0.1397 0.1397)
			(layers "F.Cu" "F.Mask" "F.Paste")
			(net "CLK_P_6_R")
			(options
				(clearance outline)
				(anchor circle)
			)
			(primitives
				(gr_poly
					(pts
						(arc
							(start -0.1778 -0.2794)
							(mid -0.249642 -0.249642)
							(end -0.2794 -0.1778)
						)
						(arc
							(start -0.2794 0.1778)
							(mid -0.249642 0.249642)
							(end -0.1778 0.2794)
						)
						(arc
							(start 0.1778 0.2794)
							(mid 0.249642 0.249642)
							(end 0.2794 0.1778)
						)
						(arc
							(start 0.2794 -0.1778)
							(mid 0.249642 -0.249642)
							(end 0.1778 -0.2794)
						)
					)
					(width 0)
					(fill yes)
				)
			)
		)
	)
	(footprint ""
		(layer "F.Cu")
		(at 134.932928 -59.746896 180)
		(property "Reference" "R651"
			(at 0 0 180)
			(layer "F.SilkS")
			(hide yes)
			(effects
				(font
					(size 1.27 1.27)
				)
			)
		)
		(property "Value" "100KR2F-L1-GP"
			(at 0.064008 -3.993896 180)
			(unlocked yes)
			(layer "F.Fab")
			(hide yes)
			(effects
				(font
					(size 1.016 1.016)
					(thickness 0.1524)
				)
			)
		)
		(property "Device Type" "R402H16"
			(at 0.064008 -5.517896 180)
			(unlocked yes)
			(layer "F.Fab")
			(hide yes)
			(effects
				(font
					(size 1.016 1.016)
					(thickness 0.1524)
				)
			)
		)
		(duplicate_pad_numbers_are_jumpers no)
		(fp_line
			(start 0.508 -0.9398)
			(end -0.508 -0.9398)
			(stroke
				(width 0.1524)
				(type default)
			)
			(layer "F.SilkS")
		)
		(fp_line
			(start -0.508 -0.9398)
			(end -0.508 0.9398)
			(stroke
				(width 0.1524)
				(type default)
			)
			(layer "F.SilkS")
		)
		(fp_rect
			(start -0.508 0.9398)
			(end 0.508 -0.9398)
			(stroke
				(width 0)
				(type default)
			)
			(fill no)
			(layer "F.CrtYd")
		)
		(fp_rect
			(start -0.508 0.9398)
			(end 0.508 -0.9398)
			(stroke
				(width 0)
				(type default)
			)
			(fill no)
			(layer "F.Fab")
		)
		(pad "1" smd custom
			(at 0 -0.4445 180)
			(size 0.1397 0.1397)
			(layers "F.Cu" "F.Mask" "F.Paste")
			(net "DUT_VDDO")
			(options
				(clearance outline)
				(anchor circle)
			)
			(primitives
				(gr_poly
					(pts
						(arc
							(start -0.1778 -0.2794)
							(mid -0.249642 -0.249642)
							(end -0.2794 -0.1778)
						)
						(arc
							(start -0.2794 0.1778)
							(mid -0.249642 0.249642)
							(end -0.1778 0.2794)
						)
						(arc
							(start 0.1778 0.2794)
							(mid 0.249642 0.249642)
							(end 0.2794 0.1778)
						)
						(arc
							(start 0.2794 -0.1778)
							(mid 0.249642 -0.249642)
							(end 0.1778 -0.2794)
						)
					)
					(width 0)
					(fill yes)
				)
			)
		)
		(pad "2" smd custom
			(at 0 0.4445 180)
			(size 0.1397 0.1397)
			(layers "F.Cu" "F.Mask" "F.Paste")
			(net "SPI_DATA0_2_R")
			(options
				(clearance outline)
				(anchor circle)
			)
			(primitives
				(gr_poly
					(pts
						(arc
							(start -0.1778 -0.2794)
							(mid -0.249642 -0.249642)
							(end -0.2794 -0.1778)
						)
						(arc
							(start -0.2794 0.1778)
							(mid -0.249642 0.249642)
							(end -0.1778 0.2794)
						)
						(arc
							(start 0.1778 0.2794)
							(mid 0.249642 0.249642)
							(end 0.2794 0.1778)
						)
						(arc
							(start 0.2794 -0.1778)
							(mid 0.249642 -0.249642)
							(end 0.1778 -0.2794)
						)
					)
					(width 0)
					(fill yes)
				)
			)
		)
	)
	(footprint ""
		(layer "F.Cu")
		(at 18.415 -128.651 -90)
		(property "Reference" "R230"
			(at 0 0 270)
			(layer "F.SilkS")
			(hide yes)
			(effects
				(font
					(size 1.27 1.27)
				)
			)
		)
		(property "Value" "4K7R2F-GP"
			(at 0.064008 -3.993896 270)
			(unlocked yes)
			(layer "F.Fab")
			(hide yes)
			(effects
				(font
					(size 1.016 1.016)
					(thickness 0.1524)
				)
			)
		)
		(property "Device Type" "R402H16"
			(at 0.064008 -5.517896 270)
			(unlocked yes)
			(layer "F.Fab")
			(hide yes)
			(effects
				(font
					(size 1.016 1.016)
					(thickness 0.1524)
				)
			)
		)
		(duplicate_pad_numbers_are_jumpers no)
		(fp_line
			(start -0.508 -0.9398)
			(end -0.508 0.9398)
			(stroke
				(width 0.1524)
				(type default)
			)
			(layer "F.SilkS")
		)
		(fp_line
			(start 0.508 -0.9398)
			(end -0.508 -0.9398)
			(stroke
				(width 0.1524)
				(type default)
			)
			(layer "F.SilkS")
		)
		(fp_rect
			(start -0.508 0.9398)
			(end 0.508 -0.9398)
			(stroke
				(width 0)
				(type default)
			)
			(fill no)
			(layer "F.CrtYd")
		)
		(fp_rect
			(start -0.508 0.9398)
			(end 0.508 -0.9398)
			(stroke
				(width 0)
				(type default)
			)
			(fill no)
			(layer "F.Fab")
		)
		(pad "1" smd custom
			(at 0 -0.4445 270)
			(size 0.1397 0.1397)
			(layers "F.Cu" "F.Mask" "F.Paste")
			(net "GND")
			(options
				(clearance outline)
				(anchor circle)
			)
			(primitives
				(gr_poly
					(pts
						(arc
							(start -0.1778 -0.2794)
							(mid -0.249642 -0.249642)
							(end -0.2794 -0.1778)
						)
						(arc
							(start -0.2794 0.1778)
							(mid -0.249642 0.249642)
							(end -0.1778 0.2794)
						)
						(arc
							(start 0.1778 0.2794)
							(mid 0.249642 0.249642)
							(end 0.2794 0.1778)
						)
						(arc
							(start 0.2794 -0.1778)
							(mid 0.249642 -0.249642)
							(end 0.1778 -0.2794)
						)
					)
					(width 0)
					(fill yes)
				)
			)
		)
		(pad "2" smd custom
			(at 0 0.4445 270)
			(size 0.1397 0.1397)
			(layers "F.Cu" "F.Mask" "F.Paste")
			(net "BMC_PERST#_R")
			(options
				(clearance outline)
				(anchor circle)
			)
			(primitives
				(gr_poly
					(pts
						(arc
							(start -0.1778 -0.2794)
							(mid -0.249642 -0.249642)
							(end -0.2794 -0.1778)
						)
						(arc
							(start -0.2794 0.1778)
							(mid -0.249642 0.249642)
							(end -0.1778 0.2794)
						)
						(arc
							(start 0.1778 0.2794)
							(mid 0.249642 0.249642)
							(end 0.2794 0.1778)
						)
						(arc
							(start 0.2794 -0.1778)
							(mid 0.249642 -0.249642)
							(end 0.1778 -0.2794)
						)
					)
					(width 0)
					(fill yes)
				)
			)
		)
	)
	(footprint ""
		(layer "F.Cu")
		(at 324.45071 -33.482788)
		(property "Reference" "C49"
			(at 0 0 0)
			(layer "F.SilkS")
			(hide yes)
			(effects
				(font
					(size 1.27 1.27)
				)
			)
		)
		(property "Value" "SCD22U10V2KX-1GP"
			(at 1.1811 -2.7051 0)
			(unlocked yes)
			(layer "F.Fab")
			(hide yes)
			(effects
				(font
					(size 1.016 1.016)
					(thickness 0.1524)
				)
			)
		)
		(property "Device Type" "C402H22"
			(at 1.1811 -4.2291 0)
			(unlocked yes)
			(layer "F.Fab")
			(hide yes)
			(effects
				(font
					(size 1.016 1.016)
					(thickness 0.1524)
				)
			)
		)
		(duplicate_pad_numbers_are_jumpers no)
		(fp_rect
			(start -0.4318 0.9525)
			(end 0.4318 -0.9525)
			(stroke
				(width 0)
				(type default)
			)
			(fill no)
			(layer "F.CrtYd")
		)
		(fp_rect
			(start -0.4318 0.9525)
			(end 0.4318 -0.9525)
			(stroke
				(width 0)
				(type default)
			)
			(fill no)
			(layer "F.Fab")
		)
		(pad "1" smd custom
			(at 0 -0.4445)
			(size 0.1524 0.1524)
			(layers "F.Cu" "F.Mask" "F.Paste")
			(net "PCIE_TX_CAP_N13")
			(options
				(clearance outline)
				(anchor circle)
			)
			(primitives
				(gr_poly
					(pts
						(arc
							(start 0.3048 -0.2032)
							(mid 0.275042 -0.275042)
							(end 0.2032 -0.3048)
						)
						(arc
							(start -0.2032 -0.3048)
							(mid -0.275042 -0.275042)
							(end -0.3048 -0.2032)
						)
						(arc
							(start -0.3048 0.2032)
							(mid -0.275042 0.275042)
							(end -0.2032 0.3048)
						)
						(arc
							(start 0.2032 0.3048)
							(mid 0.275042 0.275042)
							(end 0.3048 0.2032)
						)
					)
					(width 0)
					(fill yes)
				)
			)
		)
		(pad "2" smd custom
			(at 0 0.4445)
			(size 0.1524 0.1524)
			(layers "F.Cu" "F.Mask" "F.Paste")
			(net "PCIE_TX_N13")
			(options
				(clearance outline)
				(anchor circle)
			)
			(primitives
				(gr_poly
					(pts
						(arc
							(start 0.3048 -0.2032)
							(mid 0.275042 -0.275042)
							(end 0.2032 -0.3048)
						)
						(arc
							(start -0.2032 -0.3048)
							(mid -0.275042 -0.275042)
							(end -0.3048 -0.2032)
						)
						(arc
							(start -0.3048 0.2032)
							(mid -0.275042 0.275042)
							(end -0.2032 0.3048)
						)
						(arc
							(start 0.2032 0.3048)
							(mid 0.275042 0.275042)
							(end 0.3048 0.2032)
						)
					)
					(width 0)
					(fill yes)
				)
			)
		)
	)
	(footprint ""
		(layer "F.Cu")
		(at 20.6502 -188.1886 -90)
		(property "Reference" "R2098"
			(at 0 0 270)
			(layer "F.SilkS")
			(hide yes)
			(effects
				(font
					(size 1.27 1.27)
				)
			)
		)
		(property "Value" "10R2F-L-GP"
			(at 0.064008 -3.993896 270)
			(unlocked yes)
			(layer "F.Fab")
			(hide yes)
			(effects
				(font
					(size 1.016 1.016)
					(thickness 0.1524)
				)
			)
		)
		(property "Device Type" "R402H14"
			(at 0.064008 -5.517896 270)
			(unlocked yes)
			(layer "F.Fab")
			(hide yes)
			(effects
				(font
					(size 1.016 1.016)
					(thickness 0.1524)
				)
			)
		)
		(duplicate_pad_numbers_are_jumpers no)
		(fp_line
			(start -0.508 -0.9398)
			(end -0.508 0.9398)
			(stroke
				(width 0.1524)
				(type default)
			)
			(layer "F.SilkS")
		)
		(fp_line
			(start 0.508 -0.9398)
			(end -0.508 -0.9398)
			(stroke
				(width 0.1524)
				(type default)
			)
			(layer "F.SilkS")
		)
		(fp_rect
			(start -0.508 0.9398)
			(end 0.508 -0.9398)
			(stroke
				(width 0)
				(type default)
			)
			(fill no)
			(layer "F.CrtYd")
		)
		(fp_rect
			(start -0.508 0.9398)
			(end 0.508 -0.9398)
			(stroke
				(width 0)
				(type default)
			)
			(fill no)
			(layer "F.Fab")
		)
		(pad "1" smd custom
			(at 0 -0.4445 270)
			(size 0.1397 0.1397)
			(layers "F.Cu" "F.Mask" "F.Paste")
			(net "P12V_PCIE")
			(options
				(clearance outline)
				(anchor circle)
			)
			(primitives
				(gr_poly
					(pts
						(arc
							(start -0.1778 -0.2794)
							(mid -0.249642 -0.249642)
							(end -0.2794 -0.1778)
						)
						(arc
							(start -0.2794 0.1778)
							(mid -0.249642 0.249642)
							(end -0.1778 0.2794)
						)
						(arc
							(start 0.1778 0.2794)
							(mid 0.249642 0.249642)
							(end 0.2794 0.1778)
						)
						(arc
							(start 0.2794 -0.1778)
							(mid 0.249642 -0.249642)
							(end 0.1778 -0.2794)
						)
					)
					(width 0)
					(fill yes)
				)
			)
		)
		(pad "2" smd custom
			(at 0 0.4445 270)
			(size 0.1397 0.1397)
			(layers "F.Cu" "F.Mask" "F.Paste")
			(net "MB0_VCC")
			(options
				(clearance outline)
				(anchor circle)
			)
			(primitives
				(gr_poly
					(pts
						(arc
							(start -0.1778 -0.2794)
							(mid -0.249642 -0.249642)
							(end -0.2794 -0.1778)
						)
						(arc
							(start -0.2794 0.1778)
							(mid -0.249642 0.249642)
							(end -0.1778 0.2794)
						)
						(arc
							(start 0.1778 0.2794)
							(mid 0.249642 0.249642)
							(end 0.2794 0.1778)
						)
						(arc
							(start 0.2794 -0.1778)
							(mid 0.249642 -0.249642)
							(end 0.1778 -0.2794)
						)
					)
					(width 0)
					(fill yes)
				)
			)
		)
	)
	(footprint ""
		(layer "F.Cu")
		(at 181.61 -28.956 -90)
		(property "Reference" "C402"
			(at 0 0 270)
			(layer "F.SilkS")
			(hide yes)
			(effects
				(font
					(size 1.27 1.27)
				)
			)
		)
		(property "Value" "SCD22U10V2KX-1GP"
			(at 1.1811 -2.7051 270)
			(unlocked yes)
			(layer "F.Fab")
			(hide yes)
			(effects
				(font
					(size 1.016 1.016)
					(thickness 0.1524)
				)
			)
		)
		(property "Device Type" "C402H22"
			(at 1.1811 -4.2291 270)
			(unlocked yes)
			(layer "F.Fab")
			(hide yes)
			(effects
				(font
					(size 1.016 1.016)
					(thickness 0.1524)
				)
			)
		)
		(duplicate_pad_numbers_are_jumpers no)
		(fp_rect
			(start -0.4318 0.9525)
			(end 0.4318 -0.9525)
			(stroke
				(width 0)
				(type default)
			)
			(fill no)
			(layer "F.CrtYd")
		)
		(fp_rect
			(start -0.4318 0.9525)
			(end 0.4318 -0.9525)
			(stroke
				(width 0)
				(type default)
			)
			(fill no)
			(layer "F.Fab")
		)
		(pad "1" smd custom
			(at 0 -0.4445 270)
			(size 0.1524 0.1524)
			(layers "F.Cu" "F.Mask" "F.Paste")
			(net "PCIE_TX_CAP_N91")
			(options
				(clearance outline)
				(anchor circle)
			)
			(primitives
				(gr_poly
					(pts
						(arc
							(start 0.3048 -0.2032)
							(mid 0.275042 -0.275042)
							(end 0.2032 -0.3048)
						)
						(arc
							(start -0.2032 -0.3048)
							(mid -0.275042 -0.275042)
							(end -0.3048 -0.2032)
						)
						(arc
							(start -0.3048 0.2032)
							(mid -0.275042 0.275042)
							(end -0.2032 0.3048)
						)
						(arc
							(start 0.2032 0.3048)
							(mid 0.275042 0.275042)
							(end 0.3048 0.2032)
						)
					)
					(width 0)
					(fill yes)
				)
			)
		)
		(pad "2" smd custom
			(at 0 0.4445 270)
			(size 0.1524 0.1524)
			(layers "F.Cu" "F.Mask" "F.Paste")
			(net "PCIE_TX_N91")
			(options
				(clearance outline)
				(anchor circle)
			)
			(primitives
				(gr_poly
					(pts
						(arc
							(start 0.3048 -0.2032)
							(mid 0.275042 -0.275042)
							(end 0.2032 -0.3048)
						)
						(arc
							(start -0.2032 -0.3048)
							(mid -0.275042 -0.275042)
							(end -0.3048 -0.2032)
						)
						(arc
							(start -0.3048 0.2032)
							(mid -0.275042 0.275042)
							(end -0.2032 0.3048)
						)
						(arc
							(start 0.2032 0.3048)
							(mid 0.275042 0.275042)
							(end 0.3048 0.2032)
						)
					)
					(width 0)
					(fill yes)
				)
			)
		)
	)
	(footprint ""
		(layer "F.Cu")
		(at 107.592114 -212.420454 180)
		(property "Reference" "C147"
			(at 0 0 180)
			(layer "F.SilkS")
			(hide yes)
			(effects
				(font
					(size 1.27 1.27)
				)
			)
		)
		(property "Value" "SCD22U10V2KX-1GP"
			(at 1.1811 -2.7051 180)
			(unlocked yes)
			(layer "F.Fab")
			(hide yes)
			(effects
				(font
					(size 1.016 1.016)
					(thickness 0.1524)
				)
			)
		)
		(property "Device Type" "C402H22"
			(at 1.1811 -4.2291 180)
			(unlocked yes)
			(layer "F.Fab")
			(hide yes)
			(effects
				(font
					(size 1.016 1.016)
					(thickness 0.1524)
				)
			)
		)
		(duplicate_pad_numbers_are_jumpers no)
		(fp_rect
			(start -0.4318 0.9525)
			(end 0.4318 -0.9525)
			(stroke
				(width 0)
				(type default)
			)
			(fill no)
			(layer "F.CrtYd")
		)
		(fp_rect
			(start -0.4318 0.9525)
			(end 0.4318 -0.9525)
			(stroke
				(width 0)
				(type default)
			)
			(fill no)
			(layer "F.Fab")
		)
		(pad "1" smd custom
			(at 0 -0.4445 180)
			(size 0.1524 0.1524)
			(layers "F.Cu" "F.Mask" "F.Paste")
			(net "PCIE_TX_CAP_P60")
			(options
				(clearance outline)
				(anchor circle)
			)
			(primitives
				(gr_poly
					(pts
						(arc
							(start 0.3048 -0.2032)
							(mid 0.275042 -0.275042)
							(end 0.2032 -0.3048)
						)
						(arc
							(start -0.2032 -0.3048)
							(mid -0.275042 -0.275042)
							(end -0.3048 -0.2032)
						)
						(arc
							(start -0.3048 0.2032)
							(mid -0.275042 0.275042)
							(end -0.2032 0.3048)
						)
						(arc
							(start 0.2032 0.3048)
							(mid 0.275042 0.275042)
							(end 0.3048 0.2032)
						)
					)
					(width 0)
					(fill yes)
				)
			)
		)
		(pad "2" smd custom
			(at 0 0.4445 180)
			(size 0.1524 0.1524)
			(layers "F.Cu" "F.Mask" "F.Paste")
			(net "PCIE_TX_P60")
			(options
				(clearance outline)
				(anchor circle)
			)
			(primitives
				(gr_poly
					(pts
						(arc
							(start 0.3048 -0.2032)
							(mid 0.275042 -0.275042)
							(end 0.2032 -0.3048)
						)
						(arc
							(start -0.2032 -0.3048)
							(mid -0.275042 -0.275042)
							(end -0.3048 -0.2032)
						)
						(arc
							(start -0.3048 0.2032)
							(mid -0.275042 0.275042)
							(end -0.2032 0.3048)
						)
						(arc
							(start 0.2032 0.3048)
							(mid 0.275042 0.275042)
							(end 0.3048 0.2032)
						)
					)
					(width 0)
					(fill yes)
				)
			)
		)
	)
	(footprint ""
		(layer "F.Cu")
		(at 230.251 -80.391)
		(property "Reference" "TP171"
			(at 0 0 0)
			(layer "F.SilkS")
			(hide yes)
			(effects
				(font
					(size 1.27 1.27)
				)
			)
		)
		(property "Value" "TPAD32-GP"
			(at -0.0508 -1.6764 0)
			(unlocked yes)
			(layer "F.Fab")
			(hide yes)
			(effects
				(font
					(size 1.016 1.016)
					(thickness 0.1524)
				)
			)
		)
		(property "Device Type" "TPAD32"
			(at -0.0508 -3.2004 0)
			(unlocked yes)
			(layer "F.Fab")
			(hide yes)
			(effects
				(font
					(size 1.016 1.016)
					(thickness 0.1524)
				)
			)
		)
		(duplicate_pad_numbers_are_jumpers no)
		(fp_poly
			(pts
				(arc
					(start 0.4064 0)
					(mid -0.4064 0)
					(end 0.4064 0)
				)
			)
			(stroke
				(width 0)
				(type default)
			)
			(fill no)
			(layer "F.CrtYd")
		)
		(fp_poly
			(pts
				(arc
					(start 0.7112 0)
					(mid -0.7112 0)
					(end 0.7112 0)
				)
			)
			(stroke
				(width 0)
				(type default)
			)
			(fill no)
			(layer "F.Fab")
		)
		(pad "1" smd circle
			(at 0 0)
			(size 0.8128 0.8128)
			(layers "F.Cu" "F.Mask" "F.Paste")
			(net "TEMP_3_ALERT")
		)
	)
	(footprint ""
		(layer "F.Cu")
		(at 178.1048 -66.929 180)
		(property "Reference" "PG13"
			(at 0 0 180)
			(layer "F.SilkS")
			(hide yes)
			(effects
				(font
					(size 1.27 1.27)
				)
			)
		)
		(property "Value" "GAP-CLOSE-PWR-3-GP"
			(at 0.0254 -6.5786 180)
			(unlocked yes)
			(layer "F.Fab")
			(hide yes)
			(effects
				(font
					(size 1.016 1.016)
					(thickness 0.1524)
				)
			)
		)
		(property "Device Type" "GAP-CLOSE-PWR-3"
			(at 0.0254 -8.255 180)
			(unlocked yes)
			(layer "F.Fab")
			(hide yes)
			(effects
				(font
					(size 1.016 1.016)
					(thickness 0.1524)
				)
			)
		)
		(duplicate_pad_numbers_are_jumpers no)
		(fp_rect
			(start -0.7112 0.4572)
			(end 0.7112 -0.4572)
			(stroke
				(width 0)
				(type default)
			)
			(fill no)
			(layer "F.CrtYd")
		)
		(fp_poly
			(pts
				(xy -0.7112 -0.4572) (xy 0.7112 -0.4572) (xy 0.7112 0.4572) (xy -0.7112 0.4572)
			)
			(stroke
				(width 0)
				(type default)
			)
			(fill no)
			(layer "F.Fab")
		)
		(pad "1" smd rect
			(at -0.3048 0 180)
			(size 0.6604 0.762)
			(layers "F.Cu" "F.Mask" "F.Paste")
			(net "DUT_AVD_PCIE")
		)
		(pad "2" smd rect
			(at 0.3048 0 180)
			(size 0.6604 0.762)
			(layers "F.Cu" "F.Mask" "F.Paste")
			(net "P0V9")
		)
	)
	(footprint ""
		(layer "F.Cu")
		(at 339.884512 -172.432218)
		(property "Reference" "R7969"
			(at 0 0 0)
			(layer "F.SilkS")
			(hide yes)
			(effects
				(font
					(size 1.27 1.27)
				)
			)
		)
		(property "Value" "0R2J-2-GP"
			(at 0.064008 -3.993896 0)
			(unlocked yes)
			(layer "F.Fab")
			(hide yes)
			(effects
				(font
					(size 1.016 1.016)
					(thickness 0.1524)
				)
			)
		)
		(property "Device Type" "R402H16"
			(at 0.064008 -5.517896 0)
			(unlocked yes)
			(layer "F.Fab")
			(hide yes)
			(effects
				(font
					(size 1.016 1.016)
					(thickness 0.1524)
				)
			)
		)
		(duplicate_pad_numbers_are_jumpers no)
		(fp_line
			(start -0.508 -0.9398)
			(end -0.508 0.9398)
			(stroke
				(width 0.1524)
				(type default)
			)
			(layer "F.SilkS")
		)
		(fp_line
			(start 0.508 -0.9398)
			(end -0.508 -0.9398)
			(stroke
				(width 0.1524)
				(type default)
			)
			(layer "F.SilkS")
		)
		(fp_rect
			(start -0.508 0.9398)
			(end 0.508 -0.9398)
			(stroke
				(width 0)
				(type default)
			)
			(fill no)
			(layer "F.CrtYd")
		)
		(fp_rect
			(start -0.508 0.9398)
			(end 0.508 -0.9398)
			(stroke
				(width 0)
				(type default)
			)
			(fill no)
			(layer "F.Fab")
		)
		(pad "1" smd custom
			(at 0 -0.4445)
			(size 0.1397 0.1397)
			(layers "F.Cu" "F.Mask" "F.Paste")
			(net "SSD_PERST#9")
			(options
				(clearance outline)
				(anchor circle)
			)
			(primitives
				(gr_poly
					(pts
						(arc
							(start -0.1778 -0.2794)
							(mid -0.249642 -0.249642)
							(end -0.2794 -0.1778)
						)
						(arc
							(start -0.2794 0.1778)
							(mid -0.249642 0.249642)
							(end -0.1778 0.2794)
						)
						(arc
							(start 0.1778 0.2794)
							(mid 0.249642 0.249642)
							(end 0.2794 0.1778)
						)
						(arc
							(start 0.2794 -0.1778)
							(mid 0.249642 -0.249642)
							(end 0.1778 -0.2794)
						)
					)
					(width 0)
					(fill yes)
				)
			)
		)
		(pad "2" smd custom
			(at 0 0.4445)
			(size 0.1397 0.1397)
			(layers "F.Cu" "F.Mask" "F.Paste")
			(net "SSD_PERST#9_R")
			(options
				(clearance outline)
				(anchor circle)
			)
			(primitives
				(gr_poly
					(pts
						(arc
							(start -0.1778 -0.2794)
							(mid -0.249642 -0.249642)
							(end -0.2794 -0.1778)
						)
						(arc
							(start -0.2794 0.1778)
							(mid -0.249642 0.249642)
							(end -0.1778 0.2794)
						)
						(arc
							(start 0.1778 0.2794)
							(mid 0.249642 0.249642)
							(end 0.2794 0.1778)
						)
						(arc
							(start 0.2794 -0.1778)
							(mid 0.249642 -0.249642)
							(end 0.1778 -0.2794)
						)
					)
					(width 0)
					(fill yes)
				)
			)
		)
	)
	(footprint ""
		(layer "F.Cu")
		(at 13.9446 -195.7832 -90)
		(property "Reference" "R9027"
			(at 0 0 270)
			(layer "F.SilkS")
			(hide yes)
			(effects
				(font
					(size 1.27 1.27)
				)
			)
		)
		(property "Value" "63K4R2F-2-GP"
			(at 0.064008 -3.993896 270)
			(unlocked yes)
			(layer "F.Fab")
			(hide yes)
			(effects
				(font
					(size 1.016 1.016)
					(thickness 0.1524)
				)
			)
		)
		(property "Device Type" "R402H16"
			(at 0.064008 -5.517896 270)
			(unlocked yes)
			(layer "F.Fab")
			(hide yes)
			(effects
				(font
					(size 1.016 1.016)
					(thickness 0.1524)
				)
			)
		)
		(duplicate_pad_numbers_are_jumpers no)
		(fp_line
			(start -0.508 -0.9398)
			(end -0.508 0.9398)
			(stroke
				(width 0.1524)
				(type default)
			)
			(layer "F.SilkS")
		)
		(fp_line
			(start 0.508 -0.9398)
			(end -0.508 -0.9398)
			(stroke
				(width 0.1524)
				(type default)
			)
			(layer "F.SilkS")
		)
		(fp_rect
			(start -0.508 0.9398)
			(end 0.508 -0.9398)
			(stroke
				(width 0)
				(type default)
			)
			(fill no)
			(layer "F.CrtYd")
		)
		(fp_rect
			(start -0.508 0.9398)
			(end 0.508 -0.9398)
			(stroke
				(width 0)
				(type default)
			)
			(fill no)
			(layer "F.Fab")
		)
		(pad "1" smd custom
			(at 0 -0.4445 270)
			(size 0.1397 0.1397)
			(layers "F.Cu" "F.Mask" "F.Paste")
			(net "MB0_ISET_R")
			(options
				(clearance outline)
				(anchor circle)
			)
			(primitives
				(gr_poly
					(pts
						(arc
							(start -0.1778 -0.2794)
							(mid -0.249642 -0.249642)
							(end -0.2794 -0.1778)
						)
						(arc
							(start -0.2794 0.1778)
							(mid -0.249642 0.249642)
							(end -0.1778 0.2794)
						)
						(arc
							(start 0.1778 0.2794)
							(mid 0.249642 0.249642)
							(end 0.2794 0.1778)
						)
						(arc
							(start 0.2794 -0.1778)
							(mid 0.249642 -0.249642)
							(end 0.1778 -0.2794)
						)
					)
					(width 0)
					(fill yes)
				)
			)
		)
		(pad "2" smd custom
			(at 0 0.4445 270)
			(size 0.1397 0.1397)
			(layers "F.Cu" "F.Mask" "F.Paste")
			(net "AGND_CURRENT_MON")
			(options
				(clearance outline)
				(anchor circle)
			)
			(primitives
				(gr_poly
					(pts
						(arc
							(start -0.1778 -0.2794)
							(mid -0.249642 -0.249642)
							(end -0.2794 -0.1778)
						)
						(arc
							(start -0.2794 0.1778)
							(mid -0.249642 0.249642)
							(end -0.1778 0.2794)
						)
						(arc
							(start 0.1778 0.2794)
							(mid 0.249642 0.249642)
							(end 0.2794 0.1778)
						)
						(arc
							(start 0.2794 -0.1778)
							(mid 0.249642 -0.249642)
							(end 0.1778 -0.2794)
						)
					)
					(width 0)
					(fill yes)
				)
			)
		)
	)
	(footprint ""
		(layer "F.Cu")
		(at 241.1476 -11.2014 -90)
		(property "Reference" "L1"
			(at 0 0 270)
			(layer "F.SilkS")
			(hide yes)
			(effects
				(font
					(size 1.27 1.27)
				)
			)
		)
		(property "Value" "IND-10UH-147-GP-U"
			(at -4.699 -4.0132 270)
			(unlocked yes)
			(layer "F.Fab")
			(hide yes)
			(effects
				(font
					(size 1.016 1.016)
					(thickness 0.1524)
				)
			)
		)
		(property "Device Type" "L7066-1830-UH119"
			(at -4.699 -5.5372 270)
			(unlocked yes)
			(layer "F.Fab")
			(hide yes)
			(effects
				(font
					(size 1.016 1.016)
					(thickness 0.1524)
				)
			)
		)
		(duplicate_pad_numbers_are_jumpers no)
		(fp_line
			(start -3.556 4.4958)
			(end -3.556 -4.4958)
			(stroke
				(width 0.1524)
				(type default)
			)
			(layer "F.SilkS")
		)
		(fp_line
			(start 3.556 4.4958)
			(end -3.556 4.4958)
			(stroke
				(width 0.1524)
				(type default)
			)
			(layer "F.SilkS")
		)
		(fp_line
			(start -3.556 -4.4958)
			(end 3.556 -4.4958)
			(stroke
				(width 0.1524)
				(type default)
			)
			(layer "F.SilkS")
		)
		(fp_line
			(start 3.556 -4.4958)
			(end 3.556 4.4958)
			(stroke
				(width 0.1524)
				(type default)
			)
			(layer "F.SilkS")
		)
		(fp_rect
			(start -3.302 3.4798)
			(end 3.302 -3.4798)
			(stroke
				(width 0)
				(type default)
			)
			(fill no)
			(layer "F.CrtYd")
		)
		(fp_poly
			(pts
				(xy -3.81 4.572) (xy -3.81 -4.572) (xy 3.81 -4.572) (xy 3.81 -0.5588) (xy 3.302 -0.5588) (xy 3.302 -3.4798)
				(xy -3.302 -3.4798) (xy -3.302 3.4798) (xy 3.302 3.4798) (xy 3.302 -0.5461) (xy 3.81 -0.5461) (xy 3.81 4.572)
			)
			(stroke
				(width 0)
				(type default)
			)
			(fill no)
			(layer "F.CrtYd")
		)
		(fp_rect
			(start -3.81 4.572)
			(end 3.81 -4.572)
			(stroke
				(width 0)
				(type default)
			)
			(fill no)
			(layer "F.Fab")
		)
		(pad "1" smd rect
			(at 0 -2.779522 270)
			(size 3.5052 2.921)
			(layers "F.Cu" "F.Mask" "F.Paste")
			(net "DUT_VDDO")
		)
		(pad "2" smd rect
			(at 0 2.779522 270)
			(size 3.5052 2.921)
			(layers "F.Cu" "F.Mask" "F.Paste")
			(net "DUT_VDDO_REF")
		)
	)
	(footprint ""
		(layer "F.Cu")
		(at 20.5613 -178.7271 180)
		(property "Reference" "R691"
			(at 0 0 180)
			(layer "F.SilkS")
			(hide yes)
			(effects
				(font
					(size 1.27 1.27)
				)
			)
		)
		(property "Value" "0R2J-2-GP"
			(at 0.064008 -3.993896 180)
			(unlocked yes)
			(layer "F.Fab")
			(hide yes)
			(effects
				(font
					(size 1.016 1.016)
					(thickness 0.1524)
				)
			)
		)
		(property "Device Type" "R402H16"
			(at 0.064008 -5.517896 180)
			(unlocked yes)
			(layer "F.Fab")
			(hide yes)
			(effects
				(font
					(size 1.016 1.016)
					(thickness 0.1524)
				)
			)
		)
		(duplicate_pad_numbers_are_jumpers no)
		(fp_line
			(start 0.508 -0.9398)
			(end -0.508 -0.9398)
			(stroke
				(width 0.1524)
				(type default)
			)
			(layer "F.SilkS")
		)
		(fp_line
			(start -0.508 -0.9398)
			(end -0.508 0.9398)
			(stroke
				(width 0.1524)
				(type default)
			)
			(layer "F.SilkS")
		)
		(fp_rect
			(start -0.508 0.9398)
			(end 0.508 -0.9398)
			(stroke
				(width 0)
				(type default)
			)
			(fill no)
			(layer "F.CrtYd")
		)
		(fp_rect
			(start -0.508 0.9398)
			(end 0.508 -0.9398)
			(stroke
				(width 0)
				(type default)
			)
			(fill no)
			(layer "F.Fab")
		)
		(pad "1" smd custom
			(at 0 -0.4445 180)
			(size 0.1397 0.1397)
			(layers "F.Cu" "F.Mask" "F.Paste")
			(net "MATED_P12V_EN")
			(options
				(clearance outline)
				(anchor circle)
			)
			(primitives
				(gr_poly
					(pts
						(arc
							(start -0.1778 -0.2794)
							(mid -0.249642 -0.249642)
							(end -0.2794 -0.1778)
						)
						(arc
							(start -0.2794 0.1778)
							(mid -0.249642 0.249642)
							(end -0.1778 0.2794)
						)
						(arc
							(start 0.1778 0.2794)
							(mid 0.249642 0.249642)
							(end 0.2794 0.1778)
						)
						(arc
							(start 0.2794 -0.1778)
							(mid 0.249642 -0.249642)
							(end 0.1778 -0.2794)
						)
					)
					(width 0)
					(fill yes)
				)
			)
		)
		(pad "2" smd custom
			(at 0 0.4445 180)
			(size 0.1397 0.1397)
			(layers "F.Cu" "F.Mask" "F.Paste")
			(net "MB0_HS_ENABLE")
			(options
				(clearance outline)
				(anchor circle)
			)
			(primitives
				(gr_poly
					(pts
						(arc
							(start -0.1778 -0.2794)
							(mid -0.249642 -0.249642)
							(end -0.2794 -0.1778)
						)
						(arc
							(start -0.2794 0.1778)
							(mid -0.249642 0.249642)
							(end -0.1778 0.2794)
						)
						(arc
							(start 0.1778 0.2794)
							(mid 0.249642 0.249642)
							(end 0.2794 0.1778)
						)
						(arc
							(start 0.2794 -0.1778)
							(mid 0.249642 -0.249642)
							(end 0.1778 -0.2794)
						)
					)
					(width 0)
					(fill yes)
				)
			)
		)
	)
	(footprint ""
		(layer "F.Cu")
		(at 262.608568 -2.813304 -90)
		(property "Reference" "R673"
			(at 0 0 270)
			(layer "F.SilkS")
			(hide yes)
			(effects
				(font
					(size 1.27 1.27)
				)
			)
		)
		(property "Value" "4K7R2F-GP"
			(at 0.064008 -3.993896 270)
			(unlocked yes)
			(layer "F.Fab")
			(hide yes)
			(effects
				(font
					(size 1.016 1.016)
					(thickness 0.1524)
				)
			)
		)
		(property "Device Type" "R402H16"
			(at 0.064008 -5.517896 270)
			(unlocked yes)
			(layer "F.Fab")
			(hide yes)
			(effects
				(font
					(size 1.016 1.016)
					(thickness 0.1524)
				)
			)
		)
		(duplicate_pad_numbers_are_jumpers no)
		(fp_line
			(start -0.508 -0.9398)
			(end -0.508 0.9398)
			(stroke
				(width 0.1524)
				(type default)
			)
			(layer "F.SilkS")
		)
		(fp_line
			(start 0.508 -0.9398)
			(end -0.508 -0.9398)
			(stroke
				(width 0.1524)
				(type default)
			)
			(layer "F.SilkS")
		)
		(fp_rect
			(start -0.508 0.9398)
			(end 0.508 -0.9398)
			(stroke
				(width 0)
				(type default)
			)
			(fill no)
			(layer "F.CrtYd")
		)
		(fp_rect
			(start -0.508 0.9398)
			(end 0.508 -0.9398)
			(stroke
				(width 0)
				(type default)
			)
			(fill no)
			(layer "F.Fab")
		)
		(pad "1" smd custom
			(at 0 -0.4445 270)
			(size 0.1397 0.1397)
			(layers "F.Cu" "F.Mask" "F.Paste")
			(net "FM_BMC_RESET#_BTN")
			(options
				(clearance outline)
				(anchor circle)
			)
			(primitives
				(gr_poly
					(pts
						(arc
							(start -0.1778 -0.2794)
							(mid -0.249642 -0.249642)
							(end -0.2794 -0.1778)
						)
						(arc
							(start -0.2794 0.1778)
							(mid -0.249642 0.249642)
							(end -0.1778 0.2794)
						)
						(arc
							(start 0.1778 0.2794)
							(mid 0.249642 0.249642)
							(end 0.2794 0.1778)
						)
						(arc
							(start 0.2794 -0.1778)
							(mid 0.249642 -0.249642)
							(end 0.1778 -0.2794)
						)
					)
					(width 0)
					(fill yes)
				)
			)
		)
		(pad "2" smd custom
			(at 0 0.4445 270)
			(size 0.1397 0.1397)
			(layers "F.Cu" "F.Mask" "F.Paste")
			(net "P3V3_STBY")
			(options
				(clearance outline)
				(anchor circle)
			)
			(primitives
				(gr_poly
					(pts
						(arc
							(start -0.1778 -0.2794)
							(mid -0.249642 -0.249642)
							(end -0.2794 -0.1778)
						)
						(arc
							(start -0.2794 0.1778)
							(mid -0.249642 0.249642)
							(end -0.1778 0.2794)
						)
						(arc
							(start 0.1778 0.2794)
							(mid 0.249642 0.249642)
							(end 0.2794 0.1778)
						)
						(arc
							(start 0.2794 -0.1778)
							(mid 0.249642 -0.249642)
							(end 0.1778 -0.2794)
						)
					)
					(width 0)
					(fill yes)
				)
			)
		)
	)
	(footprint ""
		(layer "F.Cu")
		(at 330.8858 -75.3618 -90)
		(property "Reference" "PQ20"
			(at 0 0 270)
			(layer "F.SilkS")
			(hide yes)
			(effects
				(font
					(size 1.27 1.27)
				)
			)
		)
		(property "Value" "AO3400-GP-U"
			(at 0.0254 -12.3444 270)
			(unlocked yes)
			(layer "F.Fab")
			(hide yes)
			(effects
				(font
					(size 1.016 1.016)
					(thickness 0.1524)
				)
			)
		)
		(property "Device Type" "SOT23DGS2D8H50"
			(at 0.0254 -14.2494 270)
			(unlocked yes)
			(layer "F.Fab")
			(hide yes)
			(effects
				(font
					(size 1.016 1.016)
					(thickness 0.1524)
				)
			)
		)
		(duplicate_pad_numbers_are_jumpers no)
		(fp_line
			(start -1.7018 0.254)
			(end -1.7018 -0.254)
			(stroke
				(width 0.1524)
				(type default)
			)
			(layer "F.SilkS")
		)
		(fp_line
			(start 1.7018 0.254)
			(end -1.7018 0.254)
			(stroke
				(width 0.1524)
				(type default)
			)
			(layer "F.SilkS")
		)
		(fp_line
			(start -1.7018 -0.254)
			(end 1.7018 -0.254)
			(stroke
				(width 0.1524)
				(type default)
			)
			(layer "F.SilkS")
		)
		(fp_line
			(start 1.7018 -0.254)
			(end 1.7018 0.254)
			(stroke
				(width 0.1524)
				(type default)
			)
			(layer "F.SilkS")
		)
		(fp_rect
			(start -1.778 1.9812)
			(end 1.778 -1.9812)
			(stroke
				(width 0)
				(type default)
			)
			(fill no)
			(layer "F.CrtYd")
		)
		(fp_poly
			(pts
				(xy -1.778 -1.9812) (xy 1.778 -1.9812) (xy 1.778 1.9812) (xy -1.778 1.9812)
			)
			(stroke
				(width 0)
				(type default)
			)
			(fill no)
			(layer "F.Fab")
		)
		(pad "D" smd custom
			(at 0 -1.1176 270)
			(size 0.254 0.254)
			(layers "F.Cu" "F.Mask" "F.Paste")
			(net "P0V9_E_VFB_AVS")
			(options
				(clearance outline)
				(anchor circle)
			)
			(primitives
				(gr_poly
					(pts
						(arc
							(start -0.508 -0.4064)
							(mid -0.448484 -0.550084)
							(end -0.3048 -0.6096)
						)
						(arc
							(start 0.3048 -0.6096)
							(mid 0.448484 -0.550084)
							(end 0.508 -0.4064)
						)
						(arc
							(start 0.508 0.4064)
							(mid 0.448484 0.550084)
							(end 0.3048 0.6096)
						)
						(arc
							(start -0.3048 0.6096)
							(mid -0.448484 0.550084)
							(end -0.508 0.4064)
						)
					)
					(width 0)
					(fill yes)
				)
			)
		)
		(pad "G" smd custom
			(at -1.016 1.1176 270)
			(size 0.254 0.254)
			(layers "F.Cu" "F.Mask" "F.Paste")
			(net "AVS_ENB2_R")
			(options
				(clearance outline)
				(anchor circle)
			)
			(primitives
				(gr_poly
					(pts
						(arc
							(start -0.508 -0.4064)
							(mid -0.448484 -0.550084)
							(end -0.3048 -0.6096)
						)
						(arc
							(start 0.3048 -0.6096)
							(mid 0.448484 -0.550084)
							(end 0.508 -0.4064)
						)
						(arc
							(start 0.508 0.4064)
							(mid 0.448484 0.550084)
							(end 0.3048 0.6096)
						)
						(arc
							(start -0.3048 0.6096)
							(mid -0.448484 0.550084)
							(end -0.508 0.4064)
						)
					)
					(width 0)
					(fill yes)
				)
			)
		)
		(pad "S" smd custom
			(at 1.016 1.1176 270)
			(size 0.254 0.254)
			(layers "F.Cu" "F.Mask" "F.Paste")
			(net "AGND_P0V9_E")
			(options
				(clearance outline)
				(anchor circle)
			)
			(primitives
				(gr_poly
					(pts
						(arc
							(start -0.508 -0.4064)
							(mid -0.448484 -0.550084)
							(end -0.3048 -0.6096)
						)
						(arc
							(start 0.3048 -0.6096)
							(mid 0.448484 -0.550084)
							(end 0.508 -0.4064)
						)
						(arc
							(start 0.508 0.4064)
							(mid 0.448484 0.550084)
							(end 0.3048 0.6096)
						)
						(arc
							(start -0.3048 0.6096)
							(mid -0.448484 0.550084)
							(end -0.508 0.4064)
						)
					)
					(width 0)
					(fill yes)
				)
			)
		)
	)
	(footprint ""
		(layer "F.Cu")
		(at 305.63439 -9.53008)
		(property "Reference" "CN16"
			(at 0 0 0)
			(layer "F.SilkS")
			(hide yes)
			(effects
				(font
					(size 1.27 1.27)
				)
			)
		)
		(property "Value" "MLX-CONN144-12R-3-GP-U2"
			(at -33.7693 -12.9032 0)
			(unlocked yes)
			(layer "F.Fab")
			(hide yes)
			(effects
				(font
					(size 1.016 1.016)
					(thickness 0.1524)
				)
			)
		)
		(property "Device Type" "PREFIT-144P-459383U2H519"
			(at -33.7693 -14.4272 0)
			(unlocked yes)
			(layer "F.Fab")
			(hide yes)
			(effects
				(font
					(size 1.016 1.016)
					(thickness 0.1524)
				)
			)
		)
		(duplicate_pad_numbers_are_jumpers no)
		(fp_line
			(start -23.1775 -18.2118)
			(end 23.1775 -18.2118)
			(stroke
				(width 0.1524)
				(type default)
			)
			(layer "F.SilkS")
		)
		(fp_line
			(start -23.1775 20.6248)
			(end -23.1775 -18.2118)
			(stroke
				(width 0.1524)
				(type default)
			)
			(layer "F.SilkS")
		)
		(fp_line
			(start 23.1775 -18.2118)
			(end 23.1775 20.6248)
			(stroke
				(width 0.1524)
				(type default)
			)
			(layer "F.SilkS")
		)
		(fp_line
			(start 23.1775 14.489938)
			(end -23.1775 14.489938)
			(stroke
				(width 0.1524)
				(type default)
			)
			(layer "F.SilkS")
		)
		(fp_line
			(start 23.1775 20.6248)
			(end -23.1775 20.6248)
			(stroke
				(width 0.1524)
				(type default)
			)
			(layer "F.SilkS")
		)
		(fp_poly
			(pts
				(xy -23.1775 14.489938) (xy -23.1775 -18.2118) (xy 23.1775 -18.2118) (xy 23.1775 14.489938)
			)
			(stroke
				(width 0)
				(type default)
			)
			(fill yes)
			(layer "F.SilkS")
		)
		(fp_poly
			(pts
				(arc
					(start -21.745956 11.1252)
					(mid -21.999956 11.3792)
					(end -22.253956 11.1252)
				)
				(arc
					(start -22.253956 10.6172)
					(mid -21.999956 10.3632)
					(end -21.745956 10.6172)
				)
			)
			(stroke
				(width 0)
				(type default)
			)
			(fill yes)
			(layer "F.SilkS")
		)
		(fp_poly
			(pts
				(arc
					(start -19.246088 11.1252)
					(mid -19.500088 11.3792)
					(end -19.754088 11.1252)
				)
				(arc
					(start -19.754088 10.6172)
					(mid -19.500088 10.3632)
					(end -19.246088 10.6172)
				)
			)
			(stroke
				(width 0)
				(type default)
			)
			(fill yes)
			(layer "F.SilkS")
		)
		(fp_poly
			(pts
				(arc
					(start -18.496026 11.1252)
					(mid -18.750026 11.3792)
					(end -19.004026 11.1252)
				)
				(arc
					(start -19.004026 10.6172)
					(mid -18.750026 10.3632)
					(end -18.496026 10.6172)
				)
			)
			(stroke
				(width 0)
				(type default)
			)
			(fill yes)
			(layer "F.SilkS")
		)
		(fp_poly
			(pts
				(arc
					(start -17.745964 11.1252)
					(mid -17.999964 11.3792)
					(end -18.253964 11.1252)
				)
				(arc
					(start -18.253964 10.6172)
					(mid -17.999964 10.3632)
					(end -17.745964 10.6172)
				)
			)
			(stroke
				(width 0)
				(type default)
			)
			(fill yes)
			(layer "F.SilkS")
		)
		(fp_poly
			(pts
				(arc
					(start -16.995902 11.1252)
					(mid -17.249902 11.3792)
					(end -17.503902 11.1252)
				)
				(arc
					(start -17.503902 10.6172)
					(mid -17.249902 10.3632)
					(end -16.995902 10.6172)
				)
			)
			(stroke
				(width 0)
				(type default)
			)
			(fill yes)
			(layer "F.SilkS")
		)
		(fp_poly
			(pts
				(arc
					(start -16.256 -17.272)
					(mid -16.51 -17.526)
					(end -16.256 -17.78)
				)
				(arc
					(start -15.24 -17.78)
					(mid -14.986 -17.526)
					(end -15.24 -17.272)
				)
			)
			(stroke
				(width 0)
				(type default)
			)
			(fill yes)
			(layer "F.SilkS")
		)
		(fp_poly
			(pts
				(arc
					(start -16.24584 11.1252)
					(mid -16.49984 11.3792)
					(end -16.75384 11.1252)
				)
				(arc
					(start -16.75384 10.6172)
					(mid -16.49984 10.3632)
					(end -16.24584 10.6172)
				)
			)
			(stroke
				(width 0)
				(type default)
			)
			(fill yes)
			(layer "F.SilkS")
		)
		(fp_poly
			(pts
				(arc
					(start -15.495778 11.1252)
					(mid -15.749778 11.3792)
					(end -16.003778 11.1252)
				)
				(arc
					(start -16.003778 10.6172)
					(mid -15.749778 10.3632)
					(end -15.495778 10.6172)
				)
			)
			(stroke
				(width 0)
				(type default)
			)
			(fill yes)
			(layer "F.SilkS")
		)
		(fp_poly
			(pts
				(arc
					(start -14.745716 11.1252)
					(mid -14.999716 11.3792)
					(end -15.253716 11.1252)
				)
				(arc
					(start -15.253716 10.6172)
					(mid -14.999716 10.3632)
					(end -14.745716 10.6172)
				)
			)
			(stroke
				(width 0)
				(type default)
			)
			(fill yes)
			(layer "F.SilkS")
		)
		(fp_poly
			(pts
				(arc
					(start -13.995654 11.1252)
					(mid -14.249654 11.3792)
					(end -14.503654 11.1252)
				)
				(arc
					(start -14.503654 10.6172)
					(mid -14.249654 10.3632)
					(end -13.995654 10.6172)
				)
			)
			(stroke
				(width 0)
				(type default)
			)
			(fill yes)
			(layer "F.SilkS")
		)
		(fp_poly
			(pts
				(arc
					(start -13.245592 11.1252)
					(mid -13.499592 11.3792)
					(end -13.753592 11.1252)
				)
				(arc
					(start -13.753592 10.6172)
					(mid -13.499592 10.3632)
					(end -13.245592 10.6172)
				)
			)
			(stroke
				(width 0)
				(type default)
			)
			(fill yes)
			(layer "F.SilkS")
		)
		(fp_poly
			(pts
				(arc
					(start -10.745978 11.1252)
					(mid -10.999978 11.3792)
					(end -11.253978 11.1252)
				)
				(arc
					(start -11.253978 10.6172)
					(mid -10.999978 10.3632)
					(end -10.745978 10.6172)
				)
			)
			(stroke
				(width 0)
				(type default)
			)
			(fill yes)
			(layer "F.SilkS")
		)
		(fp_poly
			(pts
				(arc
					(start -8.24611 11.1252)
					(mid -8.50011 11.3792)
					(end -8.75411 11.1252)
				)
				(arc
					(start -8.75411 10.6172)
					(mid -8.50011 10.3632)
					(end -8.24611 10.6172)
				)
			)
			(stroke
				(width 0)
				(type default)
			)
			(fill yes)
			(layer "F.SilkS")
		)
		(fp_poly
			(pts
				(arc
					(start -7.496048 11.1252)
					(mid -7.750048 11.3792)
					(end -8.004048 11.1252)
				)
				(arc
					(start -8.004048 10.6172)
					(mid -7.750048 10.3632)
					(end -7.496048 10.6172)
				)
			)
			(stroke
				(width 0)
				(type default)
			)
			(fill yes)
			(layer "F.SilkS")
		)
		(fp_poly
			(pts
				(arc
					(start -6.745986 11.1252)
					(mid -6.999986 11.3792)
					(end -7.253986 11.1252)
				)
				(arc
					(start -7.253986 10.6172)
					(mid -6.999986 10.3632)
					(end -6.745986 10.6172)
				)
			)
			(stroke
				(width 0)
				(type default)
			)
			(fill yes)
			(layer "F.SilkS")
		)
		(fp_poly
			(pts
				(arc
					(start -5.995924 11.1252)
					(mid -6.249924 11.3792)
					(end -6.503924 11.1252)
				)
				(arc
					(start -6.503924 10.6172)
					(mid -6.249924 10.3632)
					(end -5.995924 10.6172)
				)
			)
			(stroke
				(width 0)
				(type default)
			)
			(fill yes)
			(layer "F.SilkS")
		)
		(fp_poly
			(pts
				(arc
					(start -5.334 -17.272)
					(mid -5.588 -17.526)
					(end -5.334 -17.78)
				)
				(arc
					(start -4.318 -17.78)
					(mid -4.064 -17.526)
					(end -4.318 -17.272)
				)
			)
			(stroke
				(width 0)
				(type default)
			)
			(fill yes)
			(layer "F.SilkS")
		)
		(fp_poly
			(pts
				(arc
					(start -5.245862 11.1252)
					(mid -5.499862 11.3792)
					(end -5.753862 11.1252)
				)
				(arc
					(start -5.753862 10.6172)
					(mid -5.499862 10.3632)
					(end -5.245862 10.6172)
				)
			)
			(stroke
				(width 0)
				(type default)
			)
			(fill yes)
			(layer "F.SilkS")
		)
		(fp_poly
			(pts
				(arc
					(start -4.4958 11.1252)
					(mid -4.7498 11.3792)
					(end -5.0038 11.1252)
				)
				(arc
					(start -5.0038 10.6172)
					(mid -4.7498 10.3632)
					(end -4.4958 10.6172)
				)
			)
			(stroke
				(width 0)
				(type default)
			)
			(fill yes)
			(layer "F.SilkS")
		)
		(fp_poly
			(pts
				(arc
					(start -3.745738 11.1252)
					(mid -3.999738 11.3792)
					(end -4.253738 11.1252)
				)
				(arc
					(start -4.253738 10.6172)
					(mid -3.999738 10.3632)
					(end -3.745738 10.6172)
				)
			)
			(stroke
				(width 0)
				(type default)
			)
			(fill yes)
			(layer "F.SilkS")
		)
		(fp_poly
			(pts
				(arc
					(start -2.995676 11.1252)
					(mid -3.249676 11.3792)
					(end -3.503676 11.1252)
				)
				(arc
					(start -3.503676 10.6172)
					(mid -3.249676 10.3632)
					(end -2.995676 10.6172)
				)
			)
			(stroke
				(width 0)
				(type default)
			)
			(fill yes)
			(layer "F.SilkS")
		)
		(fp_poly
			(pts
				(arc
					(start -2.245614 11.1252)
					(mid -2.499614 11.3792)
					(end -2.753614 11.1252)
				)
				(arc
					(start -2.753614 10.6172)
					(mid -2.499614 10.3632)
					(end -2.245614 10.6172)
				)
			)
			(stroke
				(width 0)
				(type default)
			)
			(fill yes)
			(layer "F.SilkS")
		)
		(fp_poly
			(pts
				(arc
					(start 0.254 11.1252)
					(mid 0 11.3792)
					(end -0.254 11.1252)
				)
				(arc
					(start -0.254 10.6172)
					(mid 0 10.3632)
					(end 0.254 10.6172)
				)
			)
			(stroke
				(width 0)
				(type default)
			)
			(fill yes)
			(layer "F.SilkS")
		)
		(fp_poly
			(pts
				(arc
					(start 2.753868 11.1252)
					(mid 2.499868 11.3792)
					(end 2.245868 11.1252)
				)
				(arc
					(start 2.245868 10.6172)
					(mid 2.499868 10.3632)
					(end 2.753868 10.6172)
				)
			)
			(stroke
				(width 0)
				(type default)
			)
			(fill yes)
			(layer "F.SilkS")
		)
		(fp_poly
			(pts
				(arc
					(start 3.50393 11.1252)
					(mid 3.24993 11.3792)
					(end 2.99593 11.1252)
				)
				(arc
					(start 2.99593 10.6172)
					(mid 3.24993 10.3632)
					(end 3.50393 10.6172)
				)
			)
			(stroke
				(width 0)
				(type default)
			)
			(fill yes)
			(layer "F.SilkS")
		)
		(fp_poly
			(pts
				(arc
					(start 4.253992 11.1252)
					(mid 3.999992 11.3792)
					(end 3.745992 11.1252)
				)
				(arc
					(start 3.745992 10.6172)
					(mid 3.999992 10.3632)
					(end 4.253992 10.6172)
				)
			)
			(stroke
				(width 0)
				(type default)
			)
			(fill yes)
			(layer "F.SilkS")
		)
		(fp_poly
			(pts
				(arc
					(start 5.004054 11.1252)
					(mid 4.750054 11.3792)
					(end 4.496054 11.1252)
				)
				(arc
					(start 4.496054 10.6172)
					(mid 4.750054 10.3632)
					(end 5.004054 10.6172)
				)
			)
			(stroke
				(width 0)
				(type default)
			)
			(fill yes)
			(layer "F.SilkS")
		)
		(fp_poly
			(pts
				(arc
					(start 5.754116 11.1252)
					(mid 5.500116 11.3792)
					(end 5.246116 11.1252)
				)
				(arc
					(start 5.246116 10.6172)
					(mid 5.500116 10.3632)
					(end 5.754116 10.6172)
				)
			)
			(stroke
				(width 0)
				(type default)
			)
			(fill yes)
			(layer "F.SilkS")
		)
		(fp_poly
			(pts
				(arc
					(start 5.842 -17.272)
					(mid 5.588 -17.526)
					(end 5.842 -17.78)
				)
				(arc
					(start 6.858 -17.78)
					(mid 7.112 -17.526)
					(end 6.858 -17.272)
				)
			)
			(stroke
				(width 0)
				(type default)
			)
			(fill yes)
			(layer "F.SilkS")
		)
		(fp_poly
			(pts
				(arc
					(start 6.504178 11.1252)
					(mid 6.250178 11.3792)
					(end 5.996178 11.1252)
				)
				(arc
					(start 5.996178 10.6172)
					(mid 6.250178 10.3632)
					(end 6.504178 10.6172)
				)
			)
			(stroke
				(width 0)
				(type default)
			)
			(fill yes)
			(layer "F.SilkS")
		)
		(fp_poly
			(pts
				(arc
					(start 7.25424 11.1252)
					(mid 7.00024 11.3792)
					(end 6.74624 11.1252)
				)
				(arc
					(start 6.74624 10.6172)
					(mid 7.00024 10.3632)
					(end 7.25424 10.6172)
				)
			)
			(stroke
				(width 0)
				(type default)
			)
			(fill yes)
			(layer "F.SilkS")
		)
		(fp_poly
			(pts
				(arc
					(start 8.004302 11.1252)
					(mid 7.750302 11.3792)
					(end 7.496302 11.1252)
				)
				(arc
					(start 7.496302 10.6172)
					(mid 7.750302 10.3632)
					(end 8.004302 10.6172)
				)
			)
			(stroke
				(width 0)
				(type default)
			)
			(fill yes)
			(layer "F.SilkS")
		)
		(fp_poly
			(pts
				(arc
					(start 8.754364 11.1252)
					(mid 8.500364 11.3792)
					(end 8.246364 11.1252)
				)
				(arc
					(start 8.246364 10.6172)
					(mid 8.500364 10.3632)
					(end 8.754364 10.6172)
				)
			)
			(stroke
				(width 0)
				(type default)
			)
			(fill yes)
			(layer "F.SilkS")
		)
		(fp_poly
			(pts
				(arc
					(start 11.253978 11.1252)
					(mid 10.999978 11.3792)
					(end 10.745978 11.1252)
				)
				(arc
					(start 10.745978 10.6172)
					(mid 10.999978 10.3632)
					(end 11.253978 10.6172)
				)
			)
			(stroke
				(width 0)
				(type default)
			)
			(fill yes)
			(layer "F.SilkS")
		)
		(fp_poly
			(pts
				(arc
					(start 13.753846 11.1252)
					(mid 13.499846 11.3792)
					(end 13.245846 11.1252)
				)
				(arc
					(start 13.245846 10.6172)
					(mid 13.499846 10.3632)
					(end 13.753846 10.6172)
				)
			)
			(stroke
				(width 0)
				(type default)
			)
			(fill yes)
			(layer "F.SilkS")
		)
		(fp_poly
			(pts
				(arc
					(start 14.503908 11.1252)
					(mid 14.249908 11.3792)
					(end 13.995908 11.1252)
				)
				(arc
					(start 13.995908 10.6172)
					(mid 14.249908 10.3632)
					(end 14.503908 10.6172)
				)
			)
			(stroke
				(width 0)
				(type default)
			)
			(fill yes)
			(layer "F.SilkS")
		)
		(fp_poly
			(pts
				(arc
					(start 15.25397 11.1252)
					(mid 14.99997 11.3792)
					(end 14.74597 11.1252)
				)
				(arc
					(start 14.74597 10.6172)
					(mid 14.99997 10.3632)
					(end 15.25397 10.6172)
				)
			)
			(stroke
				(width 0)
				(type default)
			)
			(fill yes)
			(layer "F.SilkS")
		)
		(fp_poly
			(pts
				(arc
					(start 16.004032 11.1252)
					(mid 15.750032 11.3792)
					(end 15.496032 11.1252)
				)
				(arc
					(start 15.496032 10.6172)
					(mid 15.750032 10.3632)
					(end 16.004032 10.6172)
				)
			)
			(stroke
				(width 0)
				(type default)
			)
			(fill yes)
			(layer "F.SilkS")
		)
		(fp_poly
			(pts
				(arc
					(start 16.754094 11.1252)
					(mid 16.500094 11.3792)
					(end 16.246094 11.1252)
				)
				(arc
					(start 16.246094 10.6172)
					(mid 16.500094 10.3632)
					(end 16.754094 10.6172)
				)
			)
			(stroke
				(width 0)
				(type default)
			)
			(fill yes)
			(layer "F.SilkS")
		)
		(fp_poly
			(pts
				(arc
					(start 16.764 -17.272)
					(mid 16.51 -17.526)
					(end 16.764 -17.78)
				)
				(arc
					(start 17.78 -17.78)
					(mid 18.034 -17.526)
					(end 17.78 -17.272)
				)
			)
			(stroke
				(width 0)
				(type default)
			)
			(fill yes)
			(layer "F.SilkS")
		)
		(fp_poly
			(pts
				(arc
					(start 17.504156 11.1252)
					(mid 17.250156 11.3792)
					(end 16.996156 11.1252)
				)
				(arc
					(start 16.996156 10.6172)
					(mid 17.250156 10.3632)
					(end 17.504156 10.6172)
				)
			)
			(stroke
				(width 0)
				(type default)
			)
			(fill yes)
			(layer "F.SilkS")
		)
		(fp_poly
			(pts
				(arc
					(start 18.254218 11.1252)
					(mid 18.000218 11.3792)
					(end 17.746218 11.1252)
				)
				(arc
					(start 17.746218 10.6172)
					(mid 18.000218 10.3632)
					(end 18.254218 10.6172)
				)
			)
			(stroke
				(width 0)
				(type default)
			)
			(fill yes)
			(layer "F.SilkS")
		)
		(fp_poly
			(pts
				(arc
					(start 19.00428 11.1252)
					(mid 18.75028 11.3792)
					(end 18.49628 11.1252)
				)
				(arc
					(start 18.49628 10.6172)
					(mid 18.75028 10.3632)
					(end 19.00428 10.6172)
				)
			)
			(stroke
				(width 0)
				(type default)
			)
			(fill yes)
			(layer "F.SilkS")
		)
		(fp_poly
			(pts
				(arc
					(start 19.754342 11.1252)
					(mid 19.500342 11.3792)
					(end 19.246342 11.1252)
				)
				(arc
					(start 19.246342 10.6172)
					(mid 19.500342 10.3632)
					(end 19.754342 10.6172)
				)
			)
			(stroke
				(width 0)
				(type default)
			)
			(fill yes)
			(layer "F.SilkS")
		)
		(fp_poly
			(pts
				(arc
					(start 22.253956 11.1252)
					(mid 21.999956 11.3792)
					(end 21.745956 11.1252)
				)
				(arc
					(start 21.745956 10.6172)
					(mid 21.999956 10.3632)
					(end 22.253956 10.6172)
				)
			)
			(stroke
				(width 0)
				(type default)
			)
			(fill yes)
			(layer "F.SilkS")
		)
		(fp_rect
			(start -27.4574 15.0622)
			(end 27.4574 -22.9616)
			(stroke
				(width 0)
				(type default)
			)
			(fill no)
			(layer "B.CrtYd")
		)
		(fp_rect
			(start -22.9235 20.3708)
			(end 22.9235 -17.8816)
			(stroke
				(width 0)
				(type default)
			)
			(fill no)
			(layer "F.CrtYd")
		)
		(fp_poly
			(pts
				(xy -27.9273 25.3746) (xy -27.9273 -22.8854) (xy 27.9273 -22.8854) (xy 27.9273 -0.00635) (xy 25.006554 -0.00635)
				(xy 25.006554 -6.197854) (xy 23.431754 -6.197854) (xy 23.431754 -18.389854) (xy 22.504654 -18.389854)
				(xy 22.504654 -21.209254) (xy -22.504654 -21.209254) (xy -22.504654 -18.389854) (xy -23.431754 -18.389854)
				(xy -23.431754 -6.197854) (xy -25.006554 -6.197854) (xy -25.006554 11.811254) (xy -23.431754 11.811254)
				(xy -23.431754 20.879054) (xy 23.431754 20.879054) (xy 23.431754 11.811254) (xy 25.006554 11.811254)
				(xy 25.006554 0.00635) (xy 27.9273 0.00635) (xy 27.9273 25.3746)
			)
			(stroke
				(width 0)
				(type default)
			)
			(fill no)
			(layer "F.CrtYd")
		)
		(fp_poly
			(pts
				(xy -23.4315 20.8788) (xy -23.4315 11.811) (xy -25.0063 11.811) (xy -25.0063 -6.1976) (xy -23.4315 -6.1976)
				(xy -23.4315 -18.3896) (xy -22.5044 -18.3896) (xy -22.5044 -21.209) (xy 22.5044 -21.209) (xy 22.5044 -18.3896)
				(xy 23.4315 -18.3896) (xy 23.4315 -6.1976) (xy 25.0063 -6.1976) (xy 25.0063 -0.00635) (xy 22.9235 -0.00635)
				(xy 22.9235 -17.8816) (xy -22.9235 -17.8816) (xy -22.9235 20.3708) (xy 22.9235 20.3708) (xy 22.9235 0.00635)
				(xy 25.0063 0.00635) (xy 25.0063 11.811) (xy 23.4315 11.811) (xy 23.4315 20.8788)
			)
			(stroke
				(width 0)
				(type default)
			)
			(fill no)
			(layer "F.CrtYd")
		)
		(fp_rect
			(start -32.4612 20.066)
			(end 32.4612 -27.9654)
			(stroke
				(width 0)
				(type default)
			)
			(fill no)
			(layer "B.Fab")
		)
		(fp_rect
			(start -27.4574 15.0622)
			(end 27.4574 -22.9616)
			(stroke
				(width 0)
				(type default)
			)
			(fill no)
			(layer "B.Fab")
		)
		(fp_rect
			(start -32.9311 30.3784)
			(end 32.9311 -27.8892)
			(stroke
				(width 0)
				(type default)
			)
			(fill no)
			(layer "F.Fab")
		)
		(fp_rect
			(start -27.9273 25.3746)
			(end 27.9273 -22.8854)
			(stroke
				(width 0)
				(type default)
			)
			(fill no)
			(layer "F.Fab")
		)
		(fp_poly
			(pts
				(xy -23.4315 20.8788) (xy -23.4315 11.811) (xy -25.0063 11.811) (xy -25.0063 -6.1976) (xy -23.4315 -6.1976)
				(xy -23.4315 -18.3896) (xy -22.5044 -18.3896) (xy -22.5044 -21.209) (xy 22.5044 -21.209) (xy 22.5044 -18.4658)
				(xy 23.4315 -18.4658) (xy 23.4315 -6.1976) (xy 25.0063 -6.1976) (xy 25.0063 11.811) (xy 23.4315 11.811)
				(xy 23.4315 20.8788)
			)
			(stroke
				(width 0)
				(type default)
			)
			(fill no)
			(layer "F.Fab")
		)
		(fp_text user "Press Fit"
			(at -5.1308 12.403836 0)
			(unlocked yes)
			(layer "F.SilkS")
			(effects
				(font
					(size 1.016 1.016)
					(thickness 0.1524)
				)
				(justify left)
			)
		)
		(fp_text user "Can not place BGA,CSP,Wave Solder Component"
			(at -25.0444 18.677636 0)
			(unlocked yes)
			(layer "B.Fab")
			(effects
				(font
					(size 1.016 1.016)
					(thickness 0.1524)
				)
				(justify left)
			)
		)
		(fp_text user "Can not place BGA,CSP,Wave Solder Component"
			(at -24.0284 28.837636 0)
			(unlocked yes)
			(layer "F.Fab")
			(effects
				(font
					(size 1.016 1.016)
					(thickness 0.1524)
				)
				(justify left)
			)
		)
		(fp_text user "High Limit 2mm"
			(at -8.1026 24.265636 0)
			(unlocked yes)
			(layer "F.Fab")
			(effects
				(font
					(size 1.016 1.016)
					(thickness 0.1524)
				)
				(justify left)
			)
		)
		(pad "AA1" thru_hole circle
			(at -19.500088 -4.400042)
			(size 0.7366 0.7366)
			(drill 0.369824)
			(layers "*.Cu" "*.Mask")
			(remove_unused_layers no)
			(net "PCIE_REFCLK_H0_P_R")
			(clearance 0.1778)
			(thermal_gap 0.1778)
		)
		(pad "AA2" thru_hole circle
			(at -18.750026 -2.999994)
			(size 0.7366 0.7366)
			(drill 0.369824)
			(layers "*.Cu" "*.Mask")
			(remove_unused_layers no)
			(net "PCIE_REFCLK_H0_N_R")
			(clearance 0.1778)
			(thermal_gap 0.1778)
		)
		(pad "AA3" thru_hole circle
			(at -17.999964 -3.700018)
			(size 0.7366 0.7366)
			(drill 0.369824)
			(layers "*.Cu" "*.Mask")
			(remove_unused_layers no)
			(net "GND")
			(clearance 0.1778)
			(thermal_gap 0.1778)
		)
		(pad "AA4" thru_hole circle
			(at -17.249902 -4.400042)
			(size 0.7366 0.7366)
			(drill 0.369824)
			(layers "*.Cu" "*.Mask")
			(remove_unused_layers no)
			(net "PCIE_RX_P0")
			(clearance 0.1778)
			(thermal_gap 0.1778)
		)
		(pad "AA5" thru_hole circle
			(at -16.500094 -2.999994)
			(size 0.7366 0.7366)
			(drill 0.369824)
			(layers "*.Cu" "*.Mask")
			(remove_unused_layers no)
			(net "PCIE_RX_N0")
			(clearance 0.1778)
			(thermal_gap 0.1778)
		)
		(pad "AA6" thru_hole circle
			(at -15.750032 -3.700018)
			(size 0.7366 0.7366)
			(drill 0.369824)
			(layers "*.Cu" "*.Mask")
			(remove_unused_layers no)
			(net "GND")
			(clearance 0.1778)
			(thermal_gap 0.1778)
		)
		(pad "AA7" thru_hole circle
			(at -14.99997 -4.400042)
			(size 0.7366 0.7366)
			(drill 0.369824)
			(layers "*.Cu" "*.Mask")
			(remove_unused_layers no)
			(net "PCIE_RX_P3")
			(clearance 0.1778)
			(thermal_gap 0.1778)
		)
		(pad "AA8" thru_hole circle
			(at -14.249908 -2.999994)
			(size 0.7366 0.7366)
			(drill 0.369824)
			(layers "*.Cu" "*.Mask")
			(remove_unused_layers no)
			(net "PCIE_RX_N3")
			(clearance 0.1778)
			(thermal_gap 0.1778)
		)
		(pad "AA9" thru_hole circle
			(at -13.5001 -3.700018)
			(size 0.7366 0.7366)
			(drill 0.369824)
			(layers "*.Cu" "*.Mask")
			(remove_unused_layers no)
			(net "GND")
			(clearance 0.1778)
			(thermal_gap 0.1778)
		)
		(pad "AB1" thru_hole circle
			(at -19.500088 -8.199882)
			(size 0.7366 0.7366)
			(drill 0.369824)
			(layers "*.Cu" "*.Mask")
			(remove_unused_layers no)
			(net "HOST5_RST_N_C")
			(clearance 0.1778)
			(thermal_gap 0.1778)
		)
		(pad "AB2" thru_hole circle
			(at -18.750026 -6.800088)
			(size 0.7366 0.7366)
			(drill 0.369824)
			(layers "*.Cu" "*.Mask")
			(remove_unused_layers no)
			(net "8644_SDA_R_5")
			(clearance 0.1778)
			(thermal_gap 0.1778)
		)
		(pad "AB3" thru_hole circle
			(at -17.999964 -7.500112)
			(size 0.7366 0.7366)
			(drill 0.369824)
			(layers "*.Cu" "*.Mask")
			(remove_unused_layers no)
			(net "GND")
			(clearance 0.1778)
			(thermal_gap 0.1778)
		)
		(pad "AB4" thru_hole circle
			(at -17.249902 -8.199882)
			(size 0.7366 0.7366)
			(drill 0.369824)
			(layers "*.Cu" "*.Mask")
			(remove_unused_layers no)
			(net "PCIE_RX_P1")
			(clearance 0.1778)
			(thermal_gap 0.1778)
		)
		(pad "AB5" thru_hole circle
			(at -16.500094 -6.800088)
			(size 0.7366 0.7366)
			(drill 0.369824)
			(layers "*.Cu" "*.Mask")
			(remove_unused_layers no)
			(net "PCIE_RX_N1")
			(clearance 0.1778)
			(thermal_gap 0.1778)
		)
		(pad "AB6" thru_hole circle
			(at -15.750032 -7.500112)
			(size 0.7366 0.7366)
			(drill 0.369824)
			(layers "*.Cu" "*.Mask")
			(remove_unused_layers no)
			(net "GND")
			(clearance 0.1778)
			(thermal_gap 0.1778)
		)
		(pad "AB7" thru_hole circle
			(at -14.99997 -8.199882)
			(size 0.7366 0.7366)
			(drill 0.369824)
			(layers "*.Cu" "*.Mask")
			(remove_unused_layers no)
			(net "PCIE_RX_P2")
			(clearance 0.1778)
			(thermal_gap 0.1778)
		)
		(pad "AB8" thru_hole circle
			(at -14.249908 -6.800088)
			(size 0.7366 0.7366)
			(drill 0.369824)
			(layers "*.Cu" "*.Mask")
			(remove_unused_layers no)
			(net "PCIE_RX_N2")
			(clearance 0.1778)
			(thermal_gap 0.1778)
		)
		(pad "AB9" thru_hole circle
			(at -13.5001 -7.500112)
			(size 0.7366 0.7366)
			(drill 0.369824)
			(layers "*.Cu" "*.Mask")
			(remove_unused_layers no)
			(net "GND")
			(clearance 0.1778)
			(thermal_gap 0.1778)
		)
		(pad "AC1" thru_hole circle
			(at -19.500088 -11.999976)
			(size 0.7366 0.7366)
			(drill 0.369824)
			(layers "*.Cu" "*.Mask")
			(remove_unused_layers no)
			(net "BMC_I2C11_MINI5_SCL")
			(clearance 0.1778)
			(thermal_gap 0.1778)
		)
		(pad "AC2" thru_hole circle
			(at -18.750026 -10.599928)
			(size 0.7366 0.7366)
			(drill 0.369824)
			(layers "*.Cu" "*.Mask")
			(remove_unused_layers no)
			(net "8644_CBL_PRSNT_R_5")
			(clearance 0.1778)
			(thermal_gap 0.1778)
		)
		(pad "AC3" thru_hole circle
			(at -17.999964 -11.299952)
			(size 0.7366 0.7366)
			(drill 0.369824)
			(layers "*.Cu" "*.Mask")
			(remove_unused_layers no)
			(net "GND")
			(clearance 0.1778)
			(thermal_gap 0.1778)
		)
		(pad "AC4" thru_hole circle
			(at -17.249902 -11.999976)
			(size 0.7366 0.7366)
			(drill 0.369824)
			(layers "*.Cu" "*.Mask")
			(remove_unused_layers no)
			(net "PCIE_TX_P0")
			(clearance 0.1778)
			(thermal_gap 0.1778)
		)
		(pad "AC5" thru_hole circle
			(at -16.500094 -10.599928)
			(size 0.7366 0.7366)
			(drill 0.369824)
			(layers "*.Cu" "*.Mask")
			(remove_unused_layers no)
			(net "PCIE_TX_N0")
			(clearance 0.1778)
			(thermal_gap 0.1778)
		)
		(pad "AC6" thru_hole circle
			(at -15.750032 -11.299952)
			(size 0.7366 0.7366)
			(drill 0.369824)
			(layers "*.Cu" "*.Mask")
			(remove_unused_layers no)
			(net "GND")
			(clearance 0.1778)
			(thermal_gap 0.1778)
		)
		(pad "AC7" thru_hole circle
			(at -14.99997 -11.999976)
			(size 0.7366 0.7366)
			(drill 0.369824)
			(layers "*.Cu" "*.Mask")
			(remove_unused_layers no)
			(net "PCIE_TX_P3")
			(clearance 0.1778)
			(thermal_gap 0.1778)
		)
		(pad "AC8" thru_hole circle
			(at -14.249908 -10.599928)
			(size 0.7366 0.7366)
			(drill 0.369824)
			(layers "*.Cu" "*.Mask")
			(remove_unused_layers no)
			(net "PCIE_TX_N3")
			(clearance 0.1778)
			(thermal_gap 0.1778)
		)
		(pad "AC9" thru_hole circle
			(at -13.5001 -11.299952)
			(size 0.7366 0.7366)
			(drill 0.369824)
			(layers "*.Cu" "*.Mask")
			(remove_unused_layers no)
			(net "GND")
			(clearance 0.1778)
			(thermal_gap 0.1778)
		)
		(pad "AD1" thru_hole circle
			(at -19.500088 -15.80007)
			(size 0.7366 0.7366)
			(drill 0.369824)
			(layers "*.Cu" "*.Mask")
			(remove_unused_layers no)
			(net "8644_USB_DN5")
			(clearance 0.1778)
			(thermal_gap 0.1778)
		)
		(pad "AD2" thru_hole circle
			(at -18.750026 -14.400022)
			(size 0.7366 0.7366)
			(drill 0.369824)
			(layers "*.Cu" "*.Mask")
			(remove_unused_layers no)
			(net "8644_USB_DP5")
			(clearance 0.1778)
			(thermal_gap 0.1778)
		)
		(pad "AD3" thru_hole circle
			(at -17.999964 -15.100046)
			(size 0.7366 0.7366)
			(drill 0.369824)
			(layers "*.Cu" "*.Mask")
			(remove_unused_layers no)
			(net "GND")
			(clearance 0.1778)
			(thermal_gap 0.1778)
		)
		(pad "AD4" thru_hole circle
			(at -17.249902 -15.80007)
			(size 0.7366 0.7366)
			(drill 0.369824)
			(layers "*.Cu" "*.Mask")
			(remove_unused_layers no)
			(net "PCIE_TX_P1")
			(clearance 0.1778)
			(thermal_gap 0.1778)
		)
		(pad "AD5" thru_hole circle
			(at -16.500094 -14.400022)
			(size 0.7366 0.7366)
			(drill 0.369824)
			(layers "*.Cu" "*.Mask")
			(remove_unused_layers no)
			(net "PCIE_TX_N1")
			(clearance 0.1778)
			(thermal_gap 0.1778)
		)
		(pad "AD6" thru_hole circle
			(at -15.750032 -15.100046)
			(size 0.7366 0.7366)
			(drill 0.369824)
			(layers "*.Cu" "*.Mask")
			(remove_unused_layers no)
			(net "GND")
			(clearance 0.1778)
			(thermal_gap 0.1778)
		)
		(pad "AD7" thru_hole circle
			(at -14.99997 -15.80007)
			(size 0.7366 0.7366)
			(drill 0.369824)
			(layers "*.Cu" "*.Mask")
			(remove_unused_layers no)
			(net "PCIE_TX_P2")
			(clearance 0.1778)
			(thermal_gap 0.1778)
		)
		(pad "AD8" thru_hole circle
			(at -14.249908 -14.400022)
			(size 0.7366 0.7366)
			(drill 0.369824)
			(layers "*.Cu" "*.Mask")
			(remove_unused_layers no)
			(net "PCIE_TX_N2")
			(clearance 0.1778)
			(thermal_gap 0.1778)
		)
		(pad "AD9" thru_hole circle
			(at -13.5001 -15.100046)
			(size 0.7366 0.7366)
			(drill 0.369824)
			(layers "*.Cu" "*.Mask")
			(remove_unused_layers no)
			(net "GND")
			(clearance 0.1778)
			(thermal_gap 0.1778)
		)
		(pad "BA1" thru_hole circle
			(at -8.50011 -4.400042)
			(size 0.7366 0.7366)
			(drill 0.369824)
			(layers "*.Cu" "*.Mask")
			(remove_unused_layers no)
			(net "CLK_P_6")
			(clearance 0.1778)
			(thermal_gap 0.1778)
		)
		(pad "BA2" thru_hole circle
			(at -7.750048 -2.999994)
			(size 0.7366 0.7366)
			(drill 0.369824)
			(layers "*.Cu" "*.Mask")
			(remove_unused_layers no)
			(net "CLK_N_6")
			(clearance 0.1778)
			(thermal_gap 0.1778)
		)
		(pad "BA3" thru_hole circle
			(at -6.999986 -3.700018)
			(size 0.7366 0.7366)
			(drill 0.369824)
			(layers "*.Cu" "*.Mask")
			(remove_unused_layers no)
			(net "GND")
			(clearance 0.1778)
			(thermal_gap 0.1778)
		)
		(pad "BA4" thru_hole circle
			(at -6.249924 -4.400042)
			(size 0.7366 0.7366)
			(drill 0.369824)
			(layers "*.Cu" "*.Mask")
			(remove_unused_layers no)
			(net "PCIE_RX_P4")
			(clearance 0.1778)
			(thermal_gap 0.1778)
		)
		(pad "BA5" thru_hole circle
			(at -5.500116 -2.999994)
			(size 0.7366 0.7366)
			(drill 0.369824)
			(layers "*.Cu" "*.Mask")
			(remove_unused_layers no)
			(net "PCIE_RX_N4")
			(clearance 0.1778)
			(thermal_gap 0.1778)
		)
		(pad "BA6" thru_hole circle
			(at -4.750054 -3.700018)
			(size 0.7366 0.7366)
			(drill 0.369824)
			(layers "*.Cu" "*.Mask")
			(remove_unused_layers no)
			(net "GND")
			(clearance 0.1778)
			(thermal_gap 0.1778)
		)
		(pad "BA7" thru_hole circle
			(at -3.999992 -4.400042)
			(size 0.7366 0.7366)
			(drill 0.369824)
			(layers "*.Cu" "*.Mask")
			(remove_unused_layers no)
			(net "PCIE_RX_P7")
			(clearance 0.1778)
			(thermal_gap 0.1778)
		)
		(pad "BA8" thru_hole circle
			(at -3.24993 -2.999994)
			(size 0.7366 0.7366)
			(drill 0.369824)
			(layers "*.Cu" "*.Mask")
			(remove_unused_layers no)
			(net "PCIE_RX_N7")
			(clearance 0.1778)
			(thermal_gap 0.1778)
		)
		(pad "BA9" thru_hole circle
			(at -2.500122 -3.700018)
			(size 0.7366 0.7366)
			(drill 0.369824)
			(layers "*.Cu" "*.Mask")
			(remove_unused_layers no)
			(net "GND")
			(clearance 0.1778)
			(thermal_gap 0.1778)
		)
		(pad "BB1" thru_hole circle
			(at -8.50011 -8.199882)
			(size 0.7366 0.7366)
			(drill 0.369824)
			(layers "*.Cu" "*.Mask")
			(remove_unused_layers no)
			(net "HOST6_RST_N_C")
			(clearance 0.1778)
			(thermal_gap 0.1778)
		)
		(pad "BB2" thru_hole circle
			(at -7.750048 -6.800088)
			(size 0.7366 0.7366)
			(drill 0.369824)
			(layers "*.Cu" "*.Mask")
			(remove_unused_layers no)
			(net "8644_SDA_R_6")
			(clearance 0.1778)
			(thermal_gap 0.1778)
		)
		(pad "BB3" thru_hole circle
			(at -6.999986 -7.500112)
			(size 0.7366 0.7366)
			(drill 0.369824)
			(layers "*.Cu" "*.Mask")
			(remove_unused_layers no)
			(net "GND")
			(clearance 0.1778)
			(thermal_gap 0.1778)
		)
		(pad "BB4" thru_hole circle
			(at -6.249924 -8.199882)
			(size 0.7366 0.7366)
			(drill 0.369824)
			(layers "*.Cu" "*.Mask")
			(remove_unused_layers no)
			(net "PCIE_RX_P5")
			(clearance 0.1778)
			(thermal_gap 0.1778)
		)
		(pad "BB5" thru_hole circle
			(at -5.500116 -6.800088)
			(size 0.7366 0.7366)
			(drill 0.369824)
			(layers "*.Cu" "*.Mask")
			(remove_unused_layers no)
			(net "PCIE_RX_N5")
			(clearance 0.1778)
			(thermal_gap 0.1778)
		)
		(pad "BB6" thru_hole circle
			(at -4.750054 -7.500112)
			(size 0.7366 0.7366)
			(drill 0.369824)
			(layers "*.Cu" "*.Mask")
			(remove_unused_layers no)
			(net "GND")
			(clearance 0.1778)
			(thermal_gap 0.1778)
		)
		(pad "BB7" thru_hole circle
			(at -3.999992 -8.199882)
			(size 0.7366 0.7366)
			(drill 0.369824)
			(layers "*.Cu" "*.Mask")
			(remove_unused_layers no)
			(net "PCIE_RX_P6")
			(clearance 0.1778)
			(thermal_gap 0.1778)
		)
		(pad "BB8" thru_hole circle
			(at -3.24993 -6.800088)
			(size 0.7366 0.7366)
			(drill 0.369824)
			(layers "*.Cu" "*.Mask")
			(remove_unused_layers no)
			(net "PCIE_RX_N6")
			(clearance 0.1778)
			(thermal_gap 0.1778)
		)
		(pad "BB9" thru_hole circle
			(at -2.500122 -7.500112)
			(size 0.7366 0.7366)
			(drill 0.369824)
			(layers "*.Cu" "*.Mask")
			(remove_unused_layers no)
			(net "GND")
			(clearance 0.1778)
			(thermal_gap 0.1778)
		)
		(pad "BC1" thru_hole circle
			(at -8.50011 -11.999976)
			(size 0.7366 0.7366)
			(drill 0.369824)
			(layers "*.Cu" "*.Mask")
			(remove_unused_layers no)
			(net "BMC_I2C12_MINI6_SCL")
			(clearance 0.1778)
			(thermal_gap 0.1778)
		)
		(pad "BC2" thru_hole circle
			(at -7.750048 -10.599928)
			(size 0.7366 0.7366)
			(drill 0.369824)
			(layers "*.Cu" "*.Mask")
			(remove_unused_layers no)
			(net "8644_CBL_PRSNT_R_6")
			(clearance 0.1778)
			(thermal_gap 0.1778)
		)
		(pad "BC3" thru_hole circle
			(at -6.999986 -11.299952)
			(size 0.7366 0.7366)
			(drill 0.369824)
			(layers "*.Cu" "*.Mask")
			(remove_unused_layers no)
			(net "GND")
			(clearance 0.1778)
			(thermal_gap 0.1778)
		)
		(pad "BC4" thru_hole circle
			(at -6.249924 -11.999976)
			(size 0.7366 0.7366)
			(drill 0.369824)
			(layers "*.Cu" "*.Mask")
			(remove_unused_layers no)
			(net "PCIE_TX_P4")
			(clearance 0.1778)
			(thermal_gap 0.1778)
		)
		(pad "BC5" thru_hole circle
			(at -5.500116 -10.599928)
			(size 0.7366 0.7366)
			(drill 0.369824)
			(layers "*.Cu" "*.Mask")
			(remove_unused_layers no)
			(net "PCIE_TX_N4")
			(clearance 0.1778)
			(thermal_gap 0.1778)
		)
		(pad "BC6" thru_hole circle
			(at -4.750054 -11.299952)
			(size 0.7366 0.7366)
			(drill 0.369824)
			(layers "*.Cu" "*.Mask")
			(remove_unused_layers no)
			(net "GND")
			(clearance 0.1778)
			(thermal_gap 0.1778)
		)
		(pad "BC7" thru_hole circle
			(at -3.999992 -11.999976)
			(size 0.7366 0.7366)
			(drill 0.369824)
			(layers "*.Cu" "*.Mask")
			(remove_unused_layers no)
			(net "PCIE_TX_P7")
			(clearance 0.1778)
			(thermal_gap 0.1778)
		)
		(pad "BC8" thru_hole circle
			(at -3.24993 -10.599928)
			(size 0.7366 0.7366)
			(drill 0.369824)
			(layers "*.Cu" "*.Mask")
			(remove_unused_layers no)
			(net "PCIE_TX_N7")
			(clearance 0.1778)
			(thermal_gap 0.1778)
		)
		(pad "BC9" thru_hole circle
			(at -2.500122 -11.299952)
			(size 0.7366 0.7366)
			(drill 0.369824)
			(layers "*.Cu" "*.Mask")
			(remove_unused_layers no)
			(net "GND")
			(clearance 0.1778)
			(thermal_gap 0.1778)
		)
		(pad "BD1" thru_hole circle
			(at -8.50011 -15.80007)
			(size 0.7366 0.7366)
			(drill 0.369824)
			(layers "*.Cu" "*.Mask")
			(remove_unused_layers no)
			(net "8644_USB_DN6")
			(clearance 0.1778)
			(thermal_gap 0.1778)
		)
		(pad "BD2" thru_hole circle
			(at -7.750048 -14.400022)
			(size 0.7366 0.7366)
			(drill 0.369824)
			(layers "*.Cu" "*.Mask")
			(remove_unused_layers no)
			(net "8644_USB_DP6")
			(clearance 0.1778)
			(thermal_gap 0.1778)
		)
		(pad "BD3" thru_hole circle
			(at -6.999986 -15.100046)
			(size 0.7366 0.7366)
			(drill 0.369824)
			(layers "*.Cu" "*.Mask")
			(remove_unused_layers no)
			(net "GND")
			(clearance 0.1778)
			(thermal_gap 0.1778)
		)
		(pad "BD4" thru_hole circle
			(at -6.249924 -15.80007)
			(size 0.7366 0.7366)
			(drill 0.369824)
			(layers "*.Cu" "*.Mask")
			(remove_unused_layers no)
			(net "PCIE_TX_P5")
			(clearance 0.1778)
			(thermal_gap 0.1778)
		)
		(pad "BD5" thru_hole circle
			(at -5.500116 -14.400022)
			(size 0.7366 0.7366)
			(drill 0.369824)
			(layers "*.Cu" "*.Mask")
			(remove_unused_layers no)
			(net "PCIE_TX_N5")
			(clearance 0.1778)
			(thermal_gap 0.1778)
		)
		(pad "BD6" thru_hole circle
			(at -4.750054 -15.100046)
			(size 0.7366 0.7366)
			(drill 0.369824)
			(layers "*.Cu" "*.Mask")
			(remove_unused_layers no)
			(net "GND")
			(clearance 0.1778)
			(thermal_gap 0.1778)
		)
		(pad "BD7" thru_hole circle
			(at -3.999992 -15.80007)
			(size 0.7366 0.7366)
			(drill 0.369824)
			(layers "*.Cu" "*.Mask")
			(remove_unused_layers no)
			(net "PCIE_TX_P6")
			(clearance 0.1778)
			(thermal_gap 0.1778)
		)
		(pad "BD8" thru_hole circle
			(at -3.24993 -14.400022)
			(size 0.7366 0.7366)
			(drill 0.369824)
			(layers "*.Cu" "*.Mask")
			(remove_unused_layers no)
			(net "PCIE_TX_N6")
			(clearance 0.1778)
			(thermal_gap 0.1778)
		)
		(pad "BD9" thru_hole circle
			(at -2.500122 -15.100046)
			(size 0.7366 0.7366)
			(drill 0.369824)
			(layers "*.Cu" "*.Mask")
			(remove_unused_layers no)
			(net "GND")
			(clearance 0.1778)
			(thermal_gap 0.1778)
		)
		(pad "CA1" thru_hole circle
			(at 2.500122 -4.400042)
			(size 0.7366 0.7366)
			(drill 0.369824)
			(layers "*.Cu" "*.Mask")
			(remove_unused_layers no)
			(net "PCIE_REFCLK_H1_P_R")
			(clearance 0.1778)
			(thermal_gap 0.1778)
		)
		(pad "CA2" thru_hole circle
			(at 3.24993 -2.999994)
			(size 0.7366 0.7366)
			(drill 0.369824)
			(layers "*.Cu" "*.Mask")
			(remove_unused_layers no)
			(net "PCIE_REFCLK_H1_N_R")
			(clearance 0.1778)
			(thermal_gap 0.1778)
		)
		(pad "CA3" thru_hole circle
			(at 3.999992 -3.700018)
			(size 0.7366 0.7366)
			(drill 0.369824)
			(layers "*.Cu" "*.Mask")
			(remove_unused_layers no)
			(net "GND")
			(clearance 0.1778)
			(thermal_gap 0.1778)
		)
		(pad "CA4" thru_hole circle
			(at 4.750054 -4.400042)
			(size 0.7366 0.7366)
			(drill 0.369824)
			(layers "*.Cu" "*.Mask")
			(remove_unused_layers no)
			(net "PCIE_RX_P8")
			(clearance 0.1778)
			(thermal_gap 0.1778)
		)
		(pad "CA5" thru_hole circle
			(at 5.500116 -2.999994)
			(size 0.7366 0.7366)
			(drill 0.369824)
			(layers "*.Cu" "*.Mask")
			(remove_unused_layers no)
			(net "PCIE_RX_N8")
			(clearance 0.1778)
			(thermal_gap 0.1778)
		)
		(pad "CA6" thru_hole circle
			(at 6.249924 -3.700018)
			(size 0.7366 0.7366)
			(drill 0.369824)
			(layers "*.Cu" "*.Mask")
			(remove_unused_layers no)
			(net "GND")
			(clearance 0.1778)
			(thermal_gap 0.1778)
		)
		(pad "CA7" thru_hole circle
			(at 6.999986 -4.400042)
			(size 0.7366 0.7366)
			(drill 0.369824)
			(layers "*.Cu" "*.Mask")
			(remove_unused_layers no)
			(net "PCIE_RX_P11")
			(clearance 0.1778)
			(thermal_gap 0.1778)
		)
		(pad "CA8" thru_hole circle
			(at 7.750048 -2.999994)
			(size 0.7366 0.7366)
			(drill 0.369824)
			(layers "*.Cu" "*.Mask")
			(remove_unused_layers no)
			(net "PCIE_RX_N11")
			(clearance 0.1778)
			(thermal_gap 0.1778)
		)
		(pad "CA9" thru_hole circle
			(at 8.50011 -3.700018)
			(size 0.7366 0.7366)
			(drill 0.369824)
			(layers "*.Cu" "*.Mask")
			(remove_unused_layers no)
			(net "GND")
			(clearance 0.1778)
			(thermal_gap 0.1778)
		)
		(pad "CB1" thru_hole circle
			(at 2.500122 -8.199882)
			(size 0.7366 0.7366)
			(drill 0.369824)
			(layers "*.Cu" "*.Mask")
			(remove_unused_layers no)
			(net "HOST7_RST_N_C")
			(clearance 0.1778)
			(thermal_gap 0.1778)
		)
		(pad "CB2" thru_hole circle
			(at 3.24993 -6.800088)
			(size 0.7366 0.7366)
			(drill 0.369824)
			(layers "*.Cu" "*.Mask")
			(remove_unused_layers no)
			(net "8644_SDA_R_7")
			(clearance 0.1778)
			(thermal_gap 0.1778)
		)
		(pad "CB3" thru_hole circle
			(at 3.999992 -7.500112)
			(size 0.7366 0.7366)
			(drill 0.369824)
			(layers "*.Cu" "*.Mask")
			(remove_unused_layers no)
			(net "GND")
			(clearance 0.1778)
			(thermal_gap 0.1778)
		)
		(pad "CB4" thru_hole circle
			(at 4.750054 -8.199882)
			(size 0.7366 0.7366)
			(drill 0.369824)
			(layers "*.Cu" "*.Mask")
			(remove_unused_layers no)
			(net "PCIE_RX_P9")
			(clearance 0.1778)
			(thermal_gap 0.1778)
		)
		(pad "CB5" thru_hole circle
			(at 5.500116 -6.800088)
			(size 0.7366 0.7366)
			(drill 0.369824)
			(layers "*.Cu" "*.Mask")
			(remove_unused_layers no)
			(net "PCIE_RX_N9")
			(clearance 0.1778)
			(thermal_gap 0.1778)
		)
		(pad "CB6" thru_hole circle
			(at 6.249924 -7.500112)
			(size 0.7366 0.7366)
			(drill 0.369824)
			(layers "*.Cu" "*.Mask")
			(remove_unused_layers no)
			(net "GND")
			(clearance 0.1778)
			(thermal_gap 0.1778)
		)
		(pad "CB7" thru_hole circle
			(at 6.999986 -8.199882)
			(size 0.7366 0.7366)
			(drill 0.369824)
			(layers "*.Cu" "*.Mask")
			(remove_unused_layers no)
			(net "PCIE_RX_P10")
			(clearance 0.1778)
			(thermal_gap 0.1778)
		)
		(pad "CB8" thru_hole circle
			(at 7.750048 -6.800088)
			(size 0.7366 0.7366)
			(drill 0.369824)
			(layers "*.Cu" "*.Mask")
			(remove_unused_layers no)
			(net "PCIE_RX_N10")
			(clearance 0.1778)
			(thermal_gap 0.1778)
		)
		(pad "CB9" thru_hole circle
			(at 8.50011 -7.500112)
			(size 0.7366 0.7366)
			(drill 0.369824)
			(layers "*.Cu" "*.Mask")
			(remove_unused_layers no)
			(net "GND")
			(clearance 0.1778)
			(thermal_gap 0.1778)
		)
		(pad "CC1" thru_hole circle
			(at 2.500122 -11.999976)
			(size 0.7366 0.7366)
			(drill 0.369824)
			(layers "*.Cu" "*.Mask")
			(remove_unused_layers no)
			(net "BMC_I2C13_MINI7_SCL")
			(clearance 0.1778)
			(thermal_gap 0.1778)
		)
		(pad "CC2" thru_hole circle
			(at 3.24993 -10.599928)
			(size 0.7366 0.7366)
			(drill 0.369824)
			(layers "*.Cu" "*.Mask")
			(remove_unused_layers no)
			(net "8644_CBL_PRSNT_R_7")
			(clearance 0.1778)
			(thermal_gap 0.1778)
		)
		(pad "CC3" thru_hole circle
			(at 3.999992 -11.299952)
			(size 0.7366 0.7366)
			(drill 0.369824)
			(layers "*.Cu" "*.Mask")
			(remove_unused_layers no)
			(net "GND")
			(clearance 0.1778)
			(thermal_gap 0.1778)
		)
		(pad "CC4" thru_hole circle
			(at 4.750054 -11.999976)
			(size 0.7366 0.7366)
			(drill 0.369824)
			(layers "*.Cu" "*.Mask")
			(remove_unused_layers no)
			(net "PCIE_TX_P8")
			(clearance 0.1778)
			(thermal_gap 0.1778)
		)
		(pad "CC5" thru_hole circle
			(at 5.500116 -10.599928)
			(size 0.7366 0.7366)
			(drill 0.369824)
			(layers "*.Cu" "*.Mask")
			(remove_unused_layers no)
			(net "PCIE_TX_N8")
			(clearance 0.1778)
			(thermal_gap 0.1778)
		)
		(pad "CC6" thru_hole circle
			(at 6.249924 -11.299952)
			(size 0.7366 0.7366)
			(drill 0.369824)
			(layers "*.Cu" "*.Mask")
			(remove_unused_layers no)
			(net "GND")
			(clearance 0.1778)
			(thermal_gap 0.1778)
		)
		(pad "CC7" thru_hole circle
			(at 6.999986 -11.999976)
			(size 0.7366 0.7366)
			(drill 0.369824)
			(layers "*.Cu" "*.Mask")
			(remove_unused_layers no)
			(net "PCIE_TX_P11")
			(clearance 0.1778)
			(thermal_gap 0.1778)
		)
		(pad "CC8" thru_hole circle
			(at 7.750048 -10.599928)
			(size 0.7366 0.7366)
			(drill 0.369824)
			(layers "*.Cu" "*.Mask")
			(remove_unused_layers no)
			(net "PCIE_TX_N11")
			(clearance 0.1778)
			(thermal_gap 0.1778)
		)
		(pad "CC9" thru_hole circle
			(at 8.50011 -11.299952)
			(size 0.7366 0.7366)
			(drill 0.369824)
			(layers "*.Cu" "*.Mask")
			(remove_unused_layers no)
			(net "GND")
			(clearance 0.1778)
			(thermal_gap 0.1778)
		)
		(pad "CD1" thru_hole circle
			(at 2.500122 -15.80007)
			(size 0.7366 0.7366)
			(drill 0.369824)
			(layers "*.Cu" "*.Mask")
			(remove_unused_layers no)
			(net "8644_USB_DN7")
			(clearance 0.1778)
			(thermal_gap 0.1778)
		)
		(pad "CD2" thru_hole circle
			(at 3.24993 -14.400022)
			(size 0.7366 0.7366)
			(drill 0.369824)
			(layers "*.Cu" "*.Mask")
			(remove_unused_layers no)
			(net "8644_USB_DP7")
			(clearance 0.1778)
			(thermal_gap 0.1778)
		)
		(pad "CD3" thru_hole circle
			(at 3.999992 -15.100046)
			(size 0.7366 0.7366)
			(drill 0.369824)
			(layers "*.Cu" "*.Mask")
			(remove_unused_layers no)
			(net "GND")
			(clearance 0.1778)
			(thermal_gap 0.1778)
		)
		(pad "CD4" thru_hole circle
			(at 4.750054 -15.80007)
			(size 0.7366 0.7366)
			(drill 0.369824)
			(layers "*.Cu" "*.Mask")
			(remove_unused_layers no)
			(net "PCIE_TX_P9")
			(clearance 0.1778)
			(thermal_gap 0.1778)
		)
		(pad "CD5" thru_hole circle
			(at 5.500116 -14.400022)
			(size 0.7366 0.7366)
			(drill 0.369824)
			(layers "*.Cu" "*.Mask")
			(remove_unused_layers no)
			(net "PCIE_TX_N9")
			(clearance 0.1778)
			(thermal_gap 0.1778)
		)
		(pad "CD6" thru_hole circle
			(at 6.249924 -15.100046)
			(size 0.7366 0.7366)
			(drill 0.369824)
			(layers "*.Cu" "*.Mask")
			(remove_unused_layers no)
			(net "GND")
			(clearance 0.1778)
			(thermal_gap 0.1778)
		)
		(pad "CD7" thru_hole circle
			(at 6.999986 -15.80007)
			(size 0.7366 0.7366)
			(drill 0.369824)
			(layers "*.Cu" "*.Mask")
			(remove_unused_layers no)
			(net "PCIE_TX_P10")
			(clearance 0.1778)
			(thermal_gap 0.1778)
		)
		(pad "CD8" thru_hole circle
			(at 7.750048 -14.400022)
			(size 0.7366 0.7366)
			(drill 0.369824)
			(layers "*.Cu" "*.Mask")
			(remove_unused_layers no)
			(net "PCIE_TX_N10")
			(clearance 0.1778)
			(thermal_gap 0.1778)
		)
		(pad "CD9" thru_hole circle
			(at 8.50011 -15.100046)
			(size 0.7366 0.7366)
			(drill 0.369824)
			(layers "*.Cu" "*.Mask")
			(remove_unused_layers no)
			(net "GND")
			(clearance 0.1778)
			(thermal_gap 0.1778)
		)
		(pad "DA1" thru_hole circle
			(at 13.5001 -4.400042)
			(size 0.7366 0.7366)
			(drill 0.369824)
			(layers "*.Cu" "*.Mask")
			(remove_unused_layers no)
			(net "CLK_P_8")
			(clearance 0.1778)
			(thermal_gap 0.1778)
		)
		(pad "DA2" thru_hole circle
			(at 14.249908 -2.999994)
			(size 0.7366 0.7366)
			(drill 0.369824)
			(layers "*.Cu" "*.Mask")
			(remove_unused_layers no)
			(net "CLK_N_8")
			(clearance 0.1778)
			(thermal_gap 0.1778)
		)
		(pad "DA3" thru_hole circle
			(at 14.99997 -3.700018)
			(size 0.7366 0.7366)
			(drill 0.369824)
			(layers "*.Cu" "*.Mask")
			(remove_unused_layers no)
			(net "GND")
			(clearance 0.1778)
			(thermal_gap 0.1778)
		)
		(pad "DA4" thru_hole circle
			(at 15.750032 -4.400042)
			(size 0.7366 0.7366)
			(drill 0.369824)
			(layers "*.Cu" "*.Mask")
			(remove_unused_layers no)
			(net "PCIE_RX_P12")
			(clearance 0.1778)
			(thermal_gap 0.1778)
		)
		(pad "DA5" thru_hole circle
			(at 16.500094 -2.999994)
			(size 0.7366 0.7366)
			(drill 0.369824)
			(layers "*.Cu" "*.Mask")
			(remove_unused_layers no)
			(net "PCIE_RX_N12")
			(clearance 0.1778)
			(thermal_gap 0.1778)
		)
		(pad "DA6" thru_hole circle
			(at 17.249902 -3.700018)
			(size 0.7366 0.7366)
			(drill 0.369824)
			(layers "*.Cu" "*.Mask")
			(remove_unused_layers no)
			(net "GND")
			(clearance 0.1778)
			(thermal_gap 0.1778)
		)
		(pad "DA7" thru_hole circle
			(at 17.999964 -4.400042)
			(size 0.7366 0.7366)
			(drill 0.369824)
			(layers "*.Cu" "*.Mask")
			(remove_unused_layers no)
			(net "PCIE_RX_P15")
			(clearance 0.1778)
			(thermal_gap 0.1778)
		)
		(pad "DA8" thru_hole circle
			(at 18.750026 -2.999994)
			(size 0.7366 0.7366)
			(drill 0.369824)
			(layers "*.Cu" "*.Mask")
			(remove_unused_layers no)
			(net "PCIE_RX_N15")
			(clearance 0.1778)
			(thermal_gap 0.1778)
		)
		(pad "DA9" thru_hole circle
			(at 19.500088 -3.700018)
			(size 0.7366 0.7366)
			(drill 0.369824)
			(layers "*.Cu" "*.Mask")
			(remove_unused_layers no)
			(net "GND")
			(clearance 0.1778)
			(thermal_gap 0.1778)
		)
		(pad "DB1" thru_hole circle
			(at 13.5001 -8.199882)
			(size 0.7366 0.7366)
			(drill 0.369824)
			(layers "*.Cu" "*.Mask")
			(remove_unused_layers no)
			(net "HOST8_RST_N_C")
			(clearance 0.1778)
			(thermal_gap 0.1778)
		)
		(pad "DB2" thru_hole circle
			(at 14.249908 -6.800088)
			(size 0.7366 0.7366)
			(drill 0.369824)
			(layers "*.Cu" "*.Mask")
			(remove_unused_layers no)
			(net "8644_SDA_R_8")
			(clearance 0.1778)
			(thermal_gap 0.1778)
		)
		(pad "DB3" thru_hole circle
			(at 14.99997 -7.500112)
			(size 0.7366 0.7366)
			(drill 0.369824)
			(layers "*.Cu" "*.Mask")
			(remove_unused_layers no)
			(net "GND")
			(clearance 0.1778)
			(thermal_gap 0.1778)
		)
		(pad "DB4" thru_hole circle
			(at 15.750032 -8.199882)
			(size 0.7366 0.7366)
			(drill 0.369824)
			(layers "*.Cu" "*.Mask")
			(remove_unused_layers no)
			(net "PCIE_RX_P13")
			(clearance 0.1778)
			(thermal_gap 0.1778)
		)
		(pad "DB5" thru_hole circle
			(at 16.500094 -6.800088)
			(size 0.7366 0.7366)
			(drill 0.369824)
			(layers "*.Cu" "*.Mask")
			(remove_unused_layers no)
			(net "PCIE_RX_N13")
			(clearance 0.1778)
			(thermal_gap 0.1778)
		)
		(pad "DB6" thru_hole circle
			(at 17.249902 -7.500112)
			(size 0.7366 0.7366)
			(drill 0.369824)
			(layers "*.Cu" "*.Mask")
			(remove_unused_layers no)
			(net "GND")
			(clearance 0.1778)
			(thermal_gap 0.1778)
		)
		(pad "DB7" thru_hole circle
			(at 17.999964 -8.199882)
			(size 0.7366 0.7366)
			(drill 0.369824)
			(layers "*.Cu" "*.Mask")
			(remove_unused_layers no)
			(net "PCIE_RX_P14")
			(clearance 0.1778)
			(thermal_gap 0.1778)
		)
		(pad "DB8" thru_hole circle
			(at 18.750026 -6.800088)
			(size 0.7366 0.7366)
			(drill 0.369824)
			(layers "*.Cu" "*.Mask")
			(remove_unused_layers no)
			(net "PCIE_RX_N14")
			(clearance 0.1778)
			(thermal_gap 0.1778)
		)
		(pad "DB9" thru_hole circle
			(at 19.500088 -7.500112)
			(size 0.7366 0.7366)
			(drill 0.369824)
			(layers "*.Cu" "*.Mask")
			(remove_unused_layers no)
			(net "GND")
			(clearance 0.1778)
			(thermal_gap 0.1778)
		)
		(pad "DC1" thru_hole circle
			(at 13.5001 -11.999976)
			(size 0.7366 0.7366)
			(drill 0.369824)
			(layers "*.Cu" "*.Mask")
			(remove_unused_layers no)
			(net "BMC_I2C14_MINI8_SCL")
			(clearance 0.1778)
			(thermal_gap 0.1778)
		)
		(pad "DC2" thru_hole circle
			(at 14.249908 -10.599928)
			(size 0.7366 0.7366)
			(drill 0.369824)
			(layers "*.Cu" "*.Mask")
			(remove_unused_layers no)
			(net "8644_CBL_PRSNT_R_8")
			(clearance 0.1778)
			(thermal_gap 0.1778)
		)
		(pad "DC3" thru_hole circle
			(at 14.99997 -11.299952)
			(size 0.7366 0.7366)
			(drill 0.369824)
			(layers "*.Cu" "*.Mask")
			(remove_unused_layers no)
			(net "GND")
			(clearance 0.1778)
			(thermal_gap 0.1778)
		)
		(pad "DC4" thru_hole circle
			(at 15.750032 -11.999976)
			(size 0.7366 0.7366)
			(drill 0.369824)
			(layers "*.Cu" "*.Mask")
			(remove_unused_layers no)
			(net "PCIE_TX_P12")
			(clearance 0.1778)
			(thermal_gap 0.1778)
		)
		(pad "DC5" thru_hole circle
			(at 16.500094 -10.599928)
			(size 0.7366 0.7366)
			(drill 0.369824)
			(layers "*.Cu" "*.Mask")
			(remove_unused_layers no)
			(net "PCIE_TX_N12")
			(clearance 0.1778)
			(thermal_gap 0.1778)
		)
		(pad "DC6" thru_hole circle
			(at 17.249902 -11.299952)
			(size 0.7366 0.7366)
			(drill 0.369824)
			(layers "*.Cu" "*.Mask")
			(remove_unused_layers no)
			(net "GND")
			(clearance 0.1778)
			(thermal_gap 0.1778)
		)
		(pad "DC7" thru_hole circle
			(at 17.999964 -11.999976)
			(size 0.7366 0.7366)
			(drill 0.369824)
			(layers "*.Cu" "*.Mask")
			(remove_unused_layers no)
			(net "PCIE_TX_P15")
			(clearance 0.1778)
			(thermal_gap 0.1778)
		)
		(pad "DC8" thru_hole circle
			(at 18.750026 -10.599928)
			(size 0.7366 0.7366)
			(drill 0.369824)
			(layers "*.Cu" "*.Mask")
			(remove_unused_layers no)
			(net "PCIE_TX_N15")
			(clearance 0.1778)
			(thermal_gap 0.1778)
		)
		(pad "DC9" thru_hole circle
			(at 19.500088 -11.299952)
			(size 0.7366 0.7366)
			(drill 0.369824)
			(layers "*.Cu" "*.Mask")
			(remove_unused_layers no)
			(net "GND")
			(clearance 0.1778)
			(thermal_gap 0.1778)
		)
		(pad "DD1" thru_hole circle
			(at 13.5001 -15.80007)
			(size 0.7366 0.7366)
			(drill 0.369824)
			(layers "*.Cu" "*.Mask")
			(remove_unused_layers no)
			(net "8644_USB_DN8")
			(clearance 0.1778)
			(thermal_gap 0.1778)
		)
		(pad "DD2" thru_hole circle
			(at 14.249908 -14.400022)
			(size 0.7366 0.7366)
			(drill 0.369824)
			(layers "*.Cu" "*.Mask")
			(remove_unused_layers no)
			(net "8644_USB_DP8")
			(clearance 0.1778)
			(thermal_gap 0.1778)
		)
		(pad "DD3" thru_hole circle
			(at 14.99997 -15.100046)
			(size 0.7366 0.7366)
			(drill 0.369824)
			(layers "*.Cu" "*.Mask")
			(remove_unused_layers no)
			(net "GND")
			(clearance 0.1778)
			(thermal_gap 0.1778)
		)
		(pad "DD4" thru_hole circle
			(at 15.750032 -15.80007)
			(size 0.7366 0.7366)
			(drill 0.369824)
			(layers "*.Cu" "*.Mask")
			(remove_unused_layers no)
			(net "PCIE_TX_P13")
			(clearance 0.1778)
			(thermal_gap 0.1778)
		)
		(pad "DD5" thru_hole circle
			(at 16.500094 -14.400022)
			(size 0.7366 0.7366)
			(drill 0.369824)
			(layers "*.Cu" "*.Mask")
			(remove_unused_layers no)
			(net "PCIE_TX_N13")
			(clearance 0.1778)
			(thermal_gap 0.1778)
		)
		(pad "DD6" thru_hole circle
			(at 17.249902 -15.100046)
			(size 0.7366 0.7366)
			(drill 0.369824)
			(layers "*.Cu" "*.Mask")
			(remove_unused_layers no)
			(net "GND")
			(clearance 0.1778)
			(thermal_gap 0.1778)
		)
		(pad "DD7" thru_hole circle
			(at 17.999964 -15.80007)
			(size 0.7366 0.7366)
			(drill 0.369824)
			(layers "*.Cu" "*.Mask")
			(remove_unused_layers no)
			(net "PCIE_TX_P14")
			(clearance 0.1778)
			(thermal_gap 0.1778)
		)
		(pad "DD8" thru_hole circle
			(at 18.750026 -14.400022)
			(size 0.7366 0.7366)
			(drill 0.369824)
			(layers "*.Cu" "*.Mask")
			(remove_unused_layers no)
			(net "PCIE_TX_N14")
			(clearance 0.1778)
			(thermal_gap 0.1778)
		)
		(pad "DD9" thru_hole circle
			(at 19.500088 -15.100046)
			(size 0.7366 0.7366)
			(drill 0.369824)
			(layers "*.Cu" "*.Mask")
			(remove_unused_layers no)
			(net "GND")
			(clearance 0.1778)
			(thermal_gap 0.1778)
		)
		(pad "PTH1" thru_hole circle
			(at -21.999956 -3.700018)
			(size 0.9144 0.9144)
			(drill 0.569976)
			(layers "*.Cu" "*.Mask")
			(remove_unused_layers no)
			(net "GND")
			(clearance 0.1905)
			(thermal_gap 0.1905)
		)
		(pad "PTH2" thru_hole circle
			(at -17.999964 -17.509998)
			(size 0.9144 0.9144)
			(drill 0.569976)
			(layers "*.Cu" "*.Mask")
			(remove_unused_layers no)
			(net "GND")
			(clearance 0.1905)
			(thermal_gap 0.1905)
		)
		(pad "PTH3" thru_hole circle
			(at -13.5001 -17.509998)
			(size 0.9144 0.9144)
			(drill 0.569976)
			(layers "*.Cu" "*.Mask")
			(remove_unused_layers no)
			(net "GND")
			(clearance 0.1905)
			(thermal_gap 0.1905)
		)
		(pad "PTH4" thru_hole circle
			(at -6.999986 -17.509998)
			(size 0.9144 0.9144)
			(drill 0.569976)
			(layers "*.Cu" "*.Mask")
			(remove_unused_layers no)
			(net "GND")
			(clearance 0.1905)
			(thermal_gap 0.1905)
		)
		(pad "PTH5" thru_hole circle
			(at -2.500122 -17.509998)
			(size 0.9144 0.9144)
			(drill 0.569976)
			(layers "*.Cu" "*.Mask")
			(remove_unused_layers no)
			(net "GND")
			(clearance 0.1905)
			(thermal_gap 0.1905)
		)
		(pad "PTH6" thru_hole circle
			(at 3.999992 -17.509998)
			(size 0.9144 0.9144)
			(drill 0.569976)
			(layers "*.Cu" "*.Mask")
			(remove_unused_layers no)
			(net "GND")
			(clearance 0.1905)
			(thermal_gap 0.1905)
		)
		(pad "PTH7" thru_hole circle
			(at 8.50011 -17.509998)
			(size 0.9144 0.9144)
			(drill 0.569976)
			(layers "*.Cu" "*.Mask")
			(remove_unused_layers no)
			(net "GND")
			(clearance 0.1905)
			(thermal_gap 0.1905)
		)
		(pad "PTH8" thru_hole circle
			(at 14.99997 -17.509998)
			(size 0.9144 0.9144)
			(drill 0.569976)
			(layers "*.Cu" "*.Mask")
			(remove_unused_layers no)
			(net "GND")
			(clearance 0.1905)
			(thermal_gap 0.1905)
		)
		(pad "PTH9" thru_hole circle
			(at 19.500088 -17.509998)
			(size 0.9144 0.9144)
			(drill 0.569976)
			(layers "*.Cu" "*.Mask")
			(remove_unused_layers no)
			(net "GND")
			(clearance 0.1905)
			(thermal_gap 0.1905)
		)
		(pad "PTH10" thru_hole circle
			(at 21.999956 -3.700018)
			(size 0.9144 0.9144)
			(drill 0.569976)
			(layers "*.Cu" "*.Mask")
			(remove_unused_layers no)
			(net "GND")
			(clearance 0.1905)
			(thermal_gap 0.1905)
		)
		(pad "PTH11" thru_hole circle
			(at 21.999956 9.61009)
			(size 0.9144 0.9144)
			(drill 0.569976)
			(layers "*.Cu" "*.Mask")
			(remove_unused_layers no)
			(net "GND")
			(clearance 0.1905)
			(thermal_gap 0.1905)
		)
		(pad "PTH12" thru_hole circle
			(at 10.999978 9.61009)
			(size 0.9144 0.9144)
			(drill 0.569976)
			(layers "*.Cu" "*.Mask")
			(remove_unused_layers no)
			(net "GND")
			(clearance 0.1905)
			(thermal_gap 0.1905)
		)
		(pad "PTH13" thru_hole circle
			(at 0 9.61009)
			(size 0.9144 0.9144)
			(drill 0.569976)
			(layers "*.Cu" "*.Mask")
			(remove_unused_layers no)
			(net "GND")
			(clearance 0.1905)
			(thermal_gap 0.1905)
		)
		(pad "PTH14" thru_hole circle
			(at -10.999978 9.61009)
			(size 0.9144 0.9144)
			(drill 0.569976)
			(layers "*.Cu" "*.Mask")
			(remove_unused_layers no)
			(net "GND")
			(clearance 0.1905)
			(thermal_gap 0.1905)
		)
		(pad "PTH15" thru_hole circle
			(at -21.999956 9.61009)
			(size 0.9144 0.9144)
			(drill 0.569976)
			(layers "*.Cu" "*.Mask")
			(remove_unused_layers no)
			(net "GND")
			(clearance 0.1905)
			(thermal_gap 0.1905)
		)
		(pad "PTH16" thru_hole circle
			(at -10.999978 -3.700018)
			(size 0.9144 0.9144)
			(drill 0.569976)
			(layers "*.Cu" "*.Mask")
			(remove_unused_layers no)
			(net "GND")
			(clearance 0.1905)
			(thermal_gap 0.1905)
		)
		(pad "PTH17" thru_hole circle
			(at 0 -3.700018)
			(size 0.9144 0.9144)
			(drill 0.569976)
			(layers "*.Cu" "*.Mask")
			(remove_unused_layers no)
			(net "GND")
			(clearance 0.1905)
			(thermal_gap 0.1905)
		)
		(pad "PTH18" thru_hole circle
			(at 10.999978 -3.700018)
			(size 0.9144 0.9144)
			(drill 0.569976)
			(layers "*.Cu" "*.Mask")
			(remove_unused_layers no)
			(net "GND")
			(clearance 0.1905)
			(thermal_gap 0.1905)
		)
		(pad "PTH19" thru_hole circle
			(at -16.500094 0)
			(size 2.6162 2.6162)
			(drill 2.2098)
			(layers "*.Cu" "*.Mask")
			(remove_unused_layers no)
			(net "GND")
			(clearance 0.3048)
			(thermal_gap 0.3048)
			(padstack
				(mode front_inner_back)
				(layer "Inner"
					(shape circle)
					(size 2.6162 2.6162)
					(clearance 0.3048)
				)
				(layer "B.Cu"
					(shape custom)
					(size 1.246578 1.246578)
					(options
						(anchor circle)
					)
					(primitives
						(gr_poly
							(pts
								(arc
									(start 0.300228 -2.49301)
									(mid 0 2.492801)
									(end -0.300228 -2.49301)
								)
								(arc
									(start -0.300228 -2.49301)
									(mid 0 -2.412041)
									(end 0.300228 -2.49301)
								)
							)
							(width 0)
							(fill yes)
						)
					)
					(clearance -0.889)
				)
			)
		)
		(pad "PTH20" thru_hole circle
			(at -5.500116 0)
			(size 2.6162 2.6162)
			(drill 2.2098)
			(layers "*.Cu" "*.Mask")
			(remove_unused_layers no)
			(net "GND")
			(clearance 0.3048)
			(thermal_gap 0.3048)
			(padstack
				(mode front_inner_back)
				(layer "Inner"
					(shape circle)
					(size 2.6162 2.6162)
					(clearance 0.3048)
				)
				(layer "B.Cu"
					(shape custom)
					(size 1.246578 1.246578)
					(options
						(anchor circle)
					)
					(primitives
						(gr_poly
							(pts
								(arc
									(start 0.300228 -2.49301)
									(mid 0 2.492801)
									(end -0.300228 -2.49301)
								)
								(arc
									(start -0.300228 -2.49301)
									(mid 0 -2.412041)
									(end 0.300228 -2.49301)
								)
							)
							(width 0)
							(fill yes)
						)
					)
					(clearance -0.889)
				)
			)
		)
		(pad "PTH21" thru_hole circle
			(at 5.500116 0)
			(size 2.6162 2.6162)
			(drill 2.2098)
			(layers "*.Cu" "*.Mask")
			(remove_unused_layers no)
			(net "GND")
			(clearance 0.3048)
			(thermal_gap 0.3048)
			(padstack
				(mode front_inner_back)
				(layer "Inner"
					(shape circle)
					(size 2.6162 2.6162)
					(clearance 0.3048)
				)
				(layer "B.Cu"
					(shape custom)
					(size 1.246578 1.246578)
					(options
						(anchor circle)
					)
					(primitives
						(gr_poly
							(pts
								(arc
									(start 0.300228 -2.49301)
									(mid 0 2.492801)
									(end -0.300228 -2.49301)
								)
								(arc
									(start -0.300228 -2.49301)
									(mid 0 -2.412041)
									(end 0.300228 -2.49301)
								)
							)
							(width 0)
							(fill yes)
						)
					)
					(clearance -0.889)
				)
			)
		)
		(pad "PTH22" thru_hole circle
			(at 16.500094 0)
			(size 2.6162 2.6162)
			(drill 2.2098)
			(layers "*.Cu" "*.Mask")
			(remove_unused_layers no)
			(net "GND")
			(clearance 0.3048)
			(thermal_gap 0.3048)
			(padstack
				(mode front_inner_back)
				(layer "Inner"
					(shape circle)
					(size 2.6162 2.6162)
					(clearance 0.3048)
				)
				(layer "B.Cu"
					(shape custom)
					(size 1.246578 1.246578)
					(options
						(anchor circle)
					)
					(primitives
						(gr_poly
							(pts
								(arc
									(start 0.300228 -2.49301)
									(mid 0 2.492801)
									(end -0.300228 -2.49301)
								)
								(arc
									(start -0.300228 -2.49301)
									(mid 0 -2.412041)
									(end 0.300228 -2.49301)
								)
							)
							(width 0)
							(fill yes)
						)
					)
					(clearance -0.889)
				)
			)
		)
		(zone
			(layer "F.Cu")
			(hatch none 0.5)
			(connect_pads
				(clearance 0)
			)
			(min_thickness 0.25)
			(keepout
				(tracks allowed)
				(vias not_allowed)
				(pads allowed)
				(copperpour not_allowed)
				(footprints allowed)
			)
			(placement
				(enabled no)
				(sheetname "")
			)
			(fill
				(thermal_gap 0.5)
				(thermal_bridge_width 0.5)
				(island_removal_mode 0)
			)
			(polygon
				(pts
					(xy 283.33446 -0.790194) (xy 283.33446 -2.090166) (xy 283.934408 -2.090166) (xy 283.934408 -0.790194)
				)
			)
		)
		(zone
			(layer "F.Cu")
			(hatch none 0.5)
			(connect_pads
				(clearance 0)
			)
			(min_thickness 0.25)
			(keepout
				(tracks not_allowed)
				(vias allowed)
				(pads allowed)
				(copperpour not_allowed)
				(footprints allowed)
			)
			(placement
				(enabled no)
				(sheetname "")
			)
			(fill
				(thermal_gap 0.5)
				(thermal_bridge_width 0.5)
				(island_removal_mode 0)
			)
			(polygon
				(pts
					(xy 283.33446 -0.790194) (xy 283.934408 -0.790194) (xy 283.934408 -2.090166) (xy 283.33446 -2.090166)
				)
			)
		)
		(zone
			(layer "F.Cu")
			(hatch none 0.5)
			(connect_pads
				(clearance 0)
			)
			(min_thickness 0.25)
			(keepout
				(tracks allowed)
				(vias not_allowed)
				(pads allowed)
				(copperpour not_allowed)
				(footprints allowed)
			)
			(placement
				(enabled no)
				(sheetname "")
			)
			(fill
				(thermal_gap 0.5)
				(thermal_bridge_width 0.5)
				(island_removal_mode 0)
			)
			(polygon
				(pts
					(xy 294.334438 -0.790194) (xy 294.334438 -2.090166) (xy 294.934386 -2.090166) (xy 294.934386 -0.790194)
				)
			)
		)
		(zone
			(layer "F.Cu")
			(hatch none 0.5)
			(connect_pads
				(clearance 0)
			)
			(min_thickness 0.25)
			(keepout
				(tracks not_allowed)
				(vias allowed)
				(pads allowed)
				(copperpour not_allowed)
				(footprints allowed)
			)
			(placement
				(enabled no)
				(sheetname "")
			)
			(fill
				(thermal_gap 0.5)
				(thermal_bridge_width 0.5)
				(island_removal_mode 0)
			)
			(polygon
				(pts
					(xy 294.334438 -0.790194) (xy 294.934386 -0.790194) (xy 294.934386 -2.090166) (xy 294.334438 -2.090166)
				)
			)
		)
		(zone
			(layer "F.Cu")
			(hatch none 0.5)
			(connect_pads
				(clearance 0)
			)
			(min_thickness 0.25)
			(keepout
				(tracks allowed)
				(vias not_allowed)
				(pads allowed)
				(copperpour not_allowed)
				(footprints allowed)
			)
			(placement
				(enabled no)
				(sheetname "")
			)
			(fill
				(thermal_gap 0.5)
				(thermal_bridge_width 0.5)
				(island_removal_mode 0)
			)
			(polygon
				(pts
					(xy 305.334416 -0.790194) (xy 305.334416 -2.090166) (xy 305.934364 -2.090166) (xy 305.934364 -0.790194)
				)
			)
		)
		(zone
			(layer "F.Cu")
			(hatch none 0.5)
			(connect_pads
				(clearance 0)
			)
			(min_thickness 0.25)
			(keepout
				(tracks not_allowed)
				(vias allowed)
				(pads allowed)
				(copperpour not_allowed)
				(footprints allowed)
			)
			(placement
				(enabled no)
				(sheetname "")
			)
			(fill
				(thermal_gap 0.5)
				(thermal_bridge_width 0.5)
				(island_removal_mode 0)
			)
			(polygon
				(pts
					(xy 305.334416 -0.790194) (xy 305.934364 -0.790194) (xy 305.934364 -2.090166) (xy 305.334416 -2.090166)
				)
			)
		)
		(zone
			(layer "F.Cu")
			(hatch none 0.5)
			(connect_pads
				(clearance 0)
			)
			(min_thickness 0.25)
			(keepout
				(tracks allowed)
				(vias not_allowed)
				(pads allowed)
				(copperpour not_allowed)
				(footprints allowed)
			)
			(placement
				(enabled no)
				(sheetname "")
			)
			(fill
				(thermal_gap 0.5)
				(thermal_bridge_width 0.5)
				(island_removal_mode 0)
			)
			(polygon
				(pts
					(xy 316.334394 -0.790194) (xy 316.334394 -2.090166) (xy 316.934342 -2.090166) (xy 316.934342 -0.790194)
				)
			)
		)
		(zone
			(layer "F.Cu")
			(hatch none 0.5)
			(connect_pads
				(clearance 0)
			)
			(min_thickness 0.25)
			(keepout
				(tracks not_allowed)
				(vias allowed)
				(pads allowed)
				(copperpour not_allowed)
				(footprints allowed)
			)
			(placement
				(enabled no)
				(sheetname "")
			)
			(fill
				(thermal_gap 0.5)
				(thermal_bridge_width 0.5)
				(island_removal_mode 0)
			)
			(polygon
				(pts
					(xy 316.334394 -0.790194) (xy 316.934342 -0.790194) (xy 316.934342 -2.090166) (xy 316.334394 -2.090166)
				)
			)
		)
		(zone
			(layer "F.Cu")
			(hatch none 0.5)
			(connect_pads
				(clearance 0)
			)
			(min_thickness 0.25)
			(keepout
				(tracks allowed)
				(vias not_allowed)
				(pads allowed)
				(copperpour not_allowed)
				(footprints allowed)
			)
			(placement
				(enabled no)
				(sheetname "")
			)
			(fill
				(thermal_gap 0.5)
				(thermal_bridge_width 0.5)
				(island_removal_mode 0)
			)
			(polygon
				(pts
					(xy 327.334372 -0.790194) (xy 327.334372 -2.090166) (xy 327.93432 -2.090166) (xy 327.93432 -0.790194)
				)
			)
		)
		(zone
			(layer "F.Cu")
			(hatch none 0.5)
			(connect_pads
				(clearance 0)
			)
			(min_thickness 0.25)
			(keepout
				(tracks not_allowed)
				(vias allowed)
				(pads allowed)
				(copperpour not_allowed)
				(footprints allowed)
			)
			(placement
				(enabled no)
				(sheetname "")
			)
			(fill
				(thermal_gap 0.5)
				(thermal_bridge_width 0.5)
				(island_removal_mode 0)
			)
			(polygon
				(pts
					(xy 327.334372 -0.790194) (xy 327.93432 -0.790194) (xy 327.93432 -2.090166) (xy 327.334372 -2.090166)
				)
			)
		)
		(zone
			(layer "F.Cu")
			(hatch none 0.5)
			(connect_pads
				(clearance 0)
			)
			(min_thickness 0.25)
			(keepout
				(tracks not_allowed)
				(vias allowed)
				(pads allowed)
				(copperpour not_allowed)
				(footprints allowed)
			)
			(placement
				(enabled no)
				(sheetname "")
			)
			(fill
				(thermal_gap 0.5)
				(thermal_bridge_width 0.5)
				(island_removal_mode 0)
			)
			(polygon
				(pts
					(arc
						(start 290.696396 -9.53008)
						(mid 287.572196 -9.53008)
						(end 290.696396 -9.53008)
					)
				)
			)
		)
		(zone
			(layer "F.Cu")
			(hatch none 0.5)
			(connect_pads
				(clearance 0)
			)
			(min_thickness 0.25)
			(keepout
				(tracks allowed)
				(vias not_allowed)
				(pads allowed)
				(copperpour not_allowed)
				(footprints allowed)
			)
			(placement
				(enabled no)
				(sheetname "")
			)
			(fill
				(thermal_gap 0.5)
				(thermal_bridge_width 0.5)
				(island_removal_mode 0)
			)
			(polygon
				(pts
					(arc
						(start 290.696396 -9.53008)
						(mid 287.572196 -9.53008)
						(end 290.696396 -9.53008)
					)
				)
			)
		)
		(zone
			(layer "F.Cu")
			(hatch none 0.5)
			(connect_pads
				(clearance 0)
			)
			(min_thickness 0.25)
			(keepout
				(tracks not_allowed)
				(vias allowed)
				(pads allowed)
				(copperpour not_allowed)
				(footprints allowed)
			)
			(placement
				(enabled no)
				(sheetname "")
			)
			(fill
				(thermal_gap 0.5)
				(thermal_bridge_width 0.5)
				(island_removal_mode 0)
			)
			(polygon
				(pts
					(arc
						(start 301.696374 -9.53008)
						(mid 298.572174 -9.53008)
						(end 301.696374 -9.53008)
					)
				)
			)
		)
		(zone
			(layer "F.Cu")
			(hatch none 0.5)
			(connect_pads
				(clearance 0)
			)
			(min_thickness 0.25)
			(keepout
				(tracks allowed)
				(vias not_allowed)
				(pads allowed)
				(copperpour not_allowed)
				(footprints allowed)
			)
			(placement
				(enabled no)
				(sheetname "")
			)
			(fill
				(thermal_gap 0.5)
				(thermal_bridge_width 0.5)
				(island_removal_mode 0)
			)
			(polygon
				(pts
					(arc
						(start 301.696374 -9.53008)
						(mid 298.572174 -9.53008)
						(end 301.696374 -9.53008)
					)
				)
			)
		)
		(zone
			(layer "F.Cu")
			(hatch none 0.5)
			(connect_pads
				(clearance 0)
			)
			(min_thickness 0.25)
			(keepout
				(tracks allowed)
				(vias not_allowed)
				(pads allowed)
				(copperpour not_allowed)
				(footprints allowed)
			)
			(placement
				(enabled no)
				(sheetname "")
			)
			(fill
				(thermal_gap 0.5)
				(thermal_bridge_width 0.5)
				(island_removal_mode 0)
			)
			(polygon
				(pts
					(arc
						(start 312.696352 -9.53008)
						(mid 309.572152 -9.53008)
						(end 312.696352 -9.53008)
					)
				)
			)
		)
		(zone
			(layer "F.Cu")
			(hatch none 0.5)
			(connect_pads
				(clearance 0)
			)
			(min_thickness 0.25)
			(keepout
				(tracks not_allowed)
				(vias allowed)
				(pads allowed)
				(copperpour not_allowed)
				(footprints allowed)
			)
			(placement
				(enabled no)
				(sheetname "")
			)
			(fill
				(thermal_gap 0.5)
				(thermal_bridge_width 0.5)
				(island_removal_mode 0)
			)
			(polygon
				(pts
					(arc
						(start 312.696352 -9.53008)
						(mid 309.572152 -9.53008)
						(end 312.696352 -9.53008)
					)
				)
			)
		)
		(zone
			(layer "F.Cu")
			(hatch none 0.5)
			(connect_pads
				(clearance 0)
			)
			(min_thickness 0.25)
			(keepout
				(tracks not_allowed)
				(vias allowed)
				(pads allowed)
				(copperpour not_allowed)
				(footprints allowed)
			)
			(placement
				(enabled no)
				(sheetname "")
			)
			(fill
				(thermal_gap 0.5)
				(thermal_bridge_width 0.5)
				(island_removal_mode 0)
			)
			(polygon
				(pts
					(arc
						(start 323.69633 -9.53008)
						(mid 320.57213 -9.53008)
						(end 323.69633 -9.53008)
					)
				)
			)
		)
		(zone
			(layer "F.Cu")
			(hatch none 0.5)
			(connect_pads
				(clearance 0)
			)
			(min_thickness 0.25)
			(keepout
				(tracks allowed)
				(vias not_allowed)
				(pads allowed)
				(copperpour not_allowed)
				(footprints allowed)
			)
			(placement
				(enabled no)
				(sheetname "")
			)
			(fill
				(thermal_gap 0.5)
				(thermal_bridge_width 0.5)
				(island_removal_mode 0)
			)
			(polygon
				(pts
					(arc
						(start 323.69633 -9.53008)
						(mid 320.57213 -9.53008)
						(end 323.69633 -9.53008)
					)
				)
			)
		)
		(zone
			(layer "B.Cu")
			(hatch none 0.5)
			(connect_pads
				(clearance 0)
			)
			(min_thickness 0.25)
			(keepout
				(tracks allowed)
				(vias not_allowed)
				(pads allowed)
				(copperpour not_allowed)
				(footprints allowed)
			)
			(placement
				(enabled no)
				(sheetname "")
			)
			(fill
				(thermal_gap 0.5)
				(thermal_bridge_width 0.5)
				(island_removal_mode 0)
			)
			(polygon
				(pts
					(arc
						(start 291.890196 -9.53008)
						(mid 286.378396 -9.53008)
						(end 291.890196 -9.53008)
					)
				)
			)
		)
		(zone
			(layer "B.Cu")
			(hatch none 0.5)
			(connect_pads
				(clearance 0)
			)
			(min_thickness 0.25)
			(keepout
				(tracks allowed)
				(vias not_allowed)
				(pads allowed)
				(copperpour not_allowed)
				(footprints allowed)
			)
			(placement
				(enabled no)
				(sheetname "")
			)
			(fill
				(thermal_gap 0.5)
				(thermal_bridge_width 0.5)
				(island_removal_mode 0)
			)
			(polygon
				(pts
					(arc
						(start 302.890174 -9.53008)
						(mid 297.378374 -9.53008)
						(end 302.890174 -9.53008)
					)
				)
			)
		)
		(zone
			(layer "B.Cu")
			(hatch none 0.5)
			(connect_pads
				(clearance 0)
			)
			(min_thickness 0.25)
			(keepout
				(tracks allowed)
				(vias not_allowed)
				(pads allowed)
				(copperpour not_allowed)
				(footprints allowed)
			)
			(placement
				(enabled no)
				(sheetname "")
			)
			(fill
				(thermal_gap 0.5)
				(thermal_bridge_width 0.5)
				(island_removal_mode 0)
			)
			(polygon
				(pts
					(arc
						(start 313.890152 -9.53008)
						(mid 308.378352 -9.53008)
						(end 313.890152 -9.53008)
					)
				)
			)
		)
		(zone
			(layer "B.Cu")
			(hatch none 0.5)
			(connect_pads
				(clearance 0)
			)
			(min_thickness 0.25)
			(keepout
				(tracks allowed)
				(vias not_allowed)
				(pads allowed)
				(copperpour not_allowed)
				(footprints allowed)
			)
			(placement
				(enabled no)
				(sheetname "")
			)
			(fill
				(thermal_gap 0.5)
				(thermal_bridge_width 0.5)
				(island_removal_mode 0)
			)
			(polygon
				(pts
					(arc
						(start 324.89013 -9.53008)
						(mid 319.37833 -9.53008)
						(end 324.89013 -9.53008)
					)
				)
			)
		)
	)
	(footprint ""
		(layer "F.Cu")
		(at 39.5732 -102.1588 90)
		(property "Reference" "R602"
			(at 0 0 90)
			(layer "F.SilkS")
			(hide yes)
			(effects
				(font
					(size 1.27 1.27)
				)
			)
		)
		(property "Value" "10KR2F-2-GP"
			(at 0.064008 -3.993896 90)
			(unlocked yes)
			(layer "F.Fab")
			(hide yes)
			(effects
				(font
					(size 1.016 1.016)
					(thickness 0.1524)
				)
			)
		)
		(property "Device Type" "R402H16"
			(at 0.064008 -5.517896 90)
			(unlocked yes)
			(layer "F.Fab")
			(hide yes)
			(effects
				(font
					(size 1.016 1.016)
					(thickness 0.1524)
				)
			)
		)
		(duplicate_pad_numbers_are_jumpers no)
		(fp_line
			(start 0.508 -0.9398)
			(end -0.508 -0.9398)
			(stroke
				(width 0.1524)
				(type default)
			)
			(layer "F.SilkS")
		)
		(fp_line
			(start -0.508 -0.9398)
			(end -0.508 0.9398)
			(stroke
				(width 0.1524)
				(type default)
			)
			(layer "F.SilkS")
		)
		(fp_rect
			(start -0.508 0.9398)
			(end 0.508 -0.9398)
			(stroke
				(width 0)
				(type default)
			)
			(fill no)
			(layer "F.CrtYd")
		)
		(fp_rect
			(start -0.508 0.9398)
			(end 0.508 -0.9398)
			(stroke
				(width 0)
				(type default)
			)
			(fill no)
			(layer "F.Fab")
		)
		(pad "1" smd custom
			(at 0 -0.4445 90)
			(size 0.1397 0.1397)
			(layers "F.Cu" "F.Mask" "F.Paste")
			(net "BUS_SW_OE#")
			(options
				(clearance outline)
				(anchor circle)
			)
			(primitives
				(gr_poly
					(pts
						(arc
							(start -0.1778 -0.2794)
							(mid -0.249642 -0.249642)
							(end -0.2794 -0.1778)
						)
						(arc
							(start -0.2794 0.1778)
							(mid -0.249642 0.249642)
							(end -0.1778 0.2794)
						)
						(arc
							(start 0.1778 0.2794)
							(mid 0.249642 0.249642)
							(end 0.2794 0.1778)
						)
						(arc
							(start 0.2794 -0.1778)
							(mid 0.249642 -0.249642)
							(end 0.1778 -0.2794)
						)
					)
					(width 0)
					(fill yes)
				)
			)
		)
		(pad "2" smd custom
			(at 0 0.4445 90)
			(size 0.1397 0.1397)
			(layers "F.Cu" "F.Mask" "F.Paste")
			(net "GND")
			(options
				(clearance outline)
				(anchor circle)
			)
			(primitives
				(gr_poly
					(pts
						(arc
							(start -0.1778 -0.2794)
							(mid -0.249642 -0.249642)
							(end -0.2794 -0.1778)
						)
						(arc
							(start -0.2794 0.1778)
							(mid -0.249642 0.249642)
							(end -0.1778 0.2794)
						)
						(arc
							(start 0.1778 0.2794)
							(mid 0.249642 0.249642)
							(end 0.2794 0.1778)
						)
						(arc
							(start 0.2794 -0.1778)
							(mid 0.249642 -0.249642)
							(end 0.1778 -0.2794)
						)
					)
					(width 0)
					(fill yes)
				)
			)
		)
	)
	(footprint ""
		(layer "F.Cu")
		(at 313.19216 -212.420454 180)
		(property "Reference" "C70"
			(at 0 0 180)
			(layer "F.SilkS")
			(hide yes)
			(effects
				(font
					(size 1.27 1.27)
				)
			)
		)
		(property "Value" "SCD22U10V2KX-1GP"
			(at 1.1811 -2.7051 180)
			(unlocked yes)
			(layer "F.Fab")
			(hide yes)
			(effects
				(font
					(size 1.016 1.016)
					(thickness 0.1524)
				)
			)
		)
		(property "Device Type" "C402H22"
			(at 1.1811 -4.2291 180)
			(unlocked yes)
			(layer "F.Fab")
			(hide yes)
			(effects
				(font
					(size 1.016 1.016)
					(thickness 0.1524)
				)
			)
		)
		(duplicate_pad_numbers_are_jumpers no)
		(fp_rect
			(start -0.4318 0.9525)
			(end 0.4318 -0.9525)
			(stroke
				(width 0)
				(type default)
			)
			(fill no)
			(layer "F.CrtYd")
		)
		(fp_rect
			(start -0.4318 0.9525)
			(end 0.4318 -0.9525)
			(stroke
				(width 0)
				(type default)
			)
			(fill no)
			(layer "F.Fab")
		)
		(pad "1" smd custom
			(at 0 -0.4445 180)
			(size 0.1524 0.1524)
			(layers "F.Cu" "F.Mask" "F.Paste")
			(net "PCIE_TX_CAP_P24")
			(options
				(clearance outline)
				(anchor circle)
			)
			(primitives
				(gr_poly
					(pts
						(arc
							(start 0.3048 -0.2032)
							(mid 0.275042 -0.275042)
							(end 0.2032 -0.3048)
						)
						(arc
							(start -0.2032 -0.3048)
							(mid -0.275042 -0.275042)
							(end -0.3048 -0.2032)
						)
						(arc
							(start -0.3048 0.2032)
							(mid -0.275042 0.275042)
							(end -0.2032 0.3048)
						)
						(arc
							(start 0.2032 0.3048)
							(mid 0.275042 0.275042)
							(end 0.3048 0.2032)
						)
					)
					(width 0)
					(fill yes)
				)
			)
		)
		(pad "2" smd custom
			(at 0 0.4445 180)
			(size 0.1524 0.1524)
			(layers "F.Cu" "F.Mask" "F.Paste")
			(net "PCIE_TX_P24")
			(options
				(clearance outline)
				(anchor circle)
			)
			(primitives
				(gr_poly
					(pts
						(arc
							(start 0.3048 -0.2032)
							(mid 0.275042 -0.275042)
							(end 0.2032 -0.3048)
						)
						(arc
							(start -0.2032 -0.3048)
							(mid -0.275042 -0.275042)
							(end -0.3048 -0.2032)
						)
						(arc
							(start -0.3048 0.2032)
							(mid -0.275042 0.275042)
							(end -0.2032 0.3048)
						)
						(arc
							(start 0.2032 0.3048)
							(mid 0.275042 0.275042)
							(end 0.3048 0.2032)
						)
					)
					(width 0)
					(fill yes)
				)
			)
		)
	)
	(footprint ""
		(layer "F.Cu")
		(at 85.09 -46.609 180)
		(property "Reference" "PC40"
			(at 0 0 180)
			(layer "F.SilkS")
			(hide yes)
			(effects
				(font
					(size 1.27 1.27)
				)
			)
		)
		(property "Value" "SC10U6D3V5KX-4GP"
			(at -0.0762 -6.1214 180)
			(unlocked yes)
			(layer "F.Fab")
			(hide yes)
			(effects
				(font
					(size 1.016 1.016)
					(thickness 0.1524)
				)
			)
		)
		(property "Device Type" "C805H58"
			(at -0.0762 -8.1534 180)
			(unlocked yes)
			(layer "F.Fab")
			(hide yes)
			(effects
				(font
					(size 1.016 1.016)
					(thickness 0.1524)
				)
			)
		)
		(duplicate_pad_numbers_are_jumpers no)
		(fp_line
			(start 0.635 0)
			(end -0.635 0)
			(stroke
				(width 0.508)
				(type default)
			)
			(layer "F.SilkS")
		)
		(fp_rect
			(start -0.9652 1.778)
			(end 0.9652 -1.778)
			(stroke
				(width 0)
				(type default)
			)
			(fill no)
			(layer "F.CrtYd")
		)
		(fp_poly
			(pts
				(xy -0.9652 -1.778) (xy 0.9652 -1.778) (xy 0.9652 1.778) (xy -0.9652 1.778)
			)
			(stroke
				(width 0)
				(type default)
			)
			(fill no)
			(layer "F.Fab")
		)
		(pad "1" smd rect
			(at 0 -0.9652 180)
			(size 1.397 1.143)
			(layers "F.Cu" "F.Mask" "F.Paste")
			(net "P3V3_PWR")
		)
		(pad "2" smd rect
			(at 0 0.9652 180)
			(size 1.397 1.143)
			(layers "F.Cu" "F.Mask" "F.Paste")
			(net "GND")
		)
	)
	(footprint ""
		(layer "F.Cu")
		(at 130.677158 -74.60996 90)
		(property "Reference" "C723"
			(at 0 0 90)
			(layer "F.SilkS")
			(hide yes)
			(effects
				(font
					(size 1.27 1.27)
				)
			)
		)
		(property "Value" "SC10U16V5KX-1-GP"
			(at -0.0762 -6.1214 90)
			(unlocked yes)
			(layer "F.Fab")
			(hide yes)
			(effects
				(font
					(size 1.016 1.016)
					(thickness 0.1524)
				)
			)
		)
		(property "Device Type" "C805H54"
			(at -0.0762 -8.1534 90)
			(unlocked yes)
			(layer "F.Fab")
			(hide yes)
			(effects
				(font
					(size 1.016 1.016)
					(thickness 0.1524)
				)
			)
		)
		(duplicate_pad_numbers_are_jumpers no)
		(fp_line
			(start 0.635 0)
			(end -0.635 0)
			(stroke
				(width 0.508)
				(type default)
			)
			(layer "F.SilkS")
		)
		(fp_rect
			(start -0.9652 1.778)
			(end 0.9652 -1.778)
			(stroke
				(width 0)
				(type default)
			)
			(fill no)
			(layer "F.CrtYd")
		)
		(fp_poly
			(pts
				(xy -0.9652 -1.778) (xy 0.9652 -1.778) (xy 0.9652 1.778) (xy -0.9652 1.778)
			)
			(stroke
				(width 0)
				(type default)
			)
			(fill no)
			(layer "F.Fab")
		)
		(pad "1" smd rect
			(at 0 -0.9652 90)
			(size 1.397 1.143)
			(layers "F.Cu" "F.Mask" "F.Paste")
			(net "P1V8_STBY")
		)
		(pad "2" smd rect
			(at 0 0.9652 90)
			(size 1.397 1.143)
			(layers "F.Cu" "F.Mask" "F.Paste")
			(net "GND")
		)
	)
	(footprint ""
		(layer "F.Cu")
		(at 35.792918 -84.64931 90)
		(property "Reference" "Q46"
			(at 0 0 90)
			(layer "F.SilkS")
			(hide yes)
			(effects
				(font
					(size 1.27 1.27)
				)
			)
		)
		(property "Value" "DSS4240T-7-GP"
			(at 0.10287 -10.29843 90)
			(unlocked yes)
			(layer "F.Fab")
			(hide yes)
			(effects
				(font
					(size 1.016 1.016)
					(thickness 0.1524)
				)
			)
		)
		(property "Device Type" "SOT23CBE2D4H44"
			(at 0.10287 -12.20343 90)
			(unlocked yes)
			(layer "F.Fab")
			(hide yes)
			(effects
				(font
					(size 1.016 1.016)
					(thickness 0.1524)
				)
			)
		)
		(duplicate_pad_numbers_are_jumpers no)
		(fp_line
			(start 1.651 -1.778)
			(end -1.651 -1.778)
			(stroke
				(width 0.1524)
				(type default)
			)
			(layer "F.SilkS")
		)
		(fp_line
			(start -1.651 -1.778)
			(end -1.651 1.778)
			(stroke
				(width 0.1524)
				(type default)
			)
			(layer "F.SilkS")
		)
		(fp_line
			(start 1.651 1.778)
			(end 1.651 -1.778)
			(stroke
				(width 0.1524)
				(type default)
			)
			(layer "F.SilkS")
		)
		(fp_line
			(start -1.651 1.778)
			(end 1.651 1.778)
			(stroke
				(width 0.1524)
				(type default)
			)
			(layer "F.SilkS")
		)
		(fp_poly
			(pts
				(xy -1.778 1.8796) (xy -1.778 -1.8796) (xy 1.778 -1.8796) (xy 1.778 1.8796)
			)
			(stroke
				(width 0)
				(type default)
			)
			(fill no)
			(layer "F.CrtYd")
		)
		(fp_poly
			(pts
				(xy -1.778 1.8796) (xy -1.778 -1.8796) (xy 1.778 -1.8796) (xy 1.778 1.8796)
			)
			(stroke
				(width 0)
				(type default)
			)
			(fill no)
			(layer "F.Fab")
		)
		(pad "B" smd custom
			(at -0.98425 0.9525 90)
			(size 0.1905 0.1905)
			(layers "F.Cu" "F.Mask" "F.Paste")
			(net "Q46_G")
			(options
				(clearance outline)
				(anchor circle)
			)
			(primitives
				(gr_poly
					(pts
						(arc
							(start -0.1778 0.5715)
							(mid -0.321484 0.511984)
							(end -0.381 0.3683)
						)
						(arc
							(start -0.381 -0.3683)
							(mid -0.321484 -0.511984)
							(end -0.1778 -0.5715)
						)
						(arc
							(start 0.1778 -0.5715)
							(mid 0.321484 -0.511984)
							(end 0.381 -0.3683)
						)
						(arc
							(start 0.381 0.3683)
							(mid 0.321484 0.511984)
							(end 0.1778 0.5715)
						)
					)
					(width 0)
					(fill yes)
				)
			)
		)
		(pad "C" smd custom
			(at 0 -0.9525 90)
			(size 0.1905 0.1905)
			(layers "F.Cu" "F.Mask" "F.Paste")
			(net "Q46_D")
			(options
				(clearance outline)
				(anchor circle)
			)
			(primitives
				(gr_poly
					(pts
						(arc
							(start -0.1778 0.5715)
							(mid -0.321484 0.511984)
							(end -0.381 0.3683)
						)
						(arc
							(start -0.381 -0.3683)
							(mid -0.321484 -0.511984)
							(end -0.1778 -0.5715)
						)
						(arc
							(start 0.1778 -0.5715)
							(mid 0.321484 -0.511984)
							(end 0.381 -0.3683)
						)
						(arc
							(start 0.381 0.3683)
							(mid 0.321484 0.511984)
							(end 0.1778 0.5715)
						)
					)
					(width 0)
					(fill yes)
				)
			)
		)
		(pad "E" smd custom
			(at 0.98425 0.9525 90)
			(size 0.1905 0.1905)
			(layers "F.Cu" "F.Mask" "F.Paste")
			(net "GND")
			(options
				(clearance outline)
				(anchor circle)
			)
			(primitives
				(gr_poly
					(pts
						(arc
							(start -0.1778 0.5715)
							(mid -0.321484 0.511984)
							(end -0.381 0.3683)
						)
						(arc
							(start -0.381 -0.3683)
							(mid -0.321484 -0.511984)
							(end -0.1778 -0.5715)
						)
						(arc
							(start 0.1778 -0.5715)
							(mid 0.321484 -0.511984)
							(end 0.381 -0.3683)
						)
						(arc
							(start 0.381 0.3683)
							(mid 0.321484 0.511984)
							(end 0.1778 0.5715)
						)
					)
					(width 0)
					(fill yes)
				)
			)
		)
	)
	(footprint ""
		(layer "F.Cu")
		(at 45.053758 -117.284246)
		(property "Reference" "TP94"
			(at 0 0 0)
			(layer "F.SilkS")
			(hide yes)
			(effects
				(font
					(size 1.27 1.27)
				)
			)
		)
		(property "Value" "TPAD28-2-GP"
			(at -0.0127 -1.6637 0)
			(unlocked yes)
			(layer "F.Fab")
			(hide yes)
			(effects
				(font
					(size 1.016 1.016)
					(thickness 0.1524)
				)
			)
		)
		(property "Device Type" "TPAD28"
			(at -0.0127 -3.1877 0)
			(unlocked yes)
			(layer "F.Fab")
			(hide yes)
			(effects
				(font
					(size 1.016 1.016)
					(thickness 0.1524)
				)
			)
		)
		(duplicate_pad_numbers_are_jumpers no)
		(fp_poly
			(pts
				(arc
					(start 0.3556 0)
					(mid -0.3556 0)
					(end 0.3556 0)
				)
			)
			(stroke
				(width 0)
				(type default)
			)
			(fill no)
			(layer "F.CrtYd")
		)
		(fp_poly
			(pts
				(arc
					(start 0.6096 0)
					(mid -0.6096 0)
					(end 0.6096 0)
				)
			)
			(stroke
				(width 0)
				(type default)
			)
			(fill no)
			(layer "F.Fab")
		)
		(pad "1" smd circle
			(at 0 0)
			(size 0.7112 0.7112)
			(layers "F.Cu" "F.Mask" "F.Paste")
			(net "TP_GPIOH5")
		)
	)
	(footprint ""
		(layer "F.Cu")
		(at 65.8368 -112.5982 90)
		(property "Reference" "R438"
			(at 0 0 90)
			(layer "F.SilkS")
			(hide yes)
			(effects
				(font
					(size 1.27 1.27)
				)
			)
		)
		(property "Value" "4K7R2F-GP"
			(at 0.064008 -3.993896 90)
			(unlocked yes)
			(layer "F.Fab")
			(hide yes)
			(effects
				(font
					(size 1.016 1.016)
					(thickness 0.1524)
				)
			)
		)
		(property "Device Type" "R402H16"
			(at 0.064008 -5.517896 90)
			(unlocked yes)
			(layer "F.Fab")
			(hide yes)
			(effects
				(font
					(size 1.016 1.016)
					(thickness 0.1524)
				)
			)
		)
		(duplicate_pad_numbers_are_jumpers no)
		(fp_line
			(start 0.508 -0.9398)
			(end -0.508 -0.9398)
			(stroke
				(width 0.1524)
				(type default)
			)
			(layer "F.SilkS")
		)
		(fp_line
			(start -0.508 -0.9398)
			(end -0.508 0.9398)
			(stroke
				(width 0.1524)
				(type default)
			)
			(layer "F.SilkS")
		)
		(fp_rect
			(start -0.508 0.9398)
			(end 0.508 -0.9398)
			(stroke
				(width 0)
				(type default)
			)
			(fill no)
			(layer "F.CrtYd")
		)
		(fp_rect
			(start -0.508 0.9398)
			(end 0.508 -0.9398)
			(stroke
				(width 0)
				(type default)
			)
			(fill no)
			(layer "F.Fab")
		)
		(pad "1" smd custom
			(at 0 -0.4445 90)
			(size 0.1397 0.1397)
			(layers "F.Cu" "F.Mask" "F.Paste")
			(net "BMC_I2C11_MINI5_SCL_S")
			(options
				(clearance outline)
				(anchor circle)
			)
			(primitives
				(gr_poly
					(pts
						(arc
							(start -0.1778 -0.2794)
							(mid -0.249642 -0.249642)
							(end -0.2794 -0.1778)
						)
						(arc
							(start -0.2794 0.1778)
							(mid -0.249642 0.249642)
							(end -0.1778 0.2794)
						)
						(arc
							(start 0.1778 0.2794)
							(mid 0.249642 0.249642)
							(end 0.2794 0.1778)
						)
						(arc
							(start 0.2794 -0.1778)
							(mid 0.249642 -0.249642)
							(end 0.1778 -0.2794)
						)
					)
					(width 0)
					(fill yes)
				)
			)
		)
		(pad "2" smd custom
			(at 0 0.4445 90)
			(size 0.1397 0.1397)
			(layers "F.Cu" "F.Mask" "F.Paste")
			(net "P3V3_STBY")
			(options
				(clearance outline)
				(anchor circle)
			)
			(primitives
				(gr_poly
					(pts
						(arc
							(start -0.1778 -0.2794)
							(mid -0.249642 -0.249642)
							(end -0.2794 -0.1778)
						)
						(arc
							(start -0.2794 0.1778)
							(mid -0.249642 0.249642)
							(end -0.1778 0.2794)
						)
						(arc
							(start 0.1778 0.2794)
							(mid 0.249642 0.249642)
							(end 0.2794 0.1778)
						)
						(arc
							(start 0.2794 -0.1778)
							(mid 0.249642 -0.249642)
							(end 0.1778 -0.2794)
						)
					)
					(width 0)
					(fill yes)
				)
			)
		)
	)
	(footprint ""
		(layer "F.Cu")
		(at 47.244 -194.564)
		(property "Reference" "C707"
			(at 0 0 0)
			(layer "F.SilkS")
			(hide yes)
			(effects
				(font
					(size 1.27 1.27)
				)
			)
		)
		(property "Value" "SCD01U50V2KX-1GP"
			(at 1.1811 -2.7051 0)
			(unlocked yes)
			(layer "F.Fab")
			(hide yes)
			(effects
				(font
					(size 1.016 1.016)
					(thickness 0.1524)
				)
			)
		)
		(property "Device Type" "C402H22"
			(at 1.1811 -4.2291 0)
			(unlocked yes)
			(layer "F.Fab")
			(hide yes)
			(effects
				(font
					(size 1.016 1.016)
					(thickness 0.1524)
				)
			)
		)
		(duplicate_pad_numbers_are_jumpers no)
		(fp_rect
			(start -0.4318 0.9525)
			(end 0.4318 -0.9525)
			(stroke
				(width 0)
				(type default)
			)
			(fill no)
			(layer "F.CrtYd")
		)
		(fp_rect
			(start -0.4318 0.9525)
			(end 0.4318 -0.9525)
			(stroke
				(width 0)
				(type default)
			)
			(fill no)
			(layer "F.Fab")
		)
		(pad "1" smd custom
			(at 0 -0.4445)
			(size 0.1524 0.1524)
			(layers "F.Cu" "F.Mask" "F.Paste")
			(net "P3V3_STBY")
			(options
				(clearance outline)
				(anchor circle)
			)
			(primitives
				(gr_poly
					(pts
						(arc
							(start 0.3048 -0.2032)
							(mid 0.275042 -0.275042)
							(end 0.2032 -0.3048)
						)
						(arc
							(start -0.2032 -0.3048)
							(mid -0.275042 -0.275042)
							(end -0.3048 -0.2032)
						)
						(arc
							(start -0.3048 0.2032)
							(mid -0.275042 0.275042)
							(end -0.2032 0.3048)
						)
						(arc
							(start 0.2032 0.3048)
							(mid 0.275042 0.275042)
							(end 0.3048 0.2032)
						)
					)
					(width 0)
					(fill yes)
				)
			)
		)
		(pad "2" smd custom
			(at 0 0.4445)
			(size 0.1524 0.1524)
			(layers "F.Cu" "F.Mask" "F.Paste")
			(net "GND")
			(options
				(clearance outline)
				(anchor circle)
			)
			(primitives
				(gr_poly
					(pts
						(arc
							(start 0.3048 -0.2032)
							(mid 0.275042 -0.275042)
							(end 0.2032 -0.3048)
						)
						(arc
							(start -0.2032 -0.3048)
							(mid -0.275042 -0.275042)
							(end -0.3048 -0.2032)
						)
						(arc
							(start -0.3048 0.2032)
							(mid -0.275042 0.275042)
							(end -0.2032 0.3048)
						)
						(arc
							(start 0.2032 0.3048)
							(mid 0.275042 0.275042)
							(end 0.3048 0.2032)
						)
					)
					(width 0)
					(fill yes)
				)
			)
		)
	)
	(footprint ""
		(layer "F.Cu")
		(at 131.040124 -196.443092)
		(property "Reference" "R7944"
			(at 0 0 0)
			(layer "F.SilkS")
			(hide yes)
			(effects
				(font
					(size 1.27 1.27)
				)
			)
		)
		(property "Value" "0R2J-2-GP"
			(at 0.064008 -3.993896 0)
			(unlocked yes)
			(layer "F.Fab")
			(hide yes)
			(effects
				(font
					(size 1.016 1.016)
					(thickness 0.1524)
				)
			)
		)
		(property "Device Type" "R402H16"
			(at 0.064008 -5.517896 0)
			(unlocked yes)
			(layer "F.Fab")
			(hide yes)
			(effects
				(font
					(size 1.016 1.016)
					(thickness 0.1524)
				)
			)
		)
		(duplicate_pad_numbers_are_jumpers no)
		(fp_line
			(start -0.508 -0.9398)
			(end -0.508 0.9398)
			(stroke
				(width 0.1524)
				(type default)
			)
			(layer "F.SilkS")
		)
		(fp_line
			(start 0.508 -0.9398)
			(end -0.508 -0.9398)
			(stroke
				(width 0.1524)
				(type default)
			)
			(layer "F.SilkS")
		)
		(fp_rect
			(start -0.508 0.9398)
			(end 0.508 -0.9398)
			(stroke
				(width 0)
				(type default)
			)
			(fill no)
			(layer "F.CrtYd")
		)
		(fp_rect
			(start -0.508 0.9398)
			(end 0.508 -0.9398)
			(stroke
				(width 0)
				(type default)
			)
			(fill no)
			(layer "F.Fab")
		)
		(pad "1" smd custom
			(at 0 -0.4445)
			(size 0.1397 0.1397)
			(layers "F.Cu" "F.Mask" "F.Paste")
			(net "SSD_ATNLED#2")
			(options
				(clearance outline)
				(anchor circle)
			)
			(primitives
				(gr_poly
					(pts
						(arc
							(start -0.1778 -0.2794)
							(mid -0.249642 -0.249642)
							(end -0.2794 -0.1778)
						)
						(arc
							(start -0.2794 0.1778)
							(mid -0.249642 0.249642)
							(end -0.1778 0.2794)
						)
						(arc
							(start 0.1778 0.2794)
							(mid 0.249642 0.249642)
							(end 0.2794 0.1778)
						)
						(arc
							(start 0.2794 -0.1778)
							(mid 0.249642 -0.249642)
							(end 0.1778 -0.2794)
						)
					)
					(width 0)
					(fill yes)
				)
			)
		)
		(pad "2" smd custom
			(at 0 0.4445)
			(size 0.1397 0.1397)
			(layers "F.Cu" "F.Mask" "F.Paste")
			(net "SSD_ATNLED#2_R")
			(options
				(clearance outline)
				(anchor circle)
			)
			(primitives
				(gr_poly
					(pts
						(arc
							(start -0.1778 -0.2794)
							(mid -0.249642 -0.249642)
							(end -0.2794 -0.1778)
						)
						(arc
							(start -0.2794 0.1778)
							(mid -0.249642 0.249642)
							(end -0.1778 0.2794)
						)
						(arc
							(start 0.1778 0.2794)
							(mid 0.249642 0.249642)
							(end 0.2794 0.1778)
						)
						(arc
							(start 0.2794 -0.1778)
							(mid 0.249642 -0.249642)
							(end 0.1778 -0.2794)
						)
					)
					(width 0)
					(fill yes)
				)
			)
		)
	)
	(footprint ""
		(layer "F.Cu")
		(at 192.9384 -21.971 -90)
		(property "Reference" "R696"
			(at 0 0 270)
			(layer "F.SilkS")
			(hide yes)
			(effects
				(font
					(size 1.27 1.27)
				)
			)
		)
		(property "Value" "4K7R2F-GP"
			(at 0.064008 -3.993896 270)
			(unlocked yes)
			(layer "F.Fab")
			(hide yes)
			(effects
				(font
					(size 1.016 1.016)
					(thickness 0.1524)
				)
			)
		)
		(property "Device Type" "R402H16"
			(at 0.064008 -5.517896 270)
			(unlocked yes)
			(layer "F.Fab")
			(hide yes)
			(effects
				(font
					(size 1.016 1.016)
					(thickness 0.1524)
				)
			)
		)
		(duplicate_pad_numbers_are_jumpers no)
		(fp_line
			(start -0.508 -0.9398)
			(end -0.508 0.9398)
			(stroke
				(width 0.1524)
				(type default)
			)
			(layer "F.SilkS")
		)
		(fp_line
			(start 0.508 -0.9398)
			(end -0.508 -0.9398)
			(stroke
				(width 0.1524)
				(type default)
			)
			(layer "F.SilkS")
		)
		(fp_rect
			(start -0.508 0.9398)
			(end 0.508 -0.9398)
			(stroke
				(width 0)
				(type default)
			)
			(fill no)
			(layer "F.CrtYd")
		)
		(fp_rect
			(start -0.508 0.9398)
			(end 0.508 -0.9398)
			(stroke
				(width 0)
				(type default)
			)
			(fill no)
			(layer "F.Fab")
		)
		(pad "1" smd custom
			(at 0 -0.4445 270)
			(size 0.1397 0.1397)
			(layers "F.Cu" "F.Mask" "F.Paste")
			(net "MINISAS_CN15_A_I2C_INT#")
			(options
				(clearance outline)
				(anchor circle)
			)
			(primitives
				(gr_poly
					(pts
						(arc
							(start -0.1778 -0.2794)
							(mid -0.249642 -0.249642)
							(end -0.2794 -0.1778)
						)
						(arc
							(start -0.2794 0.1778)
							(mid -0.249642 0.249642)
							(end -0.1778 0.2794)
						)
						(arc
							(start 0.1778 0.2794)
							(mid 0.249642 0.249642)
							(end 0.2794 0.1778)
						)
						(arc
							(start 0.2794 -0.1778)
							(mid 0.249642 -0.249642)
							(end 0.1778 -0.2794)
						)
					)
					(width 0)
					(fill yes)
				)
			)
		)
		(pad "2" smd custom
			(at 0 0.4445 270)
			(size 0.1397 0.1397)
			(layers "F.Cu" "F.Mask" "F.Paste")
			(net "P3V3_STBY")
			(options
				(clearance outline)
				(anchor circle)
			)
			(primitives
				(gr_poly
					(pts
						(arc
							(start -0.1778 -0.2794)
							(mid -0.249642 -0.249642)
							(end -0.2794 -0.1778)
						)
						(arc
							(start -0.2794 0.1778)
							(mid -0.249642 0.249642)
							(end -0.1778 0.2794)
						)
						(arc
							(start 0.1778 0.2794)
							(mid 0.249642 0.249642)
							(end 0.2794 0.1778)
						)
						(arc
							(start 0.2794 -0.1778)
							(mid 0.249642 -0.249642)
							(end 0.1778 -0.2794)
						)
					)
					(width 0)
					(fill yes)
				)
			)
		)
	)
	(footprint ""
		(layer "F.Cu")
		(at 121.059956 -41.273222 90)
		(property "Reference" "Q4"
			(at 0 0 90)
			(layer "F.SilkS")
			(hide yes)
			(effects
				(font
					(size 1.27 1.27)
				)
			)
		)
		(property "Value" "PN2907AL-T92-K-GP"
			(at 0.6223 -2.5146 90)
			(unlocked yes)
			(layer "F.Fab")
			(hide yes)
			(effects
				(font
					(size 1.016 1.016)
					(thickness 0.1524)
				)
			)
		)
		(property "Device Type" "TO-92-CBE-4635H591"
			(at 0.6223 -4.0386 90)
			(unlocked yes)
			(layer "F.Fab")
			(hide yes)
			(effects
				(font
					(size 1.016 1.016)
					(thickness 0.1524)
				)
			)
		)
		(duplicate_pad_numbers_are_jumpers no)
		(fp_line
			(start 2.54 -1.2827)
			(end 2.54 0.1905)
			(stroke
				(width 0.1524)
				(type default)
			)
			(layer "F.SilkS")
		)
		(fp_line
			(start -2.54 -1.2827)
			(end 2.54 -1.2827)
			(stroke
				(width 0.1524)
				(type default)
			)
			(layer "F.SilkS")
		)
		(fp_line
			(start -2.54 0.1905)
			(end -2.54 -1.2827)
			(stroke
				(width 0.1524)
				(type default)
			)
			(layer "F.SilkS")
		)
		(fp_arc
			(start 2.54 0.1905)
			(mid 0 2.7305)
			(end -2.54 0.1905)
			(stroke
				(width 0.1524)
				(type default)
			)
			(layer "F.SilkS")
		)
		(fp_poly
			(pts
				(arc
					(start 2.286 0.1905)
					(mid 0 2.4765)
					(end -2.286 0.1905)
				)
				(xy -2.286 -1.0287) (xy 2.286 -1.0287)
			)
			(stroke
				(width 0)
				(type default)
			)
			(fill no)
			(layer "F.CrtYd")
		)
		(fp_poly
			(pts
				(arc
					(start 2.794 0.1905)
					(mid 0 2.9845)
					(end -2.794 0.1905)
				)
				(xy -2.794 -1.5367) (xy 2.794 -1.5367) (xy 2.794 -0.00635) (xy 2.286 -0.00635) (xy 2.286 -1.0287)
				(xy -2.286 -1.0287)
				(arc
					(start -2.286 0.1905)
					(mid 0 2.4765)
					(end 2.286 0.1905)
				)
				(xy 2.286 0.00635) (xy 2.794 0.00635)
			)
			(stroke
				(width 0)
				(type default)
			)
			(fill no)
			(layer "F.CrtYd")
		)
		(fp_poly
			(pts
				(arc
					(start 2.794 0.1905)
					(mid 0 2.9845)
					(end -2.794 0.1905)
				)
				(xy -2.794 -1.5367) (xy 2.794 -1.5367)
			)
			(stroke
				(width 0)
				(type default)
			)
			(fill no)
			(layer "F.Fab")
		)
		(pad "B" thru_hole oval
			(at 0 0 90)
			(size 1.0414 1.1684)
			(drill 0.762)
			(layers "*.Cu" "*.Mask")
			(remove_unused_layers no)
			(net "TEMP_SENSOR_DXN_BJT")
			(clearance 0.2159)
			(thermal_gap 0.2159)
		)
		(pad "C" thru_hole oval
			(at -1.27 0 90)
			(size 1.0414 1.1684)
			(drill 0.762)
			(layers "*.Cu" "*.Mask")
			(remove_unused_layers no)
			(net "TEMP_SENSOR_C")
			(clearance 0.2159)
			(thermal_gap 0.2159)
		)
		(pad "E" thru_hole oval
			(at 1.27 0 90)
			(size 1.0414 1.1684)
			(drill 0.762)
			(layers "*.Cu" "*.Mask")
			(remove_unused_layers no)
			(net "TEMP_SENSOR_DXP_R")
			(clearance 0.2159)
			(thermal_gap 0.2159)
		)
	)
	(footprint ""
		(layer "F.Cu")
		(at 56.990488 -143.254476 90)
		(property "Reference" "R415"
			(at 0 0 90)
			(layer "F.SilkS")
			(hide yes)
			(effects
				(font
					(size 1.27 1.27)
				)
			)
		)
		(property "Value" "0R2J-2-GP"
			(at 0.064008 -3.993896 90)
			(unlocked yes)
			(layer "F.Fab")
			(hide yes)
			(effects
				(font
					(size 1.016 1.016)
					(thickness 0.1524)
				)
			)
		)
		(property "Device Type" "R402H16"
			(at 0.064008 -5.517896 90)
			(unlocked yes)
			(layer "F.Fab")
			(hide yes)
			(effects
				(font
					(size 1.016 1.016)
					(thickness 0.1524)
				)
			)
		)
		(duplicate_pad_numbers_are_jumpers no)
		(fp_line
			(start 0.508 -0.9398)
			(end -0.508 -0.9398)
			(stroke
				(width 0.1524)
				(type default)
			)
			(layer "F.SilkS")
		)
		(fp_line
			(start -0.508 -0.9398)
			(end -0.508 0.9398)
			(stroke
				(width 0.1524)
				(type default)
			)
			(layer "F.SilkS")
		)
		(fp_rect
			(start -0.508 0.9398)
			(end 0.508 -0.9398)
			(stroke
				(width 0)
				(type default)
			)
			(fill no)
			(layer "F.CrtYd")
		)
		(fp_rect
			(start -0.508 0.9398)
			(end 0.508 -0.9398)
			(stroke
				(width 0)
				(type default)
			)
			(fill no)
			(layer "F.Fab")
		)
		(pad "1" smd custom
			(at 0 -0.4445 90)
			(size 0.1397 0.1397)
			(layers "F.Cu" "F.Mask" "F.Paste")
			(net "GPIOM0_I210_PERST_N")
			(options
				(clearance outline)
				(anchor circle)
			)
			(primitives
				(gr_poly
					(pts
						(arc
							(start -0.1778 -0.2794)
							(mid -0.249642 -0.249642)
							(end -0.2794 -0.1778)
						)
						(arc
							(start -0.2794 0.1778)
							(mid -0.249642 0.249642)
							(end -0.1778 0.2794)
						)
						(arc
							(start 0.1778 0.2794)
							(mid 0.249642 0.249642)
							(end 0.2794 0.1778)
						)
						(arc
							(start 0.2794 -0.1778)
							(mid 0.249642 -0.249642)
							(end 0.1778 -0.2794)
						)
					)
					(width 0)
					(fill yes)
				)
			)
		)
		(pad "2" smd custom
			(at 0 0.4445 90)
			(size 0.1397 0.1397)
			(layers "F.Cu" "F.Mask" "F.Paste")
			(net "BMC_I210_PERST_N")
			(options
				(clearance outline)
				(anchor circle)
			)
			(primitives
				(gr_poly
					(pts
						(arc
							(start -0.1778 -0.2794)
							(mid -0.249642 -0.249642)
							(end -0.2794 -0.1778)
						)
						(arc
							(start -0.2794 0.1778)
							(mid -0.249642 0.249642)
							(end -0.1778 0.2794)
						)
						(arc
							(start 0.1778 0.2794)
							(mid 0.249642 0.249642)
							(end 0.2794 0.1778)
						)
						(arc
							(start 0.2794 -0.1778)
							(mid 0.249642 -0.249642)
							(end 0.1778 -0.2794)
						)
					)
					(width 0)
					(fill yes)
				)
			)
		)
	)
	(footprint ""
		(layer "F.Cu")
		(at 135.3693 -33.54324)
		(property "Reference" "C381"
			(at 0 0 0)
			(layer "F.SilkS")
			(hide yes)
			(effects
				(font
					(size 1.27 1.27)
				)
			)
		)
		(property "Value" "SCD22U10V2KX-1GP"
			(at 1.1811 -2.7051 0)
			(unlocked yes)
			(layer "F.Fab")
			(hide yes)
			(effects
				(font
					(size 1.016 1.016)
					(thickness 0.1524)
				)
			)
		)
		(property "Device Type" "C402H22"
			(at 1.1811 -4.2291 0)
			(unlocked yes)
			(layer "F.Fab")
			(hide yes)
			(effects
				(font
					(size 1.016 1.016)
					(thickness 0.1524)
				)
			)
		)
		(duplicate_pad_numbers_are_jumpers no)
		(fp_rect
			(start -0.4318 0.9525)
			(end 0.4318 -0.9525)
			(stroke
				(width 0)
				(type default)
			)
			(fill no)
			(layer "F.CrtYd")
		)
		(fp_rect
			(start -0.4318 0.9525)
			(end 0.4318 -0.9525)
			(stroke
				(width 0)
				(type default)
			)
			(fill no)
			(layer "F.Fab")
		)
		(pad "1" smd custom
			(at 0 -0.4445)
			(size 0.1524 0.1524)
			(layers "F.Cu" "F.Mask" "F.Paste")
			(net "PCIE_TX_CAP_P80")
			(options
				(clearance outline)
				(anchor circle)
			)
			(primitives
				(gr_poly
					(pts
						(arc
							(start 0.3048 -0.2032)
							(mid 0.275042 -0.275042)
							(end 0.2032 -0.3048)
						)
						(arc
							(start -0.2032 -0.3048)
							(mid -0.275042 -0.275042)
							(end -0.3048 -0.2032)
						)
						(arc
							(start -0.3048 0.2032)
							(mid -0.275042 0.275042)
							(end -0.2032 0.3048)
						)
						(arc
							(start 0.2032 0.3048)
							(mid 0.275042 0.275042)
							(end 0.3048 0.2032)
						)
					)
					(width 0)
					(fill yes)
				)
			)
		)
		(pad "2" smd custom
			(at 0 0.4445)
			(size 0.1524 0.1524)
			(layers "F.Cu" "F.Mask" "F.Paste")
			(net "PCIE_TX_P80")
			(options
				(clearance outline)
				(anchor circle)
			)
			(primitives
				(gr_poly
					(pts
						(arc
							(start 0.3048 -0.2032)
							(mid 0.275042 -0.275042)
							(end 0.2032 -0.3048)
						)
						(arc
							(start -0.2032 -0.3048)
							(mid -0.275042 -0.275042)
							(end -0.3048 -0.2032)
						)
						(arc
							(start -0.3048 0.2032)
							(mid -0.275042 0.275042)
							(end -0.2032 0.3048)
						)
						(arc
							(start 0.2032 0.3048)
							(mid 0.275042 0.275042)
							(end 0.3048 0.2032)
						)
					)
					(width 0)
					(fill yes)
				)
			)
		)
	)
	(footprint ""
		(layer "F.Cu")
		(at 225.8314 -15.4686 90)
		(property "Reference" "U82"
			(at 0 0 90)
			(layer "F.SilkS")
			(hide yes)
			(effects
				(font
					(size 1.27 1.27)
				)
			)
		)
		(property "Value" "ADM6315-26D3ARTZR7-4-GP"
			(at -0.0127 -12.8016 90)
			(unlocked yes)
			(layer "F.Fab")
			(hide yes)
			(effects
				(font
					(size 1.016 1.016)
					(thickness 0.1524)
				)
			)
		)
		(property "Device Type" "SOT-143-6H49"
			(at -0.0635 -14.6812 90)
			(unlocked yes)
			(layer "F.Fab")
			(hide yes)
			(effects
				(font
					(size 1.016 1.016)
					(thickness 0.1524)
				)
			)
		)
		(duplicate_pad_numbers_are_jumpers no)
		(fp_line
			(start 1.6891 -1.778)
			(end 1.6891 1.778)
			(stroke
				(width 0.1524)
				(type default)
			)
			(layer "F.SilkS")
		)
		(fp_line
			(start -1.6891 -1.778)
			(end 1.6891 -1.778)
			(stroke
				(width 0.1524)
				(type default)
			)
			(layer "F.SilkS")
		)
		(fp_line
			(start 1.6891 1.778)
			(end -1.6891 1.778)
			(stroke
				(width 0.1524)
				(type default)
			)
			(layer "F.SilkS")
		)
		(fp_line
			(start -1.6891 1.778)
			(end -1.6891 -1.778)
			(stroke
				(width 0.1524)
				(type default)
			)
			(layer "F.SilkS")
		)
		(fp_line
			(start -0.3175 1.8669)
			(end -1.7907 1.8669)
			(stroke
				(width 0.3302)
				(type default)
			)
			(layer "F.SilkS")
		)
		(fp_line
			(start -1.7907 1.8669)
			(end -1.7907 0.3937)
			(stroke
				(width 0.3302)
				(type default)
			)
			(layer "F.SilkS")
		)
		(fp_poly
			(pts
				(xy -0.7239 1.8542) (xy -1.3335 2.4638) (xy -0.1143 2.4638)
			)
			(stroke
				(width 0)
				(type default)
			)
			(fill yes)
			(layer "F.SilkS")
		)
		(fp_rect
			(start -1.9431 2.032)
			(end 1.9431 -2.032)
			(stroke
				(width 0)
				(type default)
			)
			(fill no)
			(layer "F.CrtYd")
		)
		(fp_poly
			(pts
				(xy 1.9431 2.032) (xy 1.9431 -2.032) (xy -1.9431 -2.032) (xy -1.9431 2.032)
			)
			(stroke
				(width 0)
				(type default)
			)
			(fill no)
			(layer "F.Fab")
		)
		(pad "1" smd rect
			(at -0.75311 0.9652 90)
			(size 1.1176 1.1176)
			(layers "F.Cu" "F.Mask" "F.Paste")
			(net "GND")
		)
		(pad "2" smd rect
			(at 0.9525 0.9652 90)
			(size 0.7112 1.1176)
			(layers "F.Cu" "F.Mask" "F.Paste")
			(net "U82_RST#")
		)
		(pad "3" smd rect
			(at 0.9525 -0.9652 90)
			(size 0.7112 1.1176)
			(layers "F.Cu" "F.Mask" "F.Paste")
			(net "U82_MR#")
		)
		(pad "4" smd rect
			(at -0.9525 -0.9652 90)
			(size 0.7112 1.1176)
			(layers "F.Cu" "F.Mask" "F.Paste")
			(net "P3V3_STBY")
		)
	)
	(footprint ""
		(layer "F.Cu")
		(at 97.992184 -212.420454 180)
		(property "Reference" "C156"
			(at 0 0 180)
			(layer "F.SilkS")
			(hide yes)
			(effects
				(font
					(size 1.27 1.27)
				)
			)
		)
		(property "Value" "SCD22U10V2KX-1GP"
			(at 1.1811 -2.7051 180)
			(unlocked yes)
			(layer "F.Fab")
			(hide yes)
			(effects
				(font
					(size 1.016 1.016)
					(thickness 0.1524)
				)
			)
		)
		(property "Device Type" "C402H22"
			(at 1.1811 -4.2291 180)
			(unlocked yes)
			(layer "F.Fab")
			(hide yes)
			(effects
				(font
					(size 1.016 1.016)
					(thickness 0.1524)
				)
			)
		)
		(duplicate_pad_numbers_are_jumpers no)
		(fp_rect
			(start -0.4318 0.9525)
			(end 0.4318 -0.9525)
			(stroke
				(width 0)
				(type default)
			)
			(fill no)
			(layer "F.CrtYd")
		)
		(fp_rect
			(start -0.4318 0.9525)
			(end 0.4318 -0.9525)
			(stroke
				(width 0)
				(type default)
			)
			(fill no)
			(layer "F.Fab")
		)
		(pad "1" smd custom
			(at 0 -0.4445 180)
			(size 0.1524 0.1524)
			(layers "F.Cu" "F.Mask" "F.Paste")
			(net "PCIE_TX_CAP_P63")
			(options
				(clearance outline)
				(anchor circle)
			)
			(primitives
				(gr_poly
					(pts
						(arc
							(start 0.3048 -0.2032)
							(mid 0.275042 -0.275042)
							(end 0.2032 -0.3048)
						)
						(arc
							(start -0.2032 -0.3048)
							(mid -0.275042 -0.275042)
							(end -0.3048 -0.2032)
						)
						(arc
							(start -0.3048 0.2032)
							(mid -0.275042 0.275042)
							(end -0.2032 0.3048)
						)
						(arc
							(start 0.2032 0.3048)
							(mid 0.275042 0.275042)
							(end 0.3048 0.2032)
						)
					)
					(width 0)
					(fill yes)
				)
			)
		)
		(pad "2" smd custom
			(at 0 0.4445 180)
			(size 0.1524 0.1524)
			(layers "F.Cu" "F.Mask" "F.Paste")
			(net "PCIE_TX_P63")
			(options
				(clearance outline)
				(anchor circle)
			)
			(primitives
				(gr_poly
					(pts
						(arc
							(start 0.3048 -0.2032)
							(mid 0.275042 -0.275042)
							(end 0.2032 -0.3048)
						)
						(arc
							(start -0.2032 -0.3048)
							(mid -0.275042 -0.275042)
							(end -0.3048 -0.2032)
						)
						(arc
							(start -0.3048 0.2032)
							(mid -0.275042 0.275042)
							(end -0.2032 0.3048)
						)
						(arc
							(start 0.2032 0.3048)
							(mid 0.275042 0.275042)
							(end 0.3048 0.2032)
						)
					)
					(width 0)
					(fill yes)
				)
			)
		)
	)
	(footprint ""
		(layer "F.Cu")
		(at 12.954 -111.633 -90)
		(property "Reference" "PC81"
			(at 0 0 270)
			(layer "F.SilkS")
			(hide yes)
			(effects
				(font
					(size 1.27 1.27)
				)
			)
		)
		(property "Value" "SC22U6D3V5MX-5-GP"
			(at -0.0762 -6.1214 270)
			(unlocked yes)
			(layer "F.Fab")
			(hide yes)
			(effects
				(font
					(size 1.016 1.016)
					(thickness 0.1524)
				)
			)
		)
		(property "Device Type" "C805H56"
			(at -0.0762 -8.1534 270)
			(unlocked yes)
			(layer "F.Fab")
			(hide yes)
			(effects
				(font
					(size 1.016 1.016)
					(thickness 0.1524)
				)
			)
		)
		(duplicate_pad_numbers_are_jumpers no)
		(fp_line
			(start 0.635 0)
			(end -0.635 0)
			(stroke
				(width 0.508)
				(type default)
			)
			(layer "F.SilkS")
		)
		(fp_rect
			(start -0.9652 1.778)
			(end 0.9652 -1.778)
			(stroke
				(width 0)
				(type default)
			)
			(fill no)
			(layer "F.CrtYd")
		)
		(fp_poly
			(pts
				(xy -0.9652 -1.778) (xy 0.9652 -1.778) (xy 0.9652 1.778) (xy -0.9652 1.778)
			)
			(stroke
				(width 0)
				(type default)
			)
			(fill no)
			(layer "F.Fab")
		)
		(pad "1" smd rect
			(at 0 -0.9652 270)
			(size 1.397 1.143)
			(layers "F.Cu" "F.Mask" "F.Paste")
			(net "P1V26_PWR")
		)
		(pad "2" smd rect
			(at 0 0.9652 270)
			(size 1.397 1.143)
			(layers "F.Cu" "F.Mask" "F.Paste")
			(net "GND")
		)
	)
	(footprint ""
		(layer "F.Cu")
		(at 20.7264 -173.2026 90)
		(property "Reference" "PR38"
			(at 0 0 90)
			(layer "F.SilkS")
			(hide yes)
			(effects
				(font
					(size 1.27 1.27)
				)
			)
		)
		(property "Value" "10KR2F-2-GP"
			(at 0.064008 -3.993896 90)
			(unlocked yes)
			(layer "F.Fab")
			(hide yes)
			(effects
				(font
					(size 1.016 1.016)
					(thickness 0.1524)
				)
			)
		)
		(property "Device Type" "R402H16"
			(at 0.064008 -5.517896 90)
			(unlocked yes)
			(layer "F.Fab")
			(hide yes)
			(effects
				(font
					(size 1.016 1.016)
					(thickness 0.1524)
				)
			)
		)
		(duplicate_pad_numbers_are_jumpers no)
		(fp_line
			(start 0.508 -0.9398)
			(end -0.508 -0.9398)
			(stroke
				(width 0.1524)
				(type default)
			)
			(layer "F.SilkS")
		)
		(fp_line
			(start -0.508 -0.9398)
			(end -0.508 0.9398)
			(stroke
				(width 0.1524)
				(type default)
			)
			(layer "F.SilkS")
		)
		(fp_rect
			(start -0.508 0.9398)
			(end 0.508 -0.9398)
			(stroke
				(width 0)
				(type default)
			)
			(fill no)
			(layer "F.CrtYd")
		)
		(fp_rect
			(start -0.508 0.9398)
			(end 0.508 -0.9398)
			(stroke
				(width 0)
				(type default)
			)
			(fill no)
			(layer "F.Fab")
		)
		(pad "1" smd custom
			(at 0 -0.4445 90)
			(size 0.1397 0.1397)
			(layers "F.Cu" "F.Mask" "F.Paste")
			(net "GND")
			(options
				(clearance outline)
				(anchor circle)
			)
			(primitives
				(gr_poly
					(pts
						(arc
							(start -0.1778 -0.2794)
							(mid -0.249642 -0.249642)
							(end -0.2794 -0.1778)
						)
						(arc
							(start -0.2794 0.1778)
							(mid -0.249642 0.249642)
							(end -0.1778 0.2794)
						)
						(arc
							(start 0.1778 0.2794)
							(mid 0.249642 0.249642)
							(end 0.2794 0.1778)
						)
						(arc
							(start 0.2794 -0.1778)
							(mid 0.249642 -0.249642)
							(end 0.1778 -0.2794)
						)
					)
					(width 0)
					(fill yes)
				)
			)
		)
		(pad "2" smd custom
			(at 0 0.4445 90)
			(size 0.1397 0.1397)
			(layers "F.Cu" "F.Mask" "F.Paste")
			(net "PCIE_MATED#_B")
			(options
				(clearance outline)
				(anchor circle)
			)
			(primitives
				(gr_poly
					(pts
						(arc
							(start -0.1778 -0.2794)
							(mid -0.249642 -0.249642)
							(end -0.2794 -0.1778)
						)
						(arc
							(start -0.2794 0.1778)
							(mid -0.249642 0.249642)
							(end -0.1778 0.2794)
						)
						(arc
							(start 0.1778 0.2794)
							(mid 0.249642 0.249642)
							(end 0.2794 0.1778)
						)
						(arc
							(start 0.2794 -0.1778)
							(mid 0.249642 -0.249642)
							(end 0.1778 -0.2794)
						)
					)
					(width 0)
					(fill yes)
				)
			)
		)
	)
	(footprint ""
		(layer "F.Cu")
		(at 131.421886 -51.326288 -90)
		(property "Reference" "R945"
			(at 0 0 270)
			(layer "F.SilkS")
			(hide yes)
			(effects
				(font
					(size 1.27 1.27)
				)
			)
		)
		(property "Value" "0R2J-2-GP"
			(at 0.064008 -3.993896 270)
			(unlocked yes)
			(layer "F.Fab")
			(hide yes)
			(effects
				(font
					(size 1.016 1.016)
					(thickness 0.1524)
				)
			)
		)
		(property "Device Type" "R402H16"
			(at 0.064008 -5.517896 270)
			(unlocked yes)
			(layer "F.Fab")
			(hide yes)
			(effects
				(font
					(size 1.016 1.016)
					(thickness 0.1524)
				)
			)
		)
		(duplicate_pad_numbers_are_jumpers no)
		(fp_line
			(start -0.508 -0.9398)
			(end -0.508 0.9398)
			(stroke
				(width 0.1524)
				(type default)
			)
			(layer "F.SilkS")
		)
		(fp_line
			(start 0.508 -0.9398)
			(end -0.508 -0.9398)
			(stroke
				(width 0.1524)
				(type default)
			)
			(layer "F.SilkS")
		)
		(fp_rect
			(start -0.508 0.9398)
			(end 0.508 -0.9398)
			(stroke
				(width 0)
				(type default)
			)
			(fill no)
			(layer "F.CrtYd")
		)
		(fp_rect
			(start -0.508 0.9398)
			(end 0.508 -0.9398)
			(stroke
				(width 0)
				(type default)
			)
			(fill no)
			(layer "F.Fab")
		)
		(pad "1" smd custom
			(at 0 -0.4445 270)
			(size 0.1397 0.1397)
			(layers "F.Cu" "F.Mask" "F.Paste")
			(net "PMC_R_TXD5")
			(options
				(clearance outline)
				(anchor circle)
			)
			(primitives
				(gr_poly
					(pts
						(arc
							(start -0.1778 -0.2794)
							(mid -0.249642 -0.249642)
							(end -0.2794 -0.1778)
						)
						(arc
							(start -0.2794 0.1778)
							(mid -0.249642 0.249642)
							(end -0.1778 0.2794)
						)
						(arc
							(start 0.1778 0.2794)
							(mid 0.249642 0.249642)
							(end 0.2794 0.1778)
						)
						(arc
							(start 0.2794 -0.1778)
							(mid 0.249642 -0.249642)
							(end 0.1778 -0.2794)
						)
					)
					(width 0)
					(fill yes)
				)
			)
		)
		(pad "2" smd custom
			(at 0 0.4445 270)
			(size 0.1397 0.1397)
			(layers "F.Cu" "F.Mask" "F.Paste")
			(net "EXP_SMART_TX")
			(options
				(clearance outline)
				(anchor circle)
			)
			(primitives
				(gr_poly
					(pts
						(arc
							(start -0.1778 -0.2794)
							(mid -0.249642 -0.249642)
							(end -0.2794 -0.1778)
						)
						(arc
							(start -0.2794 0.1778)
							(mid -0.249642 0.249642)
							(end -0.1778 0.2794)
						)
						(arc
							(start 0.1778 0.2794)
							(mid 0.249642 0.249642)
							(end 0.2794 0.1778)
						)
						(arc
							(start 0.2794 -0.1778)
							(mid 0.249642 -0.249642)
							(end 0.1778 -0.2794)
						)
					)
					(width 0)
					(fill yes)
				)
			)
		)
	)
	(footprint ""
		(layer "F.Cu")
		(at 230.251 -9.398 -90)
		(property "Reference" "R653"
			(at 0 0 270)
			(layer "F.SilkS")
			(hide yes)
			(effects
				(font
					(size 1.27 1.27)
				)
			)
		)
		(property "Value" "100KR2F-L1-GP"
			(at 0.064008 -3.993896 270)
			(unlocked yes)
			(layer "F.Fab")
			(hide yes)
			(effects
				(font
					(size 1.016 1.016)
					(thickness 0.1524)
				)
			)
		)
		(property "Device Type" "R402H16"
			(at 0.064008 -5.517896 270)
			(unlocked yes)
			(layer "F.Fab")
			(hide yes)
			(effects
				(font
					(size 1.016 1.016)
					(thickness 0.1524)
				)
			)
		)
		(duplicate_pad_numbers_are_jumpers no)
		(fp_line
			(start -0.508 -0.9398)
			(end -0.508 0.9398)
			(stroke
				(width 0.1524)
				(type default)
			)
			(layer "F.SilkS")
		)
		(fp_line
			(start 0.508 -0.9398)
			(end -0.508 -0.9398)
			(stroke
				(width 0.1524)
				(type default)
			)
			(layer "F.SilkS")
		)
		(fp_rect
			(start -0.508 0.9398)
			(end 0.508 -0.9398)
			(stroke
				(width 0)
				(type default)
			)
			(fill no)
			(layer "F.CrtYd")
		)
		(fp_rect
			(start -0.508 0.9398)
			(end 0.508 -0.9398)
			(stroke
				(width 0)
				(type default)
			)
			(fill no)
			(layer "F.Fab")
		)
		(pad "1" smd custom
			(at 0 -0.4445 270)
			(size 0.1397 0.1397)
			(layers "F.Cu" "F.Mask" "F.Paste")
			(net "P3V3_STBY")
			(options
				(clearance outline)
				(anchor circle)
			)
			(primitives
				(gr_poly
					(pts
						(arc
							(start -0.1778 -0.2794)
							(mid -0.249642 -0.249642)
							(end -0.2794 -0.1778)
						)
						(arc
							(start -0.2794 0.1778)
							(mid -0.249642 0.249642)
							(end -0.1778 0.2794)
						)
						(arc
							(start 0.1778 0.2794)
							(mid 0.249642 0.249642)
							(end 0.2794 0.1778)
						)
						(arc
							(start 0.2794 -0.1778)
							(mid 0.249642 -0.249642)
							(end 0.1778 -0.2794)
						)
					)
					(width 0)
					(fill yes)
				)
			)
		)
		(pad "2" smd custom
			(at 0 0.4445 270)
			(size 0.1397 0.1397)
			(layers "F.Cu" "F.Mask" "F.Paste")
			(net "EEPROM_WP_8536")
			(options
				(clearance outline)
				(anchor circle)
			)
			(primitives
				(gr_poly
					(pts
						(arc
							(start -0.1778 -0.2794)
							(mid -0.249642 -0.249642)
							(end -0.2794 -0.1778)
						)
						(arc
							(start -0.2794 0.1778)
							(mid -0.249642 0.249642)
							(end -0.1778 0.2794)
						)
						(arc
							(start 0.1778 0.2794)
							(mid 0.249642 0.249642)
							(end 0.2794 0.1778)
						)
						(arc
							(start 0.2794 -0.1778)
							(mid 0.249642 -0.249642)
							(end 0.1778 -0.2794)
						)
					)
					(width 0)
					(fill yes)
				)
			)
		)
	)
	(footprint ""
		(layer "F.Cu")
		(at 312.625486 -33.556448)
		(property "Reference" "C21"
			(at 0 0 0)
			(layer "F.SilkS")
			(hide yes)
			(effects
				(font
					(size 1.27 1.27)
				)
			)
		)
		(property "Value" "SCD22U10V2KX-1GP"
			(at 1.1811 -2.7051 0)
			(unlocked yes)
			(layer "F.Fab")
			(hide yes)
			(effects
				(font
					(size 1.016 1.016)
					(thickness 0.1524)
				)
			)
		)
		(property "Device Type" "C402H22"
			(at 1.1811 -4.2291 0)
			(unlocked yes)
			(layer "F.Fab")
			(hide yes)
			(effects
				(font
					(size 1.016 1.016)
					(thickness 0.1524)
				)
			)
		)
		(duplicate_pad_numbers_are_jumpers no)
		(fp_rect
			(start -0.4318 0.9525)
			(end 0.4318 -0.9525)
			(stroke
				(width 0)
				(type default)
			)
			(fill no)
			(layer "F.CrtYd")
		)
		(fp_rect
			(start -0.4318 0.9525)
			(end 0.4318 -0.9525)
			(stroke
				(width 0)
				(type default)
			)
			(fill no)
			(layer "F.Fab")
		)
		(pad "1" smd custom
			(at 0 -0.4445)
			(size 0.1524 0.1524)
			(layers "F.Cu" "F.Mask" "F.Paste")
			(net "PCIE_TX_CAP_P10")
			(options
				(clearance outline)
				(anchor circle)
			)
			(primitives
				(gr_poly
					(pts
						(arc
							(start 0.3048 -0.2032)
							(mid 0.275042 -0.275042)
							(end 0.2032 -0.3048)
						)
						(arc
							(start -0.2032 -0.3048)
							(mid -0.275042 -0.275042)
							(end -0.3048 -0.2032)
						)
						(arc
							(start -0.3048 0.2032)
							(mid -0.275042 0.275042)
							(end -0.2032 0.3048)
						)
						(arc
							(start 0.2032 0.3048)
							(mid 0.275042 0.275042)
							(end 0.3048 0.2032)
						)
					)
					(width 0)
					(fill yes)
				)
			)
		)
		(pad "2" smd custom
			(at 0 0.4445)
			(size 0.1524 0.1524)
			(layers "F.Cu" "F.Mask" "F.Paste")
			(net "PCIE_TX_P10")
			(options
				(clearance outline)
				(anchor circle)
			)
			(primitives
				(gr_poly
					(pts
						(arc
							(start 0.3048 -0.2032)
							(mid 0.275042 -0.275042)
							(end 0.2032 -0.3048)
						)
						(arc
							(start -0.2032 -0.3048)
							(mid -0.275042 -0.275042)
							(end -0.3048 -0.2032)
						)
						(arc
							(start -0.3048 0.2032)
							(mid -0.275042 0.275042)
							(end -0.2032 0.3048)
						)
						(arc
							(start 0.2032 0.3048)
							(mid 0.275042 0.275042)
							(end 0.3048 0.2032)
						)
					)
					(width 0)
					(fill yes)
				)
			)
		)
	)
	(footprint ""
		(layer "F.Cu")
		(at 76.835 -52.6288)
		(property "Reference" "JP13"
			(at 0 0 0)
			(layer "F.SilkS")
			(hide yes)
			(effects
				(font
					(size 1.27 1.27)
				)
			)
		)
		(property "Value" "PIN-CON3-S-GP"
			(at -5.588 -5.3086 0)
			(unlocked yes)
			(layer "F.Fab")
			(hide yes)
			(effects
				(font
					(size 1.016 1.016)
					(thickness 0.1524)
				)
			)
		)
		(property "Device Type" "21S-91-03GB01"
			(at -5.588 -6.8326 0)
			(unlocked yes)
			(layer "F.Fab")
			(hide yes)
			(effects
				(font
					(size 1.016 1.016)
					(thickness 0.1524)
				)
			)
		)
		(duplicate_pad_numbers_are_jumpers no)
		(fp_line
			(start -4.0132 -1.6256)
			(end -2.7432 -1.6256)
			(stroke
				(width 0.4064)
				(type default)
			)
			(layer "F.SilkS")
		)
		(fp_line
			(start -4.0132 -0.3556)
			(end -4.0132 -1.6256)
			(stroke
				(width 0.4064)
				(type default)
			)
			(layer "F.SilkS")
		)
		(fp_line
			(start -3.8862 -1.4986)
			(end -3.8862 1.4986)
			(stroke
				(width 0.1524)
				(type default)
			)
			(layer "F.SilkS")
		)
		(fp_line
			(start -3.8862 1.4986)
			(end 3.8862 1.4986)
			(stroke
				(width 0.1524)
				(type default)
			)
			(layer "F.SilkS")
		)
		(fp_line
			(start 3.8862 -1.4986)
			(end -3.8862 -1.4986)
			(stroke
				(width 0.1524)
				(type default)
			)
			(layer "F.SilkS")
		)
		(fp_line
			(start 3.8862 1.4986)
			(end 3.8862 -1.4986)
			(stroke
				(width 0.1524)
				(type default)
			)
			(layer "F.SilkS")
		)
		(fp_circle
			(center -2.54 0)
			(end -1.4732 0)
			(stroke
				(width 0.3048)
				(type default)
			)
			(fill no)
			(layer "F.SilkS")
		)
		(fp_circle
			(center 0 0)
			(end 1.0668 0)
			(stroke
				(width 0.3048)
				(type default)
			)
			(fill no)
			(layer "F.SilkS")
		)
		(fp_circle
			(center 2.54 0)
			(end 3.6068 0)
			(stroke
				(width 0.3048)
				(type default)
			)
			(fill no)
			(layer "F.SilkS")
		)
		(fp_rect
			(start -3.6322 1.2446)
			(end 3.6322 -1.2446)
			(stroke
				(width 0)
				(type default)
			)
			(fill no)
			(layer "F.CrtYd")
		)
		(fp_poly
			(pts
				(xy 4.1402 -1.2446) (xy -3.6322 -1.2446) (xy -3.6322 1.2446) (xy 3.6322 1.2446) (xy 3.6322 -1.2319)
				(xy 4.1402 -1.2319) (xy 4.1402 1.7526) (xy -4.1402 1.7526) (xy -4.1402 -1.7526) (xy 4.1402 -1.7526)
			)
			(stroke
				(width 0)
				(type default)
			)
			(fill no)
			(layer "F.CrtYd")
		)
		(fp_rect
			(start -4.1402 1.7526)
			(end 4.1402 -1.7526)
			(stroke
				(width 0)
				(type default)
			)
			(fill no)
			(layer "F.Fab")
		)
		(pad "1" thru_hole circle
			(at -2.54 0)
			(size 1.4224 1.4224)
			(drill 1.016)
			(layers "*.Cu" "*.Mask")
			(remove_unused_layers no)
			(net "BMC_CPU_EN")
			(clearance 0.1524)
			(thermal_gap 0.1524)
		)
		(pad "2" thru_hole circle
			(at 0 0)
			(size 1.4224 1.4224)
			(drill 1.016)
			(layers "*.Cu" "*.Mask")
			(remove_unused_layers no)
			(net "FLA_CS_R")
			(clearance 0.1524)
			(thermal_gap 0.1524)
		)
		(pad "3" thru_hole circle
			(at 2.54 0)
			(size 1.4224 1.4224)
			(drill 1.016)
			(layers "*.Cu" "*.Mask")
			(remove_unused_layers no)
			(net "BMC_CPU_DIS")
			(clearance 0.1524)
			(thermal_gap 0.1524)
		)
	)
	(footprint ""
		(layer "F.Cu")
		(at 67.0052 -165.5826 90)
		(property "Reference" "PR22"
			(at 0 0 90)
			(layer "F.SilkS")
			(hide yes)
			(effects
				(font
					(size 1.27 1.27)
				)
			)
		)
		(property "Value" "0R3J-0-U-GP"
			(at -0.0254 -2.5146 90)
			(unlocked yes)
			(layer "F.Fab")
			(hide yes)
			(effects
				(font
					(size 1.016 1.016)
					(thickness 0.1524)
				)
			)
		)
		(property "Device Type" "R603H22"
			(at -0.0254 -4.0386 90)
			(unlocked yes)
			(layer "F.Fab")
			(hide yes)
			(effects
				(font
					(size 1.016 1.016)
					(thickness 0.1524)
				)
			)
		)
		(duplicate_pad_numbers_are_jumpers no)
		(fp_line
			(start 0.2032 0)
			(end 0.4826 0)
			(stroke
				(width 0.2032)
				(type default)
			)
			(layer "F.SilkS")
		)
		(fp_line
			(start -0.4826 0)
			(end -0.2032 0)
			(stroke
				(width 0.2032)
				(type default)
			)
			(layer "F.SilkS")
		)
		(fp_rect
			(start -0.5842 1.3335)
			(end 0.5842 -1.3335)
			(stroke
				(width 0)
				(type default)
			)
			(fill no)
			(layer "F.CrtYd")
		)
		(fp_rect
			(start -0.5842 1.3335)
			(end 0.5842 -1.3335)
			(stroke
				(width 0)
				(type default)
			)
			(fill no)
			(layer "F.Fab")
		)
		(pad "1" smd custom
			(at 0 -0.762 90)
			(size 0.2159 0.2159)
			(layers "F.Cu" "F.Mask" "F.Paste")
			(net "PWRGD_P1V8_STBY")
			(options
				(clearance outline)
				(anchor circle)
			)
			(primitives
				(gr_poly
					(pts
						(arc
							(start -0.3302 -0.4318)
							(mid -0.402042 -0.402042)
							(end -0.4318 -0.3302)
						)
						(arc
							(start -0.4318 0.3302)
							(mid -0.402042 0.402042)
							(end -0.3302 0.4318)
						)
						(arc
							(start 0.3302 0.4318)
							(mid 0.402042 0.402042)
							(end 0.4318 0.3302)
						)
						(arc
							(start 0.4318 -0.3302)
							(mid 0.402042 -0.402042)
							(end 0.3302 -0.4318)
						)
					)
					(width 0)
					(fill yes)
				)
			)
		)
		(pad "2" smd custom
			(at 0 0.762 90)
			(size 0.2159 0.2159)
			(layers "F.Cu" "F.Mask" "F.Paste")
			(net "VR_P1V538_STBY_EN_R")
			(options
				(clearance outline)
				(anchor circle)
			)
			(primitives
				(gr_poly
					(pts
						(arc
							(start -0.3302 -0.4318)
							(mid -0.402042 -0.402042)
							(end -0.4318 -0.3302)
						)
						(arc
							(start -0.4318 0.3302)
							(mid -0.402042 0.402042)
							(end -0.3302 0.4318)
						)
						(arc
							(start 0.3302 0.4318)
							(mid 0.402042 0.402042)
							(end 0.4318 0.3302)
						)
						(arc
							(start 0.4318 -0.3302)
							(mid 0.402042 -0.402042)
							(end 0.3302 -0.4318)
						)
					)
					(width 0)
					(fill yes)
				)
			)
		)
	)
	(footprint ""
		(layer "F.Cu")
		(at 131.236466 -208.8769 180)
		(property "Reference" "R7927"
			(at 0 0 180)
			(layer "F.SilkS")
			(hide yes)
			(effects
				(font
					(size 1.27 1.27)
				)
			)
		)
		(property "Value" "0R2J-2-GP"
			(at 0.064008 -3.993896 180)
			(unlocked yes)
			(layer "F.Fab")
			(hide yes)
			(effects
				(font
					(size 1.016 1.016)
					(thickness 0.1524)
				)
			)
		)
		(property "Device Type" "R402H16"
			(at 0.064008 -5.517896 180)
			(unlocked yes)
			(layer "F.Fab")
			(hide yes)
			(effects
				(font
					(size 1.016 1.016)
					(thickness 0.1524)
				)
			)
		)
		(duplicate_pad_numbers_are_jumpers no)
		(fp_line
			(start 0.508 -0.9398)
			(end -0.508 -0.9398)
			(stroke
				(width 0.1524)
				(type default)
			)
			(layer "F.SilkS")
		)
		(fp_line
			(start -0.508 -0.9398)
			(end -0.508 0.9398)
			(stroke
				(width 0.1524)
				(type default)
			)
			(layer "F.SilkS")
		)
		(fp_rect
			(start -0.508 0.9398)
			(end 0.508 -0.9398)
			(stroke
				(width 0)
				(type default)
			)
			(fill no)
			(layer "F.CrtYd")
		)
		(fp_rect
			(start -0.508 0.9398)
			(end 0.508 -0.9398)
			(stroke
				(width 0)
				(type default)
			)
			(fill no)
			(layer "F.Fab")
		)
		(pad "1" smd custom
			(at 0 -0.4445 180)
			(size 0.1397 0.1397)
			(layers "F.Cu" "F.Mask" "F.Paste")
			(net "SSD_PRSNT#7")
			(options
				(clearance outline)
				(anchor circle)
			)
			(primitives
				(gr_poly
					(pts
						(arc
							(start -0.1778 -0.2794)
							(mid -0.249642 -0.249642)
							(end -0.2794 -0.1778)
						)
						(arc
							(start -0.2794 0.1778)
							(mid -0.249642 0.249642)
							(end -0.1778 0.2794)
						)
						(arc
							(start 0.1778 0.2794)
							(mid 0.249642 0.249642)
							(end 0.2794 0.1778)
						)
						(arc
							(start 0.2794 -0.1778)
							(mid 0.249642 -0.249642)
							(end 0.1778 -0.2794)
						)
					)
					(width 0)
					(fill yes)
				)
			)
		)
		(pad "2" smd custom
			(at 0 0.4445 180)
			(size 0.1397 0.1397)
			(layers "F.Cu" "F.Mask" "F.Paste")
			(net "SSD_PRSNT#7_R")
			(options
				(clearance outline)
				(anchor circle)
			)
			(primitives
				(gr_poly
					(pts
						(arc
							(start -0.1778 -0.2794)
							(mid -0.249642 -0.249642)
							(end -0.2794 -0.1778)
						)
						(arc
							(start -0.2794 0.1778)
							(mid -0.249642 0.249642)
							(end -0.1778 0.2794)
						)
						(arc
							(start 0.1778 0.2794)
							(mid 0.249642 0.249642)
							(end 0.2794 0.1778)
						)
						(arc
							(start 0.2794 -0.1778)
							(mid 0.249642 -0.249642)
							(end 0.1778 -0.2794)
						)
					)
					(width 0)
					(fill yes)
				)
			)
		)
	)
	(footprint ""
		(layer "F.Cu")
		(at 153.45918 -84.41436 180)
		(property "Reference" "C719"
			(at 0 0 180)
			(layer "F.SilkS")
			(hide yes)
			(effects
				(font
					(size 1.27 1.27)
				)
			)
		)
		(property "Value" "SC1U10V2KX-4-GP"
			(at 1.1811 -2.7051 180)
			(unlocked yes)
			(layer "F.Fab")
			(hide yes)
			(effects
				(font
					(size 1.016 1.016)
					(thickness 0.1524)
				)
			)
		)
		(property "Device Type" "C402H22"
			(at 1.1811 -4.2291 180)
			(unlocked yes)
			(layer "F.Fab")
			(hide yes)
			(effects
				(font
					(size 1.016 1.016)
					(thickness 0.1524)
				)
			)
		)
		(duplicate_pad_numbers_are_jumpers no)
		(fp_rect
			(start -0.4318 0.9525)
			(end 0.4318 -0.9525)
			(stroke
				(width 0)
				(type default)
			)
			(fill no)
			(layer "F.CrtYd")
		)
		(fp_rect
			(start -0.4318 0.9525)
			(end 0.4318 -0.9525)
			(stroke
				(width 0)
				(type default)
			)
			(fill no)
			(layer "F.Fab")
		)
		(pad "1" smd custom
			(at 0 -0.4445 180)
			(size 0.1524 0.1524)
			(layers "F.Cu" "F.Mask" "F.Paste")
			(net "P1V8_STBY")
			(options
				(clearance outline)
				(anchor circle)
			)
			(primitives
				(gr_poly
					(pts
						(arc
							(start 0.3048 -0.2032)
							(mid 0.275042 -0.275042)
							(end 0.2032 -0.3048)
						)
						(arc
							(start -0.2032 -0.3048)
							(mid -0.275042 -0.275042)
							(end -0.3048 -0.2032)
						)
						(arc
							(start -0.3048 0.2032)
							(mid -0.275042 0.275042)
							(end -0.2032 0.3048)
						)
						(arc
							(start 0.2032 0.3048)
							(mid 0.275042 0.275042)
							(end 0.3048 0.2032)
						)
					)
					(width 0)
					(fill yes)
				)
			)
		)
		(pad "2" smd custom
			(at 0 0.4445 180)
			(size 0.1524 0.1524)
			(layers "F.Cu" "F.Mask" "F.Paste")
			(net "GND")
			(options
				(clearance outline)
				(anchor circle)
			)
			(primitives
				(gr_poly
					(pts
						(arc
							(start 0.3048 -0.2032)
							(mid 0.275042 -0.275042)
							(end 0.2032 -0.3048)
						)
						(arc
							(start -0.2032 -0.3048)
							(mid -0.275042 -0.275042)
							(end -0.3048 -0.2032)
						)
						(arc
							(start -0.3048 0.2032)
							(mid -0.275042 0.275042)
							(end -0.2032 0.3048)
						)
						(arc
							(start 0.2032 0.3048)
							(mid 0.275042 0.275042)
							(end 0.3048 0.2032)
						)
					)
					(width 0)
					(fill yes)
				)
			)
		)
	)
	(footprint ""
		(layer "F.Cu")
		(at 139.326874 -92.85732)
		(property "Reference" "PR74"
			(at 0 0 0)
			(layer "F.SilkS")
			(hide yes)
			(effects
				(font
					(size 1.27 1.27)
				)
			)
		)
		(property "Value" "0R3J-0-U-GP"
			(at -0.0254 -2.5146 0)
			(unlocked yes)
			(layer "F.Fab")
			(hide yes)
			(effects
				(font
					(size 1.016 1.016)
					(thickness 0.1524)
				)
			)
		)
		(property "Device Type" "R603H22"
			(at -0.0254 -4.0386 0)
			(unlocked yes)
			(layer "F.Fab")
			(hide yes)
			(effects
				(font
					(size 1.016 1.016)
					(thickness 0.1524)
				)
			)
		)
		(duplicate_pad_numbers_are_jumpers no)
		(fp_line
			(start -0.4826 0)
			(end -0.2032 0)
			(stroke
				(width 0.2032)
				(type default)
			)
			(layer "F.SilkS")
		)
		(fp_line
			(start 0.2032 0)
			(end 0.4826 0)
			(stroke
				(width 0.2032)
				(type default)
			)
			(layer "F.SilkS")
		)
		(fp_rect
			(start -0.5842 1.3335)
			(end 0.5842 -1.3335)
			(stroke
				(width 0)
				(type default)
			)
			(fill no)
			(layer "F.CrtYd")
		)
		(fp_rect
			(start -0.5842 1.3335)
			(end 0.5842 -1.3335)
			(stroke
				(width 0)
				(type default)
			)
			(fill no)
			(layer "F.Fab")
		)
		(pad "1" smd custom
			(at 0 -0.762)
			(size 0.2159 0.2159)
			(layers "F.Cu" "F.Mask" "F.Paste")
			(net "P3V3_STBY_PG")
			(options
				(clearance outline)
				(anchor circle)
			)
			(primitives
				(gr_poly
					(pts
						(arc
							(start -0.3302 -0.4318)
							(mid -0.402042 -0.402042)
							(end -0.4318 -0.3302)
						)
						(arc
							(start -0.4318 0.3302)
							(mid -0.402042 0.402042)
							(end -0.3302 0.4318)
						)
						(arc
							(start 0.3302 0.4318)
							(mid 0.402042 0.402042)
							(end 0.4318 0.3302)
						)
						(arc
							(start 0.4318 -0.3302)
							(mid 0.402042 -0.402042)
							(end 0.3302 -0.4318)
						)
					)
					(width 0)
					(fill yes)
				)
			)
		)
		(pad "2" smd custom
			(at 0 0.762)
			(size 0.2159 0.2159)
			(layers "F.Cu" "F.Mask" "F.Paste")
			(net "VR_P1V8_STBY_EN_R")
			(options
				(clearance outline)
				(anchor circle)
			)
			(primitives
				(gr_poly
					(pts
						(arc
							(start -0.3302 -0.4318)
							(mid -0.402042 -0.402042)
							(end -0.4318 -0.3302)
						)
						(arc
							(start -0.4318 0.3302)
							(mid -0.402042 0.402042)
							(end -0.3302 0.4318)
						)
						(arc
							(start 0.3302 0.4318)
							(mid 0.402042 0.402042)
							(end 0.4318 0.3302)
						)
						(arc
							(start 0.4318 -0.3302)
							(mid 0.402042 -0.402042)
							(end 0.3302 -0.4318)
						)
					)
					(width 0)
					(fill yes)
				)
			)
		)
	)
	(footprint ""
		(layer "F.Cu")
		(at 219.329 -7.112 90)
		(property "Reference" "R663"
			(at 0 0 90)
			(layer "F.SilkS")
			(hide yes)
			(effects
				(font
					(size 1.27 1.27)
				)
			)
		)
		(property "Value" "100KR2F-L1-GP"
			(at 0.064008 -3.993896 90)
			(unlocked yes)
			(layer "F.Fab")
			(hide yes)
			(effects
				(font
					(size 1.016 1.016)
					(thickness 0.1524)
				)
			)
		)
		(property "Device Type" "R402H16"
			(at 0.064008 -5.517896 90)
			(unlocked yes)
			(layer "F.Fab")
			(hide yes)
			(effects
				(font
					(size 1.016 1.016)
					(thickness 0.1524)
				)
			)
		)
		(duplicate_pad_numbers_are_jumpers no)
		(fp_line
			(start 0.508 -0.9398)
			(end -0.508 -0.9398)
			(stroke
				(width 0.1524)
				(type default)
			)
			(layer "F.SilkS")
		)
		(fp_line
			(start -0.508 -0.9398)
			(end -0.508 0.9398)
			(stroke
				(width 0.1524)
				(type default)
			)
			(layer "F.SilkS")
		)
		(fp_rect
			(start -0.508 0.9398)
			(end 0.508 -0.9398)
			(stroke
				(width 0)
				(type default)
			)
			(fill no)
			(layer "F.CrtYd")
		)
		(fp_rect
			(start -0.508 0.9398)
			(end 0.508 -0.9398)
			(stroke
				(width 0)
				(type default)
			)
			(fill no)
			(layer "F.Fab")
		)
		(pad "1" smd custom
			(at 0 -0.4445 90)
			(size 0.1397 0.1397)
			(layers "F.Cu" "F.Mask" "F.Paste")
			(net "P3V3_STBY")
			(options
				(clearance outline)
				(anchor circle)
			)
			(primitives
				(gr_poly
					(pts
						(arc
							(start -0.1778 -0.2794)
							(mid -0.249642 -0.249642)
							(end -0.2794 -0.1778)
						)
						(arc
							(start -0.2794 0.1778)
							(mid -0.249642 0.249642)
							(end -0.1778 0.2794)
						)
						(arc
							(start 0.1778 0.2794)
							(mid 0.249642 0.249642)
							(end 0.2794 0.1778)
						)
						(arc
							(start 0.2794 -0.1778)
							(mid 0.249642 -0.249642)
							(end 0.1778 -0.2794)
						)
					)
					(width 0)
					(fill yes)
				)
			)
		)
		(pad "2" smd custom
			(at 0 0.4445 90)
			(size 0.1397 0.1397)
			(layers "F.Cu" "F.Mask" "F.Paste")
			(net "EEPROM_A2")
			(options
				(clearance outline)
				(anchor circle)
			)
			(primitives
				(gr_poly
					(pts
						(arc
							(start -0.1778 -0.2794)
							(mid -0.249642 -0.249642)
							(end -0.2794 -0.1778)
						)
						(arc
							(start -0.2794 0.1778)
							(mid -0.249642 0.249642)
							(end -0.1778 0.2794)
						)
						(arc
							(start 0.1778 0.2794)
							(mid 0.249642 0.249642)
							(end 0.2794 0.1778)
						)
						(arc
							(start 0.2794 -0.1778)
							(mid 0.249642 -0.249642)
							(end 0.1778 -0.2794)
						)
					)
					(width 0)
					(fill yes)
				)
			)
		)
	)
	(footprint ""
		(layer "F.Cu")
		(at 220.829124 -190.601092)
		(property "Reference" "R7950"
			(at 0 0 0)
			(layer "F.SilkS")
			(hide yes)
			(effects
				(font
					(size 1.27 1.27)
				)
			)
		)
		(property "Value" "0R2J-2-GP"
			(at 0.064008 -3.993896 0)
			(unlocked yes)
			(layer "F.Fab")
			(hide yes)
			(effects
				(font
					(size 1.016 1.016)
					(thickness 0.1524)
				)
			)
		)
		(property "Device Type" "R402H16"
			(at 0.064008 -5.517896 0)
			(unlocked yes)
			(layer "F.Fab")
			(hide yes)
			(effects
				(font
					(size 1.016 1.016)
					(thickness 0.1524)
				)
			)
		)
		(duplicate_pad_numbers_are_jumpers no)
		(fp_line
			(start -0.508 -0.9398)
			(end -0.508 0.9398)
			(stroke
				(width 0.1524)
				(type default)
			)
			(layer "F.SilkS")
		)
		(fp_line
			(start 0.508 -0.9398)
			(end -0.508 -0.9398)
			(stroke
				(width 0.1524)
				(type default)
			)
			(layer "F.SilkS")
		)
		(fp_rect
			(start -0.508 0.9398)
			(end 0.508 -0.9398)
			(stroke
				(width 0)
				(type default)
			)
			(fill no)
			(layer "F.CrtYd")
		)
		(fp_rect
			(start -0.508 0.9398)
			(end 0.508 -0.9398)
			(stroke
				(width 0)
				(type default)
			)
			(fill no)
			(layer "F.Fab")
		)
		(pad "1" smd custom
			(at 0 -0.4445)
			(size 0.1397 0.1397)
			(layers "F.Cu" "F.Mask" "F.Paste")
			(net "SSD_ATNLED#3")
			(options
				(clearance outline)
				(anchor circle)
			)
			(primitives
				(gr_poly
					(pts
						(arc
							(start -0.1778 -0.2794)
							(mid -0.249642 -0.249642)
							(end -0.2794 -0.1778)
						)
						(arc
							(start -0.2794 0.1778)
							(mid -0.249642 0.249642)
							(end -0.1778 0.2794)
						)
						(arc
							(start 0.1778 0.2794)
							(mid 0.249642 0.249642)
							(end 0.2794 0.1778)
						)
						(arc
							(start 0.2794 -0.1778)
							(mid 0.249642 -0.249642)
							(end 0.1778 -0.2794)
						)
					)
					(width 0)
					(fill yes)
				)
			)
		)
		(pad "2" smd custom
			(at 0 0.4445)
			(size 0.1397 0.1397)
			(layers "F.Cu" "F.Mask" "F.Paste")
			(net "SSD_ATNLED#3_R")
			(options
				(clearance outline)
				(anchor circle)
			)
			(primitives
				(gr_poly
					(pts
						(arc
							(start -0.1778 -0.2794)
							(mid -0.249642 -0.249642)
							(end -0.2794 -0.1778)
						)
						(arc
							(start -0.2794 0.1778)
							(mid -0.249642 0.249642)
							(end -0.1778 0.2794)
						)
						(arc
							(start 0.1778 0.2794)
							(mid 0.249642 0.249642)
							(end 0.2794 0.1778)
						)
						(arc
							(start 0.2794 -0.1778)
							(mid 0.249642 -0.249642)
							(end 0.1778 -0.2794)
						)
					)
					(width 0)
					(fill yes)
				)
			)
		)
	)
	(footprint ""
		(layer "F.Cu")
		(at 328.549 -99.568 180)
		(property "Reference" "R4167"
			(at 0 0 180)
			(layer "F.SilkS")
			(hide yes)
			(effects
				(font
					(size 1.27 1.27)
				)
			)
		)
		(property "Value" "4K7R2F-GP"
			(at 0.064008 -3.993896 180)
			(unlocked yes)
			(layer "F.Fab")
			(hide yes)
			(effects
				(font
					(size 1.016 1.016)
					(thickness 0.1524)
				)
			)
		)
		(property "Device Type" "R402H16"
			(at 0.064008 -5.517896 180)
			(unlocked yes)
			(layer "F.Fab")
			(hide yes)
			(effects
				(font
					(size 1.016 1.016)
					(thickness 0.1524)
				)
			)
		)
		(duplicate_pad_numbers_are_jumpers no)
		(fp_line
			(start 0.508 -0.9398)
			(end -0.508 -0.9398)
			(stroke
				(width 0.1524)
				(type default)
			)
			(layer "F.SilkS")
		)
		(fp_line
			(start -0.508 -0.9398)
			(end -0.508 0.9398)
			(stroke
				(width 0.1524)
				(type default)
			)
			(layer "F.SilkS")
		)
		(fp_rect
			(start -0.508 0.9398)
			(end 0.508 -0.9398)
			(stroke
				(width 0)
				(type default)
			)
			(fill no)
			(layer "F.CrtYd")
		)
		(fp_rect
			(start -0.508 0.9398)
			(end 0.508 -0.9398)
			(stroke
				(width 0)
				(type default)
			)
			(fill no)
			(layer "F.Fab")
		)
		(pad "1" smd custom
			(at 0 -0.4445 180)
			(size 0.1397 0.1397)
			(layers "F.Cu" "F.Mask" "F.Paste")
			(net "VS4_LED")
			(options
				(clearance outline)
				(anchor circle)
			)
			(primitives
				(gr_poly
					(pts
						(arc
							(start -0.1778 -0.2794)
							(mid -0.249642 -0.249642)
							(end -0.2794 -0.1778)
						)
						(arc
							(start -0.2794 0.1778)
							(mid -0.249642 0.249642)
							(end -0.1778 0.2794)
						)
						(arc
							(start 0.1778 0.2794)
							(mid 0.249642 0.249642)
							(end 0.2794 0.1778)
						)
						(arc
							(start 0.2794 -0.1778)
							(mid 0.249642 -0.249642)
							(end 0.1778 -0.2794)
						)
					)
					(width 0)
					(fill yes)
				)
			)
		)
		(pad "2" smd custom
			(at 0 0.4445 180)
			(size 0.1397 0.1397)
			(layers "F.Cu" "F.Mask" "F.Paste")
			(net "P3V3_STBY")
			(options
				(clearance outline)
				(anchor circle)
			)
			(primitives
				(gr_poly
					(pts
						(arc
							(start -0.1778 -0.2794)
							(mid -0.249642 -0.249642)
							(end -0.2794 -0.1778)
						)
						(arc
							(start -0.2794 0.1778)
							(mid -0.249642 0.249642)
							(end -0.1778 0.2794)
						)
						(arc
							(start 0.1778 0.2794)
							(mid 0.249642 0.249642)
							(end 0.2794 0.1778)
						)
						(arc
							(start 0.2794 -0.1778)
							(mid 0.249642 -0.249642)
							(end 0.1778 -0.2794)
						)
					)
					(width 0)
					(fill yes)
				)
			)
		)
	)
	(footprint ""
		(layer "F.Cu")
		(at 21.8313 -175.6791)
		(property "Reference" "Q93"
			(at 0 0 0)
			(layer "F.SilkS")
			(hide yes)
			(effects
				(font
					(size 1.27 1.27)
				)
			)
		)
		(property "Value" "2N7002K-1-GP"
			(at 0.127 -8.9662 0)
			(unlocked yes)
			(layer "F.Fab")
			(hide yes)
			(effects
				(font
					(size 1.016 1.016)
					(thickness 0.1524)
				)
			)
		)
		(property "Device Type" "SOT23DGS2D4H44"
			(at 0.127 -10.4902 0)
			(unlocked yes)
			(layer "F.Fab")
			(hide yes)
			(effects
				(font
					(size 1.016 1.016)
					(thickness 0.1524)
				)
			)
		)
		(duplicate_pad_numbers_are_jumpers no)
		(fp_line
			(start -1.651 -1.778)
			(end -1.651 1.778)
			(stroke
				(width 0.1524)
				(type default)
			)
			(layer "F.SilkS")
		)
		(fp_line
			(start -1.651 1.778)
			(end 1.651 1.778)
			(stroke
				(width 0.1524)
				(type default)
			)
			(layer "F.SilkS")
		)
		(fp_line
			(start 1.651 -1.778)
			(end -1.651 -1.778)
			(stroke
				(width 0.1524)
				(type default)
			)
			(layer "F.SilkS")
		)
		(fp_line
			(start 1.651 1.778)
			(end 1.651 -1.778)
			(stroke
				(width 0.1524)
				(type default)
			)
			(layer "F.SilkS")
		)
		(fp_poly
			(pts
				(xy -1.778 1.8796) (xy -1.778 -1.8796) (xy 1.778 -1.8796) (xy 1.778 1.8796)
			)
			(stroke
				(width 0)
				(type default)
			)
			(fill no)
			(layer "F.CrtYd")
		)
		(fp_poly
			(pts
				(xy -1.778 1.8796) (xy -1.778 -1.8796) (xy 1.778 -1.8796) (xy 1.778 1.8796)
			)
			(stroke
				(width 0)
				(type default)
			)
			(fill no)
			(layer "F.Fab")
		)
		(pad "D" smd custom
			(at 0 -0.9525)
			(size 0.1905 0.1905)
			(layers "F.Cu" "F.Mask" "F.Paste")
			(net "MATED_P12V_EN")
			(options
				(clearance outline)
				(anchor circle)
			)
			(primitives
				(gr_poly
					(pts
						(arc
							(start -0.1778 0.5715)
							(mid -0.321484 0.511984)
							(end -0.381 0.3683)
						)
						(arc
							(start -0.381 -0.3683)
							(mid -0.321484 -0.511984)
							(end -0.1778 -0.5715)
						)
						(arc
							(start 0.1778 -0.5715)
							(mid 0.321484 -0.511984)
							(end 0.381 -0.3683)
						)
						(arc
							(start 0.381 0.3683)
							(mid 0.321484 0.511984)
							(end 0.1778 0.5715)
						)
					)
					(width 0)
					(fill yes)
				)
			)
		)
		(pad "G" smd custom
			(at -0.98425 0.9525)
			(size 0.1905 0.1905)
			(layers "F.Cu" "F.Mask" "F.Paste")
			(net "PCIE_MATED#_B")
			(options
				(clearance outline)
				(anchor circle)
			)
			(primitives
				(gr_poly
					(pts
						(arc
							(start -0.1778 0.5715)
							(mid -0.321484 0.511984)
							(end -0.381 0.3683)
						)
						(arc
							(start -0.381 -0.3683)
							(mid -0.321484 -0.511984)
							(end -0.1778 -0.5715)
						)
						(arc
							(start 0.1778 -0.5715)
							(mid 0.321484 -0.511984)
							(end 0.381 -0.3683)
						)
						(arc
							(start 0.381 0.3683)
							(mid 0.321484 0.511984)
							(end 0.1778 0.5715)
						)
					)
					(width 0)
					(fill yes)
				)
			)
		)
		(pad "S" smd custom
			(at 0.98425 0.9525)
			(size 0.1905 0.1905)
			(layers "F.Cu" "F.Mask" "F.Paste")
			(net "GND")
			(options
				(clearance outline)
				(anchor circle)
			)
			(primitives
				(gr_poly
					(pts
						(arc
							(start -0.1778 0.5715)
							(mid -0.321484 0.511984)
							(end -0.381 0.3683)
						)
						(arc
							(start -0.381 -0.3683)
							(mid -0.321484 -0.511984)
							(end -0.1778 -0.5715)
						)
						(arc
							(start 0.1778 -0.5715)
							(mid 0.321484 -0.511984)
							(end 0.381 -0.3683)
						)
						(arc
							(start 0.381 0.3683)
							(mid 0.321484 0.511984)
							(end 0.1778 0.5715)
						)
					)
					(width 0)
					(fill yes)
				)
			)
		)
	)
	(footprint ""
		(layer "F.Cu")
		(at 196.9262 -34.3408 90)
		(property "Reference" "R791"
			(at 0 0 90)
			(layer "F.SilkS")
			(hide yes)
			(effects
				(font
					(size 1.27 1.27)
				)
			)
		)
		(property "Value" "4K7R2F-GP"
			(at 0.064008 -3.993896 90)
			(unlocked yes)
			(layer "F.Fab")
			(hide yes)
			(effects
				(font
					(size 1.016 1.016)
					(thickness 0.1524)
				)
			)
		)
		(property "Device Type" "R402H16"
			(at 0.064008 -5.517896 90)
			(unlocked yes)
			(layer "F.Fab")
			(hide yes)
			(effects
				(font
					(size 1.016 1.016)
					(thickness 0.1524)
				)
			)
		)
		(duplicate_pad_numbers_are_jumpers no)
		(fp_line
			(start 0.508 -0.9398)
			(end -0.508 -0.9398)
			(stroke
				(width 0.1524)
				(type default)
			)
			(layer "F.SilkS")
		)
		(fp_line
			(start -0.508 -0.9398)
			(end -0.508 0.9398)
			(stroke
				(width 0.1524)
				(type default)
			)
			(layer "F.SilkS")
		)
		(fp_rect
			(start -0.508 0.9398)
			(end 0.508 -0.9398)
			(stroke
				(width 0)
				(type default)
			)
			(fill no)
			(layer "F.CrtYd")
		)
		(fp_rect
			(start -0.508 0.9398)
			(end 0.508 -0.9398)
			(stroke
				(width 0)
				(type default)
			)
			(fill no)
			(layer "F.Fab")
		)
		(pad "1" smd custom
			(at 0 -0.4445 90)
			(size 0.1397 0.1397)
			(layers "F.Cu" "F.Mask" "F.Paste")
			(net "GND")
			(options
				(clearance outline)
				(anchor circle)
			)
			(primitives
				(gr_poly
					(pts
						(arc
							(start -0.1778 -0.2794)
							(mid -0.249642 -0.249642)
							(end -0.2794 -0.1778)
						)
						(arc
							(start -0.2794 0.1778)
							(mid -0.249642 0.249642)
							(end -0.1778 0.2794)
						)
						(arc
							(start 0.1778 0.2794)
							(mid 0.249642 0.249642)
							(end 0.2794 0.1778)
						)
						(arc
							(start 0.2794 -0.1778)
							(mid 0.249642 -0.249642)
							(end 0.1778 -0.2794)
						)
					)
					(width 0)
					(fill yes)
				)
			)
		)
		(pad "2" smd custom
			(at 0 0.4445 90)
			(size 0.1397 0.1397)
			(layers "F.Cu" "F.Mask" "F.Paste")
			(net "U55_A0")
			(options
				(clearance outline)
				(anchor circle)
			)
			(primitives
				(gr_poly
					(pts
						(arc
							(start -0.1778 -0.2794)
							(mid -0.249642 -0.249642)
							(end -0.2794 -0.1778)
						)
						(arc
							(start -0.2794 0.1778)
							(mid -0.249642 0.249642)
							(end -0.1778 0.2794)
						)
						(arc
							(start 0.1778 0.2794)
							(mid 0.249642 0.249642)
							(end 0.2794 0.1778)
						)
						(arc
							(start 0.2794 -0.1778)
							(mid 0.249642 -0.249642)
							(end 0.1778 -0.2794)
						)
					)
					(width 0)
					(fill yes)
				)
			)
		)
	)
	(footprint ""
		(layer "F.Cu")
		(at 268.608048 -212.420454 180)
		(property "Reference" "C104"
			(at 0 0 180)
			(layer "F.SilkS")
			(hide yes)
			(effects
				(font
					(size 1.27 1.27)
				)
			)
		)
		(property "Value" "SCD22U10V2KX-1GP"
			(at 1.1811 -2.7051 180)
			(unlocked yes)
			(layer "F.Fab")
			(hide yes)
			(effects
				(font
					(size 1.016 1.016)
					(thickness 0.1524)
				)
			)
		)
		(property "Device Type" "C402H22"
			(at 1.1811 -4.2291 180)
			(unlocked yes)
			(layer "F.Fab")
			(hide yes)
			(effects
				(font
					(size 1.016 1.016)
					(thickness 0.1524)
				)
			)
		)
		(duplicate_pad_numbers_are_jumpers no)
		(fp_rect
			(start -0.4318 0.9525)
			(end 0.4318 -0.9525)
			(stroke
				(width 0)
				(type default)
			)
			(fill no)
			(layer "F.CrtYd")
		)
		(fp_rect
			(start -0.4318 0.9525)
			(end 0.4318 -0.9525)
			(stroke
				(width 0)
				(type default)
			)
			(fill no)
			(layer "F.Fab")
		)
		(pad "1" smd custom
			(at 0 -0.4445 180)
			(size 0.1524 0.1524)
			(layers "F.Cu" "F.Mask" "F.Paste")
			(net "PCIE_TX_CAP_N36")
			(options
				(clearance outline)
				(anchor circle)
			)
			(primitives
				(gr_poly
					(pts
						(arc
							(start 0.3048 -0.2032)
							(mid 0.275042 -0.275042)
							(end 0.2032 -0.3048)
						)
						(arc
							(start -0.2032 -0.3048)
							(mid -0.275042 -0.275042)
							(end -0.3048 -0.2032)
						)
						(arc
							(start -0.3048 0.2032)
							(mid -0.275042 0.275042)
							(end -0.2032 0.3048)
						)
						(arc
							(start 0.2032 0.3048)
							(mid 0.275042 0.275042)
							(end 0.3048 0.2032)
						)
					)
					(width 0)
					(fill yes)
				)
			)
		)
		(pad "2" smd custom
			(at 0 0.4445 180)
			(size 0.1524 0.1524)
			(layers "F.Cu" "F.Mask" "F.Paste")
			(net "PCIE_TX_N36")
			(options
				(clearance outline)
				(anchor circle)
			)
			(primitives
				(gr_poly
					(pts
						(arc
							(start 0.3048 -0.2032)
							(mid 0.275042 -0.275042)
							(end 0.2032 -0.3048)
						)
						(arc
							(start -0.2032 -0.3048)
							(mid -0.275042 -0.275042)
							(end -0.3048 -0.2032)
						)
						(arc
							(start -0.3048 0.2032)
							(mid -0.275042 0.275042)
							(end -0.2032 0.3048)
						)
						(arc
							(start 0.2032 0.3048)
							(mid 0.275042 0.275042)
							(end 0.3048 0.2032)
						)
					)
					(width 0)
					(fill yes)
				)
			)
		)
	)
	(footprint ""
		(layer "F.Cu")
		(at 191.5922 -13.6652 -90)
		(property "Reference" "R544"
			(at 0 0 270)
			(layer "F.SilkS")
			(hide yes)
			(effects
				(font
					(size 1.27 1.27)
				)
			)
		)
		(property "Value" "1KR2F-3-GP"
			(at 0.064008 -3.993896 270)
			(unlocked yes)
			(layer "F.Fab")
			(hide yes)
			(effects
				(font
					(size 1.016 1.016)
					(thickness 0.1524)
				)
			)
		)
		(property "Device Type" "R402H16"
			(at 0.064008 -5.517896 270)
			(unlocked yes)
			(layer "F.Fab")
			(hide yes)
			(effects
				(font
					(size 1.016 1.016)
					(thickness 0.1524)
				)
			)
		)
		(duplicate_pad_numbers_are_jumpers no)
		(fp_line
			(start -0.508 -0.9398)
			(end -0.508 0.9398)
			(stroke
				(width 0.1524)
				(type default)
			)
			(layer "F.SilkS")
		)
		(fp_line
			(start 0.508 -0.9398)
			(end -0.508 -0.9398)
			(stroke
				(width 0.1524)
				(type default)
			)
			(layer "F.SilkS")
		)
		(fp_rect
			(start -0.508 0.9398)
			(end 0.508 -0.9398)
			(stroke
				(width 0)
				(type default)
			)
			(fill no)
			(layer "F.CrtYd")
		)
		(fp_rect
			(start -0.508 0.9398)
			(end 0.508 -0.9398)
			(stroke
				(width 0)
				(type default)
			)
			(fill no)
			(layer "F.Fab")
		)
		(pad "1" smd custom
			(at 0 -0.4445 270)
			(size 0.1397 0.1397)
			(layers "F.Cu" "F.Mask" "F.Paste")
			(net "ENCLO_LED_RED_D")
			(options
				(clearance outline)
				(anchor circle)
			)
			(primitives
				(gr_poly
					(pts
						(arc
							(start -0.1778 -0.2794)
							(mid -0.249642 -0.249642)
							(end -0.2794 -0.1778)
						)
						(arc
							(start -0.2794 0.1778)
							(mid -0.249642 0.249642)
							(end -0.1778 0.2794)
						)
						(arc
							(start 0.1778 0.2794)
							(mid 0.249642 0.249642)
							(end 0.2794 0.1778)
						)
						(arc
							(start 0.2794 -0.1778)
							(mid 0.249642 -0.249642)
							(end 0.1778 -0.2794)
						)
					)
					(width 0)
					(fill yes)
				)
			)
		)
		(pad "2" smd custom
			(at 0 0.4445 270)
			(size 0.1397 0.1397)
			(layers "F.Cu" "F.Mask" "F.Paste")
			(net "P3V3_STBY")
			(options
				(clearance outline)
				(anchor circle)
			)
			(primitives
				(gr_poly
					(pts
						(arc
							(start -0.1778 -0.2794)
							(mid -0.249642 -0.249642)
							(end -0.2794 -0.1778)
						)
						(arc
							(start -0.2794 0.1778)
							(mid -0.249642 0.249642)
							(end -0.1778 0.2794)
						)
						(arc
							(start 0.1778 0.2794)
							(mid 0.249642 0.249642)
							(end 0.2794 0.1778)
						)
						(arc
							(start 0.2794 -0.1778)
							(mid 0.249642 -0.249642)
							(end 0.1778 -0.2794)
						)
					)
					(width 0)
					(fill yes)
				)
			)
		)
	)
	(footprint ""
		(layer "F.Cu")
		(at 276.50948 -6.96976 90)
		(property "Reference" "R2912"
			(at 0 0 90)
			(layer "F.SilkS")
			(hide yes)
			(effects
				(font
					(size 1.27 1.27)
				)
			)
		)
		(property "Value" "0R2J-2-GP"
			(at 0.064008 -3.993896 90)
			(unlocked yes)
			(layer "F.Fab")
			(hide yes)
			(effects
				(font
					(size 1.016 1.016)
					(thickness 0.1524)
				)
			)
		)
		(property "Device Type" "R402H16"
			(at 0.064008 -5.517896 90)
			(unlocked yes)
			(layer "F.Fab")
			(hide yes)
			(effects
				(font
					(size 1.016 1.016)
					(thickness 0.1524)
				)
			)
		)
		(duplicate_pad_numbers_are_jumpers no)
		(fp_line
			(start 0.508 -0.9398)
			(end -0.508 -0.9398)
			(stroke
				(width 0.1524)
				(type default)
			)
			(layer "F.SilkS")
		)
		(fp_line
			(start -0.508 -0.9398)
			(end -0.508 0.9398)
			(stroke
				(width 0.1524)
				(type default)
			)
			(layer "F.SilkS")
		)
		(fp_rect
			(start -0.508 0.9398)
			(end 0.508 -0.9398)
			(stroke
				(width 0)
				(type default)
			)
			(fill no)
			(layer "F.CrtYd")
		)
		(fp_rect
			(start -0.508 0.9398)
			(end 0.508 -0.9398)
			(stroke
				(width 0)
				(type default)
			)
			(fill no)
			(layer "F.Fab")
		)
		(pad "1" smd custom
			(at 0 -0.4445 90)
			(size 0.1397 0.1397)
			(layers "F.Cu" "F.Mask" "F.Paste")
			(net "BMC_I2C12_MINI6_SDA")
			(options
				(clearance outline)
				(anchor circle)
			)
			(primitives
				(gr_poly
					(pts
						(arc
							(start -0.1778 -0.2794)
							(mid -0.249642 -0.249642)
							(end -0.2794 -0.1778)
						)
						(arc
							(start -0.2794 0.1778)
							(mid -0.249642 0.249642)
							(end -0.1778 0.2794)
						)
						(arc
							(start 0.1778 0.2794)
							(mid 0.249642 0.249642)
							(end 0.2794 0.1778)
						)
						(arc
							(start 0.2794 -0.1778)
							(mid 0.249642 -0.249642)
							(end 0.1778 -0.2794)
						)
					)
					(width 0)
					(fill yes)
				)
			)
		)
		(pad "2" smd custom
			(at 0 0.4445 90)
			(size 0.1397 0.1397)
			(layers "F.Cu" "F.Mask" "F.Paste")
			(net "8644_CBL_PRSNT_R_6")
			(options
				(clearance outline)
				(anchor circle)
			)
			(primitives
				(gr_poly
					(pts
						(arc
							(start -0.1778 -0.2794)
							(mid -0.249642 -0.249642)
							(end -0.2794 -0.1778)
						)
						(arc
							(start -0.2794 0.1778)
							(mid -0.249642 0.249642)
							(end -0.1778 0.2794)
						)
						(arc
							(start 0.1778 0.2794)
							(mid 0.249642 0.249642)
							(end 0.2794 0.1778)
						)
						(arc
							(start 0.2794 -0.1778)
							(mid 0.249642 -0.249642)
							(end 0.1778 -0.2794)
						)
					)
					(width 0)
					(fill yes)
				)
			)
		)
	)
	(footprint ""
		(layer "F.Cu")
		(at 310.007 -57.1246)
		(property "Reference" "PG60"
			(at 0 0 0)
			(layer "F.SilkS")
			(hide yes)
			(effects
				(font
					(size 1.27 1.27)
				)
			)
		)
		(property "Value" "GAP-CLOSE-PWR-3-GP"
			(at 0.0254 -6.5786 0)
			(unlocked yes)
			(layer "F.Fab")
			(hide yes)
			(effects
				(font
					(size 1.016 1.016)
					(thickness 0.1524)
				)
			)
		)
		(property "Device Type" "GAP-CLOSE-PWR-3"
			(at 0.0254 -8.255 0)
			(unlocked yes)
			(layer "F.Fab")
			(hide yes)
			(effects
				(font
					(size 1.016 1.016)
					(thickness 0.1524)
				)
			)
		)
		(duplicate_pad_numbers_are_jumpers no)
		(fp_rect
			(start -0.7112 0.4572)
			(end 0.7112 -0.4572)
			(stroke
				(width 0)
				(type default)
			)
			(fill no)
			(layer "F.CrtYd")
		)
		(fp_poly
			(pts
				(xy -0.7112 -0.4572) (xy 0.7112 -0.4572) (xy 0.7112 0.4572) (xy -0.7112 0.4572)
			)
			(stroke
				(width 0)
				(type default)
			)
			(fill no)
			(layer "F.Fab")
		)
		(pad "1" smd rect
			(at -0.3048 0)
			(size 0.6604 0.762)
			(layers "F.Cu" "F.Mask" "F.Paste")
			(net "DUT_VDD")
		)
		(pad "2" smd rect
			(at 0.3048 0)
			(size 0.6604 0.762)
			(layers "F.Cu" "F.Mask" "F.Paste")
			(net "P0V9_E")
		)
	)
	(footprint ""
		(layer "F.Cu")
		(at 10.541 -66.929 180)
		(property "Reference" "C623"
			(at 0 0 180)
			(layer "F.SilkS")
			(hide yes)
			(effects
				(font
					(size 1.27 1.27)
				)
			)
		)
		(property "Value" "SCD1U16V2KX-3GP"
			(at 1.1811 -2.7051 180)
			(unlocked yes)
			(layer "F.Fab")
			(hide yes)
			(effects
				(font
					(size 1.016 1.016)
					(thickness 0.1524)
				)
			)
		)
		(property "Device Type" "C402H22"
			(at 1.1811 -4.2291 180)
			(unlocked yes)
			(layer "F.Fab")
			(hide yes)
			(effects
				(font
					(size 1.016 1.016)
					(thickness 0.1524)
				)
			)
		)
		(duplicate_pad_numbers_are_jumpers no)
		(fp_rect
			(start -0.4318 0.9525)
			(end 0.4318 -0.9525)
			(stroke
				(width 0)
				(type default)
			)
			(fill no)
			(layer "F.CrtYd")
		)
		(fp_rect
			(start -0.4318 0.9525)
			(end 0.4318 -0.9525)
			(stroke
				(width 0)
				(type default)
			)
			(fill no)
			(layer "F.Fab")
		)
		(pad "1" smd custom
			(at 0 -0.4445 180)
			(size 0.1524 0.1524)
			(layers "F.Cu" "F.Mask" "F.Paste")
			(net "P1V5_I210")
			(options
				(clearance outline)
				(anchor circle)
			)
			(primitives
				(gr_poly
					(pts
						(arc
							(start 0.3048 -0.2032)
							(mid 0.275042 -0.275042)
							(end 0.2032 -0.3048)
						)
						(arc
							(start -0.2032 -0.3048)
							(mid -0.275042 -0.275042)
							(end -0.3048 -0.2032)
						)
						(arc
							(start -0.3048 0.2032)
							(mid -0.275042 0.275042)
							(end -0.2032 0.3048)
						)
						(arc
							(start 0.2032 0.3048)
							(mid 0.275042 0.275042)
							(end 0.3048 0.2032)
						)
					)
					(width 0)
					(fill yes)
				)
			)
		)
		(pad "2" smd custom
			(at 0 0.4445 180)
			(size 0.1524 0.1524)
			(layers "F.Cu" "F.Mask" "F.Paste")
			(net "GND")
			(options
				(clearance outline)
				(anchor circle)
			)
			(primitives
				(gr_poly
					(pts
						(arc
							(start 0.3048 -0.2032)
							(mid 0.275042 -0.275042)
							(end 0.2032 -0.3048)
						)
						(arc
							(start -0.2032 -0.3048)
							(mid -0.275042 -0.275042)
							(end -0.3048 -0.2032)
						)
						(arc
							(start -0.3048 0.2032)
							(mid -0.275042 0.275042)
							(end -0.2032 0.3048)
						)
						(arc
							(start 0.2032 0.3048)
							(mid 0.275042 0.275042)
							(end 0.3048 0.2032)
						)
					)
					(width 0)
					(fill yes)
				)
			)
		)
	)
	(footprint ""
		(layer "F.Cu")
		(at 330.740512 -184.878218)
		(property "Reference" "R7920"
			(at 0 0 0)
			(layer "F.SilkS")
			(hide yes)
			(effects
				(font
					(size 1.27 1.27)
				)
			)
		)
		(property "Value" "0R2J-2-GP"
			(at 0.064008 -3.993896 0)
			(unlocked yes)
			(layer "F.Fab")
			(hide yes)
			(effects
				(font
					(size 1.016 1.016)
					(thickness 0.1524)
				)
			)
		)
		(property "Device Type" "R402H16"
			(at 0.064008 -5.517896 0)
			(unlocked yes)
			(layer "F.Fab")
			(hide yes)
			(effects
				(font
					(size 1.016 1.016)
					(thickness 0.1524)
				)
			)
		)
		(duplicate_pad_numbers_are_jumpers no)
		(fp_line
			(start -0.508 -0.9398)
			(end -0.508 0.9398)
			(stroke
				(width 0.1524)
				(type default)
			)
			(layer "F.SilkS")
		)
		(fp_line
			(start 0.508 -0.9398)
			(end -0.508 -0.9398)
			(stroke
				(width 0.1524)
				(type default)
			)
			(layer "F.SilkS")
		)
		(fp_rect
			(start -0.508 0.9398)
			(end 0.508 -0.9398)
			(stroke
				(width 0)
				(type default)
			)
			(fill no)
			(layer "F.CrtYd")
		)
		(fp_rect
			(start -0.508 0.9398)
			(end 0.508 -0.9398)
			(stroke
				(width 0)
				(type default)
			)
			(fill no)
			(layer "F.Fab")
		)
		(pad "1" smd custom
			(at 0 -0.4445)
			(size 0.1397 0.1397)
			(layers "F.Cu" "F.Mask" "F.Paste")
			(net "TWI_SDA1")
			(options
				(clearance outline)
				(anchor circle)
			)
			(primitives
				(gr_poly
					(pts
						(arc
							(start -0.1778 -0.2794)
							(mid -0.249642 -0.249642)
							(end -0.2794 -0.1778)
						)
						(arc
							(start -0.2794 0.1778)
							(mid -0.249642 0.249642)
							(end -0.1778 0.2794)
						)
						(arc
							(start 0.1778 0.2794)
							(mid 0.249642 0.249642)
							(end 0.2794 0.1778)
						)
						(arc
							(start 0.2794 -0.1778)
							(mid 0.249642 -0.249642)
							(end 0.1778 -0.2794)
						)
					)
					(width 0)
					(fill yes)
				)
			)
		)
		(pad "2" smd custom
			(at 0 0.4445)
			(size 0.1397 0.1397)
			(layers "F.Cu" "F.Mask" "F.Paste")
			(net "I2C_GPIO_SDA_4")
			(options
				(clearance outline)
				(anchor circle)
			)
			(primitives
				(gr_poly
					(pts
						(arc
							(start -0.1778 -0.2794)
							(mid -0.249642 -0.249642)
							(end -0.2794 -0.1778)
						)
						(arc
							(start -0.2794 0.1778)
							(mid -0.249642 0.249642)
							(end -0.1778 0.2794)
						)
						(arc
							(start 0.1778 0.2794)
							(mid 0.249642 0.249642)
							(end 0.2794 0.1778)
						)
						(arc
							(start 0.2794 -0.1778)
							(mid 0.249642 -0.249642)
							(end 0.1778 -0.2794)
						)
					)
					(width 0)
					(fill yes)
				)
			)
		)
	)
	(footprint ""
		(layer "F.Cu")
		(at 79.097124 -195.681092 180)
		(property "Reference" "R7948"
			(at 0 0 180)
			(layer "F.SilkS")
			(hide yes)
			(effects
				(font
					(size 1.27 1.27)
				)
			)
		)
		(property "Value" "0R2J-2-GP"
			(at 0.064008 -3.993896 180)
			(unlocked yes)
			(layer "F.Fab")
			(hide yes)
			(effects
				(font
					(size 1.016 1.016)
					(thickness 0.1524)
				)
			)
		)
		(property "Device Type" "R402H16"
			(at 0.064008 -5.517896 180)
			(unlocked yes)
			(layer "F.Fab")
			(hide yes)
			(effects
				(font
					(size 1.016 1.016)
					(thickness 0.1524)
				)
			)
		)
		(duplicate_pad_numbers_are_jumpers no)
		(fp_line
			(start 0.508 -0.9398)
			(end -0.508 -0.9398)
			(stroke
				(width 0.1524)
				(type default)
			)
			(layer "F.SilkS")
		)
		(fp_line
			(start -0.508 -0.9398)
			(end -0.508 0.9398)
			(stroke
				(width 0.1524)
				(type default)
			)
			(layer "F.SilkS")
		)
		(fp_rect
			(start -0.508 0.9398)
			(end 0.508 -0.9398)
			(stroke
				(width 0)
				(type default)
			)
			(fill no)
			(layer "F.CrtYd")
		)
		(fp_rect
			(start -0.508 0.9398)
			(end 0.508 -0.9398)
			(stroke
				(width 0)
				(type default)
			)
			(fill no)
			(layer "F.Fab")
		)
		(pad "1" smd custom
			(at 0 -0.4445 180)
			(size 0.1397 0.1397)
			(layers "F.Cu" "F.Mask" "F.Paste")
			(net "SSD_ATNLED#10")
			(options
				(clearance outline)
				(anchor circle)
			)
			(primitives
				(gr_poly
					(pts
						(arc
							(start -0.1778 -0.2794)
							(mid -0.249642 -0.249642)
							(end -0.2794 -0.1778)
						)
						(arc
							(start -0.2794 0.1778)
							(mid -0.249642 0.249642)
							(end -0.1778 0.2794)
						)
						(arc
							(start 0.1778 0.2794)
							(mid 0.249642 0.249642)
							(end 0.2794 0.1778)
						)
						(arc
							(start 0.2794 -0.1778)
							(mid 0.249642 -0.249642)
							(end 0.1778 -0.2794)
						)
					)
					(width 0)
					(fill yes)
				)
			)
		)
		(pad "2" smd custom
			(at 0 0.4445 180)
			(size 0.1397 0.1397)
			(layers "F.Cu" "F.Mask" "F.Paste")
			(net "SSD_ATNLED#10_R")
			(options
				(clearance outline)
				(anchor circle)
			)
			(primitives
				(gr_poly
					(pts
						(arc
							(start -0.1778 -0.2794)
							(mid -0.249642 -0.249642)
							(end -0.2794 -0.1778)
						)
						(arc
							(start -0.2794 0.1778)
							(mid -0.249642 0.249642)
							(end -0.1778 0.2794)
						)
						(arc
							(start 0.1778 0.2794)
							(mid 0.249642 0.249642)
							(end 0.2794 0.1778)
						)
						(arc
							(start 0.2794 -0.1778)
							(mid 0.249642 -0.249642)
							(end 0.1778 -0.2794)
						)
					)
					(width 0)
					(fill yes)
				)
			)
		)
	)
	(footprint ""
		(layer "F.Cu")
		(at 158.242 -98.7044 180)
		(property "Reference" "R101"
			(at 0 0 180)
			(layer "F.SilkS")
			(hide yes)
			(effects
				(font
					(size 1.27 1.27)
				)
			)
		)
		(property "Value" "10KR2F-2-GP"
			(at 0.064008 -3.993896 180)
			(unlocked yes)
			(layer "F.Fab")
			(hide yes)
			(effects
				(font
					(size 1.016 1.016)
					(thickness 0.1524)
				)
			)
		)
		(property "Device Type" "R402H16"
			(at 0.064008 -5.517896 180)
			(unlocked yes)
			(layer "F.Fab")
			(hide yes)
			(effects
				(font
					(size 1.016 1.016)
					(thickness 0.1524)
				)
			)
		)
		(duplicate_pad_numbers_are_jumpers no)
		(fp_line
			(start 0.508 -0.9398)
			(end -0.508 -0.9398)
			(stroke
				(width 0.1524)
				(type default)
			)
			(layer "F.SilkS")
		)
		(fp_line
			(start -0.508 -0.9398)
			(end -0.508 0.9398)
			(stroke
				(width 0.1524)
				(type default)
			)
			(layer "F.SilkS")
		)
		(fp_rect
			(start -0.508 0.9398)
			(end 0.508 -0.9398)
			(stroke
				(width 0)
				(type default)
			)
			(fill no)
			(layer "F.CrtYd")
		)
		(fp_rect
			(start -0.508 0.9398)
			(end 0.508 -0.9398)
			(stroke
				(width 0)
				(type default)
			)
			(fill no)
			(layer "F.Fab")
		)
		(pad "1" smd custom
			(at 0 -0.4445 180)
			(size 0.1397 0.1397)
			(layers "F.Cu" "F.Mask" "F.Paste")
			(net "CLKGEN_PWGD")
			(options
				(clearance outline)
				(anchor circle)
			)
			(primitives
				(gr_poly
					(pts
						(arc
							(start -0.1778 -0.2794)
							(mid -0.249642 -0.249642)
							(end -0.2794 -0.1778)
						)
						(arc
							(start -0.2794 0.1778)
							(mid -0.249642 0.249642)
							(end -0.1778 0.2794)
						)
						(arc
							(start 0.1778 0.2794)
							(mid 0.249642 0.249642)
							(end 0.2794 0.1778)
						)
						(arc
							(start 0.2794 -0.1778)
							(mid 0.249642 -0.249642)
							(end 0.1778 -0.2794)
						)
					)
					(width 0)
					(fill yes)
				)
			)
		)
		(pad "2" smd custom
			(at 0 0.4445 180)
			(size 0.1397 0.1397)
			(layers "F.Cu" "F.Mask" "F.Paste")
			(net "P1V8_STBY")
			(options
				(clearance outline)
				(anchor circle)
			)
			(primitives
				(gr_poly
					(pts
						(arc
							(start -0.1778 -0.2794)
							(mid -0.249642 -0.249642)
							(end -0.2794 -0.1778)
						)
						(arc
							(start -0.2794 0.1778)
							(mid -0.249642 0.249642)
							(end -0.1778 0.2794)
						)
						(arc
							(start 0.1778 0.2794)
							(mid 0.249642 0.249642)
							(end 0.2794 0.1778)
						)
						(arc
							(start 0.2794 -0.1778)
							(mid 0.249642 -0.249642)
							(end 0.1778 -0.2794)
						)
					)
					(width 0)
					(fill yes)
				)
			)
		)
	)
	(footprint ""
		(layer "F.Cu")
		(at 271.808194 -212.420454 180)
		(property "Reference" "C102"
			(at 0 0 180)
			(layer "F.SilkS")
			(hide yes)
			(effects
				(font
					(size 1.27 1.27)
				)
			)
		)
		(property "Value" "SCD22U10V2KX-1GP"
			(at 1.1811 -2.7051 180)
			(unlocked yes)
			(layer "F.Fab")
			(hide yes)
			(effects
				(font
					(size 1.016 1.016)
					(thickness 0.1524)
				)
			)
		)
		(property "Device Type" "C402H22"
			(at 1.1811 -4.2291 180)
			(unlocked yes)
			(layer "F.Fab")
			(hide yes)
			(effects
				(font
					(size 1.016 1.016)
					(thickness 0.1524)
				)
			)
		)
		(duplicate_pad_numbers_are_jumpers no)
		(fp_rect
			(start -0.4318 0.9525)
			(end 0.4318 -0.9525)
			(stroke
				(width 0)
				(type default)
			)
			(fill no)
			(layer "F.CrtYd")
		)
		(fp_rect
			(start -0.4318 0.9525)
			(end 0.4318 -0.9525)
			(stroke
				(width 0)
				(type default)
			)
			(fill no)
			(layer "F.Fab")
		)
		(pad "1" smd custom
			(at 0 -0.4445 180)
			(size 0.1524 0.1524)
			(layers "F.Cu" "F.Mask" "F.Paste")
			(net "PCIE_TX_CAP_N35")
			(options
				(clearance outline)
				(anchor circle)
			)
			(primitives
				(gr_poly
					(pts
						(arc
							(start 0.3048 -0.2032)
							(mid 0.275042 -0.275042)
							(end 0.2032 -0.3048)
						)
						(arc
							(start -0.2032 -0.3048)
							(mid -0.275042 -0.275042)
							(end -0.3048 -0.2032)
						)
						(arc
							(start -0.3048 0.2032)
							(mid -0.275042 0.275042)
							(end -0.2032 0.3048)
						)
						(arc
							(start 0.2032 0.3048)
							(mid 0.275042 0.275042)
							(end 0.3048 0.2032)
						)
					)
					(width 0)
					(fill yes)
				)
			)
		)
		(pad "2" smd custom
			(at 0 0.4445 180)
			(size 0.1524 0.1524)
			(layers "F.Cu" "F.Mask" "F.Paste")
			(net "PCIE_TX_N35")
			(options
				(clearance outline)
				(anchor circle)
			)
			(primitives
				(gr_poly
					(pts
						(arc
							(start 0.3048 -0.2032)
							(mid 0.275042 -0.275042)
							(end 0.2032 -0.3048)
						)
						(arc
							(start -0.2032 -0.3048)
							(mid -0.275042 -0.275042)
							(end -0.3048 -0.2032)
						)
						(arc
							(start -0.3048 0.2032)
							(mid -0.275042 0.275042)
							(end -0.2032 0.3048)
						)
						(arc
							(start 0.2032 0.3048)
							(mid 0.275042 0.275042)
							(end 0.3048 0.2032)
						)
					)
					(width 0)
					(fill yes)
				)
			)
		)
	)
	(footprint ""
		(layer "F.Cu")
		(at 46.355 -180.467)
		(property "Reference" "C253"
			(at 0 0 0)
			(layer "F.SilkS")
			(hide yes)
			(effects
				(font
					(size 1.27 1.27)
				)
			)
		)
		(property "Value" "SCD1U16V2KX-3GP"
			(at 1.1811 -2.7051 0)
			(unlocked yes)
			(layer "F.Fab")
			(hide yes)
			(effects
				(font
					(size 1.016 1.016)
					(thickness 0.1524)
				)
			)
		)
		(property "Device Type" "C402H22"
			(at 1.1811 -4.2291 0)
			(unlocked yes)
			(layer "F.Fab")
			(hide yes)
			(effects
				(font
					(size 1.016 1.016)
					(thickness 0.1524)
				)
			)
		)
		(duplicate_pad_numbers_are_jumpers no)
		(fp_rect
			(start -0.4318 0.9525)
			(end 0.4318 -0.9525)
			(stroke
				(width 0)
				(type default)
			)
			(fill no)
			(layer "F.CrtYd")
		)
		(fp_rect
			(start -0.4318 0.9525)
			(end 0.4318 -0.9525)
			(stroke
				(width 0)
				(type default)
			)
			(fill no)
			(layer "F.Fab")
		)
		(pad "1" smd custom
			(at 0 -0.4445)
			(size 0.1524 0.1524)
			(layers "F.Cu" "F.Mask" "F.Paste")
			(net "P3V3_STBY")
			(options
				(clearance outline)
				(anchor circle)
			)
			(primitives
				(gr_poly
					(pts
						(arc
							(start 0.3048 -0.2032)
							(mid 0.275042 -0.275042)
							(end 0.2032 -0.3048)
						)
						(arc
							(start -0.2032 -0.3048)
							(mid -0.275042 -0.275042)
							(end -0.3048 -0.2032)
						)
						(arc
							(start -0.3048 0.2032)
							(mid -0.275042 0.275042)
							(end -0.2032 0.3048)
						)
						(arc
							(start 0.2032 0.3048)
							(mid 0.275042 0.275042)
							(end 0.3048 0.2032)
						)
					)
					(width 0)
					(fill yes)
				)
			)
		)
		(pad "2" smd custom
			(at 0 0.4445)
			(size 0.1524 0.1524)
			(layers "F.Cu" "F.Mask" "F.Paste")
			(net "GND")
			(options
				(clearance outline)
				(anchor circle)
			)
			(primitives
				(gr_poly
					(pts
						(arc
							(start 0.3048 -0.2032)
							(mid 0.275042 -0.275042)
							(end 0.2032 -0.3048)
						)
						(arc
							(start -0.2032 -0.3048)
							(mid -0.275042 -0.275042)
							(end -0.3048 -0.2032)
						)
						(arc
							(start -0.3048 0.2032)
							(mid -0.275042 0.275042)
							(end -0.2032 0.3048)
						)
						(arc
							(start 0.2032 0.3048)
							(mid 0.275042 0.275042)
							(end 0.3048 0.2032)
						)
					)
					(width 0)
					(fill yes)
				)
			)
		)
	)
	(footprint ""
		(layer "F.Cu")
		(at 55.118 -180.467 180)
		(property "Reference" "R895"
			(at 0 0 180)
			(layer "F.SilkS")
			(hide yes)
			(effects
				(font
					(size 1.27 1.27)
				)
			)
		)
		(property "Value" "10KR2F-2-GP"
			(at 0.064008 -3.993896 180)
			(unlocked yes)
			(layer "F.Fab")
			(hide yes)
			(effects
				(font
					(size 1.016 1.016)
					(thickness 0.1524)
				)
			)
		)
		(property "Device Type" "R402H16"
			(at 0.064008 -5.517896 180)
			(unlocked yes)
			(layer "F.Fab")
			(hide yes)
			(effects
				(font
					(size 1.016 1.016)
					(thickness 0.1524)
				)
			)
		)
		(duplicate_pad_numbers_are_jumpers no)
		(fp_line
			(start 0.508 -0.9398)
			(end -0.508 -0.9398)
			(stroke
				(width 0.1524)
				(type default)
			)
			(layer "F.SilkS")
		)
		(fp_line
			(start -0.508 -0.9398)
			(end -0.508 0.9398)
			(stroke
				(width 0.1524)
				(type default)
			)
			(layer "F.SilkS")
		)
		(fp_rect
			(start -0.508 0.9398)
			(end 0.508 -0.9398)
			(stroke
				(width 0)
				(type default)
			)
			(fill no)
			(layer "F.CrtYd")
		)
		(fp_rect
			(start -0.508 0.9398)
			(end 0.508 -0.9398)
			(stroke
				(width 0)
				(type default)
			)
			(fill no)
			(layer "F.Fab")
		)
		(pad "1" smd custom
			(at 0 -0.4445 180)
			(size 0.1397 0.1397)
			(layers "F.Cu" "F.Mask" "F.Paste")
			(net "P3V3_STBY")
			(options
				(clearance outline)
				(anchor circle)
			)
			(primitives
				(gr_poly
					(pts
						(arc
							(start -0.1778 -0.2794)
							(mid -0.249642 -0.249642)
							(end -0.2794 -0.1778)
						)
						(arc
							(start -0.2794 0.1778)
							(mid -0.249642 0.249642)
							(end -0.1778 0.2794)
						)
						(arc
							(start 0.1778 0.2794)
							(mid 0.249642 0.249642)
							(end 0.2794 0.1778)
						)
						(arc
							(start 0.2794 -0.1778)
							(mid 0.249642 -0.249642)
							(end 0.1778 -0.2794)
						)
					)
					(width 0)
					(fill yes)
				)
			)
		)
		(pad "2" smd custom
			(at 0 0.4445 180)
			(size 0.1397 0.1397)
			(layers "F.Cu" "F.Mask" "F.Paste")
			(net "I2C8_BUFF_EN")
			(options
				(clearance outline)
				(anchor circle)
			)
			(primitives
				(gr_poly
					(pts
						(arc
							(start -0.1778 -0.2794)
							(mid -0.249642 -0.249642)
							(end -0.2794 -0.1778)
						)
						(arc
							(start -0.2794 0.1778)
							(mid -0.249642 0.249642)
							(end -0.1778 0.2794)
						)
						(arc
							(start 0.1778 0.2794)
							(mid 0.249642 0.249642)
							(end 0.2794 0.1778)
						)
						(arc
							(start 0.2794 -0.1778)
							(mid 0.249642 -0.249642)
							(end 0.1778 -0.2794)
						)
					)
					(width 0)
					(fill yes)
				)
			)
		)
	)
	(footprint ""
		(layer "F.Cu")
		(at 143.0274 -41.402 180)
		(property "Reference" "R757"
			(at 0 0 180)
			(layer "F.SilkS")
			(hide yes)
			(effects
				(font
					(size 1.27 1.27)
				)
			)
		)
		(property "Value" "0R2J-2-GP"
			(at 0.064008 -3.993896 180)
			(unlocked yes)
			(layer "F.Fab")
			(hide yes)
			(effects
				(font
					(size 1.016 1.016)
					(thickness 0.1524)
				)
			)
		)
		(property "Device Type" "R402H16"
			(at 0.064008 -5.517896 180)
			(unlocked yes)
			(layer "F.Fab")
			(hide yes)
			(effects
				(font
					(size 1.016 1.016)
					(thickness 0.1524)
				)
			)
		)
		(duplicate_pad_numbers_are_jumpers no)
		(fp_line
			(start 0.508 -0.9398)
			(end -0.508 -0.9398)
			(stroke
				(width 0.1524)
				(type default)
			)
			(layer "F.SilkS")
		)
		(fp_line
			(start -0.508 -0.9398)
			(end -0.508 0.9398)
			(stroke
				(width 0.1524)
				(type default)
			)
			(layer "F.SilkS")
		)
		(fp_rect
			(start -0.508 0.9398)
			(end 0.508 -0.9398)
			(stroke
				(width 0)
				(type default)
			)
			(fill no)
			(layer "F.CrtYd")
		)
		(fp_rect
			(start -0.508 0.9398)
			(end 0.508 -0.9398)
			(stroke
				(width 0)
				(type default)
			)
			(fill no)
			(layer "F.Fab")
		)
		(pad "1" smd custom
			(at 0 -0.4445 180)
			(size 0.1397 0.1397)
			(layers "F.Cu" "F.Mask" "F.Paste")
			(net "EJTAG_TCK_R")
			(options
				(clearance outline)
				(anchor circle)
			)
			(primitives
				(gr_poly
					(pts
						(arc
							(start -0.1778 -0.2794)
							(mid -0.249642 -0.249642)
							(end -0.2794 -0.1778)
						)
						(arc
							(start -0.2794 0.1778)
							(mid -0.249642 0.249642)
							(end -0.1778 0.2794)
						)
						(arc
							(start 0.1778 0.2794)
							(mid 0.249642 0.249642)
							(end 0.2794 0.1778)
						)
						(arc
							(start 0.2794 -0.1778)
							(mid 0.249642 -0.249642)
							(end 0.1778 -0.2794)
						)
					)
					(width 0)
					(fill yes)
				)
			)
		)
		(pad "2" smd custom
			(at 0 0.4445 180)
			(size 0.1397 0.1397)
			(layers "F.Cu" "F.Mask" "F.Paste")
			(net "EJTAG_TCK")
			(options
				(clearance outline)
				(anchor circle)
			)
			(primitives
				(gr_poly
					(pts
						(arc
							(start -0.1778 -0.2794)
							(mid -0.249642 -0.249642)
							(end -0.2794 -0.1778)
						)
						(arc
							(start -0.2794 0.1778)
							(mid -0.249642 0.249642)
							(end -0.1778 0.2794)
						)
						(arc
							(start 0.1778 0.2794)
							(mid 0.249642 0.249642)
							(end 0.2794 0.1778)
						)
						(arc
							(start 0.2794 -0.1778)
							(mid 0.249642 -0.249642)
							(end 0.1778 -0.2794)
						)
					)
					(width 0)
					(fill yes)
				)
			)
		)
	)
	(footprint ""
		(layer "F.Cu")
		(at 76.811124 -183.235092)
		(property "Reference" "R7943"
			(at 0 0 0)
			(layer "F.SilkS")
			(hide yes)
			(effects
				(font
					(size 1.27 1.27)
				)
			)
		)
		(property "Value" "0R2J-2-GP"
			(at 0.064008 -3.993896 0)
			(unlocked yes)
			(layer "F.Fab")
			(hide yes)
			(effects
				(font
					(size 1.016 1.016)
					(thickness 0.1524)
				)
			)
		)
		(property "Device Type" "R402H16"
			(at 0.064008 -5.517896 0)
			(unlocked yes)
			(layer "F.Fab")
			(hide yes)
			(effects
				(font
					(size 1.016 1.016)
					(thickness 0.1524)
				)
			)
		)
		(duplicate_pad_numbers_are_jumpers no)
		(fp_line
			(start -0.508 -0.9398)
			(end -0.508 0.9398)
			(stroke
				(width 0.1524)
				(type default)
			)
			(layer "F.SilkS")
		)
		(fp_line
			(start 0.508 -0.9398)
			(end -0.508 -0.9398)
			(stroke
				(width 0.1524)
				(type default)
			)
			(layer "F.SilkS")
		)
		(fp_rect
			(start -0.508 0.9398)
			(end 0.508 -0.9398)
			(stroke
				(width 0)
				(type default)
			)
			(fill no)
			(layer "F.CrtYd")
		)
		(fp_rect
			(start -0.508 0.9398)
			(end 0.508 -0.9398)
			(stroke
				(width 0)
				(type default)
			)
			(fill no)
			(layer "F.Fab")
		)
		(pad "1" smd custom
			(at 0 -0.4445)
			(size 0.1397 0.1397)
			(layers "F.Cu" "F.Mask" "F.Paste")
			(net "SSD_ATNLED#5")
			(options
				(clearance outline)
				(anchor circle)
			)
			(primitives
				(gr_poly
					(pts
						(arc
							(start -0.1778 -0.2794)
							(mid -0.249642 -0.249642)
							(end -0.2794 -0.1778)
						)
						(arc
							(start -0.2794 0.1778)
							(mid -0.249642 0.249642)
							(end -0.1778 0.2794)
						)
						(arc
							(start 0.1778 0.2794)
							(mid 0.249642 0.249642)
							(end 0.2794 0.1778)
						)
						(arc
							(start 0.2794 -0.1778)
							(mid 0.249642 -0.249642)
							(end 0.1778 -0.2794)
						)
					)
					(width 0)
					(fill yes)
				)
			)
		)
		(pad "2" smd custom
			(at 0 0.4445)
			(size 0.1397 0.1397)
			(layers "F.Cu" "F.Mask" "F.Paste")
			(net "SSD_ATNLED#5_R")
			(options
				(clearance outline)
				(anchor circle)
			)
			(primitives
				(gr_poly
					(pts
						(arc
							(start -0.1778 -0.2794)
							(mid -0.249642 -0.249642)
							(end -0.2794 -0.1778)
						)
						(arc
							(start -0.2794 0.1778)
							(mid -0.249642 0.249642)
							(end -0.1778 0.2794)
						)
						(arc
							(start 0.1778 0.2794)
							(mid 0.249642 0.249642)
							(end 0.2794 0.1778)
						)
						(arc
							(start 0.2794 -0.1778)
							(mid 0.249642 -0.249642)
							(end 0.1778 -0.2794)
						)
					)
					(width 0)
					(fill yes)
				)
			)
		)
	)
	(footprint ""
		(layer "F.Cu")
		(at 19.34718 -66.27368 180)
		(property "Reference" "R166"
			(at 0 0 180)
			(layer "F.SilkS")
			(hide yes)
			(effects
				(font
					(size 1.27 1.27)
				)
			)
		)
		(property "Value" "4K7R2F-GP"
			(at 0.064008 -3.993896 180)
			(unlocked yes)
			(layer "F.Fab")
			(hide yes)
			(effects
				(font
					(size 1.016 1.016)
					(thickness 0.1524)
				)
			)
		)
		(property "Device Type" "R402H16"
			(at 0.064008 -5.517896 180)
			(unlocked yes)
			(layer "F.Fab")
			(hide yes)
			(effects
				(font
					(size 1.016 1.016)
					(thickness 0.1524)
				)
			)
		)
		(duplicate_pad_numbers_are_jumpers no)
		(fp_line
			(start 0.508 -0.9398)
			(end -0.508 -0.9398)
			(stroke
				(width 0.1524)
				(type default)
			)
			(layer "F.SilkS")
		)
		(fp_line
			(start -0.508 -0.9398)
			(end -0.508 0.9398)
			(stroke
				(width 0.1524)
				(type default)
			)
			(layer "F.SilkS")
		)
		(fp_rect
			(start -0.508 0.9398)
			(end 0.508 -0.9398)
			(stroke
				(width 0)
				(type default)
			)
			(fill no)
			(layer "F.CrtYd")
		)
		(fp_rect
			(start -0.508 0.9398)
			(end 0.508 -0.9398)
			(stroke
				(width 0)
				(type default)
			)
			(fill no)
			(layer "F.Fab")
		)
		(pad "1" smd custom
			(at 0 -0.4445 180)
			(size 0.1397 0.1397)
			(layers "F.Cu" "F.Mask" "F.Paste")
			(net "GND")
			(options
				(clearance outline)
				(anchor circle)
			)
			(primitives
				(gr_poly
					(pts
						(arc
							(start -0.1778 -0.2794)
							(mid -0.249642 -0.249642)
							(end -0.2794 -0.1778)
						)
						(arc
							(start -0.2794 0.1778)
							(mid -0.249642 0.249642)
							(end -0.1778 0.2794)
						)
						(arc
							(start 0.1778 0.2794)
							(mid 0.249642 0.249642)
							(end 0.2794 0.1778)
						)
						(arc
							(start 0.2794 -0.1778)
							(mid 0.249642 -0.249642)
							(end 0.1778 -0.2794)
						)
					)
					(width 0)
					(fill yes)
				)
			)
		)
		(pad "2" smd custom
			(at 0 0.4445 180)
			(size 0.1397 0.1397)
			(layers "F.Cu" "F.Mask" "F.Paste")
			(net "PCIE_DIS")
			(options
				(clearance outline)
				(anchor circle)
			)
			(primitives
				(gr_poly
					(pts
						(arc
							(start -0.1778 -0.2794)
							(mid -0.249642 -0.249642)
							(end -0.2794 -0.1778)
						)
						(arc
							(start -0.2794 0.1778)
							(mid -0.249642 0.249642)
							(end -0.1778 0.2794)
						)
						(arc
							(start 0.1778 0.2794)
							(mid 0.249642 0.249642)
							(end 0.2794 0.1778)
						)
						(arc
							(start 0.2794 -0.1778)
							(mid 0.249642 -0.249642)
							(end 0.1778 -0.2794)
						)
					)
					(width 0)
					(fill yes)
				)
			)
		)
	)
	(footprint ""
		(layer "F.Cu")
		(at 39.878 -198.882 -90)
		(property "Reference" "C697"
			(at 0 0 270)
			(layer "F.SilkS")
			(hide yes)
			(effects
				(font
					(size 1.27 1.27)
				)
			)
		)
		(property "Value" "SC220P50V3JN-GP"
			(at 0 -2.8194 270)
			(unlocked yes)
			(layer "F.Fab")
			(hide yes)
			(effects
				(font
					(size 1.016 1.016)
					(thickness 0.1524)
				)
			)
		)
		(property "Device Type" "C603H36"
			(at 0 -4.3434 270)
			(unlocked yes)
			(layer "F.Fab")
			(hide yes)
			(effects
				(font
					(size 1.016 1.016)
					(thickness 0.1524)
				)
			)
		)
		(duplicate_pad_numbers_are_jumpers no)
		(fp_line
			(start 0.508 0)
			(end -0.508 0)
			(stroke
				(width 0.2032)
				(type default)
			)
			(layer "F.SilkS")
		)
		(fp_rect
			(start -0.5842 1.3335)
			(end 0.5842 -1.3335)
			(stroke
				(width 0)
				(type default)
			)
			(fill no)
			(layer "F.CrtYd")
		)
		(fp_rect
			(start -0.5842 1.3335)
			(end 0.5842 -1.3335)
			(stroke
				(width 0)
				(type default)
			)
			(fill no)
			(layer "F.Fab")
		)
		(pad "1" smd custom
			(at 0 -0.762 270)
			(size 0.2159 0.2159)
			(layers "F.Cu" "F.Mask" "F.Paste")
			(net "BMC_I2C6_C_FCB_SDA_R")
			(options
				(clearance outline)
				(anchor circle)
			)
			(primitives
				(gr_poly
					(pts
						(arc
							(start -0.3302 -0.4318)
							(mid -0.402042 -0.402042)
							(end -0.4318 -0.3302)
						)
						(arc
							(start -0.4318 0.3302)
							(mid -0.402042 0.402042)
							(end -0.3302 0.4318)
						)
						(arc
							(start 0.3302 0.4318)
							(mid 0.402042 0.402042)
							(end 0.4318 0.3302)
						)
						(arc
							(start 0.4318 -0.3302)
							(mid 0.402042 -0.402042)
							(end 0.3302 -0.4318)
						)
					)
					(width 0)
					(fill yes)
				)
			)
		)
		(pad "2" smd custom
			(at 0 0.762 270)
			(size 0.2159 0.2159)
			(layers "F.Cu" "F.Mask" "F.Paste")
			(net "GND")
			(options
				(clearance outline)
				(anchor circle)
			)
			(primitives
				(gr_poly
					(pts
						(arc
							(start -0.3302 -0.4318)
							(mid -0.402042 -0.402042)
							(end -0.4318 -0.3302)
						)
						(arc
							(start -0.4318 0.3302)
							(mid -0.402042 0.402042)
							(end -0.3302 0.4318)
						)
						(arc
							(start 0.3302 0.4318)
							(mid 0.402042 0.402042)
							(end 0.4318 0.3302)
						)
						(arc
							(start 0.4318 -0.3302)
							(mid 0.402042 -0.402042)
							(end 0.3302 -0.4318)
						)
					)
					(width 0)
					(fill yes)
				)
			)
		)
	)
	(footprint ""
		(layer "F.Cu")
		(at 26.64206 -62.999874)
		(property "Reference" "CN11"
			(at 0 0 0)
			(layer "F.SilkS")
			(hide yes)
			(effects
				(font
					(size 1.27 1.27)
				)
			)
		)
		(property "Value" "FCI-CONN11-2-GP"
			(at -7.4803 1.3589 0)
			(unlocked yes)
			(layer "F.Fab")
			(hide yes)
			(effects
				(font
					(size 1.016 1.016)
					(thickness 0.1524)
				)
			)
		)
		(property "Device Type" "91932-31111LF"
			(at -7.4803 -0.1651 0)
			(unlocked yes)
			(layer "F.Fab")
			(hide yes)
			(effects
				(font
					(size 1.016 1.016)
					(thickness 0.1524)
				)
			)
		)
		(duplicate_pad_numbers_are_jumpers no)
		(fp_line
			(start -5.4102 -3.556)
			(end -5.4102 3.556)
			(stroke
				(width 0.1524)
				(type default)
			)
			(layer "F.SilkS")
		)
		(fp_line
			(start -5.4102 3.556)
			(end 5.4102 3.556)
			(stroke
				(width 0.1524)
				(type default)
			)
			(layer "F.SilkS")
		)
		(fp_line
			(start -2.8321 3.6449)
			(end -2.2479 3.6449)
			(stroke
				(width 0.3302)
				(type default)
			)
			(layer "F.SilkS")
		)
		(fp_line
			(start 5.4102 -3.556)
			(end -5.4102 -3.556)
			(stroke
				(width 0.1524)
				(type default)
			)
			(layer "F.SilkS")
		)
		(fp_line
			(start 5.4102 3.556)
			(end 5.4102 -3.556)
			(stroke
				(width 0.1524)
				(type default)
			)
			(layer "F.SilkS")
		)
		(fp_poly
			(pts
				(xy -2.546096 3.612642) (xy -3.181096 4.247642) (xy -1.911096 4.247642)
			)
			(stroke
				(width 0)
				(type default)
			)
			(fill yes)
			(layer "F.SilkS")
		)
		(fp_poly
			(pts
				(xy -2.8067 1.08839)
				(arc
					(start -2.8067 -0.422402)
					(mid -2.451868 -0.675672)
					(end -2.3114 -1.08839)
				)
				(arc
					(start 2.3114 -1.08839)
					(mid 2.451818 -0.675634)
					(end 2.8067 -0.422402)
				)
				(xy 2.8067 1.08839)
			)
			(stroke
				(width 0)
				(type default)
			)
			(fill yes)
			(layer "F.SilkS")
		)
		(fp_rect
			(start -5.1562 2.794)
			(end 5.1562 -2.794)
			(stroke
				(width 0)
				(type default)
			)
			(fill no)
			(layer "F.CrtYd")
		)
		(fp_poly
			(pts
				(xy 5.6642 -2.794) (xy -5.1562 -2.794) (xy -5.1562 2.794) (xy 5.1562 2.794) (xy 5.1562 -2.7813)
				(xy 5.6642 -2.7813) (xy 5.6642 3.81) (xy -5.6642 3.81) (xy -5.6642 -3.81) (xy 5.6642 -3.81)
			)
			(stroke
				(width 0)
				(type default)
			)
			(fill no)
			(layer "F.CrtYd")
		)
		(fp_rect
			(start -5.6642 3.81)
			(end 5.6642 -3.81)
			(stroke
				(width 0)
				(type default)
			)
			(fill no)
			(layer "F.Fab")
		)
		(pad "" np_thru_hole circle
			(at -3.0226 -1.100074)
			(size 0.254 0.254)
			(drill 0.8128)
			(layers "*.Cu" "*.Mask")
			(clearance 0.635)
			(thermal_gap 0.635)
		)
		(pad "" np_thru_hole circle
			(at 3.0226 -1.100074)
			(size 0.254 0.254)
			(drill 0.8128)
			(layers "*.Cu" "*.Mask")
			(clearance 0.635)
			(thermal_gap 0.635)
		)
		(pad "1" smd rect
			(at -2.500122 2.29489)
			(size 0.6096 2.0066)
			(layers "F.Cu" "F.Mask" "F.Paste")
			(net "Net_14")
		)
		(pad "2" smd rect
			(at -1.500124 2.29489)
			(size 0.6096 2.0066)
			(layers "F.Cu" "F.Mask" "F.Paste")
			(net "Net_13")
		)
		(pad "3" smd rect
			(at -0.500126 2.29489)
			(size 0.6096 2.0066)
			(layers "F.Cu" "F.Mask" "F.Paste")
			(net "Net_12")
		)
		(pad "4" smd rect
			(at 0.500126 2.29489)
			(size 0.6096 2.0066)
			(layers "F.Cu" "F.Mask" "F.Paste")
			(net "Net_11")
		)
		(pad "5" smd rect
			(at 1.500124 2.29489)
			(size 0.6096 2.0066)
			(layers "F.Cu" "F.Mask" "F.Paste")
			(net "Net_10")
		)
		(pad "6" smd rect
			(at 2.500122 2.29489)
			(size 0.6096 2.0066)
			(layers "F.Cu" "F.Mask" "F.Paste")
			(net "I2C_TPM_SDA")
		)
		(pad "7" smd rect
			(at -1.999996 -2.29489)
			(size 0.6096 2.0066)
			(layers "F.Cu" "F.Mask" "F.Paste")
			(net "P3V3_STBY")
		)
		(pad "8" smd rect
			(at -0.999998 -2.29489)
			(size 0.6096 2.0066)
			(layers "F.Cu" "F.Mask" "F.Paste")
			(net "FM_TPM_PRES_RST_N")
		)
		(pad "9" smd rect
			(at 0 -2.29489)
			(size 0.6096 2.0066)
			(layers "F.Cu" "F.Mask" "F.Paste")
			(net "Net_15")
		)
		(pad "10" smd rect
			(at 0.999998 -2.29489)
			(size 0.6096 2.0066)
			(layers "F.Cu" "F.Mask" "F.Paste")
			(net "I2C_TPM_SCL")
		)
		(pad "11" smd rect
			(at 1.999996 -2.29489)
			(size 0.6096 2.0066)
			(layers "F.Cu" "F.Mask" "F.Paste")
			(net "GND")
		)
		(pad "G1" smd custom
			(at -4.219956 0)
			(size 0.34925 0.34925)
			(layers "F.Cu" "F.Mask" "F.Paste")
			(net "GND")
			(options
				(clearance outline)
				(anchor circle)
			)
			(primitives
				(gr_poly
					(pts
						(xy -0.6985 2.921) (xy -0.6985 -2.921) (xy 0.6985 -2.921)
						(arc
							(start 0.6985 -1.610106)
							(mid 0.482924 -1.100074)
							(end 0.6985 -0.590042)
						)
						(xy 0.6985 2.921)
					)
					(width 0)
					(fill yes)
				)
			)
		)
		(pad "G2" smd custom
			(at 4.219956 0)
			(size 0.34925 0.34925)
			(layers "F.Cu" "F.Mask" "F.Paste")
			(net "GND")
			(options
				(clearance outline)
				(anchor circle)
			)
			(primitives
				(gr_poly
					(pts
						(xy -0.6985 2.921)
						(arc
							(start -0.6985 -0.590042)
							(mid -0.482924 -1.100074)
							(end -0.6985 -1.610106)
						)
						(xy -0.6985 -2.921) (xy 0.6985 -2.921) (xy 0.6985 2.921)
					)
					(width 0)
					(fill yes)
				)
			)
		)
		(zone
			(layer "F.Cu")
			(hatch none 0.5)
			(connect_pads
				(clearance 0)
			)
			(min_thickness 0.25)
			(keepout
				(tracks allowed)
				(vias not_allowed)
				(pads allowed)
				(copperpour not_allowed)
				(footprints allowed)
			)
			(placement
				(enabled no)
				(sheetname "")
			)
			(fill
				(thermal_gap 0.5)
				(thermal_bridge_width 0.5)
				(island_removal_mode 0)
			)
			(polygon
				(pts
					(xy 23.83536 -61.708284) (xy 29.44876 -61.708284) (xy 29.44876 -64.291464) (xy 23.83536 -64.291464)
				)
			)
		)
		(zone
			(layer "F.Cu")
			(hatch none 0.5)
			(connect_pads
				(clearance 0)
			)
			(min_thickness 0.25)
			(keepout
				(tracks not_allowed)
				(vias allowed)
				(pads allowed)
				(copperpour not_allowed)
				(footprints allowed)
			)
			(placement
				(enabled no)
				(sheetname "")
			)
			(fill
				(thermal_gap 0.5)
				(thermal_bridge_width 0.5)
				(island_removal_mode 0)
			)
			(polygon
				(pts
					(xy 23.83536 -61.708284) (xy 29.44876 -61.708284) (xy 29.44876 -64.291464) (xy 23.83536 -64.291464)
				)
			)
		)
		(zone
			(layer "F.Cu")
			(hatch none 0.5)
			(connect_pads
				(clearance 0)
			)
			(min_thickness 0.25)
			(keepout
				(tracks allowed)
				(vias not_allowed)
				(pads allowed)
				(copperpour not_allowed)
				(footprints allowed)
			)
			(placement
				(enabled no)
				(sheetname "")
			)
			(fill
				(thermal_gap 0.5)
				(thermal_bridge_width 0.5)
				(island_removal_mode 0)
			)
			(polygon
				(pts
					(xy 23.83536 -61.708284) (xy 29.44876 -61.708284) (xy 29.44876 -62.216284) (xy 23.83536 -62.216284)
				)
			)
		)
		(zone
			(layer "F.Cu")
			(hatch none 0.5)
			(connect_pads
				(clearance 0)
			)
			(min_thickness 0.25)
			(keepout
				(tracks allowed)
				(vias not_allowed)
				(pads allowed)
				(copperpour not_allowed)
				(footprints allowed)
			)
			(placement
				(enabled no)
				(sheetname "")
			)
			(fill
				(thermal_gap 0.5)
				(thermal_bridge_width 0.5)
				(island_removal_mode 0)
			)
			(polygon
				(pts
					(xy 24.33066 -63.783464) (xy 28.95346 -63.783464) (xy 28.95346 -64.291464) (xy 24.33066 -64.291464)
				)
			)
		)
		(zone
			(layers "F.Cu" "B.Cu" "In1.Cu" "In2.Cu" "In3.Cu" "In4.Cu" "In5.Cu" "In6.Cu")
			(hatch none 0.5)
			(connect_pads
				(clearance 0)
			)
			(min_thickness 0.25)
			(keepout
				(tracks not_allowed)
				(vias allowed)
				(pads allowed)
				(copperpour not_allowed)
				(footprints allowed)
			)
			(placement
				(enabled no)
				(sheetname "")
			)
			(fill
				(thermal_gap 0.5)
				(thermal_bridge_width 0.5)
				(island_removal_mode 0)
			)
			(polygon
				(pts
					(arc
						(start 24.33066 -64.099948)
						(mid 22.90826 -64.099948)
						(end 24.33066 -64.099948)
					)
				)
			)
		)
		(zone
			(layers "F.Cu" "B.Cu" "In1.Cu" "In2.Cu" "In3.Cu" "In4.Cu" "In5.Cu" "In6.Cu")
			(hatch none 0.5)
			(connect_pads
				(clearance 0)
			)
			(min_thickness 0.25)
			(keepout
				(tracks not_allowed)
				(vias allowed)
				(pads allowed)
				(copperpour not_allowed)
				(footprints allowed)
			)
			(placement
				(enabled no)
				(sheetname "")
			)
			(fill
				(thermal_gap 0.5)
				(thermal_bridge_width 0.5)
				(island_removal_mode 0)
			)
			(polygon
				(pts
					(arc
						(start 30.37586 -64.099948)
						(mid 28.95346 -64.099948)
						(end 30.37586 -64.099948)
					)
				)
			)
		)
	)
	(footprint ""
		(layer "F.Cu")
		(at 29.048456 -32.841946)
		(property "Reference" "R446"
			(at 0 0 0)
			(layer "F.SilkS")
			(hide yes)
			(effects
				(font
					(size 1.27 1.27)
				)
			)
		)
		(property "Value" "0R3J-0-U-GP"
			(at -0.0254 -2.5146 0)
			(unlocked yes)
			(layer "F.Fab")
			(hide yes)
			(effects
				(font
					(size 1.016 1.016)
					(thickness 0.1524)
				)
			)
		)
		(property "Device Type" "R603H22"
			(at -0.0254 -4.0386 0)
			(unlocked yes)
			(layer "F.Fab")
			(hide yes)
			(effects
				(font
					(size 1.016 1.016)
					(thickness 0.1524)
				)
			)
		)
		(duplicate_pad_numbers_are_jumpers no)
		(fp_line
			(start -0.4826 0)
			(end -0.2032 0)
			(stroke
				(width 0.2032)
				(type default)
			)
			(layer "F.SilkS")
		)
		(fp_line
			(start 0.2032 0)
			(end 0.4826 0)
			(stroke
				(width 0.2032)
				(type default)
			)
			(layer "F.SilkS")
		)
		(fp_rect
			(start -0.5842 1.3335)
			(end 0.5842 -1.3335)
			(stroke
				(width 0)
				(type default)
			)
			(fill no)
			(layer "F.CrtYd")
		)
		(fp_rect
			(start -0.5842 1.3335)
			(end 0.5842 -1.3335)
			(stroke
				(width 0)
				(type default)
			)
			(fill no)
			(layer "F.Fab")
		)
		(pad "1" smd custom
			(at 0 -0.762)
			(size 0.2159 0.2159)
			(layers "F.Cu" "F.Mask" "F.Paste")
			(net "AGND_USB")
			(options
				(clearance outline)
				(anchor circle)
			)
			(primitives
				(gr_poly
					(pts
						(arc
							(start -0.3302 -0.4318)
							(mid -0.402042 -0.402042)
							(end -0.4318 -0.3302)
						)
						(arc
							(start -0.4318 0.3302)
							(mid -0.402042 0.402042)
							(end -0.3302 0.4318)
						)
						(arc
							(start 0.3302 0.4318)
							(mid 0.402042 0.402042)
							(end 0.4318 0.3302)
						)
						(arc
							(start 0.4318 -0.3302)
							(mid 0.402042 -0.402042)
							(end 0.3302 -0.4318)
						)
					)
					(width 0)
					(fill yes)
				)
			)
		)
		(pad "2" smd custom
			(at 0 0.762)
			(size 0.2159 0.2159)
			(layers "F.Cu" "F.Mask" "F.Paste")
			(net "GND")
			(options
				(clearance outline)
				(anchor circle)
			)
			(primitives
				(gr_poly
					(pts
						(arc
							(start -0.3302 -0.4318)
							(mid -0.402042 -0.402042)
							(end -0.4318 -0.3302)
						)
						(arc
							(start -0.4318 0.3302)
							(mid -0.402042 0.402042)
							(end -0.3302 0.4318)
						)
						(arc
							(start 0.3302 0.4318)
							(mid 0.402042 0.402042)
							(end 0.4318 0.3302)
						)
						(arc
							(start 0.4318 -0.3302)
							(mid 0.402042 -0.402042)
							(end 0.3302 -0.4318)
						)
					)
					(width 0)
					(fill yes)
				)
			)
		)
	)
	(footprint ""
		(layer "F.Cu")
		(at 19.685 -183.6928 90)
		(property "Reference" "R9025"
			(at 0 0 90)
			(layer "F.SilkS")
			(hide yes)
			(effects
				(font
					(size 1.27 1.27)
				)
			)
		)
		(property "Value" "100R2D-GP"
			(at 0.064008 -3.993896 90)
			(unlocked yes)
			(layer "F.Fab")
			(hide yes)
			(effects
				(font
					(size 1.016 1.016)
					(thickness 0.1524)
				)
			)
		)
		(property "Device Type" "R402H14"
			(at 0.064008 -5.517896 90)
			(unlocked yes)
			(layer "F.Fab")
			(hide yes)
			(effects
				(font
					(size 1.016 1.016)
					(thickness 0.1524)
				)
			)
		)
		(duplicate_pad_numbers_are_jumpers no)
		(fp_line
			(start 0.508 -0.9398)
			(end -0.508 -0.9398)
			(stroke
				(width 0.1524)
				(type default)
			)
			(layer "F.SilkS")
		)
		(fp_line
			(start -0.508 -0.9398)
			(end -0.508 0.9398)
			(stroke
				(width 0.1524)
				(type default)
			)
			(layer "F.SilkS")
		)
		(fp_rect
			(start -0.508 0.9398)
			(end 0.508 -0.9398)
			(stroke
				(width 0)
				(type default)
			)
			(fill no)
			(layer "F.CrtYd")
		)
		(fp_rect
			(start -0.508 0.9398)
			(end 0.508 -0.9398)
			(stroke
				(width 0)
				(type default)
			)
			(fill no)
			(layer "F.Fab")
		)
		(pad "1" smd custom
			(at 0 -0.4445 90)
			(size 0.1397 0.1397)
			(layers "F.Cu" "F.Mask" "F.Paste")
			(net "MB0_TEMP")
			(options
				(clearance outline)
				(anchor circle)
			)
			(primitives
				(gr_poly
					(pts
						(arc
							(start -0.1778 -0.2794)
							(mid -0.249642 -0.249642)
							(end -0.2794 -0.1778)
						)
						(arc
							(start -0.2794 0.1778)
							(mid -0.249642 0.249642)
							(end -0.1778 0.2794)
						)
						(arc
							(start 0.1778 0.2794)
							(mid 0.249642 0.249642)
							(end 0.2794 0.1778)
						)
						(arc
							(start 0.2794 -0.1778)
							(mid 0.249642 -0.249642)
							(end 0.1778 -0.2794)
						)
					)
					(width 0)
					(fill yes)
				)
			)
		)
		(pad "2" smd custom
			(at 0 0.4445 90)
			(size 0.1397 0.1397)
			(layers "F.Cu" "F.Mask" "F.Paste")
			(net "MB0_TEMP_C")
			(options
				(clearance outline)
				(anchor circle)
			)
			(primitives
				(gr_poly
					(pts
						(arc
							(start -0.1778 -0.2794)
							(mid -0.249642 -0.249642)
							(end -0.2794 -0.1778)
						)
						(arc
							(start -0.2794 0.1778)
							(mid -0.249642 0.249642)
							(end -0.1778 0.2794)
						)
						(arc
							(start 0.1778 0.2794)
							(mid 0.249642 0.249642)
							(end 0.2794 0.1778)
						)
						(arc
							(start 0.2794 -0.1778)
							(mid 0.249642 -0.249642)
							(end 0.1778 -0.2794)
						)
					)
					(width 0)
					(fill yes)
				)
			)
		)
	)
	(footprint ""
		(layer "F.Cu")
		(at 140.335 -34.949638 -90)
		(property "Reference" "R206"
			(at 0 0 270)
			(layer "F.SilkS")
			(hide yes)
			(effects
				(font
					(size 1.27 1.27)
				)
			)
		)
		(property "Value" "4K7R2F-GP"
			(at 0.064008 -3.993896 270)
			(unlocked yes)
			(layer "F.Fab")
			(hide yes)
			(effects
				(font
					(size 1.016 1.016)
					(thickness 0.1524)
				)
			)
		)
		(property "Device Type" "R402H16"
			(at 0.064008 -5.517896 270)
			(unlocked yes)
			(layer "F.Fab")
			(hide yes)
			(effects
				(font
					(size 1.016 1.016)
					(thickness 0.1524)
				)
			)
		)
		(duplicate_pad_numbers_are_jumpers no)
		(fp_line
			(start -0.508 -0.9398)
			(end -0.508 0.9398)
			(stroke
				(width 0.1524)
				(type default)
			)
			(layer "F.SilkS")
		)
		(fp_line
			(start 0.508 -0.9398)
			(end -0.508 -0.9398)
			(stroke
				(width 0.1524)
				(type default)
			)
			(layer "F.SilkS")
		)
		(fp_rect
			(start -0.508 0.9398)
			(end 0.508 -0.9398)
			(stroke
				(width 0)
				(type default)
			)
			(fill no)
			(layer "F.CrtYd")
		)
		(fp_rect
			(start -0.508 0.9398)
			(end 0.508 -0.9398)
			(stroke
				(width 0)
				(type default)
			)
			(fill no)
			(layer "F.Fab")
		)
		(pad "1" smd custom
			(at 0 -0.4445 270)
			(size 0.1397 0.1397)
			(layers "F.Cu" "F.Mask" "F.Paste")
			(net "CLK_P_2_R")
			(options
				(clearance outline)
				(anchor circle)
			)
			(primitives
				(gr_poly
					(pts
						(arc
							(start -0.1778 -0.2794)
							(mid -0.249642 -0.249642)
							(end -0.2794 -0.1778)
						)
						(arc
							(start -0.2794 0.1778)
							(mid -0.249642 0.249642)
							(end -0.1778 0.2794)
						)
						(arc
							(start 0.1778 0.2794)
							(mid 0.249642 0.249642)
							(end 0.2794 0.1778)
						)
						(arc
							(start 0.2794 -0.1778)
							(mid 0.249642 -0.249642)
							(end 0.1778 -0.2794)
						)
					)
					(width 0)
					(fill yes)
				)
			)
		)
		(pad "2" smd custom
			(at 0 0.4445 270)
			(size 0.1397 0.1397)
			(layers "F.Cu" "F.Mask" "F.Paste")
			(net "GND")
			(options
				(clearance outline)
				(anchor circle)
			)
			(primitives
				(gr_poly
					(pts
						(arc
							(start -0.1778 -0.2794)
							(mid -0.249642 -0.249642)
							(end -0.2794 -0.1778)
						)
						(arc
							(start -0.2794 0.1778)
							(mid -0.249642 0.249642)
							(end -0.1778 0.2794)
						)
						(arc
							(start 0.1778 0.2794)
							(mid 0.249642 0.249642)
							(end 0.2794 0.1778)
						)
						(arc
							(start 0.2794 -0.1778)
							(mid 0.249642 -0.249642)
							(end 0.1778 -0.2794)
						)
					)
					(width 0)
					(fill yes)
				)
			)
		)
	)
	(footprint ""
		(layer "F.Cu")
		(at 23.3172 -183.2356 180)
		(property "Reference" "R9026"
			(at 0 0 180)
			(layer "F.SilkS")
			(hide yes)
			(effects
				(font
					(size 1.27 1.27)
				)
			)
		)
		(property "Value" "100R2D-GP"
			(at 0.064008 -3.993896 180)
			(unlocked yes)
			(layer "F.Fab")
			(hide yes)
			(effects
				(font
					(size 1.016 1.016)
					(thickness 0.1524)
				)
			)
		)
		(property "Device Type" "R402H14"
			(at 0.064008 -5.517896 180)
			(unlocked yes)
			(layer "F.Fab")
			(hide yes)
			(effects
				(font
					(size 1.016 1.016)
					(thickness 0.1524)
				)
			)
		)
		(duplicate_pad_numbers_are_jumpers no)
		(fp_line
			(start 0.508 -0.9398)
			(end -0.508 -0.9398)
			(stroke
				(width 0.1524)
				(type default)
			)
			(layer "F.SilkS")
		)
		(fp_line
			(start -0.508 -0.9398)
			(end -0.508 0.9398)
			(stroke
				(width 0.1524)
				(type default)
			)
			(layer "F.SilkS")
		)
		(fp_rect
			(start -0.508 0.9398)
			(end 0.508 -0.9398)
			(stroke
				(width 0)
				(type default)
			)
			(fill no)
			(layer "F.CrtYd")
		)
		(fp_rect
			(start -0.508 0.9398)
			(end 0.508 -0.9398)
			(stroke
				(width 0)
				(type default)
			)
			(fill no)
			(layer "F.Fab")
		)
		(pad "1" smd custom
			(at 0 -0.4445 180)
			(size 0.1397 0.1397)
			(layers "F.Cu" "F.Mask" "F.Paste")
			(net "GND")
			(options
				(clearance outline)
				(anchor circle)
			)
			(primitives
				(gr_poly
					(pts
						(arc
							(start -0.1778 -0.2794)
							(mid -0.249642 -0.249642)
							(end -0.2794 -0.1778)
						)
						(arc
							(start -0.2794 0.1778)
							(mid -0.249642 0.249642)
							(end -0.1778 0.2794)
						)
						(arc
							(start 0.1778 0.2794)
							(mid 0.249642 0.249642)
							(end 0.2794 0.1778)
						)
						(arc
							(start 0.2794 -0.1778)
							(mid 0.249642 -0.249642)
							(end 0.1778 -0.2794)
						)
					)
					(width 0)
					(fill yes)
				)
			)
		)
		(pad "2" smd custom
			(at 0 0.4445 180)
			(size 0.1397 0.1397)
			(layers "F.Cu" "F.Mask" "F.Paste")
			(net "MB0_TEMP_E")
			(options
				(clearance outline)
				(anchor circle)
			)
			(primitives
				(gr_poly
					(pts
						(arc
							(start -0.1778 -0.2794)
							(mid -0.249642 -0.249642)
							(end -0.2794 -0.1778)
						)
						(arc
							(start -0.2794 0.1778)
							(mid -0.249642 0.249642)
							(end -0.1778 0.2794)
						)
						(arc
							(start 0.1778 0.2794)
							(mid 0.249642 0.249642)
							(end 0.2794 0.1778)
						)
						(arc
							(start 0.2794 -0.1778)
							(mid 0.249642 -0.249642)
							(end 0.1778 -0.2794)
						)
					)
					(width 0)
					(fill yes)
				)
			)
		)
	)
	(footprint ""
		(layer "F.Cu")
		(at 50.673 -186.817 180)
		(property "Reference" "R900"
			(at 0 0 180)
			(layer "F.SilkS")
			(hide yes)
			(effects
				(font
					(size 1.27 1.27)
				)
			)
		)
		(property "Value" "0R2J-2-GP"
			(at 0.064008 -3.993896 180)
			(unlocked yes)
			(layer "F.Fab")
			(hide yes)
			(effects
				(font
					(size 1.016 1.016)
					(thickness 0.1524)
				)
			)
		)
		(property "Device Type" "R402H16"
			(at 0.064008 -5.517896 180)
			(unlocked yes)
			(layer "F.Fab")
			(hide yes)
			(effects
				(font
					(size 1.016 1.016)
					(thickness 0.1524)
				)
			)
		)
		(duplicate_pad_numbers_are_jumpers no)
		(fp_line
			(start 0.508 -0.9398)
			(end -0.508 -0.9398)
			(stroke
				(width 0.1524)
				(type default)
			)
			(layer "F.SilkS")
		)
		(fp_line
			(start -0.508 -0.9398)
			(end -0.508 0.9398)
			(stroke
				(width 0.1524)
				(type default)
			)
			(layer "F.SilkS")
		)
		(fp_rect
			(start -0.508 0.9398)
			(end 0.508 -0.9398)
			(stroke
				(width 0)
				(type default)
			)
			(fill no)
			(layer "F.CrtYd")
		)
		(fp_rect
			(start -0.508 0.9398)
			(end 0.508 -0.9398)
			(stroke
				(width 0)
				(type default)
			)
			(fill no)
			(layer "F.Fab")
		)
		(pad "1" smd custom
			(at 0 -0.4445 180)
			(size 0.1397 0.1397)
			(layers "F.Cu" "F.Mask" "F.Paste")
			(net "BUF_I2C8_CLKBUF1_SDA_R")
			(options
				(clearance outline)
				(anchor circle)
			)
			(primitives
				(gr_poly
					(pts
						(arc
							(start -0.1778 -0.2794)
							(mid -0.249642 -0.249642)
							(end -0.2794 -0.1778)
						)
						(arc
							(start -0.2794 0.1778)
							(mid -0.249642 0.249642)
							(end -0.1778 0.2794)
						)
						(arc
							(start 0.1778 0.2794)
							(mid 0.249642 0.249642)
							(end 0.2794 0.1778)
						)
						(arc
							(start 0.2794 -0.1778)
							(mid 0.249642 -0.249642)
							(end 0.1778 -0.2794)
						)
					)
					(width 0)
					(fill yes)
				)
			)
		)
		(pad "2" smd custom
			(at 0 0.4445 180)
			(size 0.1397 0.1397)
			(layers "F.Cu" "F.Mask" "F.Paste")
			(net "BUF_I2C8_CLKBUF1_SDA")
			(options
				(clearance outline)
				(anchor circle)
			)
			(primitives
				(gr_poly
					(pts
						(arc
							(start -0.1778 -0.2794)
							(mid -0.249642 -0.249642)
							(end -0.2794 -0.1778)
						)
						(arc
							(start -0.2794 0.1778)
							(mid -0.249642 0.249642)
							(end -0.1778 0.2794)
						)
						(arc
							(start 0.1778 0.2794)
							(mid 0.249642 0.249642)
							(end 0.2794 0.1778)
						)
						(arc
							(start 0.2794 -0.1778)
							(mid 0.249642 -0.249642)
							(end 0.1778 -0.2794)
						)
					)
					(width 0)
					(fill yes)
				)
			)
		)
	)
	(footprint ""
		(layer "F.Cu")
		(at 36.847526 -161.70148 90)
		(property "Reference" "R232"
			(at 0 0 90)
			(layer "F.SilkS")
			(hide yes)
			(effects
				(font
					(size 1.27 1.27)
				)
			)
		)
		(property "Value" "1KR2F-3-GP"
			(at 0.064008 -3.993896 90)
			(unlocked yes)
			(layer "F.Fab")
			(hide yes)
			(effects
				(font
					(size 1.016 1.016)
					(thickness 0.1524)
				)
			)
		)
		(property "Device Type" "R402H16"
			(at 0.064008 -5.517896 90)
			(unlocked yes)
			(layer "F.Fab")
			(hide yes)
			(effects
				(font
					(size 1.016 1.016)
					(thickness 0.1524)
				)
			)
		)
		(duplicate_pad_numbers_are_jumpers no)
		(fp_line
			(start 0.508 -0.9398)
			(end -0.508 -0.9398)
			(stroke
				(width 0.1524)
				(type default)
			)
			(layer "F.SilkS")
		)
		(fp_line
			(start -0.508 -0.9398)
			(end -0.508 0.9398)
			(stroke
				(width 0.1524)
				(type default)
			)
			(layer "F.SilkS")
		)
		(fp_rect
			(start -0.508 0.9398)
			(end 0.508 -0.9398)
			(stroke
				(width 0)
				(type default)
			)
			(fill no)
			(layer "F.CrtYd")
		)
		(fp_rect
			(start -0.508 0.9398)
			(end 0.508 -0.9398)
			(stroke
				(width 0)
				(type default)
			)
			(fill no)
			(layer "F.Fab")
		)
		(pad "1" smd custom
			(at 0 -0.4445 90)
			(size 0.1397 0.1397)
			(layers "F.Cu" "F.Mask" "F.Paste")
			(net "DDR_VREF")
			(options
				(clearance outline)
				(anchor circle)
			)
			(primitives
				(gr_poly
					(pts
						(arc
							(start -0.1778 -0.2794)
							(mid -0.249642 -0.249642)
							(end -0.2794 -0.1778)
						)
						(arc
							(start -0.2794 0.1778)
							(mid -0.249642 0.249642)
							(end -0.1778 0.2794)
						)
						(arc
							(start 0.1778 0.2794)
							(mid 0.249642 0.249642)
							(end 0.2794 0.1778)
						)
						(arc
							(start 0.2794 -0.1778)
							(mid 0.249642 -0.249642)
							(end 0.1778 -0.2794)
						)
					)
					(width 0)
					(fill yes)
				)
			)
		)
		(pad "2" smd custom
			(at 0 0.4445 90)
			(size 0.1397 0.1397)
			(layers "F.Cu" "F.Mask" "F.Paste")
			(net "GND")
			(options
				(clearance outline)
				(anchor circle)
			)
			(primitives
				(gr_poly
					(pts
						(arc
							(start -0.1778 -0.2794)
							(mid -0.249642 -0.249642)
							(end -0.2794 -0.1778)
						)
						(arc
							(start -0.2794 0.1778)
							(mid -0.249642 0.249642)
							(end -0.1778 0.2794)
						)
						(arc
							(start 0.1778 0.2794)
							(mid 0.249642 0.249642)
							(end 0.2794 0.1778)
						)
						(arc
							(start 0.2794 -0.1778)
							(mid 0.249642 -0.249642)
							(end 0.1778 -0.2794)
						)
					)
					(width 0)
					(fill yes)
				)
			)
		)
	)
	(footprint ""
		(layer "F.Cu")
		(at 40.259 -205.359 90)
		(property "Reference" "R876"
			(at 0 0 90)
			(layer "F.SilkS")
			(hide yes)
			(effects
				(font
					(size 1.27 1.27)
				)
			)
		)
		(property "Value" "4K7R2J-2-GP"
			(at 0.064008 -3.993896 90)
			(unlocked yes)
			(layer "F.Fab")
			(hide yes)
			(effects
				(font
					(size 1.016 1.016)
					(thickness 0.1524)
				)
			)
		)
		(property "Device Type" "R402H16"
			(at 0.064008 -5.517896 90)
			(unlocked yes)
			(layer "F.Fab")
			(hide yes)
			(effects
				(font
					(size 1.016 1.016)
					(thickness 0.1524)
				)
			)
		)
		(duplicate_pad_numbers_are_jumpers no)
		(fp_line
			(start 0.508 -0.9398)
			(end -0.508 -0.9398)
			(stroke
				(width 0.1524)
				(type default)
			)
			(layer "F.SilkS")
		)
		(fp_line
			(start -0.508 -0.9398)
			(end -0.508 0.9398)
			(stroke
				(width 0.1524)
				(type default)
			)
			(layer "F.SilkS")
		)
		(fp_rect
			(start -0.508 0.9398)
			(end 0.508 -0.9398)
			(stroke
				(width 0)
				(type default)
			)
			(fill no)
			(layer "F.CrtYd")
		)
		(fp_rect
			(start -0.508 0.9398)
			(end 0.508 -0.9398)
			(stroke
				(width 0)
				(type default)
			)
			(fill no)
			(layer "F.Fab")
		)
		(pad "1" smd custom
			(at 0 -0.4445 90)
			(size 0.1397 0.1397)
			(layers "F.Cu" "F.Mask" "F.Paste")
			(net "P3V3_STBY")
			(options
				(clearance outline)
				(anchor circle)
			)
			(primitives
				(gr_poly
					(pts
						(arc
							(start -0.1778 -0.2794)
							(mid -0.249642 -0.249642)
							(end -0.2794 -0.1778)
						)
						(arc
							(start -0.2794 0.1778)
							(mid -0.249642 0.249642)
							(end -0.1778 0.2794)
						)
						(arc
							(start 0.1778 0.2794)
							(mid 0.249642 0.249642)
							(end 0.2794 0.1778)
						)
						(arc
							(start 0.2794 -0.1778)
							(mid 0.249642 -0.249642)
							(end 0.1778 -0.2794)
						)
					)
					(width 0)
					(fill yes)
				)
			)
		)
		(pad "2" smd custom
			(at 0 0.4445 90)
			(size 0.1397 0.1397)
			(layers "F.Cu" "F.Mask" "F.Paste")
			(net "BUF_I2C6_C_FCB_SDA_R")
			(options
				(clearance outline)
				(anchor circle)
			)
			(primitives
				(gr_poly
					(pts
						(arc
							(start -0.1778 -0.2794)
							(mid -0.249642 -0.249642)
							(end -0.2794 -0.1778)
						)
						(arc
							(start -0.2794 0.1778)
							(mid -0.249642 0.249642)
							(end -0.1778 0.2794)
						)
						(arc
							(start 0.1778 0.2794)
							(mid 0.249642 0.249642)
							(end 0.2794 0.1778)
						)
						(arc
							(start 0.2794 -0.1778)
							(mid 0.249642 -0.249642)
							(end 0.1778 -0.2794)
						)
					)
					(width 0)
					(fill yes)
				)
			)
		)
	)
	(footprint ""
		(layer "F.Cu")
		(at 31.9786 -181.4322 90)
		(property "Reference" "C244"
			(at 0 0 90)
			(layer "F.SilkS")
			(hide yes)
			(effects
				(font
					(size 1.27 1.27)
				)
			)
		)
		(property "Value" "SCD01U50V2KX-1GP"
			(at 1.1811 -2.7051 90)
			(unlocked yes)
			(layer "F.Fab")
			(hide yes)
			(effects
				(font
					(size 1.016 1.016)
					(thickness 0.1524)
				)
			)
		)
		(property "Device Type" "C402H22"
			(at 1.1811 -4.2291 90)
			(unlocked yes)
			(layer "F.Fab")
			(hide yes)
			(effects
				(font
					(size 1.016 1.016)
					(thickness 0.1524)
				)
			)
		)
		(duplicate_pad_numbers_are_jumpers no)
		(fp_rect
			(start -0.4318 0.9525)
			(end 0.4318 -0.9525)
			(stroke
				(width 0)
				(type default)
			)
			(fill no)
			(layer "F.CrtYd")
		)
		(fp_rect
			(start -0.4318 0.9525)
			(end 0.4318 -0.9525)
			(stroke
				(width 0)
				(type default)
			)
			(fill no)
			(layer "F.Fab")
		)
		(pad "1" smd custom
			(at 0 -0.4445 90)
			(size 0.1524 0.1524)
			(layers "F.Cu" "F.Mask" "F.Paste")
			(net "P3V3_STBY")
			(options
				(clearance outline)
				(anchor circle)
			)
			(primitives
				(gr_poly
					(pts
						(arc
							(start 0.3048 -0.2032)
							(mid 0.275042 -0.275042)
							(end 0.2032 -0.3048)
						)
						(arc
							(start -0.2032 -0.3048)
							(mid -0.275042 -0.275042)
							(end -0.3048 -0.2032)
						)
						(arc
							(start -0.3048 0.2032)
							(mid -0.275042 0.275042)
							(end -0.2032 0.3048)
						)
						(arc
							(start 0.2032 0.3048)
							(mid 0.275042 0.275042)
							(end 0.3048 0.2032)
						)
					)
					(width 0)
					(fill yes)
				)
			)
		)
		(pad "2" smd custom
			(at 0 0.4445 90)
			(size 0.1524 0.1524)
			(layers "F.Cu" "F.Mask" "F.Paste")
			(net "GND")
			(options
				(clearance outline)
				(anchor circle)
			)
			(primitives
				(gr_poly
					(pts
						(arc
							(start 0.3048 -0.2032)
							(mid 0.275042 -0.275042)
							(end 0.2032 -0.3048)
						)
						(arc
							(start -0.2032 -0.3048)
							(mid -0.275042 -0.275042)
							(end -0.3048 -0.2032)
						)
						(arc
							(start -0.3048 0.2032)
							(mid -0.275042 0.275042)
							(end -0.2032 0.3048)
						)
						(arc
							(start 0.2032 0.3048)
							(mid 0.275042 0.275042)
							(end 0.3048 0.2032)
						)
					)
					(width 0)
					(fill yes)
				)
			)
		)
	)
	(footprint ""
		(layer "F.Cu")
		(at 16.4846 -196.5706 180)
		(property "Reference" "C7277"
			(at 0 0 180)
			(layer "F.SilkS")
			(hide yes)
			(effects
				(font
					(size 1.27 1.27)
				)
			)
		)
		(property "Value" "SC1U16V3KX-5GP"
			(at 0 -2.8194 180)
			(unlocked yes)
			(layer "F.Fab")
			(hide yes)
			(effects
				(font
					(size 1.016 1.016)
					(thickness 0.1524)
				)
			)
		)
		(property "Device Type" "C603H36"
			(at 0 -4.3434 180)
			(unlocked yes)
			(layer "F.Fab")
			(hide yes)
			(effects
				(font
					(size 1.016 1.016)
					(thickness 0.1524)
				)
			)
		)
		(duplicate_pad_numbers_are_jumpers no)
		(fp_line
			(start 0.508 0)
			(end -0.508 0)
			(stroke
				(width 0.2032)
				(type default)
			)
			(layer "F.SilkS")
		)
		(fp_rect
			(start -0.5842 1.3335)
			(end 0.5842 -1.3335)
			(stroke
				(width 0)
				(type default)
			)
			(fill no)
			(layer "F.CrtYd")
		)
		(fp_rect
			(start -0.5842 1.3335)
			(end 0.5842 -1.3335)
			(stroke
				(width 0)
				(type default)
			)
			(fill no)
			(layer "F.Fab")
		)
		(pad "1" smd custom
			(at 0 -0.762 180)
			(size 0.2159 0.2159)
			(layers "F.Cu" "F.Mask" "F.Paste")
			(net "MB0_VCAP_R")
			(options
				(clearance outline)
				(anchor circle)
			)
			(primitives
				(gr_poly
					(pts
						(arc
							(start -0.3302 -0.4318)
							(mid -0.402042 -0.402042)
							(end -0.4318 -0.3302)
						)
						(arc
							(start -0.4318 0.3302)
							(mid -0.402042 0.402042)
							(end -0.3302 0.4318)
						)
						(arc
							(start 0.3302 0.4318)
							(mid 0.402042 0.402042)
							(end 0.4318 0.3302)
						)
						(arc
							(start 0.4318 -0.3302)
							(mid 0.402042 -0.402042)
							(end 0.3302 -0.4318)
						)
					)
					(width 0)
					(fill yes)
				)
			)
		)
		(pad "2" smd custom
			(at 0 0.762 180)
			(size 0.2159 0.2159)
			(layers "F.Cu" "F.Mask" "F.Paste")
			(net "AGND_CURRENT_MON")
			(options
				(clearance outline)
				(anchor circle)
			)
			(primitives
				(gr_poly
					(pts
						(arc
							(start -0.3302 -0.4318)
							(mid -0.402042 -0.402042)
							(end -0.4318 -0.3302)
						)
						(arc
							(start -0.4318 0.3302)
							(mid -0.402042 0.402042)
							(end -0.3302 0.4318)
						)
						(arc
							(start 0.3302 0.4318)
							(mid 0.402042 0.402042)
							(end 0.4318 0.3302)
						)
						(arc
							(start 0.4318 -0.3302)
							(mid 0.402042 -0.402042)
							(end 0.3302 -0.4318)
						)
					)
					(width 0)
					(fill yes)
				)
			)
		)
	)
	(footprint ""
		(layer "F.Cu")
		(at 56.7182 -40.7924 -90)
		(property "Reference" "R628"
			(at 0 0 270)
			(layer "F.SilkS")
			(hide yes)
			(effects
				(font
					(size 1.27 1.27)
				)
			)
		)
		(property "Value" "56R6J-GP"
			(at -0.0508 -4.8514 270)
			(unlocked yes)
			(layer "F.Fab")
			(hide yes)
			(effects
				(font
					(size 1.016 1.016)
					(thickness 0.1524)
				)
			)
		)
		(property "Device Type" "R1206H26"
			(at 0 -6.3754 270)
			(unlocked yes)
			(layer "F.Fab")
			(hide yes)
			(effects
				(font
					(size 1.016 1.016)
					(thickness 0.1524)
				)
			)
		)
		(duplicate_pad_numbers_are_jumpers no)
		(fp_line
			(start -1.016 2.2352)
			(end -1.016 -2.2352)
			(stroke
				(width 0.1524)
				(type default)
			)
			(layer "F.SilkS")
		)
		(fp_line
			(start 1.016 2.2352)
			(end -1.016 2.2352)
			(stroke
				(width 0.1524)
				(type default)
			)
			(layer "F.SilkS")
		)
		(fp_line
			(start -1.016 -2.2352)
			(end 1.016 -2.2352)
			(stroke
				(width 0.1524)
				(type default)
			)
			(layer "F.SilkS")
		)
		(fp_line
			(start 1.016 -2.2352)
			(end 1.016 2.2352)
			(stroke
				(width 0.1524)
				(type default)
			)
			(layer "F.SilkS")
		)
		(fp_rect
			(start -1.0922 2.3114)
			(end 1.0922 -2.3114)
			(stroke
				(width 0)
				(type default)
			)
			(fill no)
			(layer "F.CrtYd")
		)
		(fp_poly
			(pts
				(xy -1.0922 -2.3114) (xy 1.0922 -2.3114) (xy 1.0922 2.3114) (xy -1.0922 2.3114)
			)
			(stroke
				(width 0)
				(type default)
			)
			(fill no)
			(layer "F.Fab")
		)
		(pad "1" smd rect
			(at 0 -1.397 270)
			(size 1.651 1.27)
			(layers "F.Cu" "F.Mask" "F.Paste")
			(net "P3V3_STBY")
		)
		(pad "2" smd rect
			(at 0 1.397 270)
			(size 1.651 1.27)
			(layers "F.Cu" "F.Mask" "F.Paste")
			(net "Q43_C")
		)
	)
	(footprint ""
		(layer "F.Cu")
		(at 268.31544 -17.61617 90)
		(property "Reference" "SR722"
			(at 0 0 90)
			(layer "F.SilkS")
			(hide yes)
			(effects
				(font
					(size 1.27 1.27)
				)
			)
		)
		(property "Value" "150R2F-1-GP"
			(at 0.064008 -3.993896 90)
			(unlocked yes)
			(layer "F.Fab")
			(hide yes)
			(effects
				(font
					(size 1.016 1.016)
					(thickness 0.1524)
				)
			)
		)
		(property "Device Type" "R402H16"
			(at 0.064008 -5.517896 90)
			(unlocked yes)
			(layer "F.Fab")
			(hide yes)
			(effects
				(font
					(size 1.016 1.016)
					(thickness 0.1524)
				)
			)
		)
		(duplicate_pad_numbers_are_jumpers no)
		(fp_line
			(start 0.508 -0.9398)
			(end -0.508 -0.9398)
			(stroke
				(width 0.1524)
				(type default)
			)
			(layer "F.SilkS")
		)
		(fp_line
			(start -0.508 -0.9398)
			(end -0.508 0.9398)
			(stroke
				(width 0.1524)
				(type default)
			)
			(layer "F.SilkS")
		)
		(fp_rect
			(start -0.508 0.9398)
			(end 0.508 -0.9398)
			(stroke
				(width 0)
				(type default)
			)
			(fill no)
			(layer "F.CrtYd")
		)
		(fp_rect
			(start -0.508 0.9398)
			(end 0.508 -0.9398)
			(stroke
				(width 0)
				(type default)
			)
			(fill no)
			(layer "F.Fab")
		)
		(pad "1" smd custom
			(at 0 -0.4445 90)
			(size 0.1397 0.1397)
			(layers "F.Cu" "F.Mask" "F.Paste")
			(net "P3V3_STBY")
			(options
				(clearance outline)
				(anchor circle)
			)
			(primitives
				(gr_poly
					(pts
						(arc
							(start -0.1778 -0.2794)
							(mid -0.249642 -0.249642)
							(end -0.2794 -0.1778)
						)
						(arc
							(start -0.2794 0.1778)
							(mid -0.249642 0.249642)
							(end -0.1778 0.2794)
						)
						(arc
							(start 0.1778 0.2794)
							(mid 0.249642 0.249642)
							(end 0.2794 0.1778)
						)
						(arc
							(start 0.2794 -0.1778)
							(mid 0.249642 -0.249642)
							(end 0.1778 -0.2794)
						)
					)
					(width 0)
					(fill yes)
				)
			)
		)
		(pad "2" smd custom
			(at 0 0.4445 90)
			(size 0.1397 0.1397)
			(layers "F.Cu" "F.Mask" "F.Paste")
			(net "LED_R_13")
			(options
				(clearance outline)
				(anchor circle)
			)
			(primitives
				(gr_poly
					(pts
						(arc
							(start -0.1778 -0.2794)
							(mid -0.249642 -0.249642)
							(end -0.2794 -0.1778)
						)
						(arc
							(start -0.2794 0.1778)
							(mid -0.249642 0.249642)
							(end -0.1778 0.2794)
						)
						(arc
							(start 0.1778 0.2794)
							(mid 0.249642 0.249642)
							(end 0.2794 0.1778)
						)
						(arc
							(start 0.2794 -0.1778)
							(mid 0.249642 -0.249642)
							(end 0.1778 -0.2794)
						)
					)
					(width 0)
					(fill yes)
				)
			)
		)
	)
	(footprint ""
		(layer "F.Cu")
		(at 33.1978 -189.2808 -90)
		(property "Reference" "R486"
			(at 0 0 270)
			(layer "F.SilkS")
			(hide yes)
			(effects
				(font
					(size 1.27 1.27)
				)
			)
		)
		(property "Value" "10KR2F-2-GP"
			(at 0.064008 -3.993896 270)
			(unlocked yes)
			(layer "F.Fab")
			(hide yes)
			(effects
				(font
					(size 1.016 1.016)
					(thickness 0.1524)
				)
			)
		)
		(property "Device Type" "R402H16"
			(at 0.064008 -5.517896 270)
			(unlocked yes)
			(layer "F.Fab")
			(hide yes)
			(effects
				(font
					(size 1.016 1.016)
					(thickness 0.1524)
				)
			)
		)
		(duplicate_pad_numbers_are_jumpers no)
		(fp_line
			(start -0.508 -0.9398)
			(end -0.508 0.9398)
			(stroke
				(width 0.1524)
				(type default)
			)
			(layer "F.SilkS")
		)
		(fp_line
			(start 0.508 -0.9398)
			(end -0.508 -0.9398)
			(stroke
				(width 0.1524)
				(type default)
			)
			(layer "F.SilkS")
		)
		(fp_rect
			(start -0.508 0.9398)
			(end 0.508 -0.9398)
			(stroke
				(width 0)
				(type default)
			)
			(fill no)
			(layer "F.CrtYd")
		)
		(fp_rect
			(start -0.508 0.9398)
			(end 0.508 -0.9398)
			(stroke
				(width 0)
				(type default)
			)
			(fill no)
			(layer "F.Fab")
		)
		(pad "1" smd custom
			(at 0 -0.4445 270)
			(size 0.1397 0.1397)
			(layers "F.Cu" "F.Mask" "F.Paste")
			(net "P3V3_STBY")
			(options
				(clearance outline)
				(anchor circle)
			)
			(primitives
				(gr_poly
					(pts
						(arc
							(start -0.1778 -0.2794)
							(mid -0.249642 -0.249642)
							(end -0.2794 -0.1778)
						)
						(arc
							(start -0.2794 0.1778)
							(mid -0.249642 0.249642)
							(end -0.1778 0.2794)
						)
						(arc
							(start 0.1778 0.2794)
							(mid 0.249642 0.249642)
							(end 0.2794 0.1778)
						)
						(arc
							(start 0.2794 -0.1778)
							(mid 0.249642 -0.249642)
							(end 0.1778 -0.2794)
						)
					)
					(width 0)
					(fill yes)
				)
			)
		)
		(pad "2" smd custom
			(at 0 0.4445 270)
			(size 0.1397 0.1397)
			(layers "F.Cu" "F.Mask" "F.Paste")
			(net "I2C5_BUFF_EN")
			(options
				(clearance outline)
				(anchor circle)
			)
			(primitives
				(gr_poly
					(pts
						(arc
							(start -0.1778 -0.2794)
							(mid -0.249642 -0.249642)
							(end -0.2794 -0.1778)
						)
						(arc
							(start -0.2794 0.1778)
							(mid -0.249642 0.249642)
							(end -0.1778 0.2794)
						)
						(arc
							(start 0.1778 0.2794)
							(mid 0.249642 0.249642)
							(end 0.2794 0.1778)
						)
						(arc
							(start 0.2794 -0.1778)
							(mid 0.249642 -0.249642)
							(end 0.1778 -0.2794)
						)
					)
					(width 0)
					(fill yes)
				)
			)
		)
	)
	(footprint ""
		(layer "F.Cu")
		(at 223.2152 -13.8684)
		(property "Reference" "C271"
			(at 0 0 0)
			(layer "F.SilkS")
			(hide yes)
			(effects
				(font
					(size 1.27 1.27)
				)
			)
		)
		(property "Value" "SC1U10V2KX-4-GP"
			(at 1.1811 -2.7051 0)
			(unlocked yes)
			(layer "F.Fab")
			(hide yes)
			(effects
				(font
					(size 1.016 1.016)
					(thickness 0.1524)
				)
			)
		)
		(property "Device Type" "C402H22"
			(at 1.1811 -4.2291 0)
			(unlocked yes)
			(layer "F.Fab")
			(hide yes)
			(effects
				(font
					(size 1.016 1.016)
					(thickness 0.1524)
				)
			)
		)
		(duplicate_pad_numbers_are_jumpers no)
		(fp_rect
			(start -0.4318 0.9525)
			(end 0.4318 -0.9525)
			(stroke
				(width 0)
				(type default)
			)
			(fill no)
			(layer "F.CrtYd")
		)
		(fp_rect
			(start -0.4318 0.9525)
			(end 0.4318 -0.9525)
			(stroke
				(width 0)
				(type default)
			)
			(fill no)
			(layer "F.Fab")
		)
		(pad "1" smd custom
			(at 0 -0.4445)
			(size 0.1524 0.1524)
			(layers "F.Cu" "F.Mask" "F.Paste")
			(net "U82_MR#")
			(options
				(clearance outline)
				(anchor circle)
			)
			(primitives
				(gr_poly
					(pts
						(arc
							(start 0.3048 -0.2032)
							(mid 0.275042 -0.275042)
							(end 0.2032 -0.3048)
						)
						(arc
							(start -0.2032 -0.3048)
							(mid -0.275042 -0.275042)
							(end -0.3048 -0.2032)
						)
						(arc
							(start -0.3048 0.2032)
							(mid -0.275042 0.275042)
							(end -0.2032 0.3048)
						)
						(arc
							(start 0.2032 0.3048)
							(mid 0.275042 0.275042)
							(end 0.3048 0.2032)
						)
					)
					(width 0)
					(fill yes)
				)
			)
		)
		(pad "2" smd custom
			(at 0 0.4445)
			(size 0.1524 0.1524)
			(layers "F.Cu" "F.Mask" "F.Paste")
			(net "GND")
			(options
				(clearance outline)
				(anchor circle)
			)
			(primitives
				(gr_poly
					(pts
						(arc
							(start 0.3048 -0.2032)
							(mid 0.275042 -0.275042)
							(end 0.2032 -0.3048)
						)
						(arc
							(start -0.2032 -0.3048)
							(mid -0.275042 -0.275042)
							(end -0.3048 -0.2032)
						)
						(arc
							(start -0.3048 0.2032)
							(mid -0.275042 0.275042)
							(end -0.2032 0.3048)
						)
						(arc
							(start 0.2032 0.3048)
							(mid 0.275042 0.275042)
							(end 0.3048 0.2032)
						)
					)
					(width 0)
					(fill yes)
				)
			)
		)
	)
	(footprint ""
		(layer "F.Cu")
		(at 174.721774 -51.102768 180)
		(property "Reference" "Q32"
			(at 0 0 180)
			(layer "F.SilkS")
			(hide yes)
			(effects
				(font
					(size 1.27 1.27)
				)
			)
		)
		(property "Value" "2N7002K-1-GP"
			(at 0.127 -8.9662 180)
			(unlocked yes)
			(layer "F.Fab")
			(hide yes)
			(effects
				(font
					(size 1.016 1.016)
					(thickness 0.1524)
				)
			)
		)
		(property "Device Type" "SOT23DGS2D4H44"
			(at 0.127 -10.4902 180)
			(unlocked yes)
			(layer "F.Fab")
			(hide yes)
			(effects
				(font
					(size 1.016 1.016)
					(thickness 0.1524)
				)
			)
		)
		(duplicate_pad_numbers_are_jumpers no)
		(fp_line
			(start 1.651 1.778)
			(end 1.651 -1.778)
			(stroke
				(width 0.1524)
				(type default)
			)
			(layer "F.SilkS")
		)
		(fp_line
			(start 1.651 -1.778)
			(end -1.651 -1.778)
			(stroke
				(width 0.1524)
				(type default)
			)
			(layer "F.SilkS")
		)
		(fp_line
			(start -1.651 1.778)
			(end 1.651 1.778)
			(stroke
				(width 0.1524)
				(type default)
			)
			(layer "F.SilkS")
		)
		(fp_line
			(start -1.651 -1.778)
			(end -1.651 1.778)
			(stroke
				(width 0.1524)
				(type default)
			)
			(layer "F.SilkS")
		)
		(fp_poly
			(pts
				(xy -1.778 1.8796) (xy -1.778 -1.8796) (xy 1.778 -1.8796) (xy 1.778 1.8796)
			)
			(stroke
				(width 0)
				(type default)
			)
			(fill no)
			(layer "F.CrtYd")
		)
		(fp_poly
			(pts
				(xy -1.778 1.8796) (xy -1.778 -1.8796) (xy 1.778 -1.8796) (xy 1.778 1.8796)
			)
			(stroke
				(width 0)
				(type default)
			)
			(fill no)
			(layer "F.Fab")
		)
		(pad "D" smd custom
			(at 0 -0.9525 180)
			(size 0.1905 0.1905)
			(layers "F.Cu" "F.Mask" "F.Paste")
			(net "LED_Q_11")
			(options
				(clearance outline)
				(anchor circle)
			)
			(primitives
				(gr_poly
					(pts
						(arc
							(start -0.1778 0.5715)
							(mid -0.321484 0.511984)
							(end -0.381 0.3683)
						)
						(arc
							(start -0.381 -0.3683)
							(mid -0.321484 -0.511984)
							(end -0.1778 -0.5715)
						)
						(arc
							(start 0.1778 -0.5715)
							(mid 0.321484 -0.511984)
							(end 0.381 -0.3683)
						)
						(arc
							(start 0.381 0.3683)
							(mid 0.321484 0.511984)
							(end 0.1778 0.5715)
						)
					)
					(width 0)
					(fill yes)
				)
			)
		)
		(pad "G" smd custom
			(at -0.98425 0.9525 180)
			(size 0.1905 0.1905)
			(layers "F.Cu" "F.Mask" "F.Paste")
			(net "VS3_LED_R")
			(options
				(clearance outline)
				(anchor circle)
			)
			(primitives
				(gr_poly
					(pts
						(arc
							(start -0.1778 0.5715)
							(mid -0.321484 0.511984)
							(end -0.381 0.3683)
						)
						(arc
							(start -0.381 -0.3683)
							(mid -0.321484 -0.511984)
							(end -0.1778 -0.5715)
						)
						(arc
							(start 0.1778 -0.5715)
							(mid 0.321484 -0.511984)
							(end 0.381 -0.3683)
						)
						(arc
							(start 0.381 0.3683)
							(mid 0.321484 0.511984)
							(end 0.1778 0.5715)
						)
					)
					(width 0)
					(fill yes)
				)
			)
		)
		(pad "S" smd custom
			(at 0.98425 0.9525 180)
			(size 0.1905 0.1905)
			(layers "F.Cu" "F.Mask" "F.Paste")
			(net "GND")
			(options
				(clearance outline)
				(anchor circle)
			)
			(primitives
				(gr_poly
					(pts
						(arc
							(start -0.1778 0.5715)
							(mid -0.321484 0.511984)
							(end -0.381 0.3683)
						)
						(arc
							(start -0.381 -0.3683)
							(mid -0.321484 -0.511984)
							(end -0.1778 -0.5715)
						)
						(arc
							(start 0.1778 -0.5715)
							(mid 0.321484 -0.511984)
							(end 0.381 -0.3683)
						)
						(arc
							(start 0.381 0.3683)
							(mid 0.321484 0.511984)
							(end 0.1778 0.5715)
						)
					)
					(width 0)
					(fill yes)
				)
			)
		)
	)
	(footprint ""
		(layer "F.Cu")
		(at 124.944124 -196.443092 180)
		(property "Reference" "R547"
			(at 0 0 180)
			(layer "F.SilkS")
			(hide yes)
			(effects
				(font
					(size 1.27 1.27)
				)
			)
		)
		(property "Value" "10KR2F-2-GP"
			(at 0.064008 -3.993896 180)
			(unlocked yes)
			(layer "F.Fab")
			(hide yes)
			(effects
				(font
					(size 1.016 1.016)
					(thickness 0.1524)
				)
			)
		)
		(property "Device Type" "R402H16"
			(at 0.064008 -5.517896 180)
			(unlocked yes)
			(layer "F.Fab")
			(hide yes)
			(effects
				(font
					(size 1.016 1.016)
					(thickness 0.1524)
				)
			)
		)
		(duplicate_pad_numbers_are_jumpers no)
		(fp_line
			(start 0.508 -0.9398)
			(end -0.508 -0.9398)
			(stroke
				(width 0.1524)
				(type default)
			)
			(layer "F.SilkS")
		)
		(fp_line
			(start -0.508 -0.9398)
			(end -0.508 0.9398)
			(stroke
				(width 0.1524)
				(type default)
			)
			(layer "F.SilkS")
		)
		(fp_rect
			(start -0.508 0.9398)
			(end 0.508 -0.9398)
			(stroke
				(width 0)
				(type default)
			)
			(fill no)
			(layer "F.CrtYd")
		)
		(fp_rect
			(start -0.508 0.9398)
			(end 0.508 -0.9398)
			(stroke
				(width 0)
				(type default)
			)
			(fill no)
			(layer "F.Fab")
		)
		(pad "1" smd custom
			(at 0 -0.4445 180)
			(size 0.1397 0.1397)
			(layers "F.Cu" "F.Mask" "F.Paste")
			(net "GND")
			(options
				(clearance outline)
				(anchor circle)
			)
			(primitives
				(gr_poly
					(pts
						(arc
							(start -0.1778 -0.2794)
							(mid -0.249642 -0.249642)
							(end -0.2794 -0.1778)
						)
						(arc
							(start -0.2794 0.1778)
							(mid -0.249642 0.249642)
							(end -0.1778 0.2794)
						)
						(arc
							(start 0.1778 0.2794)
							(mid 0.249642 0.249642)
							(end 0.2794 0.1778)
						)
						(arc
							(start 0.2794 -0.1778)
							(mid 0.249642 -0.249642)
							(end 0.1778 -0.2794)
						)
					)
					(width 0)
					(fill yes)
				)
			)
		)
		(pad "2" smd custom
			(at 0 0.4445 180)
			(size 0.1397 0.1397)
			(layers "F.Cu" "F.Mask" "F.Paste")
			(net "IOEXP2_AD2")
			(options
				(clearance outline)
				(anchor circle)
			)
			(primitives
				(gr_poly
					(pts
						(arc
							(start -0.1778 -0.2794)
							(mid -0.249642 -0.249642)
							(end -0.2794 -0.1778)
						)
						(arc
							(start -0.2794 0.1778)
							(mid -0.249642 0.249642)
							(end -0.1778 0.2794)
						)
						(arc
							(start 0.1778 0.2794)
							(mid 0.249642 0.249642)
							(end 0.2794 0.1778)
						)
						(arc
							(start 0.2794 -0.1778)
							(mid 0.249642 -0.249642)
							(end 0.1778 -0.2794)
						)
					)
					(width 0)
					(fill yes)
				)
			)
		)
	)
	(footprint ""
		(layer "F.Cu")
		(at 37.035486 -146.46402)
		(property "Reference" "C175"
			(at 0 0 0)
			(layer "F.SilkS")
			(hide yes)
			(effects
				(font
					(size 1.27 1.27)
				)
			)
		)
		(property "Value" "SCD1U16V2KX-3GP"
			(at 1.1811 -2.7051 0)
			(unlocked yes)
			(layer "F.Fab")
			(hide yes)
			(effects
				(font
					(size 1.016 1.016)
					(thickness 0.1524)
				)
			)
		)
		(property "Device Type" "C402H22"
			(at 1.1811 -4.2291 0)
			(unlocked yes)
			(layer "F.Fab")
			(hide yes)
			(effects
				(font
					(size 1.016 1.016)
					(thickness 0.1524)
				)
			)
		)
		(duplicate_pad_numbers_are_jumpers no)
		(fp_rect
			(start -0.4318 0.9525)
			(end 0.4318 -0.9525)
			(stroke
				(width 0)
				(type default)
			)
			(fill no)
			(layer "F.CrtYd")
		)
		(fp_rect
			(start -0.4318 0.9525)
			(end 0.4318 -0.9525)
			(stroke
				(width 0)
				(type default)
			)
			(fill no)
			(layer "F.Fab")
		)
		(pad "1" smd custom
			(at 0 -0.4445)
			(size 0.1524 0.1524)
			(layers "F.Cu" "F.Mask" "F.Paste")
			(net "P1V53_STBY")
			(options
				(clearance outline)
				(anchor circle)
			)
			(primitives
				(gr_poly
					(pts
						(arc
							(start 0.3048 -0.2032)
							(mid 0.275042 -0.275042)
							(end 0.2032 -0.3048)
						)
						(arc
							(start -0.2032 -0.3048)
							(mid -0.275042 -0.275042)
							(end -0.3048 -0.2032)
						)
						(arc
							(start -0.3048 0.2032)
							(mid -0.275042 0.275042)
							(end -0.2032 0.3048)
						)
						(arc
							(start 0.2032 0.3048)
							(mid 0.275042 0.275042)
							(end 0.3048 0.2032)
						)
					)
					(width 0)
					(fill yes)
				)
			)
		)
		(pad "2" smd custom
			(at 0 0.4445)
			(size 0.1524 0.1524)
			(layers "F.Cu" "F.Mask" "F.Paste")
			(net "GND")
			(options
				(clearance outline)
				(anchor circle)
			)
			(primitives
				(gr_poly
					(pts
						(arc
							(start 0.3048 -0.2032)
							(mid 0.275042 -0.275042)
							(end 0.2032 -0.3048)
						)
						(arc
							(start -0.2032 -0.3048)
							(mid -0.275042 -0.275042)
							(end -0.3048 -0.2032)
						)
						(arc
							(start -0.3048 0.2032)
							(mid -0.275042 0.275042)
							(end -0.2032 0.3048)
						)
						(arc
							(start 0.2032 0.3048)
							(mid 0.275042 0.275042)
							(end 0.3048 0.2032)
						)
					)
					(width 0)
					(fill yes)
				)
			)
		)
	)
	(footprint ""
		(layer "F.Cu")
		(at 35.306 -56.896 180)
		(property "Reference" "F1"
			(at 0 0 180)
			(layer "F.SilkS")
			(hide yes)
			(effects
				(font
					(size 1.27 1.27)
				)
			)
		)
		(property "Value" "POLYSW-1D5A8V-4-GP"
			(at -2.401824 -0.181102 180)
			(unlocked yes)
			(layer "F.Fab")
			(hide yes)
			(effects
				(font
					(size 1.016 1.016)
					(thickness 0.1524)
				)
			)
		)
		(property "Device Type" "POLYSW-3217-UH40"
			(at -2.401824 -1.705102 180)
			(unlocked yes)
			(layer "F.Fab")
			(hide yes)
			(effects
				(font
					(size 1.016 1.016)
					(thickness 0.1524)
				)
			)
		)
		(duplicate_pad_numbers_are_jumpers no)
		(fp_line
			(start 1.2065 2.2479)
			(end 1.2065 -2.2479)
			(stroke
				(width 0.1524)
				(type default)
			)
			(layer "F.SilkS")
		)
		(fp_line
			(start 1.2065 -2.2479)
			(end -1.2065 -2.2479)
			(stroke
				(width 0.1524)
				(type default)
			)
			(layer "F.SilkS")
		)
		(fp_line
			(start -1.2065 2.2479)
			(end 1.2065 2.2479)
			(stroke
				(width 0.1524)
				(type default)
			)
			(layer "F.SilkS")
		)
		(fp_line
			(start -1.2065 -2.2479)
			(end -1.2065 2.2479)
			(stroke
				(width 0.1524)
				(type default)
			)
			(layer "F.SilkS")
		)
		(fp_rect
			(start -0.8255 1.6002)
			(end 0.8255 -1.6002)
			(stroke
				(width 0)
				(type default)
			)
			(fill no)
			(layer "F.CrtYd")
		)
		(fp_poly
			(pts
				(xy -1.4605 2.3241) (xy -1.4605 -2.3241) (xy 1.4605 -2.3241) (xy 1.4605 1.59512) (xy 0.8255 1.59512)
				(xy 0.8255 -1.6002) (xy -0.8255 -1.6002) (xy -0.8255 1.6002) (xy 1.4605 1.6002) (xy 1.4605 2.3241)
			)
			(stroke
				(width 0)
				(type default)
			)
			(fill no)
			(layer "F.CrtYd")
		)
		(fp_rect
			(start -1.4605 2.3241)
			(end 1.4605 -2.3241)
			(stroke
				(width 0)
				(type default)
			)
			(fill no)
			(layer "F.Fab")
		)
		(pad "1" smd rect
			(at 0 -1.417574 180)
			(size 1.905 1.143)
			(layers "F.Cu" "F.Mask" "F.Paste")
			(net "P5V_USB")
		)
		(pad "2" smd rect
			(at 0 1.417574 180)
			(size 1.905 1.143)
			(layers "F.Cu" "F.Mask" "F.Paste")
			(net "P5V_USB_BP1_F")
		)
	)
	(footprint ""
		(layer "F.Cu")
		(at 145.8722 -33.52292)
		(property "Reference" "C390"
			(at 0 0 0)
			(layer "F.SilkS")
			(hide yes)
			(effects
				(font
					(size 1.27 1.27)
				)
			)
		)
		(property "Value" "SCD22U10V2KX-1GP"
			(at 1.1811 -2.7051 0)
			(unlocked yes)
			(layer "F.Fab")
			(hide yes)
			(effects
				(font
					(size 1.016 1.016)
					(thickness 0.1524)
				)
			)
		)
		(property "Device Type" "C402H22"
			(at 1.1811 -4.2291 0)
			(unlocked yes)
			(layer "F.Fab")
			(hide yes)
			(effects
				(font
					(size 1.016 1.016)
					(thickness 0.1524)
				)
			)
		)
		(duplicate_pad_numbers_are_jumpers no)
		(fp_rect
			(start -0.4318 0.9525)
			(end 0.4318 -0.9525)
			(stroke
				(width 0)
				(type default)
			)
			(fill no)
			(layer "F.CrtYd")
		)
		(fp_rect
			(start -0.4318 0.9525)
			(end 0.4318 -0.9525)
			(stroke
				(width 0)
				(type default)
			)
			(fill no)
			(layer "F.Fab")
		)
		(pad "1" smd custom
			(at 0 -0.4445)
			(size 0.1524 0.1524)
			(layers "F.Cu" "F.Mask" "F.Paste")
			(net "PCIE_TX_CAP_P85")
			(options
				(clearance outline)
				(anchor circle)
			)
			(primitives
				(gr_poly
					(pts
						(arc
							(start 0.3048 -0.2032)
							(mid 0.275042 -0.275042)
							(end 0.2032 -0.3048)
						)
						(arc
							(start -0.2032 -0.3048)
							(mid -0.275042 -0.275042)
							(end -0.3048 -0.2032)
						)
						(arc
							(start -0.3048 0.2032)
							(mid -0.275042 0.275042)
							(end -0.2032 0.3048)
						)
						(arc
							(start 0.2032 0.3048)
							(mid 0.275042 0.275042)
							(end 0.3048 0.2032)
						)
					)
					(width 0)
					(fill yes)
				)
			)
		)
		(pad "2" smd custom
			(at 0 0.4445)
			(size 0.1524 0.1524)
			(layers "F.Cu" "F.Mask" "F.Paste")
			(net "PCIE_TX_P85")
			(options
				(clearance outline)
				(anchor circle)
			)
			(primitives
				(gr_poly
					(pts
						(arc
							(start 0.3048 -0.2032)
							(mid 0.275042 -0.275042)
							(end 0.2032 -0.3048)
						)
						(arc
							(start -0.2032 -0.3048)
							(mid -0.275042 -0.275042)
							(end -0.3048 -0.2032)
						)
						(arc
							(start -0.3048 0.2032)
							(mid -0.275042 0.275042)
							(end -0.2032 0.3048)
						)
						(arc
							(start 0.2032 0.3048)
							(mid 0.275042 0.275042)
							(end 0.3048 0.2032)
						)
					)
					(width 0)
					(fill yes)
				)
			)
		)
	)
	(footprint ""
		(layer "F.Cu")
		(at 52.578 -184.15 90)
		(property "Reference" "C711"
			(at 0 0 90)
			(layer "F.SilkS")
			(hide yes)
			(effects
				(font
					(size 1.27 1.27)
				)
			)
		)
		(property "Value" "SC220P50V3JN-GP"
			(at 0 -2.8194 90)
			(unlocked yes)
			(layer "F.Fab")
			(hide yes)
			(effects
				(font
					(size 1.016 1.016)
					(thickness 0.1524)
				)
			)
		)
		(property "Device Type" "C603H36"
			(at 0 -4.3434 90)
			(unlocked yes)
			(layer "F.Fab")
			(hide yes)
			(effects
				(font
					(size 1.016 1.016)
					(thickness 0.1524)
				)
			)
		)
		(duplicate_pad_numbers_are_jumpers no)
		(fp_line
			(start 0.508 0)
			(end -0.508 0)
			(stroke
				(width 0.2032)
				(type default)
			)
			(layer "F.SilkS")
		)
		(fp_rect
			(start -0.5842 1.3335)
			(end 0.5842 -1.3335)
			(stroke
				(width 0)
				(type default)
			)
			(fill no)
			(layer "F.CrtYd")
		)
		(fp_rect
			(start -0.5842 1.3335)
			(end 0.5842 -1.3335)
			(stroke
				(width 0)
				(type default)
			)
			(fill no)
			(layer "F.Fab")
		)
		(pad "1" smd custom
			(at 0 -0.762 90)
			(size 0.2159 0.2159)
			(layers "F.Cu" "F.Mask" "F.Paste")
			(net "BUF_I2C8_CLKBUF1_SCL_R")
			(options
				(clearance outline)
				(anchor circle)
			)
			(primitives
				(gr_poly
					(pts
						(arc
							(start -0.3302 -0.4318)
							(mid -0.402042 -0.402042)
							(end -0.4318 -0.3302)
						)
						(arc
							(start -0.4318 0.3302)
							(mid -0.402042 0.402042)
							(end -0.3302 0.4318)
						)
						(arc
							(start 0.3302 0.4318)
							(mid 0.402042 0.402042)
							(end 0.4318 0.3302)
						)
						(arc
							(start 0.4318 -0.3302)
							(mid 0.402042 -0.402042)
							(end 0.3302 -0.4318)
						)
					)
					(width 0)
					(fill yes)
				)
			)
		)
		(pad "2" smd custom
			(at 0 0.762 90)
			(size 0.2159 0.2159)
			(layers "F.Cu" "F.Mask" "F.Paste")
			(net "GND")
			(options
				(clearance outline)
				(anchor circle)
			)
			(primitives
				(gr_poly
					(pts
						(arc
							(start -0.3302 -0.4318)
							(mid -0.402042 -0.402042)
							(end -0.4318 -0.3302)
						)
						(arc
							(start -0.4318 0.3302)
							(mid -0.402042 0.402042)
							(end -0.3302 0.4318)
						)
						(arc
							(start 0.3302 0.4318)
							(mid 0.402042 0.402042)
							(end 0.4318 0.3302)
						)
						(arc
							(start 0.4318 -0.3302)
							(mid 0.402042 -0.402042)
							(end 0.3302 -0.4318)
						)
					)
					(width 0)
					(fill yes)
				)
			)
		)
	)
	(footprint ""
		(layer "F.Cu")
		(at 144.7038 -33.45942 180)
		(property "Reference" "R634"
			(at 0 0 180)
			(layer "F.SilkS")
			(hide yes)
			(effects
				(font
					(size 1.27 1.27)
				)
			)
		)
		(property "Value" "0R2J-2-GP"
			(at 0.064008 -3.993896 180)
			(unlocked yes)
			(layer "F.Fab")
			(hide yes)
			(effects
				(font
					(size 1.016 1.016)
					(thickness 0.1524)
				)
			)
		)
		(property "Device Type" "R402H16"
			(at 0.064008 -5.517896 180)
			(unlocked yes)
			(layer "F.Fab")
			(hide yes)
			(effects
				(font
					(size 1.016 1.016)
					(thickness 0.1524)
				)
			)
		)
		(duplicate_pad_numbers_are_jumpers no)
		(fp_line
			(start 0.508 -0.9398)
			(end -0.508 -0.9398)
			(stroke
				(width 0.1524)
				(type default)
			)
			(layer "F.SilkS")
		)
		(fp_line
			(start -0.508 -0.9398)
			(end -0.508 0.9398)
			(stroke
				(width 0.1524)
				(type default)
			)
			(layer "F.SilkS")
		)
		(fp_rect
			(start -0.508 0.9398)
			(end 0.508 -0.9398)
			(stroke
				(width 0)
				(type default)
			)
			(fill no)
			(layer "F.CrtYd")
		)
		(fp_rect
			(start -0.508 0.9398)
			(end 0.508 -0.9398)
			(stroke
				(width 0)
				(type default)
			)
			(fill no)
			(layer "F.Fab")
		)
		(pad "1" smd custom
			(at 0 -0.4445 180)
			(size 0.1397 0.1397)
			(layers "F.Cu" "F.Mask" "F.Paste")
			(net "8644_USB_DP2")
			(options
				(clearance outline)
				(anchor circle)
			)
			(primitives
				(gr_poly
					(pts
						(arc
							(start -0.1778 -0.2794)
							(mid -0.249642 -0.249642)
							(end -0.2794 -0.1778)
						)
						(arc
							(start -0.2794 0.1778)
							(mid -0.249642 0.249642)
							(end -0.1778 0.2794)
						)
						(arc
							(start 0.1778 0.2794)
							(mid 0.249642 0.249642)
							(end 0.2794 0.1778)
						)
						(arc
							(start 0.2794 -0.1778)
							(mid 0.249642 -0.249642)
							(end 0.1778 -0.2794)
						)
					)
					(width 0)
					(fill yes)
				)
			)
		)
		(pad "2" smd custom
			(at 0 0.4445 180)
			(size 0.1397 0.1397)
			(layers "F.Cu" "F.Mask" "F.Paste")
			(net "P3V3_STBY")
			(options
				(clearance outline)
				(anchor circle)
			)
			(primitives
				(gr_poly
					(pts
						(arc
							(start -0.1778 -0.2794)
							(mid -0.249642 -0.249642)
							(end -0.2794 -0.1778)
						)
						(arc
							(start -0.2794 0.1778)
							(mid -0.249642 0.249642)
							(end -0.1778 0.2794)
						)
						(arc
							(start 0.1778 0.2794)
							(mid 0.249642 0.249642)
							(end 0.2794 0.1778)
						)
						(arc
							(start 0.2794 -0.1778)
							(mid 0.249642 -0.249642)
							(end 0.1778 -0.2794)
						)
					)
					(width 0)
					(fill yes)
				)
			)
		)
	)
	(footprint ""
		(layer "F.Cu")
		(at 324.8406 -93.0656)
		(property "Reference" "U203"
			(at 0 0 0)
			(layer "F.SilkS")
			(hide yes)
			(effects
				(font
					(size 1.27 1.27)
				)
			)
		)
		(property "Value" "MAX7311AUG-GP"
			(at 0 -12.1412 0)
			(unlocked yes)
			(layer "F.Fab")
			(hide yes)
			(effects
				(font
					(size 1.016 1.016)
					(thickness 0.1524)
				)
			)
		)
		(property "Device Type" "TSOIC24H44"
			(at 0 -13.6652 0)
			(unlocked yes)
			(layer "F.Fab")
			(hide yes)
			(effects
				(font
					(size 1.016 1.016)
					(thickness 0.1524)
				)
			)
		)
		(duplicate_pad_numbers_are_jumpers no)
		(fp_line
			(start -4.1148 -1.778)
			(end -4.1148 1.778)
			(stroke
				(width 0.1524)
				(type default)
			)
			(layer "F.SilkS")
		)
		(fp_line
			(start -4.1148 -1.778)
			(end 3.683 -1.778)
			(stroke
				(width 0.1524)
				(type default)
			)
			(layer "F.SilkS")
		)
		(fp_line
			(start -4.0386 1.778)
			(end -4.0386 3.556)
			(stroke
				(width 0.3556)
				(type default)
			)
			(layer "F.SilkS")
		)
		(fp_line
			(start -3.8354 0)
			(end -4.1148 -0.2794)
			(stroke
				(width 0.1524)
				(type default)
			)
			(layer "F.SilkS")
		)
		(fp_line
			(start -3.8354 0)
			(end -4.1148 0.2794)
			(stroke
				(width 0.1524)
				(type default)
			)
			(layer "F.SilkS")
		)
		(fp_line
			(start 3.683 -1.778)
			(end 3.683 1.778)
			(stroke
				(width 0.1524)
				(type default)
			)
			(layer "F.SilkS")
		)
		(fp_line
			(start 3.683 1.778)
			(end -4.1148 1.778)
			(stroke
				(width 0.1524)
				(type default)
			)
			(layer "F.SilkS")
		)
		(fp_poly
			(pts
				(xy -3.7592 -1.778) (xy 3.683 -1.778) (xy 3.683 1.778) (xy -3.7592 1.778)
			)
			(stroke
				(width 0)
				(type default)
			)
			(fill yes)
			(layer "F.SilkS")
		)
		(fp_poly
			(pts
				(xy -4.22656 3.81) (xy 4.22656 3.81) (xy 4.22656 -3.81) (xy -4.22656 -3.81)
			)
			(stroke
				(width 0)
				(type default)
			)
			(fill no)
			(layer "F.CrtYd")
		)
		(fp_poly
			(pts
				(xy -4.22656 -3.81) (xy 4.22656 -3.81) (xy 4.22656 3.81) (xy -4.22656 3.81)
			)
			(stroke
				(width 0)
				(type default)
			)
			(fill no)
			(layer "F.Fab")
		)
		(pad "1" smd rect
			(at -3.57632 2.8194)
			(size 0.3556 1.524)
			(layers "F.Cu" "F.Mask" "F.Paste")
			(net "IOEXP_PMC1_INT#")
		)
		(pad "2" smd rect
			(at -2.92608 2.8194)
			(size 0.3556 1.524)
			(layers "F.Cu" "F.Mask" "F.Paste")
			(net "IOEXP_PMC1_AD1")
		)
		(pad "3" smd rect
			(at -2.27584 2.8194)
			(size 0.3556 1.524)
			(layers "F.Cu" "F.Mask" "F.Paste")
			(net "IOEXP_PMC1_AD2")
		)
		(pad "4" smd rect
			(at -1.6256 2.8194)
			(size 0.3556 1.524)
			(layers "F.Cu" "F.Mask" "F.Paste")
			(net "UPLINK1")
		)
		(pad "5" smd rect
			(at -0.97536 2.8194)
			(size 0.3556 1.524)
			(layers "F.Cu" "F.Mask" "F.Paste")
			(net "UPLINK2")
		)
		(pad "6" smd rect
			(at -0.32512 2.8194)
			(size 0.3556 1.524)
			(layers "F.Cu" "F.Mask" "F.Paste")
			(net "UPLINK3")
		)
		(pad "7" smd rect
			(at 0.32512 2.8194)
			(size 0.3556 1.524)
			(layers "F.Cu" "F.Mask" "F.Paste")
			(net "UPLINK4")
		)
		(pad "8" smd rect
			(at 0.97536 2.8194)
			(size 0.3556 1.524)
			(layers "F.Cu" "F.Mask" "F.Paste")
			(net "UPLINK5")
		)
		(pad "9" smd rect
			(at 1.6256 2.8194)
			(size 0.3556 1.524)
			(layers "F.Cu" "F.Mask" "F.Paste")
			(net "UPLINK6")
		)
		(pad "10" smd rect
			(at 2.27584 2.8194)
			(size 0.3556 1.524)
			(layers "F.Cu" "F.Mask" "F.Paste")
			(net "UPLINK7")
		)
		(pad "11" smd rect
			(at 2.92608 2.8194)
			(size 0.3556 1.524)
			(layers "F.Cu" "F.Mask" "F.Paste")
			(net "UPLINK8")
		)
		(pad "12" smd rect
			(at 3.57632 2.8194)
			(size 0.3556 1.524)
			(layers "F.Cu" "F.Mask" "F.Paste")
			(net "GND")
		)
		(pad "13" smd rect
			(at 3.57632 -2.8194)
			(size 0.3556 1.524)
			(layers "F.Cu" "F.Mask" "F.Paste")
			(net "VS1_LED")
		)
		(pad "14" smd rect
			(at 2.92608 -2.8194)
			(size 0.3556 1.524)
			(layers "F.Cu" "F.Mask" "F.Paste")
			(net "VS2_LED")
		)
		(pad "15" smd rect
			(at 2.27584 -2.8194)
			(size 0.3556 1.524)
			(layers "F.Cu" "F.Mask" "F.Paste")
			(net "VS3_LED")
		)
		(pad "16" smd rect
			(at 1.6256 -2.8194)
			(size 0.3556 1.524)
			(layers "F.Cu" "F.Mask" "F.Paste")
			(net "VS4_LED")
		)
		(pad "17" smd rect
			(at 0.97536 -2.8194)
			(size 0.3556 1.524)
			(layers "F.Cu" "F.Mask" "F.Paste")
			(net "VS5_LED")
		)
		(pad "18" smd rect
			(at 0.32512 -2.8194)
			(size 0.3556 1.524)
			(layers "F.Cu" "F.Mask" "F.Paste")
			(net "VS6_LED")
		)
		(pad "19" smd rect
			(at -0.32512 -2.8194)
			(size 0.3556 1.524)
			(layers "F.Cu" "F.Mask" "F.Paste")
			(net "MAX7311_TP301")
		)
		(pad "20" smd rect
			(at -0.97536 -2.8194)
			(size 0.3556 1.524)
			(layers "F.Cu" "F.Mask" "F.Paste")
			(net "IOEXP_PEWAKE#")
		)
		(pad "21" smd rect
			(at -1.6256 -2.8194)
			(size 0.3556 1.524)
			(layers "F.Cu" "F.Mask" "F.Paste")
			(net "IOEXP_PMC1_AD0")
		)
		(pad "22" smd rect
			(at -2.27584 -2.8194)
			(size 0.3556 1.524)
			(layers "F.Cu" "F.Mask" "F.Paste")
			(net "IOEXP_TWI_SCL3")
		)
		(pad "23" smd rect
			(at -2.92608 -2.8194)
			(size 0.3556 1.524)
			(layers "F.Cu" "F.Mask" "F.Paste")
			(net "IOEXP_TWI_SDA3")
		)
		(pad "24" smd rect
			(at -3.57632 -2.8194)
			(size 0.3556 1.524)
			(layers "F.Cu" "F.Mask" "F.Paste")
			(net "P3V3_STBY")
		)
	)
	(footprint ""
		(layer "F.Cu")
		(at 61.595 -133.985)
		(property "Reference" "R321"
			(at 0 0 0)
			(layer "F.SilkS")
			(hide yes)
			(effects
				(font
					(size 1.27 1.27)
				)
			)
		)
		(property "Value" "0R2J-2-GP"
			(at 0.064008 -3.993896 0)
			(unlocked yes)
			(layer "F.Fab")
			(hide yes)
			(effects
				(font
					(size 1.016 1.016)
					(thickness 0.1524)
				)
			)
		)
		(property "Device Type" "R402H16"
			(at 0.064008 -5.517896 0)
			(unlocked yes)
			(layer "F.Fab")
			(hide yes)
			(effects
				(font
					(size 1.016 1.016)
					(thickness 0.1524)
				)
			)
		)
		(duplicate_pad_numbers_are_jumpers no)
		(fp_line
			(start -0.508 -0.9398)
			(end -0.508 0.9398)
			(stroke
				(width 0.1524)
				(type default)
			)
			(layer "F.SilkS")
		)
		(fp_line
			(start 0.508 -0.9398)
			(end -0.508 -0.9398)
			(stroke
				(width 0.1524)
				(type default)
			)
			(layer "F.SilkS")
		)
		(fp_rect
			(start -0.508 0.9398)
			(end 0.508 -0.9398)
			(stroke
				(width 0)
				(type default)
			)
			(fill no)
			(layer "F.CrtYd")
		)
		(fp_rect
			(start -0.508 0.9398)
			(end 0.508 -0.9398)
			(stroke
				(width 0)
				(type default)
			)
			(fill no)
			(layer "F.Fab")
		)
		(pad "1" smd custom
			(at 0 -0.4445)
			(size 0.1397 0.1397)
			(layers "F.Cu" "F.Mask" "F.Paste")
			(net "ADC_P0V9")
			(options
				(clearance outline)
				(anchor circle)
			)
			(primitives
				(gr_poly
					(pts
						(arc
							(start -0.1778 -0.2794)
							(mid -0.249642 -0.249642)
							(end -0.2794 -0.1778)
						)
						(arc
							(start -0.2794 0.1778)
							(mid -0.249642 0.249642)
							(end -0.1778 0.2794)
						)
						(arc
							(start 0.1778 0.2794)
							(mid 0.249642 0.249642)
							(end 0.2794 0.1778)
						)
						(arc
							(start 0.2794 -0.1778)
							(mid 0.249642 -0.249642)
							(end 0.1778 -0.2794)
						)
					)
					(width 0)
					(fill yes)
				)
			)
		)
		(pad "2" smd custom
			(at 0 0.4445)
			(size 0.1397 0.1397)
			(layers "F.Cu" "F.Mask" "F.Paste")
			(net "ADC_P0V9_BMC")
			(options
				(clearance outline)
				(anchor circle)
			)
			(primitives
				(gr_poly
					(pts
						(arc
							(start -0.1778 -0.2794)
							(mid -0.249642 -0.249642)
							(end -0.2794 -0.1778)
						)
						(arc
							(start -0.2794 0.1778)
							(mid -0.249642 0.249642)
							(end -0.1778 0.2794)
						)
						(arc
							(start 0.1778 0.2794)
							(mid 0.249642 0.249642)
							(end 0.2794 0.1778)
						)
						(arc
							(start 0.2794 -0.1778)
							(mid 0.249642 -0.249642)
							(end 0.1778 -0.2794)
						)
					)
					(width 0)
					(fill yes)
				)
			)
		)
	)
	(footprint ""
		(layer "F.Cu")
		(at 190.392304 -212.420454 180)
		(property "Reference" "C123"
			(at 0 0 180)
			(layer "F.SilkS")
			(hide yes)
			(effects
				(font
					(size 1.27 1.27)
				)
			)
		)
		(property "Value" "SCD22U10V2KX-1GP"
			(at 1.1811 -2.7051 180)
			(unlocked yes)
			(layer "F.Fab")
			(hide yes)
			(effects
				(font
					(size 1.016 1.016)
					(thickness 0.1524)
				)
			)
		)
		(property "Device Type" "C402H22"
			(at 1.1811 -4.2291 180)
			(unlocked yes)
			(layer "F.Fab")
			(hide yes)
			(effects
				(font
					(size 1.016 1.016)
					(thickness 0.1524)
				)
			)
		)
		(duplicate_pad_numbers_are_jumpers no)
		(fp_rect
			(start -0.4318 0.9525)
			(end 0.4318 -0.9525)
			(stroke
				(width 0)
				(type default)
			)
			(fill no)
			(layer "F.CrtYd")
		)
		(fp_rect
			(start -0.4318 0.9525)
			(end 0.4318 -0.9525)
			(stroke
				(width 0)
				(type default)
			)
			(fill no)
			(layer "F.Fab")
		)
		(pad "1" smd custom
			(at 0 -0.4445 180)
			(size 0.1524 0.1524)
			(layers "F.Cu" "F.Mask" "F.Paste")
			(net "PCIE_TX_CAP_P45")
			(options
				(clearance outline)
				(anchor circle)
			)
			(primitives
				(gr_poly
					(pts
						(arc
							(start 0.3048 -0.2032)
							(mid 0.275042 -0.275042)
							(end 0.2032 -0.3048)
						)
						(arc
							(start -0.2032 -0.3048)
							(mid -0.275042 -0.275042)
							(end -0.3048 -0.2032)
						)
						(arc
							(start -0.3048 0.2032)
							(mid -0.275042 0.275042)
							(end -0.2032 0.3048)
						)
						(arc
							(start 0.2032 0.3048)
							(mid 0.275042 0.275042)
							(end 0.3048 0.2032)
						)
					)
					(width 0)
					(fill yes)
				)
			)
		)
		(pad "2" smd custom
			(at 0 0.4445 180)
			(size 0.1524 0.1524)
			(layers "F.Cu" "F.Mask" "F.Paste")
			(net "PCIE_TX_P45")
			(options
				(clearance outline)
				(anchor circle)
			)
			(primitives
				(gr_poly
					(pts
						(arc
							(start 0.3048 -0.2032)
							(mid 0.275042 -0.275042)
							(end 0.2032 -0.3048)
						)
						(arc
							(start -0.2032 -0.3048)
							(mid -0.275042 -0.275042)
							(end -0.3048 -0.2032)
						)
						(arc
							(start -0.3048 0.2032)
							(mid -0.275042 0.275042)
							(end -0.2032 0.3048)
						)
						(arc
							(start 0.2032 0.3048)
							(mid 0.275042 0.275042)
							(end 0.3048 0.2032)
						)
					)
					(width 0)
					(fill yes)
				)
			)
		)
	)
	(footprint ""
		(layer "F.Cu")
		(at 30.936946 -91.888056)
		(property "Reference" "C3216"
			(at 0 0 0)
			(layer "F.SilkS")
			(hide yes)
			(effects
				(font
					(size 1.27 1.27)
				)
			)
		)
		(property "Value" "SCD1U25V2KX-2-GP"
			(at 1.1811 -2.7051 0)
			(unlocked yes)
			(layer "F.Fab")
			(hide yes)
			(effects
				(font
					(size 1.016 1.016)
					(thickness 0.1524)
				)
			)
		)
		(property "Device Type" "C402H22"
			(at 1.1811 -4.2291 0)
			(unlocked yes)
			(layer "F.Fab")
			(hide yes)
			(effects
				(font
					(size 1.016 1.016)
					(thickness 0.1524)
				)
			)
		)
		(duplicate_pad_numbers_are_jumpers no)
		(fp_rect
			(start -0.4318 0.9525)
			(end 0.4318 -0.9525)
			(stroke
				(width 0)
				(type default)
			)
			(fill no)
			(layer "F.CrtYd")
		)
		(fp_rect
			(start -0.4318 0.9525)
			(end 0.4318 -0.9525)
			(stroke
				(width 0)
				(type default)
			)
			(fill no)
			(layer "F.Fab")
		)
		(pad "1" smd custom
			(at 0 -0.4445)
			(size 0.1524 0.1524)
			(layers "F.Cu" "F.Mask" "F.Paste")
			(net "P3V3_STBY")
			(options
				(clearance outline)
				(anchor circle)
			)
			(primitives
				(gr_poly
					(pts
						(arc
							(start 0.3048 -0.2032)
							(mid 0.275042 -0.275042)
							(end 0.2032 -0.3048)
						)
						(arc
							(start -0.2032 -0.3048)
							(mid -0.275042 -0.275042)
							(end -0.3048 -0.2032)
						)
						(arc
							(start -0.3048 0.2032)
							(mid -0.275042 0.275042)
							(end -0.2032 0.3048)
						)
						(arc
							(start 0.2032 0.3048)
							(mid 0.275042 0.275042)
							(end 0.3048 0.2032)
						)
					)
					(width 0)
					(fill yes)
				)
			)
		)
		(pad "2" smd custom
			(at 0 0.4445)
			(size 0.1524 0.1524)
			(layers "F.Cu" "F.Mask" "F.Paste")
			(net "GND")
			(options
				(clearance outline)
				(anchor circle)
			)
			(primitives
				(gr_poly
					(pts
						(arc
							(start 0.3048 -0.2032)
							(mid 0.275042 -0.275042)
							(end 0.2032 -0.3048)
						)
						(arc
							(start -0.2032 -0.3048)
							(mid -0.275042 -0.275042)
							(end -0.3048 -0.2032)
						)
						(arc
							(start -0.3048 0.2032)
							(mid -0.275042 0.275042)
							(end -0.2032 0.3048)
						)
						(arc
							(start 0.2032 0.3048)
							(mid 0.275042 0.275042)
							(end 0.3048 0.2032)
						)
					)
					(width 0)
					(fill yes)
				)
			)
		)
	)
	(footprint ""
		(layer "F.Cu")
		(at 65.4812 -156.0576 90)
		(property "Reference" "PC75"
			(at 0 0 90)
			(layer "F.SilkS")
			(hide yes)
			(effects
				(font
					(size 1.27 1.27)
				)
			)
		)
		(property "Value" "SC22U6D3V5MX-5-GP"
			(at -0.0762 -6.1214 90)
			(unlocked yes)
			(layer "F.Fab")
			(hide yes)
			(effects
				(font
					(size 1.016 1.016)
					(thickness 0.1524)
				)
			)
		)
		(property "Device Type" "C805H56"
			(at -0.0762 -8.1534 90)
			(unlocked yes)
			(layer "F.Fab")
			(hide yes)
			(effects
				(font
					(size 1.016 1.016)
					(thickness 0.1524)
				)
			)
		)
		(duplicate_pad_numbers_are_jumpers no)
		(fp_line
			(start 0.635 0)
			(end -0.635 0)
			(stroke
				(width 0.508)
				(type default)
			)
			(layer "F.SilkS")
		)
		(fp_rect
			(start -0.9652 1.778)
			(end 0.9652 -1.778)
			(stroke
				(width 0)
				(type default)
			)
			(fill no)
			(layer "F.CrtYd")
		)
		(fp_poly
			(pts
				(xy -0.9652 -1.778) (xy 0.9652 -1.778) (xy 0.9652 1.778) (xy -0.9652 1.778)
			)
			(stroke
				(width 0)
				(type default)
			)
			(fill no)
			(layer "F.Fab")
		)
		(pad "1" smd rect
			(at 0 -0.9652 90)
			(size 1.397 1.143)
			(layers "F.Cu" "F.Mask" "F.Paste")
			(net "P1V53_PWR")
		)
		(pad "2" smd rect
			(at 0 0.9652 90)
			(size 1.397 1.143)
			(layers "F.Cu" "F.Mask" "F.Paste")
			(net "GND")
		)
	)
	(footprint ""
		(layer "F.Cu")
		(at 220.345 -3.683 180)
		(property "Reference" "R275"
			(at 0 0 180)
			(layer "F.SilkS")
			(hide yes)
			(effects
				(font
					(size 1.27 1.27)
				)
			)
		)
		(property "Value" "0R2J-2-GP"
			(at 0.064008 -3.993896 180)
			(unlocked yes)
			(layer "F.Fab")
			(hide yes)
			(effects
				(font
					(size 1.016 1.016)
					(thickness 0.1524)
				)
			)
		)
		(property "Device Type" "R402H16"
			(at 0.064008 -5.517896 180)
			(unlocked yes)
			(layer "F.Fab")
			(hide yes)
			(effects
				(font
					(size 1.016 1.016)
					(thickness 0.1524)
				)
			)
		)
		(duplicate_pad_numbers_are_jumpers no)
		(fp_line
			(start 0.508 -0.9398)
			(end -0.508 -0.9398)
			(stroke
				(width 0.1524)
				(type default)
			)
			(layer "F.SilkS")
		)
		(fp_line
			(start -0.508 -0.9398)
			(end -0.508 0.9398)
			(stroke
				(width 0.1524)
				(type default)
			)
			(layer "F.SilkS")
		)
		(fp_rect
			(start -0.508 0.9398)
			(end 0.508 -0.9398)
			(stroke
				(width 0)
				(type default)
			)
			(fill no)
			(layer "F.CrtYd")
		)
		(fp_rect
			(start -0.508 0.9398)
			(end 0.508 -0.9398)
			(stroke
				(width 0)
				(type default)
			)
			(fill no)
			(layer "F.Fab")
		)
		(pad "1" smd custom
			(at 0 -0.4445 180)
			(size 0.1397 0.1397)
			(layers "F.Cu" "F.Mask" "F.Paste")
			(net "UART_SWITCH_R")
			(options
				(clearance outline)
				(anchor circle)
			)
			(primitives
				(gr_poly
					(pts
						(arc
							(start -0.1778 -0.2794)
							(mid -0.249642 -0.249642)
							(end -0.2794 -0.1778)
						)
						(arc
							(start -0.2794 0.1778)
							(mid -0.249642 0.249642)
							(end -0.1778 0.2794)
						)
						(arc
							(start 0.1778 0.2794)
							(mid 0.249642 0.249642)
							(end 0.2794 0.1778)
						)
						(arc
							(start 0.2794 -0.1778)
							(mid 0.249642 -0.249642)
							(end 0.1778 -0.2794)
						)
					)
					(width 0)
					(fill yes)
				)
			)
		)
		(pad "2" smd custom
			(at 0 0.4445 180)
			(size 0.1397 0.1397)
			(layers "F.Cu" "F.Mask" "F.Paste")
			(net "BMC_UART_SWITCH_1")
			(options
				(clearance outline)
				(anchor circle)
			)
			(primitives
				(gr_poly
					(pts
						(arc
							(start -0.1778 -0.2794)
							(mid -0.249642 -0.249642)
							(end -0.2794 -0.1778)
						)
						(arc
							(start -0.2794 0.1778)
							(mid -0.249642 0.249642)
							(end -0.1778 0.2794)
						)
						(arc
							(start 0.1778 0.2794)
							(mid 0.249642 0.249642)
							(end 0.2794 0.1778)
						)
						(arc
							(start 0.2794 -0.1778)
							(mid 0.249642 -0.249642)
							(end 0.1778 -0.2794)
						)
					)
					(width 0)
					(fill yes)
				)
			)
		)
	)
	(footprint ""
		(layer "F.Cu")
		(at 222.999046 -203.708 180)
		(property "Reference" "R7949"
			(at 0 0 180)
			(layer "F.SilkS")
			(hide yes)
			(effects
				(font
					(size 1.27 1.27)
				)
			)
		)
		(property "Value" "0R2J-2-GP"
			(at 0.064008 -3.993896 180)
			(unlocked yes)
			(layer "F.Fab")
			(hide yes)
			(effects
				(font
					(size 1.016 1.016)
					(thickness 0.1524)
				)
			)
		)
		(property "Device Type" "R402H16"
			(at 0.064008 -5.517896 180)
			(unlocked yes)
			(layer "F.Fab")
			(hide yes)
			(effects
				(font
					(size 1.016 1.016)
					(thickness 0.1524)
				)
			)
		)
		(duplicate_pad_numbers_are_jumpers no)
		(fp_line
			(start 0.508 -0.9398)
			(end -0.508 -0.9398)
			(stroke
				(width 0.1524)
				(type default)
			)
			(layer "F.SilkS")
		)
		(fp_line
			(start -0.508 -0.9398)
			(end -0.508 0.9398)
			(stroke
				(width 0.1524)
				(type default)
			)
			(layer "F.SilkS")
		)
		(fp_rect
			(start -0.508 0.9398)
			(end 0.508 -0.9398)
			(stroke
				(width 0)
				(type default)
			)
			(fill no)
			(layer "F.CrtYd")
		)
		(fp_rect
			(start -0.508 0.9398)
			(end 0.508 -0.9398)
			(stroke
				(width 0)
				(type default)
			)
			(fill no)
			(layer "F.Fab")
		)
		(pad "1" smd custom
			(at 0 -0.4445 180)
			(size 0.1397 0.1397)
			(layers "F.Cu" "F.Mask" "F.Paste")
			(net "SSD_ATNLED#13")
			(options
				(clearance outline)
				(anchor circle)
			)
			(primitives
				(gr_poly
					(pts
						(arc
							(start -0.1778 -0.2794)
							(mid -0.249642 -0.249642)
							(end -0.2794 -0.1778)
						)
						(arc
							(start -0.2794 0.1778)
							(mid -0.249642 0.249642)
							(end -0.1778 0.2794)
						)
						(arc
							(start 0.1778 0.2794)
							(mid 0.249642 0.249642)
							(end 0.2794 0.1778)
						)
						(arc
							(start 0.2794 -0.1778)
							(mid 0.249642 -0.249642)
							(end 0.1778 -0.2794)
						)
					)
					(width 0)
					(fill yes)
				)
			)
		)
		(pad "2" smd custom
			(at 0 0.4445 180)
			(size 0.1397 0.1397)
			(layers "F.Cu" "F.Mask" "F.Paste")
			(net "SSD_ATNLED#13_R")
			(options
				(clearance outline)
				(anchor circle)
			)
			(primitives
				(gr_poly
					(pts
						(arc
							(start -0.1778 -0.2794)
							(mid -0.249642 -0.249642)
							(end -0.2794 -0.1778)
						)
						(arc
							(start -0.2794 0.1778)
							(mid -0.249642 0.249642)
							(end -0.1778 0.2794)
						)
						(arc
							(start 0.1778 0.2794)
							(mid 0.249642 0.249642)
							(end 0.2794 0.1778)
						)
						(arc
							(start 0.2794 -0.1778)
							(mid 0.249642 -0.249642)
							(end 0.1778 -0.2794)
						)
					)
					(width 0)
					(fill yes)
				)
			)
		)
	)
	(footprint ""
		(layer "F.Cu")
		(at 54.6608 -113.284 90)
		(property "Reference" "R440"
			(at 0 0 90)
			(layer "F.SilkS")
			(hide yes)
			(effects
				(font
					(size 1.27 1.27)
				)
			)
		)
		(property "Value" "4K7R2F-GP"
			(at 0.064008 -3.993896 90)
			(unlocked yes)
			(layer "F.Fab")
			(hide yes)
			(effects
				(font
					(size 1.016 1.016)
					(thickness 0.1524)
				)
			)
		)
		(property "Device Type" "R402H16"
			(at 0.064008 -5.517896 90)
			(unlocked yes)
			(layer "F.Fab")
			(hide yes)
			(effects
				(font
					(size 1.016 1.016)
					(thickness 0.1524)
				)
			)
		)
		(duplicate_pad_numbers_are_jumpers no)
		(fp_line
			(start 0.508 -0.9398)
			(end -0.508 -0.9398)
			(stroke
				(width 0.1524)
				(type default)
			)
			(layer "F.SilkS")
		)
		(fp_line
			(start -0.508 -0.9398)
			(end -0.508 0.9398)
			(stroke
				(width 0.1524)
				(type default)
			)
			(layer "F.SilkS")
		)
		(fp_rect
			(start -0.508 0.9398)
			(end 0.508 -0.9398)
			(stroke
				(width 0)
				(type default)
			)
			(fill no)
			(layer "F.CrtYd")
		)
		(fp_rect
			(start -0.508 0.9398)
			(end 0.508 -0.9398)
			(stroke
				(width 0)
				(type default)
			)
			(fill no)
			(layer "F.Fab")
		)
		(pad "1" smd custom
			(at 0 -0.4445 90)
			(size 0.1397 0.1397)
			(layers "F.Cu" "F.Mask" "F.Paste")
			(net "BMC_I2C13_MINI7_SCL_S")
			(options
				(clearance outline)
				(anchor circle)
			)
			(primitives
				(gr_poly
					(pts
						(arc
							(start -0.1778 -0.2794)
							(mid -0.249642 -0.249642)
							(end -0.2794 -0.1778)
						)
						(arc
							(start -0.2794 0.1778)
							(mid -0.249642 0.249642)
							(end -0.1778 0.2794)
						)
						(arc
							(start 0.1778 0.2794)
							(mid 0.249642 0.249642)
							(end 0.2794 0.1778)
						)
						(arc
							(start 0.2794 -0.1778)
							(mid 0.249642 -0.249642)
							(end 0.1778 -0.2794)
						)
					)
					(width 0)
					(fill yes)
				)
			)
		)
		(pad "2" smd custom
			(at 0 0.4445 90)
			(size 0.1397 0.1397)
			(layers "F.Cu" "F.Mask" "F.Paste")
			(net "P3V3_STBY")
			(options
				(clearance outline)
				(anchor circle)
			)
			(primitives
				(gr_poly
					(pts
						(arc
							(start -0.1778 -0.2794)
							(mid -0.249642 -0.249642)
							(end -0.2794 -0.1778)
						)
						(arc
							(start -0.2794 0.1778)
							(mid -0.249642 0.249642)
							(end -0.1778 0.2794)
						)
						(arc
							(start 0.1778 0.2794)
							(mid 0.249642 0.249642)
							(end 0.2794 0.1778)
						)
						(arc
							(start 0.2794 -0.1778)
							(mid 0.249642 -0.249642)
							(end 0.1778 -0.2794)
						)
					)
					(width 0)
					(fill yes)
				)
			)
		)
	)
	(footprint ""
		(layer "F.Cu")
		(at 325.991982 -212.420454 180)
		(property "Reference" "C62"
			(at 0 0 180)
			(layer "F.SilkS")
			(hide yes)
			(effects
				(font
					(size 1.27 1.27)
				)
			)
		)
		(property "Value" "SCD22U10V2KX-1GP"
			(at 1.1811 -2.7051 180)
			(unlocked yes)
			(layer "F.Fab")
			(hide yes)
			(effects
				(font
					(size 1.016 1.016)
					(thickness 0.1524)
				)
			)
		)
		(property "Device Type" "C402H22"
			(at 1.1811 -4.2291 180)
			(unlocked yes)
			(layer "F.Fab")
			(hide yes)
			(effects
				(font
					(size 1.016 1.016)
					(thickness 0.1524)
				)
			)
		)
		(duplicate_pad_numbers_are_jumpers no)
		(fp_rect
			(start -0.4318 0.9525)
			(end 0.4318 -0.9525)
			(stroke
				(width 0)
				(type default)
			)
			(fill no)
			(layer "F.CrtYd")
		)
		(fp_rect
			(start -0.4318 0.9525)
			(end 0.4318 -0.9525)
			(stroke
				(width 0)
				(type default)
			)
			(fill no)
			(layer "F.Fab")
		)
		(pad "1" smd custom
			(at 0 -0.4445 180)
			(size 0.1524 0.1524)
			(layers "F.Cu" "F.Mask" "F.Paste")
			(net "PCIE_TX_CAP_P20")
			(options
				(clearance outline)
				(anchor circle)
			)
			(primitives
				(gr_poly
					(pts
						(arc
							(start 0.3048 -0.2032)
							(mid 0.275042 -0.275042)
							(end 0.2032 -0.3048)
						)
						(arc
							(start -0.2032 -0.3048)
							(mid -0.275042 -0.275042)
							(end -0.3048 -0.2032)
						)
						(arc
							(start -0.3048 0.2032)
							(mid -0.275042 0.275042)
							(end -0.2032 0.3048)
						)
						(arc
							(start 0.2032 0.3048)
							(mid 0.275042 0.275042)
							(end 0.3048 0.2032)
						)
					)
					(width 0)
					(fill yes)
				)
			)
		)
		(pad "2" smd custom
			(at 0 0.4445 180)
			(size 0.1524 0.1524)
			(layers "F.Cu" "F.Mask" "F.Paste")
			(net "PCIE_TX_P20")
			(options
				(clearance outline)
				(anchor circle)
			)
			(primitives
				(gr_poly
					(pts
						(arc
							(start 0.3048 -0.2032)
							(mid 0.275042 -0.275042)
							(end 0.2032 -0.3048)
						)
						(arc
							(start -0.2032 -0.3048)
							(mid -0.275042 -0.275042)
							(end -0.3048 -0.2032)
						)
						(arc
							(start -0.3048 0.2032)
							(mid -0.275042 0.275042)
							(end -0.2032 0.3048)
						)
						(arc
							(start 0.2032 0.3048)
							(mid 0.275042 0.275042)
							(end 0.3048 0.2032)
						)
					)
					(width 0)
					(fill yes)
				)
			)
		)
	)
	(footprint ""
		(layer "F.Cu")
		(at 79.591916 -212.420454 180)
		(property "Reference" "C352"
			(at 0 0 180)
			(layer "F.SilkS")
			(hide yes)
			(effects
				(font
					(size 1.27 1.27)
				)
			)
		)
		(property "Value" "SCD22U10V2KX-1GP"
			(at 1.1811 -2.7051 180)
			(unlocked yes)
			(layer "F.Fab")
			(hide yes)
			(effects
				(font
					(size 1.016 1.016)
					(thickness 0.1524)
				)
			)
		)
		(property "Device Type" "C402H22"
			(at 1.1811 -4.2291 180)
			(unlocked yes)
			(layer "F.Fab")
			(hide yes)
			(effects
				(font
					(size 1.016 1.016)
					(thickness 0.1524)
				)
			)
		)
		(duplicate_pad_numbers_are_jumpers no)
		(fp_rect
			(start -0.4318 0.9525)
			(end 0.4318 -0.9525)
			(stroke
				(width 0)
				(type default)
			)
			(fill no)
			(layer "F.CrtYd")
		)
		(fp_rect
			(start -0.4318 0.9525)
			(end 0.4318 -0.9525)
			(stroke
				(width 0)
				(type default)
			)
			(fill no)
			(layer "F.Fab")
		)
		(pad "1" smd custom
			(at 0 -0.4445 180)
			(size 0.1524 0.1524)
			(layers "F.Cu" "F.Mask" "F.Paste")
			(net "PCIE_TX_CAP_P68")
			(options
				(clearance outline)
				(anchor circle)
			)
			(primitives
				(gr_poly
					(pts
						(arc
							(start 0.3048 -0.2032)
							(mid 0.275042 -0.275042)
							(end 0.2032 -0.3048)
						)
						(arc
							(start -0.2032 -0.3048)
							(mid -0.275042 -0.275042)
							(end -0.3048 -0.2032)
						)
						(arc
							(start -0.3048 0.2032)
							(mid -0.275042 0.275042)
							(end -0.2032 0.3048)
						)
						(arc
							(start 0.2032 0.3048)
							(mid 0.275042 0.275042)
							(end 0.3048 0.2032)
						)
					)
					(width 0)
					(fill yes)
				)
			)
		)
		(pad "2" smd custom
			(at 0 0.4445 180)
			(size 0.1524 0.1524)
			(layers "F.Cu" "F.Mask" "F.Paste")
			(net "PCIE_TX_P68")
			(options
				(clearance outline)
				(anchor circle)
			)
			(primitives
				(gr_poly
					(pts
						(arc
							(start 0.3048 -0.2032)
							(mid 0.275042 -0.275042)
							(end 0.2032 -0.3048)
						)
						(arc
							(start -0.2032 -0.3048)
							(mid -0.275042 -0.275042)
							(end -0.3048 -0.2032)
						)
						(arc
							(start -0.3048 0.2032)
							(mid -0.275042 0.275042)
							(end -0.2032 0.3048)
						)
						(arc
							(start 0.2032 0.3048)
							(mid 0.275042 0.275042)
							(end 0.3048 0.2032)
						)
					)
					(width 0)
					(fill yes)
				)
			)
		)
	)
	(footprint ""
		(layer "F.Cu")
		(at 135.358886 -82.941414 180)
		(property "Reference" "X2"
			(at 0 0 180)
			(layer "F.SilkS")
			(hide yes)
			(effects
				(font
					(size 1.27 1.27)
				)
			)
		)
		(property "Value" "XTAL-32D768KHZ-137-GP"
			(at 0.0127 -3.6322 180)
			(unlocked yes)
			(layer "F.Fab")
			(hide yes)
			(effects
				(font
					(size 1.016 1.016)
					(thickness 0.1524)
				)
			)
		)
		(property "Device Type" "SMD49-12H34"
			(at 0.0127 -5.1562 180)
			(unlocked yes)
			(layer "F.Fab")
			(hide yes)
			(effects
				(font
					(size 1.016 1.016)
					(thickness 0.1524)
				)
			)
		)
		(duplicate_pad_numbers_are_jumpers no)
		(fp_line
			(start 1.1303 2.2479)
			(end -1.1303 2.2479)
			(stroke
				(width 0.1524)
				(type default)
			)
			(layer "F.SilkS")
		)
		(fp_line
			(start 1.1303 -2.2479)
			(end 1.1303 2.2479)
			(stroke
				(width 0.1524)
				(type default)
			)
			(layer "F.SilkS")
		)
		(fp_line
			(start -1.1303 2.2479)
			(end -1.1303 -2.2479)
			(stroke
				(width 0.1524)
				(type default)
			)
			(layer "F.SilkS")
		)
		(fp_line
			(start -1.1303 -2.2479)
			(end 1.1303 -2.2479)
			(stroke
				(width 0.1524)
				(type default)
			)
			(layer "F.SilkS")
		)
		(fp_rect
			(start -0.7493 1.6002)
			(end 0.7493 -1.6002)
			(stroke
				(width 0)
				(type default)
			)
			(fill no)
			(layer "F.CrtYd")
		)
		(fp_poly
			(pts
				(xy -1.3843 2.5019) (xy -1.3843 -2.5019) (xy 1.3843 -2.5019) (xy 1.3843 -1.6002) (xy -0.7493 -1.6002)
				(xy -0.7493 1.6002) (xy 0.7493 1.6002) (xy 0.7493 -1.5875) (xy 1.3843 -1.5875) (xy 1.3843 2.5019)
			)
			(stroke
				(width 0)
				(type default)
			)
			(fill no)
			(layer "F.CrtYd")
		)
		(fp_rect
			(start -1.3843 2.5019)
			(end 1.3843 -2.5019)
			(stroke
				(width 0)
				(type default)
			)
			(fill no)
			(layer "F.Fab")
		)
		(pad "1" smd rect
			(at 0 -1.2954 180)
			(size 1.7526 1.397)
			(layers "F.Cu" "F.Mask" "F.Paste")
			(net "RTC_OSCI")
		)
		(pad "2" smd rect
			(at 0 1.2954 180)
			(size 1.7526 1.397)
			(layers "F.Cu" "F.Mask" "F.Paste")
			(net "RTC_OSCO")
		)
		(zone
			(layer "F.Cu")
			(hatch none 0.5)
			(connect_pads
				(clearance 0)
			)
			(min_thickness 0.25)
			(keepout
				(tracks allowed)
				(vias not_allowed)
				(pads allowed)
				(copperpour not_allowed)
				(footprints allowed)
			)
			(placement
				(enabled no)
				(sheetname "")
			)
			(fill
				(thermal_gap 0.5)
				(thermal_bridge_width 0.5)
				(island_removal_mode 0)
			)
			(polygon
				(pts
					(xy 136.235186 -82.344514) (xy 136.235186 -83.538314) (xy 134.482586 -83.538314) (xy 134.482586 -82.344514)
				)
			)
		)
	)
	(footprint ""
		(layer "F.Cu")
		(at 323.723 -86.487)
		(property "Reference" "R4175"
			(at 0 0 0)
			(layer "F.SilkS")
			(hide yes)
			(effects
				(font
					(size 1.27 1.27)
				)
			)
		)
		(property "Value" "4K7R2F-GP"
			(at 0.064008 -3.993896 0)
			(unlocked yes)
			(layer "F.Fab")
			(hide yes)
			(effects
				(font
					(size 1.016 1.016)
					(thickness 0.1524)
				)
			)
		)
		(property "Device Type" "R402H16"
			(at 0.064008 -5.517896 0)
			(unlocked yes)
			(layer "F.Fab")
			(hide yes)
			(effects
				(font
					(size 1.016 1.016)
					(thickness 0.1524)
				)
			)
		)
		(duplicate_pad_numbers_are_jumpers no)
		(fp_line
			(start -0.508 -0.9398)
			(end -0.508 0.9398)
			(stroke
				(width 0.1524)
				(type default)
			)
			(layer "F.SilkS")
		)
		(fp_line
			(start 0.508 -0.9398)
			(end -0.508 -0.9398)
			(stroke
				(width 0.1524)
				(type default)
			)
			(layer "F.SilkS")
		)
		(fp_rect
			(start -0.508 0.9398)
			(end 0.508 -0.9398)
			(stroke
				(width 0)
				(type default)
			)
			(fill no)
			(layer "F.CrtYd")
		)
		(fp_rect
			(start -0.508 0.9398)
			(end 0.508 -0.9398)
			(stroke
				(width 0)
				(type default)
			)
			(fill no)
			(layer "F.Fab")
		)
		(pad "1" smd custom
			(at 0 -0.4445)
			(size 0.1397 0.1397)
			(layers "F.Cu" "F.Mask" "F.Paste")
			(net "UPLINK1")
			(options
				(clearance outline)
				(anchor circle)
			)
			(primitives
				(gr_poly
					(pts
						(arc
							(start -0.1778 -0.2794)
							(mid -0.249642 -0.249642)
							(end -0.2794 -0.1778)
						)
						(arc
							(start -0.2794 0.1778)
							(mid -0.249642 0.249642)
							(end -0.1778 0.2794)
						)
						(arc
							(start 0.1778 0.2794)
							(mid 0.249642 0.249642)
							(end 0.2794 0.1778)
						)
						(arc
							(start 0.2794 -0.1778)
							(mid 0.249642 -0.249642)
							(end 0.1778 -0.2794)
						)
					)
					(width 0)
					(fill yes)
				)
			)
		)
		(pad "2" smd custom
			(at 0 0.4445)
			(size 0.1397 0.1397)
			(layers "F.Cu" "F.Mask" "F.Paste")
			(net "P3V3_STBY")
			(options
				(clearance outline)
				(anchor circle)
			)
			(primitives
				(gr_poly
					(pts
						(arc
							(start -0.1778 -0.2794)
							(mid -0.249642 -0.249642)
							(end -0.2794 -0.1778)
						)
						(arc
							(start -0.2794 0.1778)
							(mid -0.249642 0.249642)
							(end -0.1778 0.2794)
						)
						(arc
							(start 0.1778 0.2794)
							(mid 0.249642 0.249642)
							(end 0.2794 0.1778)
						)
						(arc
							(start 0.2794 -0.1778)
							(mid 0.249642 -0.249642)
							(end 0.1778 -0.2794)
						)
					)
					(width 0)
					(fill yes)
				)
			)
		)
	)
	(footprint ""
		(layer "F.Cu")
		(at 177.008028 -212.420454 180)
		(property "Reference" "C137"
			(at 0 0 180)
			(layer "F.SilkS")
			(hide yes)
			(effects
				(font
					(size 1.27 1.27)
				)
			)
		)
		(property "Value" "SCD22U10V2KX-1GP"
			(at 1.1811 -2.7051 180)
			(unlocked yes)
			(layer "F.Fab")
			(hide yes)
			(effects
				(font
					(size 1.016 1.016)
					(thickness 0.1524)
				)
			)
		)
		(property "Device Type" "C402H22"
			(at 1.1811 -4.2291 180)
			(unlocked yes)
			(layer "F.Fab")
			(hide yes)
			(effects
				(font
					(size 1.016 1.016)
					(thickness 0.1524)
				)
			)
		)
		(duplicate_pad_numbers_are_jumpers no)
		(fp_rect
			(start -0.4318 0.9525)
			(end 0.4318 -0.9525)
			(stroke
				(width 0)
				(type default)
			)
			(fill no)
			(layer "F.CrtYd")
		)
		(fp_rect
			(start -0.4318 0.9525)
			(end 0.4318 -0.9525)
			(stroke
				(width 0)
				(type default)
			)
			(fill no)
			(layer "F.Fab")
		)
		(pad "1" smd custom
			(at 0 -0.4445 180)
			(size 0.1524 0.1524)
			(layers "F.Cu" "F.Mask" "F.Paste")
			(net "PCIE_TX_CAP_N48")
			(options
				(clearance outline)
				(anchor circle)
			)
			(primitives
				(gr_poly
					(pts
						(arc
							(start 0.3048 -0.2032)
							(mid 0.275042 -0.275042)
							(end 0.2032 -0.3048)
						)
						(arc
							(start -0.2032 -0.3048)
							(mid -0.275042 -0.275042)
							(end -0.3048 -0.2032)
						)
						(arc
							(start -0.3048 0.2032)
							(mid -0.275042 0.275042)
							(end -0.2032 0.3048)
						)
						(arc
							(start 0.2032 0.3048)
							(mid 0.275042 0.275042)
							(end 0.3048 0.2032)
						)
					)
					(width 0)
					(fill yes)
				)
			)
		)
		(pad "2" smd custom
			(at 0 0.4445 180)
			(size 0.1524 0.1524)
			(layers "F.Cu" "F.Mask" "F.Paste")
			(net "PCIE_TX_N48")
			(options
				(clearance outline)
				(anchor circle)
			)
			(primitives
				(gr_poly
					(pts
						(arc
							(start 0.3048 -0.2032)
							(mid 0.275042 -0.275042)
							(end 0.2032 -0.3048)
						)
						(arc
							(start -0.2032 -0.3048)
							(mid -0.275042 -0.275042)
							(end -0.3048 -0.2032)
						)
						(arc
							(start -0.3048 0.2032)
							(mid -0.275042 0.275042)
							(end -0.2032 0.3048)
						)
						(arc
							(start 0.2032 0.3048)
							(mid 0.275042 0.275042)
							(end 0.3048 0.2032)
						)
					)
					(width 0)
					(fill yes)
				)
			)
		)
	)
	(footprint ""
		(layer "F.Cu")
		(at 273.702526 -5.7023 -90)
		(property "Reference" "R2911"
			(at 0 0 270)
			(layer "F.SilkS")
			(hide yes)
			(effects
				(font
					(size 1.27 1.27)
				)
			)
		)
		(property "Value" "0R2J-2-GP"
			(at 0.064008 -3.993896 270)
			(unlocked yes)
			(layer "F.Fab")
			(hide yes)
			(effects
				(font
					(size 1.016 1.016)
					(thickness 0.1524)
				)
			)
		)
		(property "Device Type" "R402H16"
			(at 0.064008 -5.517896 270)
			(unlocked yes)
			(layer "F.Fab")
			(hide yes)
			(effects
				(font
					(size 1.016 1.016)
					(thickness 0.1524)
				)
			)
		)
		(duplicate_pad_numbers_are_jumpers no)
		(fp_line
			(start -0.508 -0.9398)
			(end -0.508 0.9398)
			(stroke
				(width 0.1524)
				(type default)
			)
			(layer "F.SilkS")
		)
		(fp_line
			(start 0.508 -0.9398)
			(end -0.508 -0.9398)
			(stroke
				(width 0.1524)
				(type default)
			)
			(layer "F.SilkS")
		)
		(fp_rect
			(start -0.508 0.9398)
			(end 0.508 -0.9398)
			(stroke
				(width 0)
				(type default)
			)
			(fill no)
			(layer "F.CrtYd")
		)
		(fp_rect
			(start -0.508 0.9398)
			(end 0.508 -0.9398)
			(stroke
				(width 0)
				(type default)
			)
			(fill no)
			(layer "F.Fab")
		)
		(pad "1" smd custom
			(at 0 -0.4445 270)
			(size 0.1397 0.1397)
			(layers "F.Cu" "F.Mask" "F.Paste")
			(net "CBL_PRSNT_N_6")
			(options
				(clearance outline)
				(anchor circle)
			)
			(primitives
				(gr_poly
					(pts
						(arc
							(start -0.1778 -0.2794)
							(mid -0.249642 -0.249642)
							(end -0.2794 -0.1778)
						)
						(arc
							(start -0.2794 0.1778)
							(mid -0.249642 0.249642)
							(end -0.1778 0.2794)
						)
						(arc
							(start 0.1778 0.2794)
							(mid 0.249642 0.249642)
							(end 0.2794 0.1778)
						)
						(arc
							(start 0.2794 -0.1778)
							(mid 0.249642 -0.249642)
							(end 0.1778 -0.2794)
						)
					)
					(width 0)
					(fill yes)
				)
			)
		)
		(pad "2" smd custom
			(at 0 0.4445 270)
			(size 0.1397 0.1397)
			(layers "F.Cu" "F.Mask" "F.Paste")
			(net "8644_SDA_R_6")
			(options
				(clearance outline)
				(anchor circle)
			)
			(primitives
				(gr_poly
					(pts
						(arc
							(start -0.1778 -0.2794)
							(mid -0.249642 -0.249642)
							(end -0.2794 -0.1778)
						)
						(arc
							(start -0.2794 0.1778)
							(mid -0.249642 0.249642)
							(end -0.1778 0.2794)
						)
						(arc
							(start 0.1778 0.2794)
							(mid 0.249642 0.249642)
							(end 0.2794 0.1778)
						)
						(arc
							(start 0.2794 -0.1778)
							(mid 0.249642 -0.249642)
							(end 0.1778 -0.2794)
						)
					)
					(width 0)
					(fill yes)
				)
			)
		)
	)
	(footprint ""
		(layer "F.Cu")
		(at 56.134 -132.08)
		(property "Reference" "C8086"
			(at 0 0 0)
			(layer "F.SilkS")
			(hide yes)
			(effects
				(font
					(size 1.27 1.27)
				)
			)
		)
		(property "Value" "SCD1U25V2KX-2-GP"
			(at 1.1811 -2.7051 0)
			(unlocked yes)
			(layer "F.Fab")
			(hide yes)
			(effects
				(font
					(size 1.016 1.016)
					(thickness 0.1524)
				)
			)
		)
		(property "Device Type" "C402H22"
			(at 1.1811 -4.2291 0)
			(unlocked yes)
			(layer "F.Fab")
			(hide yes)
			(effects
				(font
					(size 1.016 1.016)
					(thickness 0.1524)
				)
			)
		)
		(duplicate_pad_numbers_are_jumpers no)
		(fp_rect
			(start -0.4318 0.9525)
			(end 0.4318 -0.9525)
			(stroke
				(width 0)
				(type default)
			)
			(fill no)
			(layer "F.CrtYd")
		)
		(fp_rect
			(start -0.4318 0.9525)
			(end 0.4318 -0.9525)
			(stroke
				(width 0)
				(type default)
			)
			(fill no)
			(layer "F.Fab")
		)
		(pad "1" smd custom
			(at 0 -0.4445)
			(size 0.1524 0.1524)
			(layers "F.Cu" "F.Mask" "F.Paste")
			(net "ADC_P1V53V")
			(options
				(clearance outline)
				(anchor circle)
			)
			(primitives
				(gr_poly
					(pts
						(arc
							(start 0.3048 -0.2032)
							(mid 0.275042 -0.275042)
							(end 0.2032 -0.3048)
						)
						(arc
							(start -0.2032 -0.3048)
							(mid -0.275042 -0.275042)
							(end -0.3048 -0.2032)
						)
						(arc
							(start -0.3048 0.2032)
							(mid -0.275042 0.275042)
							(end -0.2032 0.3048)
						)
						(arc
							(start 0.2032 0.3048)
							(mid 0.275042 0.275042)
							(end 0.3048 0.2032)
						)
					)
					(width 0)
					(fill yes)
				)
			)
		)
		(pad "2" smd custom
			(at 0 0.4445)
			(size 0.1524 0.1524)
			(layers "F.Cu" "F.Mask" "F.Paste")
			(net "GND")
			(options
				(clearance outline)
				(anchor circle)
			)
			(primitives
				(gr_poly
					(pts
						(arc
							(start 0.3048 -0.2032)
							(mid 0.275042 -0.275042)
							(end 0.2032 -0.3048)
						)
						(arc
							(start -0.2032 -0.3048)
							(mid -0.275042 -0.275042)
							(end -0.3048 -0.2032)
						)
						(arc
							(start -0.3048 0.2032)
							(mid -0.275042 0.275042)
							(end -0.2032 0.3048)
						)
						(arc
							(start 0.2032 0.3048)
							(mid 0.275042 0.275042)
							(end 0.3048 0.2032)
						)
					)
					(width 0)
					(fill yes)
				)
			)
		)
	)
	(footprint ""
		(layer "F.Cu")
		(at 181.61 -26.797 -90)
		(property "Reference" "C407"
			(at 0 0 270)
			(layer "F.SilkS")
			(hide yes)
			(effects
				(font
					(size 1.27 1.27)
				)
			)
		)
		(property "Value" "SCD22U10V2KX-1GP"
			(at 1.1811 -2.7051 270)
			(unlocked yes)
			(layer "F.Fab")
			(hide yes)
			(effects
				(font
					(size 1.016 1.016)
					(thickness 0.1524)
				)
			)
		)
		(property "Device Type" "C402H22"
			(at 1.1811 -4.2291 270)
			(unlocked yes)
			(layer "F.Fab")
			(hide yes)
			(effects
				(font
					(size 1.016 1.016)
					(thickness 0.1524)
				)
			)
		)
		(duplicate_pad_numbers_are_jumpers no)
		(fp_rect
			(start -0.4318 0.9525)
			(end 0.4318 -0.9525)
			(stroke
				(width 0)
				(type default)
			)
			(fill no)
			(layer "F.CrtYd")
		)
		(fp_rect
			(start -0.4318 0.9525)
			(end 0.4318 -0.9525)
			(stroke
				(width 0)
				(type default)
			)
			(fill no)
			(layer "F.Fab")
		)
		(pad "1" smd custom
			(at 0 -0.4445 270)
			(size 0.1524 0.1524)
			(layers "F.Cu" "F.Mask" "F.Paste")
			(net "PCIE_TX_CAP_P93")
			(options
				(clearance outline)
				(anchor circle)
			)
			(primitives
				(gr_poly
					(pts
						(arc
							(start 0.3048 -0.2032)
							(mid 0.275042 -0.275042)
							(end 0.2032 -0.3048)
						)
						(arc
							(start -0.2032 -0.3048)
							(mid -0.275042 -0.275042)
							(end -0.3048 -0.2032)
						)
						(arc
							(start -0.3048 0.2032)
							(mid -0.275042 0.275042)
							(end -0.2032 0.3048)
						)
						(arc
							(start 0.2032 0.3048)
							(mid 0.275042 0.275042)
							(end 0.3048 0.2032)
						)
					)
					(width 0)
					(fill yes)
				)
			)
		)
		(pad "2" smd custom
			(at 0 0.4445 270)
			(size 0.1524 0.1524)
			(layers "F.Cu" "F.Mask" "F.Paste")
			(net "PCIE_TX_P93")
			(options
				(clearance outline)
				(anchor circle)
			)
			(primitives
				(gr_poly
					(pts
						(arc
							(start 0.3048 -0.2032)
							(mid 0.275042 -0.275042)
							(end 0.2032 -0.3048)
						)
						(arc
							(start -0.2032 -0.3048)
							(mid -0.275042 -0.275042)
							(end -0.3048 -0.2032)
						)
						(arc
							(start -0.3048 0.2032)
							(mid -0.275042 0.275042)
							(end -0.2032 0.3048)
						)
						(arc
							(start 0.2032 0.3048)
							(mid 0.275042 0.275042)
							(end 0.3048 0.2032)
						)
					)
					(width 0)
					(fill yes)
				)
			)
		)
	)
	(footprint ""
		(layer "F.Cu")
		(at 31.496 -195.199 90)
		(property "Reference" "D36"
			(at 0 0 90)
			(layer "F.SilkS")
			(hide yes)
			(effects
				(font
					(size 1.27 1.27)
				)
			)
		)
		(property "Value" "MM3Z15VT1G-GP-U"
			(at 0 -6.7818 90)
			(unlocked yes)
			(layer "F.Fab")
			(hide yes)
			(effects
				(font
					(size 1.016 1.016)
					(thickness 0.1524)
				)
			)
		)
		(property "Device Type" "SOD323AKH44"
			(at 0 -8.6868 90)
			(unlocked yes)
			(layer "F.Fab")
			(hide yes)
			(effects
				(font
					(size 1.016 1.016)
					(thickness 0.1524)
				)
			)
		)
		(duplicate_pad_numbers_are_jumpers no)
		(fp_line
			(start 0.889 -1.9304)
			(end 0.889 2.159)
			(stroke
				(width 0.1524)
				(type default)
			)
			(layer "F.SilkS")
		)
		(fp_line
			(start -0.889 -1.9304)
			(end 0.889 -1.9304)
			(stroke
				(width 0.1524)
				(type default)
			)
			(layer "F.SilkS")
		)
		(fp_line
			(start 0.762 2.0574)
			(end -0.762 2.0574)
			(stroke
				(width 0.508)
				(type default)
			)
			(layer "F.SilkS")
		)
		(fp_line
			(start 0.889 2.159)
			(end -0.889 2.159)
			(stroke
				(width 0.1524)
				(type default)
			)
			(layer "F.SilkS")
		)
		(fp_line
			(start -0.889 2.159)
			(end -0.889 -1.9304)
			(stroke
				(width 0.1524)
				(type default)
			)
			(layer "F.SilkS")
		)
		(fp_rect
			(start -1.016 2.3114)
			(end 1.016 -2.0066)
			(stroke
				(width 0)
				(type default)
			)
			(fill no)
			(layer "F.CrtYd")
		)
		(fp_poly
			(pts
				(xy -1.016 -2.0066) (xy 1.016 -2.0066) (xy 1.016 2.3114) (xy -1.016 2.3114)
			)
			(stroke
				(width 0)
				(type default)
			)
			(fill no)
			(layer "F.Fab")
		)
		(pad "A" smd rect
			(at 0 -1.143 90)
			(size 0.5588 1.016)
			(layers "F.Cu" "F.Mask" "F.Paste")
			(net "MB0_P12V_R")
		)
		(pad "K" smd rect
			(at 0 1.143 90)
			(size 0.5588 1.016)
			(layers "F.Cu" "F.Mask" "F.Paste")
			(net "MB0_CM_GATE_R")
		)
	)
	(footprint ""
		(layer "F.Cu")
		(at 195.4276 -26.8986)
		(property "Reference" "R837"
			(at 0 0 0)
			(layer "F.SilkS")
			(hide yes)
			(effects
				(font
					(size 1.27 1.27)
				)
			)
		)
		(property "Value" "4K7R2F-GP"
			(at 0.064008 -3.993896 0)
			(unlocked yes)
			(layer "F.Fab")
			(hide yes)
			(effects
				(font
					(size 1.016 1.016)
					(thickness 0.1524)
				)
			)
		)
		(property "Device Type" "R402H16"
			(at 0.064008 -5.517896 0)
			(unlocked yes)
			(layer "F.Fab")
			(hide yes)
			(effects
				(font
					(size 1.016 1.016)
					(thickness 0.1524)
				)
			)
		)
		(duplicate_pad_numbers_are_jumpers no)
		(fp_line
			(start -0.508 -0.9398)
			(end -0.508 0.9398)
			(stroke
				(width 0.1524)
				(type default)
			)
			(layer "F.SilkS")
		)
		(fp_line
			(start 0.508 -0.9398)
			(end -0.508 -0.9398)
			(stroke
				(width 0.1524)
				(type default)
			)
			(layer "F.SilkS")
		)
		(fp_rect
			(start -0.508 0.9398)
			(end 0.508 -0.9398)
			(stroke
				(width 0)
				(type default)
			)
			(fill no)
			(layer "F.CrtYd")
		)
		(fp_rect
			(start -0.508 0.9398)
			(end 0.508 -0.9398)
			(stroke
				(width 0)
				(type default)
			)
			(fill no)
			(layer "F.Fab")
		)
		(pad "1" smd custom
			(at 0 -0.4445)
			(size 0.1397 0.1397)
			(layers "F.Cu" "F.Mask" "F.Paste")
			(net "GND")
			(options
				(clearance outline)
				(anchor circle)
			)
			(primitives
				(gr_poly
					(pts
						(arc
							(start -0.1778 -0.2794)
							(mid -0.249642 -0.249642)
							(end -0.2794 -0.1778)
						)
						(arc
							(start -0.2794 0.1778)
							(mid -0.249642 0.249642)
							(end -0.1778 0.2794)
						)
						(arc
							(start 0.1778 0.2794)
							(mid 0.249642 0.249642)
							(end 0.2794 0.1778)
						)
						(arc
							(start 0.2794 -0.1778)
							(mid 0.249642 -0.249642)
							(end 0.1778 -0.2794)
						)
					)
					(width 0)
					(fill yes)
				)
			)
		)
		(pad "2" smd custom
			(at 0 0.4445)
			(size 0.1397 0.1397)
			(layers "F.Cu" "F.Mask" "F.Paste")
			(net "U56_A0")
			(options
				(clearance outline)
				(anchor circle)
			)
			(primitives
				(gr_poly
					(pts
						(arc
							(start -0.1778 -0.2794)
							(mid -0.249642 -0.249642)
							(end -0.2794 -0.1778)
						)
						(arc
							(start -0.2794 0.1778)
							(mid -0.249642 0.249642)
							(end -0.1778 0.2794)
						)
						(arc
							(start 0.1778 0.2794)
							(mid 0.249642 0.249642)
							(end 0.2794 0.1778)
						)
						(arc
							(start 0.2794 -0.1778)
							(mid 0.249642 -0.249642)
							(end 0.1778 -0.2794)
						)
					)
					(width 0)
					(fill yes)
				)
			)
		)
	)
	(footprint ""
		(layer "F.Cu")
		(at 93.407992 -212.420454 180)
		(property "Reference" "C379"
			(at 0 0 180)
			(layer "F.SilkS")
			(hide yes)
			(effects
				(font
					(size 1.27 1.27)
				)
			)
		)
		(property "Value" "SCD22U10V2KX-1GP"
			(at 1.1811 -2.7051 180)
			(unlocked yes)
			(layer "F.Fab")
			(hide yes)
			(effects
				(font
					(size 1.016 1.016)
					(thickness 0.1524)
				)
			)
		)
		(property "Device Type" "C402H22"
			(at 1.1811 -4.2291 180)
			(unlocked yes)
			(layer "F.Fab")
			(hide yes)
			(effects
				(font
					(size 1.016 1.016)
					(thickness 0.1524)
				)
			)
		)
		(duplicate_pad_numbers_are_jumpers no)
		(fp_rect
			(start -0.4318 0.9525)
			(end 0.4318 -0.9525)
			(stroke
				(width 0)
				(type default)
			)
			(fill no)
			(layer "F.CrtYd")
		)
		(fp_rect
			(start -0.4318 0.9525)
			(end 0.4318 -0.9525)
			(stroke
				(width 0)
				(type default)
			)
			(fill no)
			(layer "F.Fab")
		)
		(pad "1" smd custom
			(at 0 -0.4445 180)
			(size 0.1524 0.1524)
			(layers "F.Cu" "F.Mask" "F.Paste")
			(net "PCIE_TX_CAP_N64")
			(options
				(clearance outline)
				(anchor circle)
			)
			(primitives
				(gr_poly
					(pts
						(arc
							(start 0.3048 -0.2032)
							(mid 0.275042 -0.275042)
							(end 0.2032 -0.3048)
						)
						(arc
							(start -0.2032 -0.3048)
							(mid -0.275042 -0.275042)
							(end -0.3048 -0.2032)
						)
						(arc
							(start -0.3048 0.2032)
							(mid -0.275042 0.275042)
							(end -0.2032 0.3048)
						)
						(arc
							(start 0.2032 0.3048)
							(mid 0.275042 0.275042)
							(end 0.3048 0.2032)
						)
					)
					(width 0)
					(fill yes)
				)
			)
		)
		(pad "2" smd custom
			(at 0 0.4445 180)
			(size 0.1524 0.1524)
			(layers "F.Cu" "F.Mask" "F.Paste")
			(net "PCIE_TX_N64")
			(options
				(clearance outline)
				(anchor circle)
			)
			(primitives
				(gr_poly
					(pts
						(arc
							(start 0.3048 -0.2032)
							(mid 0.275042 -0.275042)
							(end 0.2032 -0.3048)
						)
						(arc
							(start -0.2032 -0.3048)
							(mid -0.275042 -0.275042)
							(end -0.3048 -0.2032)
						)
						(arc
							(start -0.3048 0.2032)
							(mid -0.275042 0.275042)
							(end -0.2032 0.3048)
						)
						(arc
							(start 0.2032 0.3048)
							(mid 0.275042 0.275042)
							(end 0.3048 0.2032)
						)
					)
					(width 0)
					(fill yes)
				)
			)
		)
	)
	(footprint ""
		(layer "F.Cu")
		(at 145.1356 -41.402 180)
		(property "Reference" "R768"
			(at 0 0 180)
			(layer "F.SilkS")
			(hide yes)
			(effects
				(font
					(size 1.27 1.27)
				)
			)
		)
		(property "Value" "4K7R2F-GP"
			(at 0.064008 -3.993896 180)
			(unlocked yes)
			(layer "F.Fab")
			(hide yes)
			(effects
				(font
					(size 1.016 1.016)
					(thickness 0.1524)
				)
			)
		)
		(property "Device Type" "R402H16"
			(at 0.064008 -5.517896 180)
			(unlocked yes)
			(layer "F.Fab")
			(hide yes)
			(effects
				(font
					(size 1.016 1.016)
					(thickness 0.1524)
				)
			)
		)
		(duplicate_pad_numbers_are_jumpers no)
		(fp_line
			(start 0.508 -0.9398)
			(end -0.508 -0.9398)
			(stroke
				(width 0.1524)
				(type default)
			)
			(layer "F.SilkS")
		)
		(fp_line
			(start -0.508 -0.9398)
			(end -0.508 0.9398)
			(stroke
				(width 0.1524)
				(type default)
			)
			(layer "F.SilkS")
		)
		(fp_rect
			(start -0.508 0.9398)
			(end 0.508 -0.9398)
			(stroke
				(width 0)
				(type default)
			)
			(fill no)
			(layer "F.CrtYd")
		)
		(fp_rect
			(start -0.508 0.9398)
			(end 0.508 -0.9398)
			(stroke
				(width 0)
				(type default)
			)
			(fill no)
			(layer "F.Fab")
		)
		(pad "1" smd custom
			(at 0 -0.4445 180)
			(size 0.1397 0.1397)
			(layers "F.Cu" "F.Mask" "F.Paste")
			(net "DUT_VDDO")
			(options
				(clearance outline)
				(anchor circle)
			)
			(primitives
				(gr_poly
					(pts
						(arc
							(start -0.1778 -0.2794)
							(mid -0.249642 -0.249642)
							(end -0.2794 -0.1778)
						)
						(arc
							(start -0.2794 0.1778)
							(mid -0.249642 0.249642)
							(end -0.1778 0.2794)
						)
						(arc
							(start 0.1778 0.2794)
							(mid 0.249642 0.249642)
							(end 0.2794 0.1778)
						)
						(arc
							(start 0.2794 -0.1778)
							(mid 0.249642 -0.249642)
							(end 0.1778 -0.2794)
						)
					)
					(width 0)
					(fill yes)
				)
			)
		)
		(pad "2" smd custom
			(at 0 0.4445 180)
			(size 0.1397 0.1397)
			(layers "F.Cu" "F.Mask" "F.Paste")
			(net "EJTAG_RSTB")
			(options
				(clearance outline)
				(anchor circle)
			)
			(primitives
				(gr_poly
					(pts
						(arc
							(start -0.1778 -0.2794)
							(mid -0.249642 -0.249642)
							(end -0.2794 -0.1778)
						)
						(arc
							(start -0.2794 0.1778)
							(mid -0.249642 0.249642)
							(end -0.1778 0.2794)
						)
						(arc
							(start 0.1778 0.2794)
							(mid 0.249642 0.249642)
							(end 0.2794 0.1778)
						)
						(arc
							(start 0.2794 -0.1778)
							(mid 0.249642 -0.249642)
							(end 0.1778 -0.2794)
						)
					)
					(width 0)
					(fill yes)
				)
			)
		)
	)
	(footprint ""
		(layer "F.Cu")
		(at 226.925124 -190.601092)
		(property "Reference" "R7972"
			(at 0 0 0)
			(layer "F.SilkS")
			(hide yes)
			(effects
				(font
					(size 1.27 1.27)
				)
			)
		)
		(property "Value" "0R2J-2-GP"
			(at 0.064008 -3.993896 0)
			(unlocked yes)
			(layer "F.Fab")
			(hide yes)
			(effects
				(font
					(size 1.016 1.016)
					(thickness 0.1524)
				)
			)
		)
		(property "Device Type" "R402H16"
			(at 0.064008 -5.517896 0)
			(unlocked yes)
			(layer "F.Fab")
			(hide yes)
			(effects
				(font
					(size 1.016 1.016)
					(thickness 0.1524)
				)
			)
		)
		(duplicate_pad_numbers_are_jumpers no)
		(fp_line
			(start -0.508 -0.9398)
			(end -0.508 0.9398)
			(stroke
				(width 0.1524)
				(type default)
			)
			(layer "F.SilkS")
		)
		(fp_line
			(start 0.508 -0.9398)
			(end -0.508 -0.9398)
			(stroke
				(width 0.1524)
				(type default)
			)
			(layer "F.SilkS")
		)
		(fp_rect
			(start -0.508 0.9398)
			(end 0.508 -0.9398)
			(stroke
				(width 0)
				(type default)
			)
			(fill no)
			(layer "F.CrtYd")
		)
		(fp_rect
			(start -0.508 0.9398)
			(end 0.508 -0.9398)
			(stroke
				(width 0)
				(type default)
			)
			(fill no)
			(layer "F.Fab")
		)
		(pad "1" smd custom
			(at 0 -0.4445)
			(size 0.1397 0.1397)
			(layers "F.Cu" "F.Mask" "F.Paste")
			(net "SSD_PERST#8")
			(options
				(clearance outline)
				(anchor circle)
			)
			(primitives
				(gr_poly
					(pts
						(arc
							(start -0.1778 -0.2794)
							(mid -0.249642 -0.249642)
							(end -0.2794 -0.1778)
						)
						(arc
							(start -0.2794 0.1778)
							(mid -0.249642 0.249642)
							(end -0.1778 0.2794)
						)
						(arc
							(start 0.1778 0.2794)
							(mid 0.249642 0.249642)
							(end 0.2794 0.1778)
						)
						(arc
							(start 0.2794 -0.1778)
							(mid 0.249642 -0.249642)
							(end 0.1778 -0.2794)
						)
					)
					(width 0)
					(fill yes)
				)
			)
		)
		(pad "2" smd custom
			(at 0 0.4445)
			(size 0.1397 0.1397)
			(layers "F.Cu" "F.Mask" "F.Paste")
			(net "SSD_PERST#8_R")
			(options
				(clearance outline)
				(anchor circle)
			)
			(primitives
				(gr_poly
					(pts
						(arc
							(start -0.1778 -0.2794)
							(mid -0.249642 -0.249642)
							(end -0.2794 -0.1778)
						)
						(arc
							(start -0.2794 0.1778)
							(mid -0.249642 0.249642)
							(end -0.1778 0.2794)
						)
						(arc
							(start 0.1778 0.2794)
							(mid 0.249642 0.249642)
							(end 0.2794 0.1778)
						)
						(arc
							(start 0.2794 -0.1778)
							(mid 0.249642 -0.249642)
							(end 0.1778 -0.2794)
						)
					)
					(width 0)
					(fill yes)
				)
			)
		)
	)
	(footprint ""
		(layer "F.Cu")
		(at 79.502 -56.3626 -90)
		(property "Reference" "R961"
			(at 0 0 270)
			(layer "F.SilkS")
			(hide yes)
			(effects
				(font
					(size 1.27 1.27)
				)
			)
		)
		(property "Value" "300R2F-GP"
			(at 0.064008 -3.993896 270)
			(unlocked yes)
			(layer "F.Fab")
			(hide yes)
			(effects
				(font
					(size 1.016 1.016)
					(thickness 0.1524)
				)
			)
		)
		(property "Device Type" "R402H16"
			(at 0.064008 -5.517896 270)
			(unlocked yes)
			(layer "F.Fab")
			(hide yes)
			(effects
				(font
					(size 1.016 1.016)
					(thickness 0.1524)
				)
			)
		)
		(duplicate_pad_numbers_are_jumpers no)
		(fp_line
			(start -0.508 -0.9398)
			(end -0.508 0.9398)
			(stroke
				(width 0.1524)
				(type default)
			)
			(layer "F.SilkS")
		)
		(fp_line
			(start 0.508 -0.9398)
			(end -0.508 -0.9398)
			(stroke
				(width 0.1524)
				(type default)
			)
			(layer "F.SilkS")
		)
		(fp_rect
			(start -0.508 0.9398)
			(end 0.508 -0.9398)
			(stroke
				(width 0)
				(type default)
			)
			(fill no)
			(layer "F.CrtYd")
		)
		(fp_rect
			(start -0.508 0.9398)
			(end 0.508 -0.9398)
			(stroke
				(width 0)
				(type default)
			)
			(fill no)
			(layer "F.Fab")
		)
		(pad "1" smd custom
			(at 0 -0.4445 270)
			(size 0.1397 0.1397)
			(layers "F.Cu" "F.Mask" "F.Paste")
			(net "BMC_CPU_DIS")
			(options
				(clearance outline)
				(anchor circle)
			)
			(primitives
				(gr_poly
					(pts
						(arc
							(start -0.1778 -0.2794)
							(mid -0.249642 -0.249642)
							(end -0.2794 -0.1778)
						)
						(arc
							(start -0.2794 0.1778)
							(mid -0.249642 0.249642)
							(end -0.1778 0.2794)
						)
						(arc
							(start 0.1778 0.2794)
							(mid 0.249642 0.249642)
							(end 0.2794 0.1778)
						)
						(arc
							(start 0.2794 -0.1778)
							(mid 0.249642 -0.249642)
							(end 0.1778 -0.2794)
						)
					)
					(width 0)
					(fill yes)
				)
			)
		)
		(pad "2" smd custom
			(at 0 0.4445 270)
			(size 0.1397 0.1397)
			(layers "F.Cu" "F.Mask" "F.Paste")
			(net "GND")
			(options
				(clearance outline)
				(anchor circle)
			)
			(primitives
				(gr_poly
					(pts
						(arc
							(start -0.1778 -0.2794)
							(mid -0.249642 -0.249642)
							(end -0.2794 -0.1778)
						)
						(arc
							(start -0.2794 0.1778)
							(mid -0.249642 0.249642)
							(end -0.1778 0.2794)
						)
						(arc
							(start 0.1778 0.2794)
							(mid 0.249642 0.249642)
							(end 0.2794 0.1778)
						)
						(arc
							(start 0.2794 -0.1778)
							(mid 0.249642 -0.249642)
							(end 0.1778 -0.2794)
						)
					)
					(width 0)
					(fill yes)
				)
			)
		)
	)
	(footprint ""
		(layer "F.Cu")
		(at 18.415 -107.315 180)
		(property "Reference" "PR70"
			(at 0 0 180)
			(layer "F.SilkS")
			(hide yes)
			(effects
				(font
					(size 1.27 1.27)
				)
			)
		)
		(property "Value" "4K75R2F-1-GP"
			(at 0.064008 -3.993896 180)
			(unlocked yes)
			(layer "F.Fab")
			(hide yes)
			(effects
				(font
					(size 1.016 1.016)
					(thickness 0.1524)
				)
			)
		)
		(property "Device Type" "R402H16"
			(at 0.064008 -5.517896 180)
			(unlocked yes)
			(layer "F.Fab")
			(hide yes)
			(effects
				(font
					(size 1.016 1.016)
					(thickness 0.1524)
				)
			)
		)
		(duplicate_pad_numbers_are_jumpers no)
		(fp_line
			(start 0.508 -0.9398)
			(end -0.508 -0.9398)
			(stroke
				(width 0.1524)
				(type default)
			)
			(layer "F.SilkS")
		)
		(fp_line
			(start -0.508 -0.9398)
			(end -0.508 0.9398)
			(stroke
				(width 0.1524)
				(type default)
			)
			(layer "F.SilkS")
		)
		(fp_rect
			(start -0.508 0.9398)
			(end 0.508 -0.9398)
			(stroke
				(width 0)
				(type default)
			)
			(fill no)
			(layer "F.CrtYd")
		)
		(fp_rect
			(start -0.508 0.9398)
			(end 0.508 -0.9398)
			(stroke
				(width 0)
				(type default)
			)
			(fill no)
			(layer "F.Fab")
		)
		(pad "1" smd custom
			(at 0 -0.4445 180)
			(size 0.1397 0.1397)
			(layers "F.Cu" "F.Mask" "F.Paste")
			(net "VR_P1V26_STBY_FB")
			(options
				(clearance outline)
				(anchor circle)
			)
			(primitives
				(gr_poly
					(pts
						(arc
							(start -0.1778 -0.2794)
							(mid -0.249642 -0.249642)
							(end -0.2794 -0.1778)
						)
						(arc
							(start -0.2794 0.1778)
							(mid -0.249642 0.249642)
							(end -0.1778 0.2794)
						)
						(arc
							(start 0.1778 0.2794)
							(mid 0.249642 0.249642)
							(end 0.2794 0.1778)
						)
						(arc
							(start 0.2794 -0.1778)
							(mid 0.249642 -0.249642)
							(end 0.1778 -0.2794)
						)
					)
					(width 0)
					(fill yes)
				)
			)
		)
		(pad "2" smd custom
			(at 0 0.4445 180)
			(size 0.1397 0.1397)
			(layers "F.Cu" "F.Mask" "F.Paste")
			(net "GND")
			(options
				(clearance outline)
				(anchor circle)
			)
			(primitives
				(gr_poly
					(pts
						(arc
							(start -0.1778 -0.2794)
							(mid -0.249642 -0.249642)
							(end -0.2794 -0.1778)
						)
						(arc
							(start -0.2794 0.1778)
							(mid -0.249642 0.249642)
							(end -0.1778 0.2794)
						)
						(arc
							(start 0.1778 0.2794)
							(mid 0.249642 0.249642)
							(end 0.2794 0.1778)
						)
						(arc
							(start 0.2794 -0.1778)
							(mid 0.249642 -0.249642)
							(end 0.1778 -0.2794)
						)
					)
					(width 0)
					(fill yes)
				)
			)
		)
	)
	(footprint ""
		(layer "F.Cu")
		(at 53.721 -140.843 -90)
		(property "Reference" "SR944"
			(at 0 0 270)
			(layer "F.SilkS")
			(hide yes)
			(effects
				(font
					(size 1.27 1.27)
				)
			)
		)
		(property "Value" "4K75R2F-1-GP"
			(at 0.064008 -3.993896 270)
			(unlocked yes)
			(layer "F.Fab")
			(hide yes)
			(effects
				(font
					(size 1.016 1.016)
					(thickness 0.1524)
				)
			)
		)
		(property "Device Type" "R402H16"
			(at 0.064008 -5.517896 270)
			(unlocked yes)
			(layer "F.Fab")
			(hide yes)
			(effects
				(font
					(size 1.016 1.016)
					(thickness 0.1524)
				)
			)
		)
		(duplicate_pad_numbers_are_jumpers no)
		(fp_line
			(start -0.508 -0.9398)
			(end -0.508 0.9398)
			(stroke
				(width 0.1524)
				(type default)
			)
			(layer "F.SilkS")
		)
		(fp_line
			(start 0.508 -0.9398)
			(end -0.508 -0.9398)
			(stroke
				(width 0.1524)
				(type default)
			)
			(layer "F.SilkS")
		)
		(fp_rect
			(start -0.508 0.9398)
			(end 0.508 -0.9398)
			(stroke
				(width 0)
				(type default)
			)
			(fill no)
			(layer "F.CrtYd")
		)
		(fp_rect
			(start -0.508 0.9398)
			(end 0.508 -0.9398)
			(stroke
				(width 0)
				(type default)
			)
			(fill no)
			(layer "F.Fab")
		)
		(pad "1" smd custom
			(at 0 -0.4445 270)
			(size 0.1397 0.1397)
			(layers "F.Cu" "F.Mask" "F.Paste")
			(net "P3V3_STBY")
			(options
				(clearance outline)
				(anchor circle)
			)
			(primitives
				(gr_poly
					(pts
						(arc
							(start -0.1778 -0.2794)
							(mid -0.249642 -0.249642)
							(end -0.2794 -0.1778)
						)
						(arc
							(start -0.2794 0.1778)
							(mid -0.249642 0.249642)
							(end -0.1778 0.2794)
						)
						(arc
							(start 0.1778 0.2794)
							(mid 0.249642 0.249642)
							(end 0.2794 0.1778)
						)
						(arc
							(start 0.2794 -0.1778)
							(mid 0.249642 -0.249642)
							(end 0.1778 -0.2794)
						)
					)
					(width 0)
					(fill yes)
				)
			)
		)
		(pad "2" smd custom
			(at 0 0.4445 270)
			(size 0.1397 0.1397)
			(layers "F.Cu" "F.Mask" "F.Paste")
			(net "BMC_FW_DET_BOARD_VER_0")
			(options
				(clearance outline)
				(anchor circle)
			)
			(primitives
				(gr_poly
					(pts
						(arc
							(start -0.1778 -0.2794)
							(mid -0.249642 -0.249642)
							(end -0.2794 -0.1778)
						)
						(arc
							(start -0.2794 0.1778)
							(mid -0.249642 0.249642)
							(end -0.1778 0.2794)
						)
						(arc
							(start 0.1778 0.2794)
							(mid 0.249642 0.249642)
							(end 0.2794 0.1778)
						)
						(arc
							(start 0.2794 -0.1778)
							(mid 0.249642 -0.249642)
							(end 0.1778 -0.2794)
						)
					)
					(width 0)
					(fill yes)
				)
			)
		)
	)
	(footprint ""
		(layer "F.Cu")
		(at 80.6196 -137.795 -90)
		(property "Reference" "R5772"
			(at 0 0 270)
			(layer "F.SilkS")
			(hide yes)
			(effects
				(font
					(size 1.27 1.27)
				)
			)
		)
		(property "Value" "1KR2F-3-GP"
			(at 0.064008 -3.993896 270)
			(unlocked yes)
			(layer "F.Fab")
			(hide yes)
			(effects
				(font
					(size 1.016 1.016)
					(thickness 0.1524)
				)
			)
		)
		(property "Device Type" "R402H16"
			(at 0.064008 -5.517896 270)
			(unlocked yes)
			(layer "F.Fab")
			(hide yes)
			(effects
				(font
					(size 1.016 1.016)
					(thickness 0.1524)
				)
			)
		)
		(duplicate_pad_numbers_are_jumpers no)
		(fp_line
			(start -0.508 -0.9398)
			(end -0.508 0.9398)
			(stroke
				(width 0.1524)
				(type default)
			)
			(layer "F.SilkS")
		)
		(fp_line
			(start 0.508 -0.9398)
			(end -0.508 -0.9398)
			(stroke
				(width 0.1524)
				(type default)
			)
			(layer "F.SilkS")
		)
		(fp_rect
			(start -0.508 0.9398)
			(end 0.508 -0.9398)
			(stroke
				(width 0)
				(type default)
			)
			(fill no)
			(layer "F.CrtYd")
		)
		(fp_rect
			(start -0.508 0.9398)
			(end 0.508 -0.9398)
			(stroke
				(width 0)
				(type default)
			)
			(fill no)
			(layer "F.Fab")
		)
		(pad "1" smd custom
			(at 0 -0.4445 270)
			(size 0.1397 0.1397)
			(layers "F.Cu" "F.Mask" "F.Paste")
			(net "P1V26_STBY")
			(options
				(clearance outline)
				(anchor circle)
			)
			(primitives
				(gr_poly
					(pts
						(arc
							(start -0.1778 -0.2794)
							(mid -0.249642 -0.249642)
							(end -0.2794 -0.1778)
						)
						(arc
							(start -0.2794 0.1778)
							(mid -0.249642 0.249642)
							(end -0.1778 0.2794)
						)
						(arc
							(start 0.1778 0.2794)
							(mid 0.249642 0.249642)
							(end 0.2794 0.1778)
						)
						(arc
							(start 0.2794 -0.1778)
							(mid 0.249642 -0.249642)
							(end 0.1778 -0.2794)
						)
					)
					(width 0)
					(fill yes)
				)
			)
		)
		(pad "2" smd custom
			(at 0 0.4445 270)
			(size 0.1397 0.1397)
			(layers "F.Cu" "F.Mask" "F.Paste")
			(net "ADC_P1V26")
			(options
				(clearance outline)
				(anchor circle)
			)
			(primitives
				(gr_poly
					(pts
						(arc
							(start -0.1778 -0.2794)
							(mid -0.249642 -0.249642)
							(end -0.2794 -0.1778)
						)
						(arc
							(start -0.2794 0.1778)
							(mid -0.249642 0.249642)
							(end -0.1778 0.2794)
						)
						(arc
							(start 0.1778 0.2794)
							(mid 0.249642 0.249642)
							(end 0.2794 0.1778)
						)
						(arc
							(start 0.2794 -0.1778)
							(mid 0.249642 -0.249642)
							(end 0.1778 -0.2794)
						)
					)
					(width 0)
					(fill yes)
				)
			)
		)
	)
	(footprint ""
		(layer "F.Cu")
		(at 45.339 -146.399504)
		(property "Reference" "TP237"
			(at 0 0 0)
			(layer "F.SilkS")
			(hide yes)
			(effects
				(font
					(size 1.27 1.27)
				)
			)
		)
		(property "Value" "TPAD28-2-GP"
			(at -0.0127 -1.6637 0)
			(unlocked yes)
			(layer "F.Fab")
			(hide yes)
			(effects
				(font
					(size 1.016 1.016)
					(thickness 0.1524)
				)
			)
		)
		(property "Device Type" "TPAD28"
			(at -0.0127 -3.1877 0)
			(unlocked yes)
			(layer "F.Fab")
			(hide yes)
			(effects
				(font
					(size 1.016 1.016)
					(thickness 0.1524)
				)
			)
		)
		(duplicate_pad_numbers_are_jumpers no)
		(fp_poly
			(pts
				(arc
					(start 0.3556 0)
					(mid -0.3556 0)
					(end 0.3556 0)
				)
			)
			(stroke
				(width 0)
				(type default)
			)
			(fill no)
			(layer "F.CrtYd")
		)
		(fp_poly
			(pts
				(arc
					(start 0.6096 0)
					(mid -0.6096 0)
					(end 0.6096 0)
				)
			)
			(stroke
				(width 0)
				(type default)
			)
			(fill no)
			(layer "F.Fab")
		)
		(pad "1" smd circle
			(at 0 0)
			(size 0.7112 0.7112)
			(layers "F.Cu" "F.Mask" "F.Paste")
			(net "TP_GPIOO6")
		)
	)
	(footprint ""
		(layer "F.Cu")
		(at 192.8368 -27.7622 -90)
		(property "Reference" "C143"
			(at 0 0 270)
			(layer "F.SilkS")
			(hide yes)
			(effects
				(font
					(size 1.27 1.27)
				)
			)
		)
		(property "Value" "SCD1U10V2KX-5GP"
			(at 1.1811 -2.7051 270)
			(unlocked yes)
			(layer "F.Fab")
			(hide yes)
			(effects
				(font
					(size 1.016 1.016)
					(thickness 0.1524)
				)
			)
		)
		(property "Device Type" "C402H22"
			(at 1.1811 -4.2291 270)
			(unlocked yes)
			(layer "F.Fab")
			(hide yes)
			(effects
				(font
					(size 1.016 1.016)
					(thickness 0.1524)
				)
			)
		)
		(duplicate_pad_numbers_are_jumpers no)
		(fp_rect
			(start -0.4318 0.9525)
			(end 0.4318 -0.9525)
			(stroke
				(width 0)
				(type default)
			)
			(fill no)
			(layer "F.CrtYd")
		)
		(fp_rect
			(start -0.4318 0.9525)
			(end 0.4318 -0.9525)
			(stroke
				(width 0)
				(type default)
			)
			(fill no)
			(layer "F.Fab")
		)
		(pad "1" smd custom
			(at 0 -0.4445 270)
			(size 0.1524 0.1524)
			(layers "F.Cu" "F.Mask" "F.Paste")
			(net "P3V3_STBY")
			(options
				(clearance outline)
				(anchor circle)
			)
			(primitives
				(gr_poly
					(pts
						(arc
							(start 0.3048 -0.2032)
							(mid 0.275042 -0.275042)
							(end 0.2032 -0.3048)
						)
						(arc
							(start -0.2032 -0.3048)
							(mid -0.275042 -0.275042)
							(end -0.3048 -0.2032)
						)
						(arc
							(start -0.3048 0.2032)
							(mid -0.275042 0.275042)
							(end -0.2032 0.3048)
						)
						(arc
							(start 0.2032 0.3048)
							(mid 0.275042 0.275042)
							(end 0.3048 0.2032)
						)
					)
					(width 0)
					(fill yes)
				)
			)
		)
		(pad "2" smd custom
			(at 0 0.4445 270)
			(size 0.1524 0.1524)
			(layers "F.Cu" "F.Mask" "F.Paste")
			(net "GND")
			(options
				(clearance outline)
				(anchor circle)
			)
			(primitives
				(gr_poly
					(pts
						(arc
							(start 0.3048 -0.2032)
							(mid 0.275042 -0.275042)
							(end 0.2032 -0.3048)
						)
						(arc
							(start -0.2032 -0.3048)
							(mid -0.275042 -0.275042)
							(end -0.3048 -0.2032)
						)
						(arc
							(start -0.3048 0.2032)
							(mid -0.275042 0.275042)
							(end -0.2032 0.3048)
						)
						(arc
							(start 0.2032 0.3048)
							(mid 0.275042 0.275042)
							(end 0.3048 0.2032)
						)
					)
					(width 0)
					(fill yes)
				)
			)
		)
	)
	(footprint ""
		(layer "F.Cu")
		(at 345.821 -68.199 180)
		(property "Reference" "PR158"
			(at 0 0 180)
			(layer "F.SilkS")
			(hide yes)
			(effects
				(font
					(size 1.27 1.27)
				)
			)
		)
		(property "Value" "100KR2F-L1-GP"
			(at 0.064008 -3.993896 180)
			(unlocked yes)
			(layer "F.Fab")
			(hide yes)
			(effects
				(font
					(size 1.016 1.016)
					(thickness 0.1524)
				)
			)
		)
		(property "Device Type" "R402H16"
			(at 0.064008 -5.517896 180)
			(unlocked yes)
			(layer "F.Fab")
			(hide yes)
			(effects
				(font
					(size 1.016 1.016)
					(thickness 0.1524)
				)
			)
		)
		(duplicate_pad_numbers_are_jumpers no)
		(fp_line
			(start 0.508 -0.9398)
			(end -0.508 -0.9398)
			(stroke
				(width 0.1524)
				(type default)
			)
			(layer "F.SilkS")
		)
		(fp_line
			(start -0.508 -0.9398)
			(end -0.508 0.9398)
			(stroke
				(width 0.1524)
				(type default)
			)
			(layer "F.SilkS")
		)
		(fp_rect
			(start -0.508 0.9398)
			(end 0.508 -0.9398)
			(stroke
				(width 0)
				(type default)
			)
			(fill no)
			(layer "F.CrtYd")
		)
		(fp_rect
			(start -0.508 0.9398)
			(end 0.508 -0.9398)
			(stroke
				(width 0)
				(type default)
			)
			(fill no)
			(layer "F.Fab")
		)
		(pad "1" smd custom
			(at 0 -0.4445 180)
			(size 0.1397 0.1397)
			(layers "F.Cu" "F.Mask" "F.Paste")
			(net "P0V9_E_VREG")
			(options
				(clearance outline)
				(anchor circle)
			)
			(primitives
				(gr_poly
					(pts
						(arc
							(start -0.1778 -0.2794)
							(mid -0.249642 -0.249642)
							(end -0.2794 -0.1778)
						)
						(arc
							(start -0.2794 0.1778)
							(mid -0.249642 0.249642)
							(end -0.1778 0.2794)
						)
						(arc
							(start 0.1778 0.2794)
							(mid 0.249642 0.249642)
							(end 0.2794 0.1778)
						)
						(arc
							(start 0.2794 -0.1778)
							(mid 0.249642 -0.249642)
							(end 0.1778 -0.2794)
						)
					)
					(width 0)
					(fill yes)
				)
			)
		)
		(pad "2" smd custom
			(at 0 0.4445 180)
			(size 0.1397 0.1397)
			(layers "F.Cu" "F.Mask" "F.Paste")
			(net "P0V9_E_RF")
			(options
				(clearance outline)
				(anchor circle)
			)
			(primitives
				(gr_poly
					(pts
						(arc
							(start -0.1778 -0.2794)
							(mid -0.249642 -0.249642)
							(end -0.2794 -0.1778)
						)
						(arc
							(start -0.2794 0.1778)
							(mid -0.249642 0.249642)
							(end -0.1778 0.2794)
						)
						(arc
							(start 0.1778 0.2794)
							(mid 0.249642 0.249642)
							(end 0.2794 0.1778)
						)
						(arc
							(start 0.2794 -0.1778)
							(mid 0.249642 -0.249642)
							(end 0.1778 -0.2794)
						)
					)
					(width 0)
					(fill yes)
				)
			)
		)
	)
	(footprint ""
		(layer "F.Cu")
		(at 140.32992 -33.9217 90)
		(property "Reference" "R274"
			(at 0 0 90)
			(layer "F.SilkS")
			(hide yes)
			(effects
				(font
					(size 1.27 1.27)
				)
			)
		)
		(property "Value" "0R2J-2-GP"
			(at 0.064008 -3.993896 90)
			(unlocked yes)
			(layer "F.Fab")
			(hide yes)
			(effects
				(font
					(size 1.016 1.016)
					(thickness 0.1524)
				)
			)
		)
		(property "Device Type" "R402H16"
			(at 0.064008 -5.517896 90)
			(unlocked yes)
			(layer "F.Fab")
			(hide yes)
			(effects
				(font
					(size 1.016 1.016)
					(thickness 0.1524)
				)
			)
		)
		(duplicate_pad_numbers_are_jumpers no)
		(fp_line
			(start 0.508 -0.9398)
			(end -0.508 -0.9398)
			(stroke
				(width 0.1524)
				(type default)
			)
			(layer "F.SilkS")
		)
		(fp_line
			(start -0.508 -0.9398)
			(end -0.508 0.9398)
			(stroke
				(width 0.1524)
				(type default)
			)
			(layer "F.SilkS")
		)
		(fp_rect
			(start -0.508 0.9398)
			(end 0.508 -0.9398)
			(stroke
				(width 0)
				(type default)
			)
			(fill no)
			(layer "F.CrtYd")
		)
		(fp_rect
			(start -0.508 0.9398)
			(end 0.508 -0.9398)
			(stroke
				(width 0)
				(type default)
			)
			(fill no)
			(layer "F.Fab")
		)
		(pad "1" smd custom
			(at 0 -0.4445 90)
			(size 0.1397 0.1397)
			(layers "F.Cu" "F.Mask" "F.Paste")
			(net "MINISAS_CN15_B_I2C_INT#")
			(options
				(clearance outline)
				(anchor circle)
			)
			(primitives
				(gr_poly
					(pts
						(arc
							(start -0.1778 -0.2794)
							(mid -0.249642 -0.249642)
							(end -0.2794 -0.1778)
						)
						(arc
							(start -0.2794 0.1778)
							(mid -0.249642 0.249642)
							(end -0.1778 0.2794)
						)
						(arc
							(start 0.1778 0.2794)
							(mid 0.249642 0.249642)
							(end 0.2794 0.1778)
						)
						(arc
							(start 0.2794 -0.1778)
							(mid 0.249642 -0.249642)
							(end 0.1778 -0.2794)
						)
					)
					(width 0)
					(fill yes)
				)
			)
		)
		(pad "2" smd custom
			(at 0 0.4445 90)
			(size 0.1397 0.1397)
			(layers "F.Cu" "F.Mask" "F.Paste")
			(net "CLK_N_2")
			(options
				(clearance outline)
				(anchor circle)
			)
			(primitives
				(gr_poly
					(pts
						(arc
							(start -0.1778 -0.2794)
							(mid -0.249642 -0.249642)
							(end -0.2794 -0.1778)
						)
						(arc
							(start -0.2794 0.1778)
							(mid -0.249642 0.249642)
							(end -0.1778 0.2794)
						)
						(arc
							(start 0.1778 0.2794)
							(mid 0.249642 0.249642)
							(end 0.2794 0.1778)
						)
						(arc
							(start 0.2794 -0.1778)
							(mid 0.249642 -0.249642)
							(end 0.1778 -0.2794)
						)
					)
					(width 0)
					(fill yes)
				)
			)
		)
	)
	(footprint ""
		(layer "F.Cu")
		(at 321.691 -86.487 180)
		(property "Reference" "R526"
			(at 0 0 180)
			(layer "F.SilkS")
			(hide yes)
			(effects
				(font
					(size 1.27 1.27)
				)
			)
		)
		(property "Value" "10KR2F-2-GP"
			(at 0.064008 -3.993896 180)
			(unlocked yes)
			(layer "F.Fab")
			(hide yes)
			(effects
				(font
					(size 1.016 1.016)
					(thickness 0.1524)
				)
			)
		)
		(property "Device Type" "R402H16"
			(at 0.064008 -5.517896 180)
			(unlocked yes)
			(layer "F.Fab")
			(hide yes)
			(effects
				(font
					(size 1.016 1.016)
					(thickness 0.1524)
				)
			)
		)
		(duplicate_pad_numbers_are_jumpers no)
		(fp_line
			(start 0.508 -0.9398)
			(end -0.508 -0.9398)
			(stroke
				(width 0.1524)
				(type default)
			)
			(layer "F.SilkS")
		)
		(fp_line
			(start -0.508 -0.9398)
			(end -0.508 0.9398)
			(stroke
				(width 0.1524)
				(type default)
			)
			(layer "F.SilkS")
		)
		(fp_rect
			(start -0.508 0.9398)
			(end 0.508 -0.9398)
			(stroke
				(width 0)
				(type default)
			)
			(fill no)
			(layer "F.CrtYd")
		)
		(fp_rect
			(start -0.508 0.9398)
			(end 0.508 -0.9398)
			(stroke
				(width 0)
				(type default)
			)
			(fill no)
			(layer "F.Fab")
		)
		(pad "1" smd custom
			(at 0 -0.4445 180)
			(size 0.1397 0.1397)
			(layers "F.Cu" "F.Mask" "F.Paste")
			(net "GND")
			(options
				(clearance outline)
				(anchor circle)
			)
			(primitives
				(gr_poly
					(pts
						(arc
							(start -0.1778 -0.2794)
							(mid -0.249642 -0.249642)
							(end -0.2794 -0.1778)
						)
						(arc
							(start -0.2794 0.1778)
							(mid -0.249642 0.249642)
							(end -0.1778 0.2794)
						)
						(arc
							(start 0.1778 0.2794)
							(mid 0.249642 0.249642)
							(end 0.2794 0.1778)
						)
						(arc
							(start 0.2794 -0.1778)
							(mid 0.249642 -0.249642)
							(end 0.1778 -0.2794)
						)
					)
					(width 0)
					(fill yes)
				)
			)
		)
		(pad "2" smd custom
			(at 0 0.4445 180)
			(size 0.1397 0.1397)
			(layers "F.Cu" "F.Mask" "F.Paste")
			(net "IOEXP_PMC1_AD2")
			(options
				(clearance outline)
				(anchor circle)
			)
			(primitives
				(gr_poly
					(pts
						(arc
							(start -0.1778 -0.2794)
							(mid -0.249642 -0.249642)
							(end -0.2794 -0.1778)
						)
						(arc
							(start -0.2794 0.1778)
							(mid -0.249642 0.249642)
							(end -0.1778 0.2794)
						)
						(arc
							(start 0.1778 0.2794)
							(mid 0.249642 0.249642)
							(end 0.2794 0.1778)
						)
						(arc
							(start 0.2794 -0.1778)
							(mid 0.249642 -0.249642)
							(end 0.1778 -0.2794)
						)
					)
					(width 0)
					(fill yes)
				)
			)
		)
	)
	(footprint ""
		(layer "F.Cu")
		(at 76.108306 -84.937854)
		(property "Reference" "R485"
			(at 0 0 0)
			(layer "F.SilkS")
			(hide yes)
			(effects
				(font
					(size 1.27 1.27)
				)
			)
		)
		(property "Value" "1KR2F-3-GP"
			(at 0.064008 -3.993896 0)
			(unlocked yes)
			(layer "F.Fab")
			(hide yes)
			(effects
				(font
					(size 1.016 1.016)
					(thickness 0.1524)
				)
			)
		)
		(property "Device Type" "R402H16"
			(at 0.064008 -5.517896 0)
			(unlocked yes)
			(layer "F.Fab")
			(hide yes)
			(effects
				(font
					(size 1.016 1.016)
					(thickness 0.1524)
				)
			)
		)
		(duplicate_pad_numbers_are_jumpers no)
		(fp_line
			(start -0.508 -0.9398)
			(end -0.508 0.9398)
			(stroke
				(width 0.1524)
				(type default)
			)
			(layer "F.SilkS")
		)
		(fp_line
			(start 0.508 -0.9398)
			(end -0.508 -0.9398)
			(stroke
				(width 0.1524)
				(type default)
			)
			(layer "F.SilkS")
		)
		(fp_rect
			(start -0.508 0.9398)
			(end 0.508 -0.9398)
			(stroke
				(width 0)
				(type default)
			)
			(fill no)
			(layer "F.CrtYd")
		)
		(fp_rect
			(start -0.508 0.9398)
			(end 0.508 -0.9398)
			(stroke
				(width 0)
				(type default)
			)
			(fill no)
			(layer "F.Fab")
		)
		(pad "1" smd custom
			(at 0 -0.4445)
			(size 0.1397 0.1397)
			(layers "F.Cu" "F.Mask" "F.Paste")
			(net "DIVIDER_2_IN")
			(options
				(clearance outline)
				(anchor circle)
			)
			(primitives
				(gr_poly
					(pts
						(arc
							(start -0.1778 -0.2794)
							(mid -0.249642 -0.249642)
							(end -0.2794 -0.1778)
						)
						(arc
							(start -0.2794 0.1778)
							(mid -0.249642 0.249642)
							(end -0.1778 0.2794)
						)
						(arc
							(start 0.1778 0.2794)
							(mid 0.249642 0.249642)
							(end 0.2794 0.1778)
						)
						(arc
							(start 0.2794 -0.1778)
							(mid 0.249642 -0.249642)
							(end 0.1778 -0.2794)
						)
					)
					(width 0)
					(fill yes)
				)
			)
		)
		(pad "2" smd custom
			(at 0 0.4445)
			(size 0.1397 0.1397)
			(layers "F.Cu" "F.Mask" "F.Paste")
			(net "GND")
			(options
				(clearance outline)
				(anchor circle)
			)
			(primitives
				(gr_poly
					(pts
						(arc
							(start -0.1778 -0.2794)
							(mid -0.249642 -0.249642)
							(end -0.2794 -0.1778)
						)
						(arc
							(start -0.2794 0.1778)
							(mid -0.249642 0.249642)
							(end -0.1778 0.2794)
						)
						(arc
							(start 0.1778 0.2794)
							(mid 0.249642 0.249642)
							(end 0.2794 0.1778)
						)
						(arc
							(start 0.2794 -0.1778)
							(mid 0.249642 -0.249642)
							(end 0.1778 -0.2794)
						)
					)
					(width 0)
					(fill yes)
				)
			)
		)
	)
	(footprint ""
		(layer "F.Cu")
		(at 319.592198 -212.420454 180)
		(property "Reference" "C67"
			(at 0 0 180)
			(layer "F.SilkS")
			(hide yes)
			(effects
				(font
					(size 1.27 1.27)
				)
			)
		)
		(property "Value" "SCD22U10V2KX-1GP"
			(at 1.1811 -2.7051 180)
			(unlocked yes)
			(layer "F.Fab")
			(hide yes)
			(effects
				(font
					(size 1.016 1.016)
					(thickness 0.1524)
				)
			)
		)
		(property "Device Type" "C402H22"
			(at 1.1811 -4.2291 180)
			(unlocked yes)
			(layer "F.Fab")
			(hide yes)
			(effects
				(font
					(size 1.016 1.016)
					(thickness 0.1524)
				)
			)
		)
		(duplicate_pad_numbers_are_jumpers no)
		(fp_rect
			(start -0.4318 0.9525)
			(end 0.4318 -0.9525)
			(stroke
				(width 0)
				(type default)
			)
			(fill no)
			(layer "F.CrtYd")
		)
		(fp_rect
			(start -0.4318 0.9525)
			(end 0.4318 -0.9525)
			(stroke
				(width 0)
				(type default)
			)
			(fill no)
			(layer "F.Fab")
		)
		(pad "1" smd custom
			(at 0 -0.4445 180)
			(size 0.1524 0.1524)
			(layers "F.Cu" "F.Mask" "F.Paste")
			(net "PCIE_TX_CAP_P22")
			(options
				(clearance outline)
				(anchor circle)
			)
			(primitives
				(gr_poly
					(pts
						(arc
							(start 0.3048 -0.2032)
							(mid 0.275042 -0.275042)
							(end 0.2032 -0.3048)
						)
						(arc
							(start -0.2032 -0.3048)
							(mid -0.275042 -0.275042)
							(end -0.3048 -0.2032)
						)
						(arc
							(start -0.3048 0.2032)
							(mid -0.275042 0.275042)
							(end -0.2032 0.3048)
						)
						(arc
							(start 0.2032 0.3048)
							(mid 0.275042 0.275042)
							(end 0.3048 0.2032)
						)
					)
					(width 0)
					(fill yes)
				)
			)
		)
		(pad "2" smd custom
			(at 0 0.4445 180)
			(size 0.1524 0.1524)
			(layers "F.Cu" "F.Mask" "F.Paste")
			(net "PCIE_TX_P22")
			(options
				(clearance outline)
				(anchor circle)
			)
			(primitives
				(gr_poly
					(pts
						(arc
							(start 0.3048 -0.2032)
							(mid 0.275042 -0.275042)
							(end 0.2032 -0.3048)
						)
						(arc
							(start -0.2032 -0.3048)
							(mid -0.275042 -0.275042)
							(end -0.3048 -0.2032)
						)
						(arc
							(start -0.3048 0.2032)
							(mid -0.275042 0.275042)
							(end -0.2032 0.3048)
						)
						(arc
							(start 0.2032 0.3048)
							(mid 0.275042 0.275042)
							(end 0.3048 0.2032)
						)
					)
					(width 0)
					(fill yes)
				)
			)
		)
	)
	(footprint ""
		(layer "F.Cu")
		(at 16.256 -145.415 90)
		(property "Reference" "L5"
			(at 0 0 90)
			(layer "F.SilkS")
			(hide yes)
			(effects
				(font
					(size 1.27 1.27)
				)
			)
		)
		(property "Value" "MMZ2012S601ATA1N-GP"
			(at 0 -4.2418 90)
			(unlocked yes)
			(layer "F.Fab")
			(hide yes)
			(effects
				(font
					(size 1.016 1.016)
					(thickness 0.1524)
				)
			)
		)
		(property "Device Type" "L805H42"
			(at 0 -5.7912 90)
			(unlocked yes)
			(layer "F.Fab")
			(hide yes)
			(effects
				(font
					(size 1.016 1.016)
					(thickness 0.1524)
				)
			)
		)
		(duplicate_pad_numbers_are_jumpers no)
		(fp_line
			(start 0.889 -1.7018)
			(end 0.889 1.7018)
			(stroke
				(width 0.1524)
				(type default)
			)
			(layer "F.SilkS")
		)
		(fp_line
			(start -0.889 -1.7018)
			(end 0.889 -1.7018)
			(stroke
				(width 0.1524)
				(type default)
			)
			(layer "F.SilkS")
		)
		(fp_line
			(start 0.889 1.7018)
			(end -0.889 1.7018)
			(stroke
				(width 0.1524)
				(type default)
			)
			(layer "F.SilkS")
		)
		(fp_line
			(start -0.889 1.7018)
			(end -0.889 -1.7018)
			(stroke
				(width 0.1524)
				(type default)
			)
			(layer "F.SilkS")
		)
		(fp_rect
			(start -0.9652 1.778)
			(end 0.9652 -1.778)
			(stroke
				(width 0)
				(type default)
			)
			(fill no)
			(layer "F.CrtYd")
		)
		(fp_rect
			(start -0.9652 1.778)
			(end 0.9652 -1.778)
			(stroke
				(width 0)
				(type default)
			)
			(fill no)
			(layer "F.Fab")
		)
		(pad "1" smd rect
			(at 0 -0.9652 90)
			(size 1.397 1.143)
			(layers "F.Cu" "F.Mask" "F.Paste")
			(net "P3V3_STBY")
		)
		(pad "2" smd rect
			(at 0 0.9652 90)
			(size 1.397 1.143)
			(layers "F.Cu" "F.Mask" "F.Paste")
			(net "MPLLAV33")
		)
	)
	(footprint ""
		(layer "F.Cu")
		(at 333.381604 -38.404546 90)
		(property "Reference" "R624"
			(at 0 0 90)
			(layer "F.SilkS")
			(hide yes)
			(effects
				(font
					(size 1.27 1.27)
				)
			)
		)
		(property "Value" "0R2J-2-GP"
			(at 0.064008 -3.993896 90)
			(unlocked yes)
			(layer "F.Fab")
			(hide yes)
			(effects
				(font
					(size 1.016 1.016)
					(thickness 0.1524)
				)
			)
		)
		(property "Device Type" "R402H16"
			(at 0.064008 -5.517896 90)
			(unlocked yes)
			(layer "F.Fab")
			(hide yes)
			(effects
				(font
					(size 1.016 1.016)
					(thickness 0.1524)
				)
			)
		)
		(duplicate_pad_numbers_are_jumpers no)
		(fp_line
			(start 0.508 -0.9398)
			(end -0.508 -0.9398)
			(stroke
				(width 0.1524)
				(type default)
			)
			(layer "F.SilkS")
		)
		(fp_line
			(start -0.508 -0.9398)
			(end -0.508 0.9398)
			(stroke
				(width 0.1524)
				(type default)
			)
			(layer "F.SilkS")
		)
		(fp_rect
			(start -0.508 0.9398)
			(end 0.508 -0.9398)
			(stroke
				(width 0)
				(type default)
			)
			(fill no)
			(layer "F.CrtYd")
		)
		(fp_rect
			(start -0.508 0.9398)
			(end 0.508 -0.9398)
			(stroke
				(width 0)
				(type default)
			)
			(fill no)
			(layer "F.Fab")
		)
		(pad "1" smd custom
			(at 0 -0.4445 90)
			(size 0.1397 0.1397)
			(layers "F.Cu" "F.Mask" "F.Paste")
			(net "UPLINK5_R")
			(options
				(clearance outline)
				(anchor circle)
			)
			(primitives
				(gr_poly
					(pts
						(arc
							(start -0.1778 -0.2794)
							(mid -0.249642 -0.249642)
							(end -0.2794 -0.1778)
						)
						(arc
							(start -0.2794 0.1778)
							(mid -0.249642 0.249642)
							(end -0.1778 0.2794)
						)
						(arc
							(start 0.1778 0.2794)
							(mid 0.249642 0.249642)
							(end 0.2794 0.1778)
						)
						(arc
							(start 0.2794 -0.1778)
							(mid 0.249642 -0.249642)
							(end 0.1778 -0.2794)
						)
					)
					(width 0)
					(fill yes)
				)
			)
		)
		(pad "2" smd custom
			(at 0 0.4445 90)
			(size 0.1397 0.1397)
			(layers "F.Cu" "F.Mask" "F.Paste")
			(net "UPLINK5")
			(options
				(clearance outline)
				(anchor circle)
			)
			(primitives
				(gr_poly
					(pts
						(arc
							(start -0.1778 -0.2794)
							(mid -0.249642 -0.249642)
							(end -0.2794 -0.1778)
						)
						(arc
							(start -0.2794 0.1778)
							(mid -0.249642 0.249642)
							(end -0.1778 0.2794)
						)
						(arc
							(start 0.1778 0.2794)
							(mid 0.249642 0.249642)
							(end 0.2794 0.1778)
						)
						(arc
							(start 0.2794 -0.1778)
							(mid 0.249642 -0.249642)
							(end 0.1778 -0.2794)
						)
					)
					(width 0)
					(fill yes)
				)
			)
		)
	)
	(footprint ""
		(layer "F.Cu")
		(at 297.044618 -33.496504 180)
		(property "Reference" "R727"
			(at 0 0 180)
			(layer "F.SilkS")
			(hide yes)
			(effects
				(font
					(size 1.27 1.27)
				)
			)
		)
		(property "Value" "0R2J-2-GP"
			(at 0.064008 -3.993896 180)
			(unlocked yes)
			(layer "F.Fab")
			(hide yes)
			(effects
				(font
					(size 1.016 1.016)
					(thickness 0.1524)
				)
			)
		)
		(property "Device Type" "R402H16"
			(at 0.064008 -5.517896 180)
			(unlocked yes)
			(layer "F.Fab")
			(hide yes)
			(effects
				(font
					(size 1.016 1.016)
					(thickness 0.1524)
				)
			)
		)
		(duplicate_pad_numbers_are_jumpers no)
		(fp_line
			(start 0.508 -0.9398)
			(end -0.508 -0.9398)
			(stroke
				(width 0.1524)
				(type default)
			)
			(layer "F.SilkS")
		)
		(fp_line
			(start -0.508 -0.9398)
			(end -0.508 0.9398)
			(stroke
				(width 0.1524)
				(type default)
			)
			(layer "F.SilkS")
		)
		(fp_rect
			(start -0.508 0.9398)
			(end 0.508 -0.9398)
			(stroke
				(width 0)
				(type default)
			)
			(fill no)
			(layer "F.CrtYd")
		)
		(fp_rect
			(start -0.508 0.9398)
			(end 0.508 -0.9398)
			(stroke
				(width 0)
				(type default)
			)
			(fill no)
			(layer "F.Fab")
		)
		(pad "1" smd custom
			(at 0 -0.4445 180)
			(size 0.1397 0.1397)
			(layers "F.Cu" "F.Mask" "F.Paste")
			(net "8644_USB_DN6")
			(options
				(clearance outline)
				(anchor circle)
			)
			(primitives
				(gr_poly
					(pts
						(arc
							(start -0.1778 -0.2794)
							(mid -0.249642 -0.249642)
							(end -0.2794 -0.1778)
						)
						(arc
							(start -0.2794 0.1778)
							(mid -0.249642 0.249642)
							(end -0.1778 0.2794)
						)
						(arc
							(start 0.1778 0.2794)
							(mid 0.249642 0.249642)
							(end 0.2794 0.1778)
						)
						(arc
							(start 0.2794 -0.1778)
							(mid 0.249642 -0.249642)
							(end 0.1778 -0.2794)
						)
					)
					(width 0)
					(fill yes)
				)
			)
		)
		(pad "2" smd custom
			(at 0 0.4445 180)
			(size 0.1397 0.1397)
			(layers "F.Cu" "F.Mask" "F.Paste")
			(net "P3V3_STBY")
			(options
				(clearance outline)
				(anchor circle)
			)
			(primitives
				(gr_poly
					(pts
						(arc
							(start -0.1778 -0.2794)
							(mid -0.249642 -0.249642)
							(end -0.2794 -0.1778)
						)
						(arc
							(start -0.2794 0.1778)
							(mid -0.249642 0.249642)
							(end -0.1778 0.2794)
						)
						(arc
							(start 0.1778 0.2794)
							(mid 0.249642 0.249642)
							(end 0.2794 0.1778)
						)
						(arc
							(start 0.2794 -0.1778)
							(mid 0.249642 -0.249642)
							(end 0.1778 -0.2794)
						)
					)
					(width 0)
					(fill yes)
				)
			)
		)
	)
	(footprint ""
		(layer "F.Cu")
		(at 15.3035 -50.8254 90)
		(property "Reference" "D15"
			(at 0 0 90)
			(layer "F.SilkS")
			(hide yes)
			(effects
				(font
					(size 1.27 1.27)
				)
			)
		)
		(property "Value" "PGB1010603MR-GP"
			(at -0.0254 -2.8956 90)
			(unlocked yes)
			(layer "F.Fab")
			(hide yes)
			(effects
				(font
					(size 1.016 1.016)
					(thickness 0.1524)
				)
			)
		)
		(property "Device Type" "L1608-UH15"
			(at -0.0254 -4.4196 90)
			(unlocked yes)
			(layer "F.Fab")
			(hide yes)
			(effects
				(font
					(size 1.016 1.016)
					(thickness 0.1524)
				)
			)
		)
		(duplicate_pad_numbers_are_jumpers no)
		(fp_line
			(start 0.254 0)
			(end -0.254 0)
			(stroke
				(width 0.2032)
				(type default)
			)
			(layer "F.SilkS")
		)
		(fp_rect
			(start -0.5842 1.3335)
			(end 0.5842 -1.3335)
			(stroke
				(width 0)
				(type default)
			)
			(fill no)
			(layer "F.CrtYd")
		)
		(fp_rect
			(start -0.5842 1.3335)
			(end 0.5842 -1.3335)
			(stroke
				(width 0)
				(type default)
			)
			(fill no)
			(layer "F.Fab")
		)
		(pad "1" smd custom
			(at 0 -0.762 90)
			(size 0.2159 0.2159)
			(layers "F.Cu" "F.Mask" "F.Paste")
			(net "NIC0_MDI0_P1_R")
			(options
				(clearance outline)
				(anchor circle)
			)
			(primitives
				(gr_poly
					(pts
						(arc
							(start -0.3302 -0.4318)
							(mid -0.402042 -0.402042)
							(end -0.4318 -0.3302)
						)
						(arc
							(start -0.4318 0.3302)
							(mid -0.402042 0.402042)
							(end -0.3302 0.4318)
						)
						(arc
							(start 0.3302 0.4318)
							(mid 0.402042 0.402042)
							(end 0.4318 0.3302)
						)
						(arc
							(start 0.4318 -0.3302)
							(mid 0.402042 -0.402042)
							(end 0.3302 -0.4318)
						)
					)
					(width 0)
					(fill yes)
				)
			)
		)
		(pad "2" smd custom
			(at 0 0.762 90)
			(size 0.2159 0.2159)
			(layers "F.Cu" "F.Mask" "F.Paste")
			(net "GND")
			(options
				(clearance outline)
				(anchor circle)
			)
			(primitives
				(gr_poly
					(pts
						(arc
							(start -0.3302 -0.4318)
							(mid -0.402042 -0.402042)
							(end -0.4318 -0.3302)
						)
						(arc
							(start -0.4318 0.3302)
							(mid -0.402042 0.402042)
							(end -0.3302 0.4318)
						)
						(arc
							(start 0.3302 0.4318)
							(mid 0.402042 0.402042)
							(end 0.4318 0.3302)
						)
						(arc
							(start 0.4318 -0.3302)
							(mid 0.402042 -0.402042)
							(end 0.3302 -0.4318)
						)
					)
					(width 0)
					(fill yes)
				)
			)
		)
	)
	(footprint ""
		(layer "F.Cu")
		(at 137.79246 -41.173654 180)
		(property "Reference" "R754"
			(at 0 0 180)
			(layer "F.SilkS")
			(hide yes)
			(effects
				(font
					(size 1.27 1.27)
				)
			)
		)
		(property "Value" "33D2R2F-GP"
			(at 0.064008 -3.993896 180)
			(unlocked yes)
			(layer "F.Fab")
			(hide yes)
			(effects
				(font
					(size 1.016 1.016)
					(thickness 0.1524)
				)
			)
		)
		(property "Device Type" "R402H16"
			(at 0.064008 -5.517896 180)
			(unlocked yes)
			(layer "F.Fab")
			(hide yes)
			(effects
				(font
					(size 1.016 1.016)
					(thickness 0.1524)
				)
			)
		)
		(duplicate_pad_numbers_are_jumpers no)
		(fp_line
			(start 0.508 -0.9398)
			(end -0.508 -0.9398)
			(stroke
				(width 0.1524)
				(type default)
			)
			(layer "F.SilkS")
		)
		(fp_line
			(start -0.508 -0.9398)
			(end -0.508 0.9398)
			(stroke
				(width 0.1524)
				(type default)
			)
			(layer "F.SilkS")
		)
		(fp_rect
			(start -0.508 0.9398)
			(end 0.508 -0.9398)
			(stroke
				(width 0)
				(type default)
			)
			(fill no)
			(layer "F.CrtYd")
		)
		(fp_rect
			(start -0.508 0.9398)
			(end 0.508 -0.9398)
			(stroke
				(width 0)
				(type default)
			)
			(fill no)
			(layer "F.Fab")
		)
		(pad "1" smd custom
			(at 0 -0.4445 180)
			(size 0.1397 0.1397)
			(layers "F.Cu" "F.Mask" "F.Paste")
			(net "DUT_TDO")
			(options
				(clearance outline)
				(anchor circle)
			)
			(primitives
				(gr_poly
					(pts
						(arc
							(start -0.1778 -0.2794)
							(mid -0.249642 -0.249642)
							(end -0.2794 -0.1778)
						)
						(arc
							(start -0.2794 0.1778)
							(mid -0.249642 0.249642)
							(end -0.1778 0.2794)
						)
						(arc
							(start 0.1778 0.2794)
							(mid 0.249642 0.249642)
							(end 0.2794 0.1778)
						)
						(arc
							(start 0.2794 -0.1778)
							(mid 0.249642 -0.249642)
							(end 0.1778 -0.2794)
						)
					)
					(width 0)
					(fill yes)
				)
			)
		)
		(pad "2" smd custom
			(at 0 0.4445 180)
			(size 0.1397 0.1397)
			(layers "F.Cu" "F.Mask" "F.Paste")
			(net "EJTAG_TDO")
			(options
				(clearance outline)
				(anchor circle)
			)
			(primitives
				(gr_poly
					(pts
						(arc
							(start -0.1778 -0.2794)
							(mid -0.249642 -0.249642)
							(end -0.2794 -0.1778)
						)
						(arc
							(start -0.2794 0.1778)
							(mid -0.249642 0.249642)
							(end -0.1778 0.2794)
						)
						(arc
							(start 0.1778 0.2794)
							(mid 0.249642 0.249642)
							(end 0.2794 0.1778)
						)
						(arc
							(start 0.2794 -0.1778)
							(mid 0.249642 -0.249642)
							(end 0.1778 -0.2794)
						)
					)
					(width 0)
					(fill yes)
				)
			)
		)
	)
	(footprint ""
		(layer "F.Cu")
		(at 307.975 -68.834 180)
		(property "Reference" "C630"
			(at 0 0 180)
			(layer "F.SilkS")
			(hide yes)
			(effects
				(font
					(size 1.27 1.27)
				)
			)
		)
		(property "Value" "SC10U16V5KX-1-GP"
			(at -0.0762 -6.1214 180)
			(unlocked yes)
			(layer "F.Fab")
			(hide yes)
			(effects
				(font
					(size 1.016 1.016)
					(thickness 0.1524)
				)
			)
		)
		(property "Device Type" "C805H54"
			(at -0.0762 -8.1534 180)
			(unlocked yes)
			(layer "F.Fab")
			(hide yes)
			(effects
				(font
					(size 1.016 1.016)
					(thickness 0.1524)
				)
			)
		)
		(duplicate_pad_numbers_are_jumpers no)
		(fp_line
			(start 0.635 0)
			(end -0.635 0)
			(stroke
				(width 0.508)
				(type default)
			)
			(layer "F.SilkS")
		)
		(fp_rect
			(start -0.9652 1.778)
			(end 0.9652 -1.778)
			(stroke
				(width 0)
				(type default)
			)
			(fill no)
			(layer "F.CrtYd")
		)
		(fp_poly
			(pts
				(xy -0.9652 -1.778) (xy 0.9652 -1.778) (xy 0.9652 1.778) (xy -0.9652 1.778)
			)
			(stroke
				(width 0)
				(type default)
			)
			(fill no)
			(layer "F.Fab")
		)
		(pad "1" smd rect
			(at 0 -0.9652 180)
			(size 1.397 1.143)
			(layers "F.Cu" "F.Mask" "F.Paste")
			(net "DUT_VDD")
		)
		(pad "2" smd rect
			(at 0 0.9652 180)
			(size 1.397 1.143)
			(layers "F.Cu" "F.Mask" "F.Paste")
			(net "GND")
		)
	)
	(footprint ""
		(layer "F.Cu")
		(at 31.41472 -79.429356)
		(property "Reference" "PC73"
			(at 0 0 0)
			(layer "F.SilkS")
			(hide yes)
			(effects
				(font
					(size 1.27 1.27)
				)
			)
		)
		(property "Value" "SC22P50V3JN-GP"
			(at 0 -2.8194 0)
			(unlocked yes)
			(layer "F.Fab")
			(hide yes)
			(effects
				(font
					(size 1.016 1.016)
					(thickness 0.1524)
				)
			)
		)
		(property "Device Type" "C603H36"
			(at 0 -4.3434 0)
			(unlocked yes)
			(layer "F.Fab")
			(hide yes)
			(effects
				(font
					(size 1.016 1.016)
					(thickness 0.1524)
				)
			)
		)
		(duplicate_pad_numbers_are_jumpers no)
		(fp_line
			(start 0.508 0)
			(end -0.508 0)
			(stroke
				(width 0.2032)
				(type default)
			)
			(layer "F.SilkS")
		)
		(fp_rect
			(start -0.5842 1.3335)
			(end 0.5842 -1.3335)
			(stroke
				(width 0)
				(type default)
			)
			(fill no)
			(layer "F.CrtYd")
		)
		(fp_rect
			(start -0.5842 1.3335)
			(end 0.5842 -1.3335)
			(stroke
				(width 0)
				(type default)
			)
			(fill no)
			(layer "F.Fab")
		)
		(pad "1" smd custom
			(at 0 -0.762)
			(size 0.2159 0.2159)
			(layers "F.Cu" "F.Mask" "F.Paste")
			(net "P5V_STBY_LR")
			(options
				(clearance outline)
				(anchor circle)
			)
			(primitives
				(gr_poly
					(pts
						(arc
							(start -0.3302 -0.4318)
							(mid -0.402042 -0.402042)
							(end -0.4318 -0.3302)
						)
						(arc
							(start -0.4318 0.3302)
							(mid -0.402042 0.402042)
							(end -0.3302 0.4318)
						)
						(arc
							(start 0.3302 0.4318)
							(mid 0.402042 0.402042)
							(end 0.4318 0.3302)
						)
						(arc
							(start 0.4318 -0.3302)
							(mid 0.402042 -0.402042)
							(end 0.3302 -0.4318)
						)
					)
					(width 0)
					(fill yes)
				)
			)
		)
		(pad "2" smd custom
			(at 0 0.762)
			(size 0.2159 0.2159)
			(layers "F.Cu" "F.Mask" "F.Paste")
			(net "P5V_STBY_FB")
			(options
				(clearance outline)
				(anchor circle)
			)
			(primitives
				(gr_poly
					(pts
						(arc
							(start -0.3302 -0.4318)
							(mid -0.402042 -0.402042)
							(end -0.4318 -0.3302)
						)
						(arc
							(start -0.4318 0.3302)
							(mid -0.402042 0.402042)
							(end -0.3302 0.4318)
						)
						(arc
							(start 0.3302 0.4318)
							(mid 0.402042 0.402042)
							(end 0.4318 0.3302)
						)
						(arc
							(start 0.4318 -0.3302)
							(mid 0.402042 -0.402042)
							(end 0.3302 -0.4318)
						)
					)
					(width 0)
					(fill yes)
				)
			)
		)
	)
	(footprint ""
		(layer "F.Cu")
		(at 23.4696 -55.118 180)
		(property "Reference" "R603"
			(at 0 0 180)
			(layer "F.SilkS")
			(hide yes)
			(effects
				(font
					(size 1.27 1.27)
				)
			)
		)
		(property "Value" "0R2J-2-GP"
			(at 0.064008 -3.993896 180)
			(unlocked yes)
			(layer "F.Fab")
			(hide yes)
			(effects
				(font
					(size 1.016 1.016)
					(thickness 0.1524)
				)
			)
		)
		(property "Device Type" "R402H16"
			(at 0.064008 -5.517896 180)
			(unlocked yes)
			(layer "F.Fab")
			(hide yes)
			(effects
				(font
					(size 1.016 1.016)
					(thickness 0.1524)
				)
			)
		)
		(duplicate_pad_numbers_are_jumpers no)
		(fp_line
			(start 0.508 -0.9398)
			(end -0.508 -0.9398)
			(stroke
				(width 0.1524)
				(type default)
			)
			(layer "F.SilkS")
		)
		(fp_line
			(start -0.508 -0.9398)
			(end -0.508 0.9398)
			(stroke
				(width 0.1524)
				(type default)
			)
			(layer "F.SilkS")
		)
		(fp_rect
			(start -0.508 0.9398)
			(end 0.508 -0.9398)
			(stroke
				(width 0)
				(type default)
			)
			(fill no)
			(layer "F.CrtYd")
		)
		(fp_rect
			(start -0.508 0.9398)
			(end 0.508 -0.9398)
			(stroke
				(width 0)
				(type default)
			)
			(fill no)
			(layer "F.Fab")
		)
		(pad "1" smd custom
			(at 0 -0.4445 180)
			(size 0.1397 0.1397)
			(layers "F.Cu" "F.Mask" "F.Paste")
			(net "NIC0_MDI0_P3")
			(options
				(clearance outline)
				(anchor circle)
			)
			(primitives
				(gr_poly
					(pts
						(arc
							(start -0.1778 -0.2794)
							(mid -0.249642 -0.249642)
							(end -0.2794 -0.1778)
						)
						(arc
							(start -0.2794 0.1778)
							(mid -0.249642 0.249642)
							(end -0.1778 0.2794)
						)
						(arc
							(start 0.1778 0.2794)
							(mid 0.249642 0.249642)
							(end 0.2794 0.1778)
						)
						(arc
							(start 0.2794 -0.1778)
							(mid 0.249642 -0.249642)
							(end 0.1778 -0.2794)
						)
					)
					(width 0)
					(fill yes)
				)
			)
		)
		(pad "2" smd custom
			(at 0 0.4445 180)
			(size 0.1397 0.1397)
			(layers "F.Cu" "F.Mask" "F.Paste")
			(net "MNG_RX_DP")
			(options
				(clearance outline)
				(anchor circle)
			)
			(primitives
				(gr_poly
					(pts
						(arc
							(start -0.1778 -0.2794)
							(mid -0.249642 -0.249642)
							(end -0.2794 -0.1778)
						)
						(arc
							(start -0.2794 0.1778)
							(mid -0.249642 0.249642)
							(end -0.1778 0.2794)
						)
						(arc
							(start 0.1778 0.2794)
							(mid 0.249642 0.249642)
							(end 0.2794 0.1778)
						)
						(arc
							(start 0.2794 -0.1778)
							(mid 0.249642 -0.249642)
							(end 0.1778 -0.2794)
						)
					)
					(width 0)
					(fill yes)
				)
			)
		)
	)
	(footprint ""
		(layer "F.Cu")
		(at 80.607916 -212.420454 180)
		(property "Reference" "C351"
			(at 0 0 180)
			(layer "F.SilkS")
			(hide yes)
			(effects
				(font
					(size 1.27 1.27)
				)
			)
		)
		(property "Value" "SCD22U10V2KX-1GP"
			(at 1.1811 -2.7051 180)
			(unlocked yes)
			(layer "F.Fab")
			(hide yes)
			(effects
				(font
					(size 1.016 1.016)
					(thickness 0.1524)
				)
			)
		)
		(property "Device Type" "C402H22"
			(at 1.1811 -4.2291 180)
			(unlocked yes)
			(layer "F.Fab")
			(hide yes)
			(effects
				(font
					(size 1.016 1.016)
					(thickness 0.1524)
				)
			)
		)
		(duplicate_pad_numbers_are_jumpers no)
		(fp_rect
			(start -0.4318 0.9525)
			(end 0.4318 -0.9525)
			(stroke
				(width 0)
				(type default)
			)
			(fill no)
			(layer "F.CrtYd")
		)
		(fp_rect
			(start -0.4318 0.9525)
			(end 0.4318 -0.9525)
			(stroke
				(width 0)
				(type default)
			)
			(fill no)
			(layer "F.Fab")
		)
		(pad "1" smd custom
			(at 0 -0.4445 180)
			(size 0.1524 0.1524)
			(layers "F.Cu" "F.Mask" "F.Paste")
			(net "PCIE_TX_CAP_N68")
			(options
				(clearance outline)
				(anchor circle)
			)
			(primitives
				(gr_poly
					(pts
						(arc
							(start 0.3048 -0.2032)
							(mid 0.275042 -0.275042)
							(end 0.2032 -0.3048)
						)
						(arc
							(start -0.2032 -0.3048)
							(mid -0.275042 -0.275042)
							(end -0.3048 -0.2032)
						)
						(arc
							(start -0.3048 0.2032)
							(mid -0.275042 0.275042)
							(end -0.2032 0.3048)
						)
						(arc
							(start 0.2032 0.3048)
							(mid 0.275042 0.275042)
							(end 0.3048 0.2032)
						)
					)
					(width 0)
					(fill yes)
				)
			)
		)
		(pad "2" smd custom
			(at 0 0.4445 180)
			(size 0.1524 0.1524)
			(layers "F.Cu" "F.Mask" "F.Paste")
			(net "PCIE_TX_N68")
			(options
				(clearance outline)
				(anchor circle)
			)
			(primitives
				(gr_poly
					(pts
						(arc
							(start 0.3048 -0.2032)
							(mid 0.275042 -0.275042)
							(end 0.2032 -0.3048)
						)
						(arc
							(start -0.2032 -0.3048)
							(mid -0.275042 -0.275042)
							(end -0.3048 -0.2032)
						)
						(arc
							(start -0.3048 0.2032)
							(mid -0.275042 0.275042)
							(end -0.2032 0.3048)
						)
						(arc
							(start 0.2032 0.3048)
							(mid 0.275042 0.275042)
							(end 0.3048 0.2032)
						)
					)
					(width 0)
					(fill yes)
				)
			)
		)
	)
	(footprint ""
		(layer "F.Cu")
		(at 129.388362 -39.469568 180)
		(property "Reference" "Q27"
			(at 0 0 180)
			(layer "F.SilkS")
			(hide yes)
			(effects
				(font
					(size 1.27 1.27)
				)
			)
		)
		(property "Value" "2N7002K-1-GP"
			(at 0.127 -8.9662 180)
			(unlocked yes)
			(layer "F.Fab")
			(hide yes)
			(effects
				(font
					(size 1.016 1.016)
					(thickness 0.1524)
				)
			)
		)
		(property "Device Type" "SOT23DGS2D4H44"
			(at 0.127 -10.4902 180)
			(unlocked yes)
			(layer "F.Fab")
			(hide yes)
			(effects
				(font
					(size 1.016 1.016)
					(thickness 0.1524)
				)
			)
		)
		(duplicate_pad_numbers_are_jumpers no)
		(fp_line
			(start 1.651 1.778)
			(end 1.651 -1.778)
			(stroke
				(width 0.1524)
				(type default)
			)
			(layer "F.SilkS")
		)
		(fp_line
			(start 1.651 -1.778)
			(end -1.651 -1.778)
			(stroke
				(width 0.1524)
				(type default)
			)
			(layer "F.SilkS")
		)
		(fp_line
			(start -1.651 1.778)
			(end 1.651 1.778)
			(stroke
				(width 0.1524)
				(type default)
			)
			(layer "F.SilkS")
		)
		(fp_line
			(start -1.651 -1.778)
			(end -1.651 1.778)
			(stroke
				(width 0.1524)
				(type default)
			)
			(layer "F.SilkS")
		)
		(fp_poly
			(pts
				(xy -1.778 1.8796) (xy -1.778 -1.8796) (xy 1.778 -1.8796) (xy 1.778 1.8796)
			)
			(stroke
				(width 0)
				(type default)
			)
			(fill no)
			(layer "F.CrtYd")
		)
		(fp_poly
			(pts
				(xy -1.778 1.8796) (xy -1.778 -1.8796) (xy 1.778 -1.8796) (xy 1.778 1.8796)
			)
			(stroke
				(width 0)
				(type default)
			)
			(fill no)
			(layer "F.Fab")
		)
		(pad "D" smd custom
			(at 0 -0.9525 180)
			(size 0.1905 0.1905)
			(layers "F.Cu" "F.Mask" "F.Paste")
			(net "LED_Q_4")
			(options
				(clearance outline)
				(anchor circle)
			)
			(primitives
				(gr_poly
					(pts
						(arc
							(start -0.1778 0.5715)
							(mid -0.321484 0.511984)
							(end -0.381 0.3683)
						)
						(arc
							(start -0.381 -0.3683)
							(mid -0.321484 -0.511984)
							(end -0.1778 -0.5715)
						)
						(arc
							(start 0.1778 -0.5715)
							(mid 0.321484 -0.511984)
							(end 0.381 -0.3683)
						)
						(arc
							(start 0.381 0.3683)
							(mid 0.321484 0.511984)
							(end 0.1778 0.5715)
						)
					)
					(width 0)
					(fill yes)
				)
			)
		)
		(pad "G" smd custom
			(at -0.98425 0.9525 180)
			(size 0.1905 0.1905)
			(layers "F.Cu" "F.Mask" "F.Paste")
			(net "UPLINK4_R")
			(options
				(clearance outline)
				(anchor circle)
			)
			(primitives
				(gr_poly
					(pts
						(arc
							(start -0.1778 0.5715)
							(mid -0.321484 0.511984)
							(end -0.381 0.3683)
						)
						(arc
							(start -0.381 -0.3683)
							(mid -0.321484 -0.511984)
							(end -0.1778 -0.5715)
						)
						(arc
							(start 0.1778 -0.5715)
							(mid 0.321484 -0.511984)
							(end 0.381 -0.3683)
						)
						(arc
							(start 0.381 0.3683)
							(mid 0.321484 0.511984)
							(end 0.1778 0.5715)
						)
					)
					(width 0)
					(fill yes)
				)
			)
		)
		(pad "S" smd custom
			(at 0.98425 0.9525 180)
			(size 0.1905 0.1905)
			(layers "F.Cu" "F.Mask" "F.Paste")
			(net "GND")
			(options
				(clearance outline)
				(anchor circle)
			)
			(primitives
				(gr_poly
					(pts
						(arc
							(start -0.1778 0.5715)
							(mid -0.321484 0.511984)
							(end -0.381 0.3683)
						)
						(arc
							(start -0.381 -0.3683)
							(mid -0.321484 -0.511984)
							(end -0.1778 -0.5715)
						)
						(arc
							(start 0.1778 -0.5715)
							(mid 0.321484 -0.511984)
							(end 0.381 -0.3683)
						)
						(arc
							(start 0.381 0.3683)
							(mid 0.321484 0.511984)
							(end 0.1778 0.5715)
						)
					)
					(width 0)
					(fill yes)
				)
			)
		)
	)
	(footprint ""
		(layer "F.Cu")
		(at 128.8542 -45.8978 180)
		(property "Reference" "R762"
			(at 0 0 180)
			(layer "F.SilkS")
			(hide yes)
			(effects
				(font
					(size 1.27 1.27)
				)
			)
		)
		(property "Value" "0R2J-2-GP"
			(at 0.064008 -3.993896 180)
			(unlocked yes)
			(layer "F.Fab")
			(hide yes)
			(effects
				(font
					(size 1.016 1.016)
					(thickness 0.1524)
				)
			)
		)
		(property "Device Type" "R402H16"
			(at 0.064008 -5.517896 180)
			(unlocked yes)
			(layer "F.Fab")
			(hide yes)
			(effects
				(font
					(size 1.016 1.016)
					(thickness 0.1524)
				)
			)
		)
		(duplicate_pad_numbers_are_jumpers no)
		(fp_line
			(start 0.508 -0.9398)
			(end -0.508 -0.9398)
			(stroke
				(width 0.1524)
				(type default)
			)
			(layer "F.SilkS")
		)
		(fp_line
			(start -0.508 -0.9398)
			(end -0.508 0.9398)
			(stroke
				(width 0.1524)
				(type default)
			)
			(layer "F.SilkS")
		)
		(fp_rect
			(start -0.508 0.9398)
			(end 0.508 -0.9398)
			(stroke
				(width 0)
				(type default)
			)
			(fill no)
			(layer "F.CrtYd")
		)
		(fp_rect
			(start -0.508 0.9398)
			(end 0.508 -0.9398)
			(stroke
				(width 0)
				(type default)
			)
			(fill no)
			(layer "F.Fab")
		)
		(pad "1" smd custom
			(at 0 -0.4445 180)
			(size 0.1397 0.1397)
			(layers "F.Cu" "F.Mask" "F.Paste")
			(net "EJTAG_TRSTB_R")
			(options
				(clearance outline)
				(anchor circle)
			)
			(primitives
				(gr_poly
					(pts
						(arc
							(start -0.1778 -0.2794)
							(mid -0.249642 -0.249642)
							(end -0.2794 -0.1778)
						)
						(arc
							(start -0.2794 0.1778)
							(mid -0.249642 0.249642)
							(end -0.1778 0.2794)
						)
						(arc
							(start 0.1778 0.2794)
							(mid 0.249642 0.249642)
							(end 0.2794 0.1778)
						)
						(arc
							(start 0.2794 -0.1778)
							(mid 0.249642 -0.249642)
							(end 0.1778 -0.2794)
						)
					)
					(width 0)
					(fill yes)
				)
			)
		)
		(pad "2" smd custom
			(at 0 0.4445 180)
			(size 0.1397 0.1397)
			(layers "F.Cu" "F.Mask" "F.Paste")
			(net "EJTAG_TRSTB")
			(options
				(clearance outline)
				(anchor circle)
			)
			(primitives
				(gr_poly
					(pts
						(arc
							(start -0.1778 -0.2794)
							(mid -0.249642 -0.249642)
							(end -0.2794 -0.1778)
						)
						(arc
							(start -0.2794 0.1778)
							(mid -0.249642 0.249642)
							(end -0.1778 0.2794)
						)
						(arc
							(start 0.1778 0.2794)
							(mid 0.249642 0.249642)
							(end 0.2794 0.1778)
						)
						(arc
							(start 0.2794 -0.1778)
							(mid 0.249642 -0.249642)
							(end 0.1778 -0.2794)
						)
					)
					(width 0)
					(fill yes)
				)
			)
		)
	)
	(footprint ""
		(layer "F.Cu")
		(at 25.019 -147.574 -90)
		(property "Reference" "OSC1"
			(at 0 0 270)
			(layer "F.SilkS")
			(hide yes)
			(effects
				(font
					(size 1.27 1.27)
				)
			)
		)
		(property "Value" "OSC-48MHZ-28-GP"
			(at 0.0127 -2.7686 270)
			(unlocked yes)
			(layer "F.Fab")
			(hide yes)
			(effects
				(font
					(size 1.016 1.016)
					(thickness 0.1524)
				)
			)
		)
		(property "Device Type" "OSC-3225-4P-3H48"
			(at 0.0127 -4.2926 270)
			(unlocked yes)
			(layer "F.Fab")
			(hide yes)
			(effects
				(font
					(size 1.016 1.016)
					(thickness 0.1524)
				)
			)
		)
		(duplicate_pad_numbers_are_jumpers no)
		(fp_line
			(start -2.2352 1.6256)
			(end -2.2352 0.635)
			(stroke
				(width 0.3302)
				(type default)
			)
			(layer "F.SilkS")
		)
		(fp_line
			(start -1.3208 1.6256)
			(end -2.2352 1.6256)
			(stroke
				(width 0.3302)
				(type default)
			)
			(layer "F.SilkS")
		)
		(fp_line
			(start -2.1209 1.5367)
			(end -2.1209 -1.5367)
			(stroke
				(width 0.1524)
				(type default)
			)
			(layer "F.SilkS")
		)
		(fp_line
			(start 2.1209 1.5367)
			(end -2.1209 1.5367)
			(stroke
				(width 0.1524)
				(type default)
			)
			(layer "F.SilkS")
		)
		(fp_line
			(start -2.1209 -1.5367)
			(end 2.1209 -1.5367)
			(stroke
				(width 0.1524)
				(type default)
			)
			(layer "F.SilkS")
		)
		(fp_line
			(start 2.1209 -1.5367)
			(end 2.1209 1.5367)
			(stroke
				(width 0.1524)
				(type default)
			)
			(layer "F.SilkS")
		)
		(fp_poly
			(pts
				(xy -2.8321 1.459992) (xy -2.8321 0.189992) (xy -2.1971 0.824992)
			)
			(stroke
				(width 0)
				(type default)
			)
			(fill yes)
			(layer "F.SilkS")
		)
		(fp_rect
			(start -1.6002 1.2446)
			(end 1.6002 -1.2446)
			(stroke
				(width 0)
				(type default)
			)
			(fill no)
			(layer "F.CrtYd")
		)
		(fp_poly
			(pts
				(xy -2.3749 1.7907) (xy -2.3749 -1.7907) (xy 2.3749 -1.7907) (xy 2.3749 1.7907) (xy 1.6002 1.7907)
				(xy 1.6002 -1.2446) (xy -1.6002 -1.2446) (xy -1.6002 1.2446) (xy 1.59512 1.2446) (xy 1.59512 1.7907)
			)
			(stroke
				(width 0)
				(type default)
			)
			(fill no)
			(layer "F.CrtYd")
		)
		(fp_rect
			(start -2.3749 1.7907)
			(end 2.3749 -1.7907)
			(stroke
				(width 0)
				(type default)
			)
			(fill no)
			(layer "F.Fab")
		)
		(pad "1" smd rect
			(at -1.171448 0.824992 270)
			(size 1.397 0.9144)
			(layers "F.Cu" "F.Mask" "F.Paste")
			(net "OSC2_CONT")
		)
		(pad "2" smd rect
			(at 1.171448 0.824992 270)
			(size 1.397 0.9144)
			(layers "F.Cu" "F.Mask" "F.Paste")
			(net "GND")
		)
		(pad "3" smd rect
			(at 1.171448 -0.824992 270)
			(size 1.397 0.9144)
			(layers "F.Cu" "F.Mask" "F.Paste")
			(net "OSC2_OUT")
		)
		(pad "4" smd rect
			(at -1.171448 -0.824992 270)
			(size 1.397 0.9144)
			(layers "F.Cu" "F.Mask" "F.Paste")
			(net "P3V3_STBY")
		)
		(zone
			(layer "F.Cu")
			(hatch none 0.5)
			(connect_pads
				(clearance 0)
			)
			(min_thickness 0.25)
			(keepout
				(tracks not_allowed)
				(vias allowed)
				(pads allowed)
				(copperpour not_allowed)
				(footprints allowed)
			)
			(placement
				(enabled no)
				(sheetname "")
			)
			(fill
				(thermal_gap 0.5)
				(thermal_bridge_width 0.5)
				(island_removal_mode 0)
			)
			(polygon
				(pts
					(xy 24.976328 -147.721828) (xy 24.976328 -147.426172) (xy 25.061672 -147.426172) (xy 25.061672 -147.721828)
				)
			)
		)
		(zone
			(layer "F.Cu")
			(hatch none 0.5)
			(connect_pads
				(clearance 0)
			)
			(min_thickness 0.25)
			(keepout
				(tracks allowed)
				(vias not_allowed)
				(pads allowed)
				(copperpour not_allowed)
				(footprints allowed)
			)
			(placement
				(enabled no)
				(sheetname "")
			)
			(fill
				(thermal_gap 0.5)
				(thermal_bridge_width 0.5)
				(island_removal_mode 0)
			)
			(polygon
				(pts
					(xy 23.736808 -148.046948) (xy 24.651208 -148.046948) (xy 24.651208 -149.443948) (xy 25.386792 -149.443948)
					(xy 25.386792 -148.046948) (xy 26.301192 -148.046948) (xy 26.301192 -147.101052) (xy 25.386792 -147.101052)
					(xy 25.386792 -145.704052) (xy 24.651208 -145.704052) (xy 24.651208 -147.101052) (xy 23.736808 -147.101052)
				)
			)
		)
	)
	(footprint ""
		(layer "F.Cu")
		(at 149.733 -89.535 180)
		(property "Reference" "PC69"
			(at 0 0 180)
			(layer "F.SilkS")
			(hide yes)
			(effects
				(font
					(size 1.27 1.27)
				)
			)
		)
		(property "Value" "SC4D7U16V5KX-1-GP"
			(at -0.0762 -6.1214 180)
			(unlocked yes)
			(layer "F.Fab")
			(hide yes)
			(effects
				(font
					(size 1.016 1.016)
					(thickness 0.1524)
				)
			)
		)
		(property "Device Type" "C805H56"
			(at -0.0762 -8.1534 180)
			(unlocked yes)
			(layer "F.Fab")
			(hide yes)
			(effects
				(font
					(size 1.016 1.016)
					(thickness 0.1524)
				)
			)
		)
		(duplicate_pad_numbers_are_jumpers no)
		(fp_line
			(start 0.635 0)
			(end -0.635 0)
			(stroke
				(width 0.508)
				(type default)
			)
			(layer "F.SilkS")
		)
		(fp_rect
			(start -0.9652 1.778)
			(end 0.9652 -1.778)
			(stroke
				(width 0)
				(type default)
			)
			(fill no)
			(layer "F.CrtYd")
		)
		(fp_poly
			(pts
				(xy -0.9652 -1.778) (xy 0.9652 -1.778) (xy 0.9652 1.778) (xy -0.9652 1.778)
			)
			(stroke
				(width 0)
				(type default)
			)
			(fill no)
			(layer "F.Fab")
		)
		(pad "1" smd rect
			(at 0 -0.9652 180)
			(size 1.397 1.143)
			(layers "F.Cu" "F.Mask" "F.Paste")
			(net "P1V8_PWR")
		)
		(pad "2" smd rect
			(at 0 0.9652 180)
			(size 1.397 1.143)
			(layers "F.Cu" "F.Mask" "F.Paste")
			(net "GND")
		)
	)
	(footprint ""
		(layer "F.Cu")
		(at 15.0114 -120.4468 90)
		(property "Reference" "R238"
			(at 0 0 90)
			(layer "F.SilkS")
			(hide yes)
			(effects
				(font
					(size 1.27 1.27)
				)
			)
		)
		(property "Value" "0R2J-2-GP"
			(at 0.064008 -3.993896 90)
			(unlocked yes)
			(layer "F.Fab")
			(hide yes)
			(effects
				(font
					(size 1.016 1.016)
					(thickness 0.1524)
				)
			)
		)
		(property "Device Type" "R402H16"
			(at 0.064008 -5.517896 90)
			(unlocked yes)
			(layer "F.Fab")
			(hide yes)
			(effects
				(font
					(size 1.016 1.016)
					(thickness 0.1524)
				)
			)
		)
		(duplicate_pad_numbers_are_jumpers no)
		(fp_line
			(start 0.508 -0.9398)
			(end -0.508 -0.9398)
			(stroke
				(width 0.1524)
				(type default)
			)
			(layer "F.SilkS")
		)
		(fp_line
			(start -0.508 -0.9398)
			(end -0.508 0.9398)
			(stroke
				(width 0.1524)
				(type default)
			)
			(layer "F.SilkS")
		)
		(fp_rect
			(start -0.508 0.9398)
			(end 0.508 -0.9398)
			(stroke
				(width 0)
				(type default)
			)
			(fill no)
			(layer "F.CrtYd")
		)
		(fp_rect
			(start -0.508 0.9398)
			(end 0.508 -0.9398)
			(stroke
				(width 0)
				(type default)
			)
			(fill no)
			(layer "F.Fab")
		)
		(pad "1" smd custom
			(at 0 -0.4445 90)
			(size 0.1397 0.1397)
			(layers "F.Cu" "F.Mask" "F.Paste")
			(net "BMC_I2C1_MINI1_SCL_S")
			(options
				(clearance outline)
				(anchor circle)
			)
			(primitives
				(gr_poly
					(pts
						(arc
							(start -0.1778 -0.2794)
							(mid -0.249642 -0.249642)
							(end -0.2794 -0.1778)
						)
						(arc
							(start -0.2794 0.1778)
							(mid -0.249642 0.249642)
							(end -0.1778 0.2794)
						)
						(arc
							(start 0.1778 0.2794)
							(mid 0.249642 0.249642)
							(end 0.2794 0.1778)
						)
						(arc
							(start 0.2794 -0.1778)
							(mid 0.249642 -0.249642)
							(end 0.1778 -0.2794)
						)
					)
					(width 0)
					(fill yes)
				)
			)
		)
		(pad "2" smd custom
			(at 0 0.4445 90)
			(size 0.1397 0.1397)
			(layers "F.Cu" "F.Mask" "F.Paste")
			(net "BMC0_SMB1_CLK")
			(options
				(clearance outline)
				(anchor circle)
			)
			(primitives
				(gr_poly
					(pts
						(arc
							(start -0.1778 -0.2794)
							(mid -0.249642 -0.249642)
							(end -0.2794 -0.1778)
						)
						(arc
							(start -0.2794 0.1778)
							(mid -0.249642 0.249642)
							(end -0.1778 0.2794)
						)
						(arc
							(start 0.1778 0.2794)
							(mid 0.249642 0.249642)
							(end 0.2794 0.1778)
						)
						(arc
							(start 0.2794 -0.1778)
							(mid 0.249642 -0.249642)
							(end 0.1778 -0.2794)
						)
					)
					(width 0)
					(fill yes)
				)
			)
		)
	)
	(footprint ""
		(layer "F.Cu")
		(at 251.680726 -6.920992 -90)
		(property "Reference" "R270"
			(at 0 0 270)
			(layer "F.SilkS")
			(hide yes)
			(effects
				(font
					(size 1.27 1.27)
				)
			)
		)
		(property "Value" "0R2J-2-GP"
			(at 0.064008 -3.993896 270)
			(unlocked yes)
			(layer "F.Fab")
			(hide yes)
			(effects
				(font
					(size 1.016 1.016)
					(thickness 0.1524)
				)
			)
		)
		(property "Device Type" "R402H16"
			(at 0.064008 -5.517896 270)
			(unlocked yes)
			(layer "F.Fab")
			(hide yes)
			(effects
				(font
					(size 1.016 1.016)
					(thickness 0.1524)
				)
			)
		)
		(duplicate_pad_numbers_are_jumpers no)
		(fp_line
			(start -0.508 -0.9398)
			(end -0.508 0.9398)
			(stroke
				(width 0.1524)
				(type default)
			)
			(layer "F.SilkS")
		)
		(fp_line
			(start 0.508 -0.9398)
			(end -0.508 -0.9398)
			(stroke
				(width 0.1524)
				(type default)
			)
			(layer "F.SilkS")
		)
		(fp_rect
			(start -0.508 0.9398)
			(end 0.508 -0.9398)
			(stroke
				(width 0)
				(type default)
			)
			(fill no)
			(layer "F.CrtYd")
		)
		(fp_rect
			(start -0.508 0.9398)
			(end 0.508 -0.9398)
			(stroke
				(width 0)
				(type default)
			)
			(fill no)
			(layer "F.Fab")
		)
		(pad "1" smd custom
			(at 0 -0.4445 270)
			(size 0.1397 0.1397)
			(layers "F.Cu" "F.Mask" "F.Paste")
			(net "I2C_MAX6654_CLK")
			(options
				(clearance outline)
				(anchor circle)
			)
			(primitives
				(gr_poly
					(pts
						(arc
							(start -0.1778 -0.2794)
							(mid -0.249642 -0.249642)
							(end -0.2794 -0.1778)
						)
						(arc
							(start -0.2794 0.1778)
							(mid -0.249642 0.249642)
							(end -0.1778 0.2794)
						)
						(arc
							(start 0.1778 0.2794)
							(mid 0.249642 0.249642)
							(end 0.2794 0.1778)
						)
						(arc
							(start 0.2794 -0.1778)
							(mid 0.249642 -0.249642)
							(end 0.1778 -0.2794)
						)
					)
					(width 0)
					(fill yes)
				)
			)
		)
		(pad "2" smd custom
			(at 0 0.4445 270)
			(size 0.1397 0.1397)
			(layers "F.Cu" "F.Mask" "F.Paste")
			(net "BMC_I2C5_D_PEB_SCL")
			(options
				(clearance outline)
				(anchor circle)
			)
			(primitives
				(gr_poly
					(pts
						(arc
							(start -0.1778 -0.2794)
							(mid -0.249642 -0.249642)
							(end -0.2794 -0.1778)
						)
						(arc
							(start -0.2794 0.1778)
							(mid -0.249642 0.249642)
							(end -0.1778 0.2794)
						)
						(arc
							(start 0.1778 0.2794)
							(mid 0.249642 0.249642)
							(end 0.2794 0.1778)
						)
						(arc
							(start 0.2794 -0.1778)
							(mid 0.249642 -0.249642)
							(end 0.1778 -0.2794)
						)
					)
					(width 0)
					(fill yes)
				)
			)
		)
	)
	(footprint ""
		(layer "F.Cu")
		(at 298.958 -68.834 180)
		(property "Reference" "C455"
			(at 0 0 180)
			(layer "F.SilkS")
			(hide yes)
			(effects
				(font
					(size 1.27 1.27)
				)
			)
		)
		(property "Value" "SC100U4V5MX-1-GP"
			(at -0.0762 -6.1214 180)
			(unlocked yes)
			(layer "F.Fab")
			(hide yes)
			(effects
				(font
					(size 1.016 1.016)
					(thickness 0.1524)
				)
			)
		)
		(property "Device Type" "C805H58"
			(at -0.0762 -8.1534 180)
			(unlocked yes)
			(layer "F.Fab")
			(hide yes)
			(effects
				(font
					(size 1.016 1.016)
					(thickness 0.1524)
				)
			)
		)
		(duplicate_pad_numbers_are_jumpers no)
		(fp_line
			(start 0.635 0)
			(end -0.635 0)
			(stroke
				(width 0.508)
				(type default)
			)
			(layer "F.SilkS")
		)
		(fp_rect
			(start -0.9652 1.778)
			(end 0.9652 -1.778)
			(stroke
				(width 0)
				(type default)
			)
			(fill no)
			(layer "F.CrtYd")
		)
		(fp_poly
			(pts
				(xy -0.9652 -1.778) (xy 0.9652 -1.778) (xy 0.9652 1.778) (xy -0.9652 1.778)
			)
			(stroke
				(width 0)
				(type default)
			)
			(fill no)
			(layer "F.Fab")
		)
		(pad "1" smd rect
			(at 0 -0.9652 180)
			(size 1.397 1.143)
			(layers "F.Cu" "F.Mask" "F.Paste")
			(net "DUT_VDD")
		)
		(pad "2" smd rect
			(at 0 0.9652 180)
			(size 1.397 1.143)
			(layers "F.Cu" "F.Mask" "F.Paste")
			(net "GND")
		)
	)
	(footprint ""
		(layer "F.Cu")
		(at 166.116 -93.2434 90)
		(property "Reference" "R3107"
			(at 0 0 90)
			(layer "F.SilkS")
			(hide yes)
			(effects
				(font
					(size 1.27 1.27)
				)
			)
		)
		(property "Value" "27R2F-GP"
			(at 0.064008 -3.993896 90)
			(unlocked yes)
			(layer "F.Fab")
			(hide yes)
			(effects
				(font
					(size 1.016 1.016)
					(thickness 0.1524)
				)
			)
		)
		(property "Device Type" "R402H16"
			(at 0.064008 -5.517896 90)
			(unlocked yes)
			(layer "F.Fab")
			(hide yes)
			(effects
				(font
					(size 1.016 1.016)
					(thickness 0.1524)
				)
			)
		)
		(duplicate_pad_numbers_are_jumpers no)
		(fp_line
			(start 0.508 -0.9398)
			(end -0.508 -0.9398)
			(stroke
				(width 0.1524)
				(type default)
			)
			(layer "F.SilkS")
		)
		(fp_line
			(start -0.508 -0.9398)
			(end -0.508 0.9398)
			(stroke
				(width 0.1524)
				(type default)
			)
			(layer "F.SilkS")
		)
		(fp_rect
			(start -0.508 0.9398)
			(end 0.508 -0.9398)
			(stroke
				(width 0)
				(type default)
			)
			(fill no)
			(layer "F.CrtYd")
		)
		(fp_rect
			(start -0.508 0.9398)
			(end 0.508 -0.9398)
			(stroke
				(width 0)
				(type default)
			)
			(fill no)
			(layer "F.Fab")
		)
		(pad "1" smd custom
			(at 0 -0.4445 90)
			(size 0.1397 0.1397)
			(layers "F.Cu" "F.Mask" "F.Paste")
			(net "CLKGEN_N2_R")
			(options
				(clearance outline)
				(anchor circle)
			)
			(primitives
				(gr_poly
					(pts
						(arc
							(start -0.1778 -0.2794)
							(mid -0.249642 -0.249642)
							(end -0.2794 -0.1778)
						)
						(arc
							(start -0.2794 0.1778)
							(mid -0.249642 0.249642)
							(end -0.1778 0.2794)
						)
						(arc
							(start 0.1778 0.2794)
							(mid 0.249642 0.249642)
							(end 0.2794 0.1778)
						)
						(arc
							(start 0.2794 -0.1778)
							(mid 0.249642 -0.249642)
							(end 0.1778 -0.2794)
						)
					)
					(width 0)
					(fill yes)
				)
			)
		)
		(pad "2" smd custom
			(at 0 0.4445 90)
			(size 0.1397 0.1397)
			(layers "F.Cu" "F.Mask" "F.Paste")
			(net "CLKGEN_N2")
			(options
				(clearance outline)
				(anchor circle)
			)
			(primitives
				(gr_poly
					(pts
						(arc
							(start -0.1778 -0.2794)
							(mid -0.249642 -0.249642)
							(end -0.2794 -0.1778)
						)
						(arc
							(start -0.2794 0.1778)
							(mid -0.249642 0.249642)
							(end -0.1778 0.2794)
						)
						(arc
							(start 0.1778 0.2794)
							(mid 0.249642 0.249642)
							(end 0.2794 0.1778)
						)
						(arc
							(start 0.2794 -0.1778)
							(mid 0.249642 -0.249642)
							(end 0.1778 -0.2794)
						)
					)
					(width 0)
					(fill yes)
				)
			)
		)
	)
	(footprint ""
		(layer "F.Cu")
		(at 26.035 -74.9046 90)
		(property "Reference" "R376"
			(at 0 0 90)
			(layer "F.SilkS")
			(hide yes)
			(effects
				(font
					(size 1.27 1.27)
				)
			)
		)
		(property "Value" "0R2J-2-GP"
			(at 0.064008 -3.993896 90)
			(unlocked yes)
			(layer "F.Fab")
			(hide yes)
			(effects
				(font
					(size 1.016 1.016)
					(thickness 0.1524)
				)
			)
		)
		(property "Device Type" "R402H16"
			(at 0.064008 -5.517896 90)
			(unlocked yes)
			(layer "F.Fab")
			(hide yes)
			(effects
				(font
					(size 1.016 1.016)
					(thickness 0.1524)
				)
			)
		)
		(duplicate_pad_numbers_are_jumpers no)
		(fp_line
			(start 0.508 -0.9398)
			(end -0.508 -0.9398)
			(stroke
				(width 0.1524)
				(type default)
			)
			(layer "F.SilkS")
		)
		(fp_line
			(start -0.508 -0.9398)
			(end -0.508 0.9398)
			(stroke
				(width 0.1524)
				(type default)
			)
			(layer "F.SilkS")
		)
		(fp_rect
			(start -0.508 0.9398)
			(end 0.508 -0.9398)
			(stroke
				(width 0)
				(type default)
			)
			(fill no)
			(layer "F.CrtYd")
		)
		(fp_rect
			(start -0.508 0.9398)
			(end 0.508 -0.9398)
			(stroke
				(width 0)
				(type default)
			)
			(fill no)
			(layer "F.Fab")
		)
		(pad "1" smd custom
			(at 0 -0.4445 90)
			(size 0.1397 0.1397)
			(layers "F.Cu" "F.Mask" "F.Paste")
			(net "RMII_PHY_BMC_RXD0_R")
			(options
				(clearance outline)
				(anchor circle)
			)
			(primitives
				(gr_poly
					(pts
						(arc
							(start -0.1778 -0.2794)
							(mid -0.249642 -0.249642)
							(end -0.2794 -0.1778)
						)
						(arc
							(start -0.2794 0.1778)
							(mid -0.249642 0.249642)
							(end -0.1778 0.2794)
						)
						(arc
							(start 0.1778 0.2794)
							(mid 0.249642 0.249642)
							(end 0.2794 0.1778)
						)
						(arc
							(start 0.2794 -0.1778)
							(mid 0.249642 -0.249642)
							(end 0.1778 -0.2794)
						)
					)
					(width 0)
					(fill yes)
				)
			)
		)
		(pad "2" smd custom
			(at 0 0.4445 90)
			(size 0.1397 0.1397)
			(layers "F.Cu" "F.Mask" "F.Paste")
			(net "RMII_PHY_BMC_RXD0")
			(options
				(clearance outline)
				(anchor circle)
			)
			(primitives
				(gr_poly
					(pts
						(arc
							(start -0.1778 -0.2794)
							(mid -0.249642 -0.249642)
							(end -0.2794 -0.1778)
						)
						(arc
							(start -0.2794 0.1778)
							(mid -0.249642 0.249642)
							(end -0.1778 0.2794)
						)
						(arc
							(start 0.1778 0.2794)
							(mid 0.249642 0.249642)
							(end 0.2794 0.1778)
						)
						(arc
							(start 0.2794 -0.1778)
							(mid 0.249642 -0.249642)
							(end 0.1778 -0.2794)
						)
					)
					(width 0)
					(fill yes)
				)
			)
		)
	)
	(footprint ""
		(layer "F.Cu")
		(at 57.318148 -125.8062 90)
		(property "Reference" "R707"
			(at 0 0 90)
			(layer "F.SilkS")
			(hide yes)
			(effects
				(font
					(size 1.27 1.27)
				)
			)
		)
		(property "Value" "0R2J-2-GP"
			(at 0.064008 -3.993896 90)
			(unlocked yes)
			(layer "F.Fab")
			(hide yes)
			(effects
				(font
					(size 1.016 1.016)
					(thickness 0.1524)
				)
			)
		)
		(property "Device Type" "R402H16"
			(at 0.064008 -5.517896 90)
			(unlocked yes)
			(layer "F.Fab")
			(hide yes)
			(effects
				(font
					(size 1.016 1.016)
					(thickness 0.1524)
				)
			)
		)
		(duplicate_pad_numbers_are_jumpers no)
		(fp_line
			(start 0.508 -0.9398)
			(end -0.508 -0.9398)
			(stroke
				(width 0.1524)
				(type default)
			)
			(layer "F.SilkS")
		)
		(fp_line
			(start -0.508 -0.9398)
			(end -0.508 0.9398)
			(stroke
				(width 0.1524)
				(type default)
			)
			(layer "F.SilkS")
		)
		(fp_rect
			(start -0.508 0.9398)
			(end 0.508 -0.9398)
			(stroke
				(width 0)
				(type default)
			)
			(fill no)
			(layer "F.CrtYd")
		)
		(fp_rect
			(start -0.508 0.9398)
			(end 0.508 -0.9398)
			(stroke
				(width 0)
				(type default)
			)
			(fill no)
			(layer "F.Fab")
		)
		(pad "1" smd custom
			(at 0 -0.4445 90)
			(size 0.1397 0.1397)
			(layers "F.Cu" "F.Mask" "F.Paste")
			(net "I2C_MUX_RESET_PEB_R")
			(options
				(clearance outline)
				(anchor circle)
			)
			(primitives
				(gr_poly
					(pts
						(arc
							(start -0.1778 -0.2794)
							(mid -0.249642 -0.249642)
							(end -0.2794 -0.1778)
						)
						(arc
							(start -0.2794 0.1778)
							(mid -0.249642 0.249642)
							(end -0.1778 0.2794)
						)
						(arc
							(start 0.1778 0.2794)
							(mid 0.249642 0.249642)
							(end 0.2794 0.1778)
						)
						(arc
							(start 0.2794 -0.1778)
							(mid 0.249642 -0.249642)
							(end 0.1778 -0.2794)
						)
					)
					(width 0)
					(fill yes)
				)
			)
		)
		(pad "2" smd custom
			(at 0 0.4445 90)
			(size 0.1397 0.1397)
			(layers "F.Cu" "F.Mask" "F.Paste")
			(net "I2C_MUX_RESET_PEB")
			(options
				(clearance outline)
				(anchor circle)
			)
			(primitives
				(gr_poly
					(pts
						(arc
							(start -0.1778 -0.2794)
							(mid -0.249642 -0.249642)
							(end -0.2794 -0.1778)
						)
						(arc
							(start -0.2794 0.1778)
							(mid -0.249642 0.249642)
							(end -0.1778 0.2794)
						)
						(arc
							(start 0.1778 0.2794)
							(mid 0.249642 0.249642)
							(end 0.2794 0.1778)
						)
						(arc
							(start 0.2794 -0.1778)
							(mid 0.249642 -0.249642)
							(end 0.1778 -0.2794)
						)
					)
					(width 0)
					(fill yes)
				)
			)
		)
	)
	(footprint ""
		(layer "F.Cu")
		(at 192.5574 -6.6548 90)
		(property "Reference" "R305"
			(at 0 0 90)
			(layer "F.SilkS")
			(hide yes)
			(effects
				(font
					(size 1.27 1.27)
				)
			)
		)
		(property "Value" "0R2J-2-GP"
			(at 0.064008 -3.993896 90)
			(unlocked yes)
			(layer "F.Fab")
			(hide yes)
			(effects
				(font
					(size 1.016 1.016)
					(thickness 0.1524)
				)
			)
		)
		(property "Device Type" "R402H16"
			(at 0.064008 -5.517896 90)
			(unlocked yes)
			(layer "F.Fab")
			(hide yes)
			(effects
				(font
					(size 1.016 1.016)
					(thickness 0.1524)
				)
			)
		)
		(duplicate_pad_numbers_are_jumpers no)
		(fp_line
			(start 0.508 -0.9398)
			(end -0.508 -0.9398)
			(stroke
				(width 0.1524)
				(type default)
			)
			(layer "F.SilkS")
		)
		(fp_line
			(start -0.508 -0.9398)
			(end -0.508 0.9398)
			(stroke
				(width 0.1524)
				(type default)
			)
			(layer "F.SilkS")
		)
		(fp_rect
			(start -0.508 0.9398)
			(end 0.508 -0.9398)
			(stroke
				(width 0)
				(type default)
			)
			(fill no)
			(layer "F.CrtYd")
		)
		(fp_rect
			(start -0.508 0.9398)
			(end 0.508 -0.9398)
			(stroke
				(width 0)
				(type default)
			)
			(fill no)
			(layer "F.Fab")
		)
		(pad "1" smd custom
			(at 0 -0.4445 90)
			(size 0.1397 0.1397)
			(layers "F.Cu" "F.Mask" "F.Paste")
			(net "HB_OUT_R")
			(options
				(clearance outline)
				(anchor circle)
			)
			(primitives
				(gr_poly
					(pts
						(arc
							(start -0.1778 -0.2794)
							(mid -0.249642 -0.249642)
							(end -0.2794 -0.1778)
						)
						(arc
							(start -0.2794 0.1778)
							(mid -0.249642 0.249642)
							(end -0.1778 0.2794)
						)
						(arc
							(start 0.1778 0.2794)
							(mid 0.249642 0.249642)
							(end 0.2794 0.1778)
						)
						(arc
							(start 0.2794 -0.1778)
							(mid 0.249642 -0.249642)
							(end 0.1778 -0.2794)
						)
					)
					(width 0)
					(fill yes)
				)
			)
		)
		(pad "2" smd custom
			(at 0 0.4445 90)
			(size 0.1397 0.1397)
			(layers "F.Cu" "F.Mask" "F.Paste")
			(net "HB_OUT")
			(options
				(clearance outline)
				(anchor circle)
			)
			(primitives
				(gr_poly
					(pts
						(arc
							(start -0.1778 -0.2794)
							(mid -0.249642 -0.249642)
							(end -0.2794 -0.1778)
						)
						(arc
							(start -0.2794 0.1778)
							(mid -0.249642 0.249642)
							(end -0.1778 0.2794)
						)
						(arc
							(start 0.1778 0.2794)
							(mid 0.249642 0.249642)
							(end 0.2794 0.1778)
						)
						(arc
							(start 0.2794 -0.1778)
							(mid 0.249642 -0.249642)
							(end 0.1778 -0.2794)
						)
					)
					(width 0)
					(fill yes)
				)
			)
		)
	)
	(footprint ""
		(layer "F.Cu")
		(at 48.954182 -116.797328)
		(property "Reference" "R806"
			(at 0 0 0)
			(layer "F.SilkS")
			(hide yes)
			(effects
				(font
					(size 1.27 1.27)
				)
			)
		)
		(property "Value" "0R2J-2-GP"
			(at 0.064008 -3.993896 0)
			(unlocked yes)
			(layer "F.Fab")
			(hide yes)
			(effects
				(font
					(size 1.016 1.016)
					(thickness 0.1524)
				)
			)
		)
		(property "Device Type" "R402H16"
			(at 0.064008 -5.517896 0)
			(unlocked yes)
			(layer "F.Fab")
			(hide yes)
			(effects
				(font
					(size 1.016 1.016)
					(thickness 0.1524)
				)
			)
		)
		(duplicate_pad_numbers_are_jumpers no)
		(fp_line
			(start -0.508 -0.9398)
			(end -0.508 0.9398)
			(stroke
				(width 0.1524)
				(type default)
			)
			(layer "F.SilkS")
		)
		(fp_line
			(start 0.508 -0.9398)
			(end -0.508 -0.9398)
			(stroke
				(width 0.1524)
				(type default)
			)
			(layer "F.SilkS")
		)
		(fp_rect
			(start -0.508 0.9398)
			(end 0.508 -0.9398)
			(stroke
				(width 0)
				(type default)
			)
			(fill no)
			(layer "F.CrtYd")
		)
		(fp_rect
			(start -0.508 0.9398)
			(end 0.508 -0.9398)
			(stroke
				(width 0)
				(type default)
			)
			(fill no)
			(layer "F.Fab")
		)
		(pad "1" smd custom
			(at 0 -0.4445)
			(size 0.1397 0.1397)
			(layers "F.Cu" "F.Mask" "F.Paste")
			(net "DP_BMC_CPU_RST_N_R")
			(options
				(clearance outline)
				(anchor circle)
			)
			(primitives
				(gr_poly
					(pts
						(arc
							(start -0.1778 -0.2794)
							(mid -0.249642 -0.249642)
							(end -0.2794 -0.1778)
						)
						(arc
							(start -0.2794 0.1778)
							(mid -0.249642 0.249642)
							(end -0.1778 0.2794)
						)
						(arc
							(start 0.1778 0.2794)
							(mid 0.249642 0.249642)
							(end 0.2794 0.1778)
						)
						(arc
							(start 0.2794 -0.1778)
							(mid 0.249642 -0.249642)
							(end 0.1778 -0.2794)
						)
					)
					(width 0)
					(fill yes)
				)
			)
		)
		(pad "2" smd custom
			(at 0 0.4445)
			(size 0.1397 0.1397)
			(layers "F.Cu" "F.Mask" "F.Paste")
			(net "BMC_USB_EN_1")
			(options
				(clearance outline)
				(anchor circle)
			)
			(primitives
				(gr_poly
					(pts
						(arc
							(start -0.1778 -0.2794)
							(mid -0.249642 -0.249642)
							(end -0.2794 -0.1778)
						)
						(arc
							(start -0.2794 0.1778)
							(mid -0.249642 0.249642)
							(end -0.1778 0.2794)
						)
						(arc
							(start 0.1778 0.2794)
							(mid 0.249642 0.249642)
							(end 0.2794 0.1778)
						)
						(arc
							(start 0.2794 -0.1778)
							(mid 0.249642 -0.249642)
							(end 0.1778 -0.2794)
						)
					)
					(width 0)
					(fill yes)
				)
			)
		)
	)
	(footprint ""
		(layer "F.Cu")
		(at 42.9768 -187.5536 90)
		(property "Reference" "U29"
			(at 0 0 90)
			(layer "F.SilkS")
			(hide yes)
			(effects
				(font
					(size 1.27 1.27)
				)
			)
		)
		(property "Value" "PCA9511ADP-T-GP"
			(at 0 -13.1572 90)
			(unlocked yes)
			(layer "F.Fab")
			(hide yes)
			(effects
				(font
					(size 1.016 1.016)
					(thickness 0.1524)
				)
			)
		)
		(property "Device Type" "SSOIC8-2H44"
			(at 0 -15.1892 90)
			(unlocked yes)
			(layer "F.Fab")
			(hide yes)
			(effects
				(font
					(size 1.016 1.016)
					(thickness 0.1524)
				)
			)
		)
		(duplicate_pad_numbers_are_jumpers no)
		(fp_line
			(start 1.0922 -1.016)
			(end 1.0922 1.016)
			(stroke
				(width 0.1524)
				(type default)
			)
			(layer "F.SilkS")
		)
		(fp_line
			(start -1.9304 -1.016)
			(end 1.0922 -1.016)
			(stroke
				(width 0.1524)
				(type default)
			)
			(layer "F.SilkS")
		)
		(fp_line
			(start -1.524 0)
			(end -1.9304 -0.4064)
			(stroke
				(width 0.1524)
				(type default)
			)
			(layer "F.SilkS")
		)
		(fp_line
			(start -1.524 0)
			(end -1.9304 0.4064)
			(stroke
				(width 0.1524)
				(type default)
			)
			(layer "F.SilkS")
		)
		(fp_line
			(start 1.0922 1.016)
			(end -1.9304 1.016)
			(stroke
				(width 0.1524)
				(type default)
			)
			(layer "F.SilkS")
		)
		(fp_line
			(start -1.9304 1.016)
			(end -1.9304 -1.016)
			(stroke
				(width 0.1524)
				(type default)
			)
			(layer "F.SilkS")
		)
		(fp_line
			(start -1.7018 1.0414)
			(end -1.7018 2.9718)
			(stroke
				(width 0.635)
				(type default)
			)
			(layer "F.SilkS")
		)
		(fp_poly
			(pts
				(xy -1.1938 -1.016) (xy 1.0922 -1.016) (xy 1.0922 1.016) (xy -1.1938 1.016)
			)
			(stroke
				(width 0)
				(type default)
			)
			(fill yes)
			(layer "F.SilkS")
		)
		(fp_rect
			(start -2.0066 3.3401)
			(end 2.0066 -3.3401)
			(stroke
				(width 0)
				(type default)
			)
			(fill no)
			(layer "F.CrtYd")
		)
		(fp_poly
			(pts
				(xy -2.0066 -3.3401) (xy 2.0066 -3.3401) (xy 2.0066 3.3401) (xy -2.0066 3.3401)
			)
			(stroke
				(width 0)
				(type default)
			)
			(fill no)
			(layer "F.Fab")
		)
		(pad "1" smd rect
			(at -0.97536 2.0701 90)
			(size 0.4064 1.524)
			(layers "F.Cu" "F.Mask" "F.Paste")
			(net "I2C9_BUFF_EN")
		)
		(pad "2" smd rect
			(at -0.32512 2.0701 90)
			(size 0.4064 1.524)
			(layers "F.Cu" "F.Mask" "F.Paste")
			(net "BMC_I2C9_CLKBUF2_SCL_R")
		)
		(pad "3" smd rect
			(at 0.32512 2.0701 90)
			(size 0.4064 1.524)
			(layers "F.Cu" "F.Mask" "F.Paste")
			(net "BUF_I2C9_CLKBUF2_SCL_R")
		)
		(pad "4" smd rect
			(at 0.97536 2.0701 90)
			(size 0.4064 1.524)
			(layers "F.Cu" "F.Mask" "F.Paste")
			(net "GND")
		)
		(pad "5" smd rect
			(at 0.97536 -2.0701 90)
			(size 0.4064 1.524)
			(layers "F.Cu" "F.Mask" "F.Paste")
			(net "I2C9_BUF_READY")
		)
		(pad "6" smd rect
			(at 0.32512 -2.0701 90)
			(size 0.4064 1.524)
			(layers "F.Cu" "F.Mask" "F.Paste")
			(net "BUF_I2C9_CLKBUF2_SDA_R")
		)
		(pad "7" smd rect
			(at -0.32512 -2.0701 90)
			(size 0.4064 1.524)
			(layers "F.Cu" "F.Mask" "F.Paste")
			(net "BMC_I2C9_CLKBUF2_SDA_R")
		)
		(pad "8" smd rect
			(at -0.97536 -2.0701 90)
			(size 0.4064 1.524)
			(layers "F.Cu" "F.Mask" "F.Paste")
			(net "P3V3_STBY")
		)
	)
	(footprint ""
		(layer "F.Cu")
		(at 74.779124 -183.235092)
		(property "Reference" "R7981"
			(at 0 0 0)
			(layer "F.SilkS")
			(hide yes)
			(effects
				(font
					(size 1.27 1.27)
				)
			)
		)
		(property "Value" "0R2J-2-GP"
			(at 0.064008 -3.993896 0)
			(unlocked yes)
			(layer "F.Fab")
			(hide yes)
			(effects
				(font
					(size 1.016 1.016)
					(thickness 0.1524)
				)
			)
		)
		(property "Device Type" "R402H16"
			(at 0.064008 -5.517896 0)
			(unlocked yes)
			(layer "F.Fab")
			(hide yes)
			(effects
				(font
					(size 1.016 1.016)
					(thickness 0.1524)
				)
			)
		)
		(duplicate_pad_numbers_are_jumpers no)
		(fp_line
			(start -0.508 -0.9398)
			(end -0.508 0.9398)
			(stroke
				(width 0.1524)
				(type default)
			)
			(layer "F.SilkS")
		)
		(fp_line
			(start 0.508 -0.9398)
			(end -0.508 -0.9398)
			(stroke
				(width 0.1524)
				(type default)
			)
			(layer "F.SilkS")
		)
		(fp_rect
			(start -0.508 0.9398)
			(end 0.508 -0.9398)
			(stroke
				(width 0)
				(type default)
			)
			(fill no)
			(layer "F.CrtYd")
		)
		(fp_rect
			(start -0.508 0.9398)
			(end 0.508 -0.9398)
			(stroke
				(width 0)
				(type default)
			)
			(fill no)
			(layer "F.Fab")
		)
		(pad "1" smd custom
			(at 0 -0.4445)
			(size 0.1397 0.1397)
			(layers "F.Cu" "F.Mask" "F.Paste")
			(net "SSD_PERST#0")
			(options
				(clearance outline)
				(anchor circle)
			)
			(primitives
				(gr_poly
					(pts
						(arc
							(start -0.1778 -0.2794)
							(mid -0.249642 -0.249642)
							(end -0.2794 -0.1778)
						)
						(arc
							(start -0.2794 0.1778)
							(mid -0.249642 0.249642)
							(end -0.1778 0.2794)
						)
						(arc
							(start 0.1778 0.2794)
							(mid 0.249642 0.249642)
							(end 0.2794 0.1778)
						)
						(arc
							(start 0.2794 -0.1778)
							(mid 0.249642 -0.249642)
							(end 0.1778 -0.2794)
						)
					)
					(width 0)
					(fill yes)
				)
			)
		)
		(pad "2" smd custom
			(at 0 0.4445)
			(size 0.1397 0.1397)
			(layers "F.Cu" "F.Mask" "F.Paste")
			(net "SSD_PERST#0_R")
			(options
				(clearance outline)
				(anchor circle)
			)
			(primitives
				(gr_poly
					(pts
						(arc
							(start -0.1778 -0.2794)
							(mid -0.249642 -0.249642)
							(end -0.2794 -0.1778)
						)
						(arc
							(start -0.2794 0.1778)
							(mid -0.249642 0.249642)
							(end -0.1778 0.2794)
						)
						(arc
							(start 0.1778 0.2794)
							(mid 0.249642 0.249642)
							(end 0.2794 0.1778)
						)
						(arc
							(start 0.2794 -0.1778)
							(mid 0.249642 -0.249642)
							(end 0.1778 -0.2794)
						)
					)
					(width 0)
					(fill yes)
				)
			)
		)
	)
	(footprint ""
		(layer "F.Cu")
		(at 66.792094 -212.420454 180)
		(property "Reference" "C355"
			(at 0 0 180)
			(layer "F.SilkS")
			(hide yes)
			(effects
				(font
					(size 1.27 1.27)
				)
			)
		)
		(property "Value" "SCD22U10V2KX-1GP"
			(at 1.1811 -2.7051 180)
			(unlocked yes)
			(layer "F.Fab")
			(hide yes)
			(effects
				(font
					(size 1.016 1.016)
					(thickness 0.1524)
				)
			)
		)
		(property "Device Type" "C402H22"
			(at 1.1811 -4.2291 180)
			(unlocked yes)
			(layer "F.Fab")
			(hide yes)
			(effects
				(font
					(size 1.016 1.016)
					(thickness 0.1524)
				)
			)
		)
		(duplicate_pad_numbers_are_jumpers no)
		(fp_rect
			(start -0.4318 0.9525)
			(end 0.4318 -0.9525)
			(stroke
				(width 0)
				(type default)
			)
			(fill no)
			(layer "F.CrtYd")
		)
		(fp_rect
			(start -0.4318 0.9525)
			(end 0.4318 -0.9525)
			(stroke
				(width 0)
				(type default)
			)
			(fill no)
			(layer "F.Fab")
		)
		(pad "1" smd custom
			(at 0 -0.4445 180)
			(size 0.1524 0.1524)
			(layers "F.Cu" "F.Mask" "F.Paste")
			(net "PCIE_TX_CAP_P70")
			(options
				(clearance outline)
				(anchor circle)
			)
			(primitives
				(gr_poly
					(pts
						(arc
							(start 0.3048 -0.2032)
							(mid 0.275042 -0.275042)
							(end 0.2032 -0.3048)
						)
						(arc
							(start -0.2032 -0.3048)
							(mid -0.275042 -0.275042)
							(end -0.3048 -0.2032)
						)
						(arc
							(start -0.3048 0.2032)
							(mid -0.275042 0.275042)
							(end -0.2032 0.3048)
						)
						(arc
							(start 0.2032 0.3048)
							(mid 0.275042 0.275042)
							(end 0.3048 0.2032)
						)
					)
					(width 0)
					(fill yes)
				)
			)
		)
		(pad "2" smd custom
			(at 0 0.4445 180)
			(size 0.1524 0.1524)
			(layers "F.Cu" "F.Mask" "F.Paste")
			(net "PCIE_TX_P70")
			(options
				(clearance outline)
				(anchor circle)
			)
			(primitives
				(gr_poly
					(pts
						(arc
							(start 0.3048 -0.2032)
							(mid 0.275042 -0.275042)
							(end 0.2032 -0.3048)
						)
						(arc
							(start -0.2032 -0.3048)
							(mid -0.275042 -0.275042)
							(end -0.3048 -0.2032)
						)
						(arc
							(start -0.3048 0.2032)
							(mid -0.275042 0.275042)
							(end -0.2032 0.3048)
						)
						(arc
							(start 0.2032 0.3048)
							(mid 0.275042 0.275042)
							(end 0.3048 0.2032)
						)
					)
					(width 0)
					(fill yes)
				)
			)
		)
	)
	(footprint ""
		(layer "F.Cu")
		(at 193.592196 -212.420454 180)
		(property "Reference" "C121"
			(at 0 0 180)
			(layer "F.SilkS")
			(hide yes)
			(effects
				(font
					(size 1.27 1.27)
				)
			)
		)
		(property "Value" "SCD22U10V2KX-1GP"
			(at 1.1811 -2.7051 180)
			(unlocked yes)
			(layer "F.Fab")
			(hide yes)
			(effects
				(font
					(size 1.016 1.016)
					(thickness 0.1524)
				)
			)
		)
		(property "Device Type" "C402H22"
			(at 1.1811 -4.2291 180)
			(unlocked yes)
			(layer "F.Fab")
			(hide yes)
			(effects
				(font
					(size 1.016 1.016)
					(thickness 0.1524)
				)
			)
		)
		(duplicate_pad_numbers_are_jumpers no)
		(fp_rect
			(start -0.4318 0.9525)
			(end 0.4318 -0.9525)
			(stroke
				(width 0)
				(type default)
			)
			(fill no)
			(layer "F.CrtYd")
		)
		(fp_rect
			(start -0.4318 0.9525)
			(end 0.4318 -0.9525)
			(stroke
				(width 0)
				(type default)
			)
			(fill no)
			(layer "F.Fab")
		)
		(pad "1" smd custom
			(at 0 -0.4445 180)
			(size 0.1524 0.1524)
			(layers "F.Cu" "F.Mask" "F.Paste")
			(net "PCIE_TX_CAP_P44")
			(options
				(clearance outline)
				(anchor circle)
			)
			(primitives
				(gr_poly
					(pts
						(arc
							(start 0.3048 -0.2032)
							(mid 0.275042 -0.275042)
							(end 0.2032 -0.3048)
						)
						(arc
							(start -0.2032 -0.3048)
							(mid -0.275042 -0.275042)
							(end -0.3048 -0.2032)
						)
						(arc
							(start -0.3048 0.2032)
							(mid -0.275042 0.275042)
							(end -0.2032 0.3048)
						)
						(arc
							(start 0.2032 0.3048)
							(mid 0.275042 0.275042)
							(end 0.3048 0.2032)
						)
					)
					(width 0)
					(fill yes)
				)
			)
		)
		(pad "2" smd custom
			(at 0 0.4445 180)
			(size 0.1524 0.1524)
			(layers "F.Cu" "F.Mask" "F.Paste")
			(net "PCIE_TX_P44")
			(options
				(clearance outline)
				(anchor circle)
			)
			(primitives
				(gr_poly
					(pts
						(arc
							(start 0.3048 -0.2032)
							(mid 0.275042 -0.275042)
							(end 0.2032 -0.3048)
						)
						(arc
							(start -0.2032 -0.3048)
							(mid -0.275042 -0.275042)
							(end -0.3048 -0.2032)
						)
						(arc
							(start -0.3048 0.2032)
							(mid -0.275042 0.275042)
							(end -0.2032 0.3048)
						)
						(arc
							(start 0.2032 0.3048)
							(mid 0.275042 0.275042)
							(end 0.3048 0.2032)
						)
					)
					(width 0)
					(fill yes)
				)
			)
		)
	)
	(footprint ""
		(layer "F.Cu")
		(at 248.7676 -13.3604 180)
		(property "Reference" "C463"
			(at 0 0 180)
			(layer "F.SilkS")
			(hide yes)
			(effects
				(font
					(size 1.27 1.27)
				)
			)
		)
		(property "Value" "SC4D7U16V5KX-1-GP"
			(at -0.0762 -6.1214 180)
			(unlocked yes)
			(layer "F.Fab")
			(hide yes)
			(effects
				(font
					(size 1.016 1.016)
					(thickness 0.1524)
				)
			)
		)
		(property "Device Type" "C805H56"
			(at -0.0762 -8.1534 180)
			(unlocked yes)
			(layer "F.Fab")
			(hide yes)
			(effects
				(font
					(size 1.016 1.016)
					(thickness 0.1524)
				)
			)
		)
		(duplicate_pad_numbers_are_jumpers no)
		(fp_line
			(start 0.635 0)
			(end -0.635 0)
			(stroke
				(width 0.508)
				(type default)
			)
			(layer "F.SilkS")
		)
		(fp_rect
			(start -0.9652 1.778)
			(end 0.9652 -1.778)
			(stroke
				(width 0)
				(type default)
			)
			(fill no)
			(layer "F.CrtYd")
		)
		(fp_poly
			(pts
				(xy -0.9652 -1.778) (xy 0.9652 -1.778) (xy 0.9652 1.778) (xy -0.9652 1.778)
			)
			(stroke
				(width 0)
				(type default)
			)
			(fill no)
			(layer "F.Fab")
		)
		(pad "1" smd rect
			(at 0 -0.9652 180)
			(size 1.397 1.143)
			(layers "F.Cu" "F.Mask" "F.Paste")
			(net "DUT_VDDO")
		)
		(pad "2" smd rect
			(at 0 0.9652 180)
			(size 1.397 1.143)
			(layers "F.Cu" "F.Mask" "F.Paste")
			(net "GND")
		)
	)
	(footprint ""
		(layer "F.Cu")
		(at 186.7154 -71.628 180)
		(property "Reference" "C549"
			(at 0 0 180)
			(layer "F.SilkS")
			(hide yes)
			(effects
				(font
					(size 1.27 1.27)
				)
			)
		)
		(property "Value" "SC4D7U16V5KX-1-GP"
			(at -0.0762 -6.1214 180)
			(unlocked yes)
			(layer "F.Fab")
			(hide yes)
			(effects
				(font
					(size 1.016 1.016)
					(thickness 0.1524)
				)
			)
		)
		(property "Device Type" "C805H56"
			(at -0.0762 -8.1534 180)
			(unlocked yes)
			(layer "F.Fab")
			(hide yes)
			(effects
				(font
					(size 1.016 1.016)
					(thickness 0.1524)
				)
			)
		)
		(duplicate_pad_numbers_are_jumpers no)
		(fp_line
			(start 0.635 0)
			(end -0.635 0)
			(stroke
				(width 0.508)
				(type default)
			)
			(layer "F.SilkS")
		)
		(fp_rect
			(start -0.9652 1.778)
			(end 0.9652 -1.778)
			(stroke
				(width 0)
				(type default)
			)
			(fill no)
			(layer "F.CrtYd")
		)
		(fp_poly
			(pts
				(xy -0.9652 -1.778) (xy 0.9652 -1.778) (xy 0.9652 1.778) (xy -0.9652 1.778)
			)
			(stroke
				(width 0)
				(type default)
			)
			(fill no)
			(layer "F.Fab")
		)
		(pad "1" smd rect
			(at 0 -0.9652 180)
			(size 1.397 1.143)
			(layers "F.Cu" "F.Mask" "F.Paste")
			(net "DUT_AVD_PCIE")
		)
		(pad "2" smd rect
			(at 0 0.9652 180)
			(size 1.397 1.143)
			(layers "F.Cu" "F.Mask" "F.Paste")
			(net "GND")
		)
	)
	(footprint ""
		(layer "F.Cu")
		(at 341.99195 -212.420454 180)
		(property "Reference" "C54"
			(at 0 0 180)
			(layer "F.SilkS")
			(hide yes)
			(effects
				(font
					(size 1.27 1.27)
				)
			)
		)
		(property "Value" "SCD22U10V2KX-1GP"
			(at 1.1811 -2.7051 180)
			(unlocked yes)
			(layer "F.Fab")
			(hide yes)
			(effects
				(font
					(size 1.016 1.016)
					(thickness 0.1524)
				)
			)
		)
		(property "Device Type" "C402H22"
			(at 1.1811 -4.2291 180)
			(unlocked yes)
			(layer "F.Fab")
			(hide yes)
			(effects
				(font
					(size 1.016 1.016)
					(thickness 0.1524)
				)
			)
		)
		(duplicate_pad_numbers_are_jumpers no)
		(fp_rect
			(start -0.4318 0.9525)
			(end 0.4318 -0.9525)
			(stroke
				(width 0)
				(type default)
			)
			(fill no)
			(layer "F.CrtYd")
		)
		(fp_rect
			(start -0.4318 0.9525)
			(end 0.4318 -0.9525)
			(stroke
				(width 0)
				(type default)
			)
			(fill no)
			(layer "F.Fab")
		)
		(pad "1" smd custom
			(at 0 -0.4445 180)
			(size 0.1524 0.1524)
			(layers "F.Cu" "F.Mask" "F.Paste")
			(net "PCIE_TX_CAP_P16")
			(options
				(clearance outline)
				(anchor circle)
			)
			(primitives
				(gr_poly
					(pts
						(arc
							(start 0.3048 -0.2032)
							(mid 0.275042 -0.275042)
							(end 0.2032 -0.3048)
						)
						(arc
							(start -0.2032 -0.3048)
							(mid -0.275042 -0.275042)
							(end -0.3048 -0.2032)
						)
						(arc
							(start -0.3048 0.2032)
							(mid -0.275042 0.275042)
							(end -0.2032 0.3048)
						)
						(arc
							(start 0.2032 0.3048)
							(mid 0.275042 0.275042)
							(end 0.3048 0.2032)
						)
					)
					(width 0)
					(fill yes)
				)
			)
		)
		(pad "2" smd custom
			(at 0 0.4445 180)
			(size 0.1524 0.1524)
			(layers "F.Cu" "F.Mask" "F.Paste")
			(net "PCIE_TX_P16")
			(options
				(clearance outline)
				(anchor circle)
			)
			(primitives
				(gr_poly
					(pts
						(arc
							(start 0.3048 -0.2032)
							(mid 0.275042 -0.275042)
							(end 0.2032 -0.3048)
						)
						(arc
							(start -0.2032 -0.3048)
							(mid -0.275042 -0.275042)
							(end -0.3048 -0.2032)
						)
						(arc
							(start -0.3048 0.2032)
							(mid -0.275042 0.275042)
							(end -0.2032 0.3048)
						)
						(arc
							(start 0.2032 0.3048)
							(mid 0.275042 0.275042)
							(end 0.3048 0.2032)
						)
					)
					(width 0)
					(fill yes)
				)
			)
		)
	)
	(footprint ""
		(layer "F.Cu")
		(at 14.097 -125.095)
		(property "Reference" "U12"
			(at 0 0 0)
			(layer "F.SilkS")
			(hide yes)
			(effects
				(font
					(size 1.27 1.27)
				)
			)
		)
		(property "Value" "2N7002DW-7F-GP"
			(at -2.3622 -8.2042 0)
			(unlocked yes)
			(layer "F.Fab")
			(hide yes)
			(effects
				(font
					(size 1.016 1.016)
					(thickness 0.1524)
				)
			)
		)
		(property "Device Type" "SOT-363H44"
			(at -2.3622 -10.1092 0)
			(unlocked yes)
			(layer "F.Fab")
			(hide yes)
			(effects
				(font
					(size 1.016 1.016)
					(thickness 0.1524)
				)
			)
		)
		(duplicate_pad_numbers_are_jumpers no)
		(fp_line
			(start -1.4478 -1.7018)
			(end -1.4478 1.7018)
			(stroke
				(width 0.1524)
				(type default)
			)
			(layer "F.SilkS")
		)
		(fp_line
			(start -1.4478 1.7018)
			(end 1.4478 1.7018)
			(stroke
				(width 0.1524)
				(type default)
			)
			(layer "F.SilkS")
		)
		(fp_line
			(start -1.27 1.524)
			(end -1.27 0.6604)
			(stroke
				(width 0.4826)
				(type default)
			)
			(layer "F.SilkS")
		)
		(fp_line
			(start 1.4478 -1.7018)
			(end -1.4478 -1.7018)
			(stroke
				(width 0.1524)
				(type default)
			)
			(layer "F.SilkS")
		)
		(fp_line
			(start 1.4478 1.7018)
			(end 1.4478 -1.7018)
			(stroke
				(width 0.1524)
				(type default)
			)
			(layer "F.SilkS")
		)
		(fp_poly
			(pts
				(xy -1.524 -1.778) (xy 1.524 -1.778) (xy 1.524 1.778) (xy -1.524 1.778)
			)
			(stroke
				(width 0)
				(type default)
			)
			(fill no)
			(layer "F.CrtYd")
		)
		(fp_poly
			(pts
				(xy -1.524 -1.778) (xy 1.524 -1.778) (xy 1.524 1.778) (xy -1.524 1.778)
			)
			(stroke
				(width 0)
				(type default)
			)
			(fill no)
			(layer "F.Fab")
		)
		(pad "1" smd rect
			(at -0.65024 0.9398)
			(size 0.4064 1.016)
			(layers "F.Cu" "F.Mask" "F.Paste")
			(net "BMC_I2C2_MINI2_SCL_S")
		)
		(pad "2" smd rect
			(at 0 0.9398)
			(size 0.4064 1.016)
			(layers "F.Cu" "F.Mask" "F.Paste")
			(net "I2C2_LS_G2")
		)
		(pad "3" smd rect
			(at 0.65024 0.9398)
			(size 0.4064 1.016)
			(layers "F.Cu" "F.Mask" "F.Paste")
			(net "BMC_I2C2_MINI2_SDA")
		)
		(pad "4" smd rect
			(at 0.65024 -0.9398)
			(size 0.4064 1.016)
			(layers "F.Cu" "F.Mask" "F.Paste")
			(net "BMC_I2C2_MINI2_SDA_S")
		)
		(pad "5" smd rect
			(at 0 -0.9398)
			(size 0.4064 1.016)
			(layers "F.Cu" "F.Mask" "F.Paste")
			(net "I2C2_LS_G1")
		)
		(pad "6" smd rect
			(at -0.65024 -0.9398)
			(size 0.4064 1.016)
			(layers "F.Cu" "F.Mask" "F.Paste")
			(net "BMC_I2C2_MINI2_SCL")
		)
	)
	(footprint ""
		(layer "F.Cu")
		(at 9.779 -71.7804)
		(property "Reference" "C235"
			(at 0 0 0)
			(layer "F.SilkS")
			(hide yes)
			(effects
				(font
					(size 1.27 1.27)
				)
			)
		)
		(property "Value" "SC12P50V2JN-3GP"
			(at 1.1811 -2.7051 0)
			(unlocked yes)
			(layer "F.Fab")
			(hide yes)
			(effects
				(font
					(size 1.016 1.016)
					(thickness 0.1524)
				)
			)
		)
		(property "Device Type" "C402H24"
			(at 1.1811 -4.2291 0)
			(unlocked yes)
			(layer "F.Fab")
			(hide yes)
			(effects
				(font
					(size 1.016 1.016)
					(thickness 0.1524)
				)
			)
		)
		(duplicate_pad_numbers_are_jumpers no)
		(fp_rect
			(start -0.4318 0.9525)
			(end 0.4318 -0.9525)
			(stroke
				(width 0)
				(type default)
			)
			(fill no)
			(layer "F.CrtYd")
		)
		(fp_rect
			(start -0.4318 0.9525)
			(end 0.4318 -0.9525)
			(stroke
				(width 0)
				(type default)
			)
			(fill no)
			(layer "F.Fab")
		)
		(pad "1" smd custom
			(at 0 -0.4445)
			(size 0.1524 0.1524)
			(layers "F.Cu" "F.Mask" "F.Paste")
			(net "GND")
			(options
				(clearance outline)
				(anchor circle)
			)
			(primitives
				(gr_poly
					(pts
						(arc
							(start 0.3048 -0.2032)
							(mid 0.275042 -0.275042)
							(end 0.2032 -0.3048)
						)
						(arc
							(start -0.2032 -0.3048)
							(mid -0.275042 -0.275042)
							(end -0.3048 -0.2032)
						)
						(arc
							(start -0.3048 0.2032)
							(mid -0.275042 0.275042)
							(end -0.2032 0.3048)
						)
						(arc
							(start 0.2032 0.3048)
							(mid 0.275042 0.275042)
							(end 0.3048 0.2032)
						)
					)
					(width 0)
					(fill yes)
				)
			)
		)
		(pad "2" smd custom
			(at 0 0.4445)
			(size 0.1524 0.1524)
			(layers "F.Cu" "F.Mask" "F.Paste")
			(net "XTAL_OUT_I210_R")
			(options
				(clearance outline)
				(anchor circle)
			)
			(primitives
				(gr_poly
					(pts
						(arc
							(start 0.3048 -0.2032)
							(mid 0.275042 -0.275042)
							(end 0.2032 -0.3048)
						)
						(arc
							(start -0.2032 -0.3048)
							(mid -0.275042 -0.275042)
							(end -0.3048 -0.2032)
						)
						(arc
							(start -0.3048 0.2032)
							(mid -0.275042 0.275042)
							(end -0.2032 0.3048)
						)
						(arc
							(start 0.2032 0.3048)
							(mid 0.275042 0.275042)
							(end 0.3048 0.2032)
						)
					)
					(width 0)
					(fill yes)
				)
			)
		)
	)
	(footprint ""
		(layer "F.Cu")
		(at 15.696946 -95.086678 180)
		(property "Reference" "C155"
			(at 0 0 180)
			(layer "F.SilkS")
			(hide yes)
			(effects
				(font
					(size 1.27 1.27)
				)
			)
		)
		(property "Value" "SCD1U16V2JX-1-GP"
			(at 1.1811 -2.7051 180)
			(unlocked yes)
			(layer "F.Fab")
			(hide yes)
			(effects
				(font
					(size 1.016 1.016)
					(thickness 0.1524)
				)
			)
		)
		(property "Device Type" "C402H22"
			(at 1.1811 -4.2291 180)
			(unlocked yes)
			(layer "F.Fab")
			(hide yes)
			(effects
				(font
					(size 1.016 1.016)
					(thickness 0.1524)
				)
			)
		)
		(duplicate_pad_numbers_are_jumpers no)
		(fp_rect
			(start -0.4318 0.9525)
			(end 0.4318 -0.9525)
			(stroke
				(width 0)
				(type default)
			)
			(fill no)
			(layer "F.CrtYd")
		)
		(fp_rect
			(start -0.4318 0.9525)
			(end 0.4318 -0.9525)
			(stroke
				(width 0)
				(type default)
			)
			(fill no)
			(layer "F.Fab")
		)
		(pad "1" smd custom
			(at 0 -0.4445 180)
			(size 0.1524 0.1524)
			(layers "F.Cu" "F.Mask" "F.Paste")
			(net "Q20_G")
			(options
				(clearance outline)
				(anchor circle)
			)
			(primitives
				(gr_poly
					(pts
						(arc
							(start 0.3048 -0.2032)
							(mid 0.275042 -0.275042)
							(end 0.2032 -0.3048)
						)
						(arc
							(start -0.2032 -0.3048)
							(mid -0.275042 -0.275042)
							(end -0.3048 -0.2032)
						)
						(arc
							(start -0.3048 0.2032)
							(mid -0.275042 0.275042)
							(end -0.2032 0.3048)
						)
						(arc
							(start 0.2032 0.3048)
							(mid 0.275042 0.275042)
							(end 0.3048 0.2032)
						)
					)
					(width 0)
					(fill yes)
				)
			)
		)
		(pad "2" smd custom
			(at 0 0.4445 180)
			(size 0.1524 0.1524)
			(layers "F.Cu" "F.Mask" "F.Paste")
			(net "GND")
			(options
				(clearance outline)
				(anchor circle)
			)
			(primitives
				(gr_poly
					(pts
						(arc
							(start 0.3048 -0.2032)
							(mid 0.275042 -0.275042)
							(end 0.2032 -0.3048)
						)
						(arc
							(start -0.2032 -0.3048)
							(mid -0.275042 -0.275042)
							(end -0.3048 -0.2032)
						)
						(arc
							(start -0.3048 0.2032)
							(mid -0.275042 0.275042)
							(end -0.2032 0.3048)
						)
						(arc
							(start 0.2032 0.3048)
							(mid 0.275042 0.275042)
							(end 0.3048 0.2032)
						)
					)
					(width 0)
					(fill yes)
				)
			)
		)
	)
	(footprint ""
		(layer "F.Cu")
		(at 27.723084 -91.314016 90)
		(property "Reference" "U83"
			(at 0 0 90)
			(layer "F.SilkS")
			(hide yes)
			(effects
				(font
					(size 1.27 1.27)
				)
			)
		)
		(property "Value" "SN74LVC1G08DCKR-GP"
			(at -2.3368 -8.6868 90)
			(unlocked yes)
			(layer "F.Fab")
			(hide yes)
			(effects
				(font
					(size 1.016 1.016)
					(thickness 0.1524)
				)
			)
		)
		(property "Device Type" "SC70-5H44"
			(at -2.3114 -10.414 90)
			(unlocked yes)
			(layer "F.Fab")
			(hide yes)
			(effects
				(font
					(size 1.016 1.016)
					(thickness 0.1524)
				)
			)
		)
		(duplicate_pad_numbers_are_jumpers no)
		(fp_line
			(start 1.3843 -1.8034)
			(end 1.3843 -1.1176)
			(stroke
				(width 0.3302)
				(type default)
			)
			(layer "F.SilkS")
		)
		(fp_line
			(start 0.6604 -1.8034)
			(end 1.3843 -1.8034)
			(stroke
				(width 0.3302)
				(type default)
			)
			(layer "F.SilkS")
		)
		(fp_line
			(start 1.27 -1.7018)
			(end 1.27 1.7018)
			(stroke
				(width 0.1524)
				(type default)
			)
			(layer "F.SilkS")
		)
		(fp_line
			(start -1.27 -1.7018)
			(end 1.27 -1.7018)
			(stroke
				(width 0.1524)
				(type default)
			)
			(layer "F.SilkS")
		)
		(fp_line
			(start 1.27 1.7018)
			(end -1.27 1.7018)
			(stroke
				(width 0.1524)
				(type default)
			)
			(layer "F.SilkS")
		)
		(fp_line
			(start -1.27 1.7018)
			(end -1.27 -1.7018)
			(stroke
				(width 0.1524)
				(type default)
			)
			(layer "F.SilkS")
		)
		(fp_rect
			(start -1.524 1.9558)
			(end 1.524 -1.9558)
			(stroke
				(width 0)
				(type default)
			)
			(fill no)
			(layer "F.CrtYd")
		)
		(fp_poly
			(pts
				(xy -1.524 -1.9558) (xy 1.524 -1.9558) (xy 1.524 1.9558) (xy -1.524 1.9558)
			)
			(stroke
				(width 0)
				(type default)
			)
			(fill no)
			(layer "F.Fab")
		)
		(pad "1" smd rect
			(at 0.65024 -0.8255 90)
			(size 0.4064 1.2192)
			(layers "F.Cu" "F.Mask" "F.Paste")
			(net "FM_BMC_RESET_N")
		)
		(pad "2" smd rect
			(at 0 -0.8255 90)
			(size 0.4064 1.2192)
			(layers "F.Cu" "F.Mask" "F.Paste")
			(net "BMC_I210_PERST_N")
		)
		(pad "3" smd rect
			(at -0.65024 -0.8255 90)
			(size 0.4064 1.2192)
			(layers "F.Cu" "F.Mask" "F.Paste")
			(net "GND")
		)
		(pad "4" smd rect
			(at -0.65024 0.8255 90)
			(size 0.4064 1.2192)
			(layers "F.Cu" "F.Mask" "F.Paste")
			(net "I210_PERST_N")
		)
		(pad "5" smd rect
			(at 0.65024 0.8255 90)
			(size 0.4064 1.2192)
			(layers "F.Cu" "F.Mask" "F.Paste")
			(net "P3V3_STBY")
		)
	)
	(footprint ""
		(layer "F.Cu")
		(at 19.2532 -68.4784 -90)
		(property "Reference" "TP150"
			(at 0 0 270)
			(layer "F.SilkS")
			(hide yes)
			(effects
				(font
					(size 1.27 1.27)
				)
			)
		)
		(property "Value" "TPAD28-2-GP"
			(at -0.0127 -1.6637 270)
			(unlocked yes)
			(layer "F.Fab")
			(hide yes)
			(effects
				(font
					(size 1.016 1.016)
					(thickness 0.1524)
				)
			)
		)
		(property "Device Type" "TPAD28"
			(at -0.0127 -3.1877 270)
			(unlocked yes)
			(layer "F.Fab")
			(hide yes)
			(effects
				(font
					(size 1.016 1.016)
					(thickness 0.1524)
				)
			)
		)
		(duplicate_pad_numbers_are_jumpers no)
		(fp_poly
			(pts
				(arc
					(start 0 -0.3556)
					(mid 0 0.3556)
					(end 0 -0.3556)
				)
			)
			(stroke
				(width 0)
				(type default)
			)
			(fill no)
			(layer "F.CrtYd")
		)
		(fp_poly
			(pts
				(arc
					(start 0 -0.6096)
					(mid 0 0.6096)
					(end 0 -0.6096)
				)
			)
			(stroke
				(width 0)
				(type default)
			)
			(fill no)
			(layer "F.Fab")
		)
		(pad "1" smd circle
			(at 0 0 270)
			(size 0.7112 0.7112)
			(layers "F.Cu" "F.Mask" "F.Paste")
			(net "TP_SDP3")
		)
	)
	(footprint ""
		(layer "F.Cu")
		(at 72.771 -197.612 180)
		(property "Reference" "R7976"
			(at 0 0 180)
			(layer "F.SilkS")
			(hide yes)
			(effects
				(font
					(size 1.27 1.27)
				)
			)
		)
		(property "Value" "0R2J-2-GP"
			(at 0.064008 -3.993896 180)
			(unlocked yes)
			(layer "F.Fab")
			(hide yes)
			(effects
				(font
					(size 1.016 1.016)
					(thickness 0.1524)
				)
			)
		)
		(property "Device Type" "R402H16"
			(at 0.064008 -5.517896 180)
			(unlocked yes)
			(layer "F.Fab")
			(hide yes)
			(effects
				(font
					(size 1.016 1.016)
					(thickness 0.1524)
				)
			)
		)
		(duplicate_pad_numbers_are_jumpers no)
		(fp_line
			(start 0.508 -0.9398)
			(end -0.508 -0.9398)
			(stroke
				(width 0.1524)
				(type default)
			)
			(layer "F.SilkS")
		)
		(fp_line
			(start -0.508 -0.9398)
			(end -0.508 0.9398)
			(stroke
				(width 0.1524)
				(type default)
			)
			(layer "F.SilkS")
		)
		(fp_rect
			(start -0.508 0.9398)
			(end 0.508 -0.9398)
			(stroke
				(width 0)
				(type default)
			)
			(fill no)
			(layer "F.CrtYd")
		)
		(fp_rect
			(start -0.508 0.9398)
			(end 0.508 -0.9398)
			(stroke
				(width 0)
				(type default)
			)
			(fill no)
			(layer "F.Fab")
		)
		(pad "1" smd custom
			(at 0 -0.4445 180)
			(size 0.1397 0.1397)
			(layers "F.Cu" "F.Mask" "F.Paste")
			(net "SSD_PERST#11")
			(options
				(clearance outline)
				(anchor circle)
			)
			(primitives
				(gr_poly
					(pts
						(arc
							(start -0.1778 -0.2794)
							(mid -0.249642 -0.249642)
							(end -0.2794 -0.1778)
						)
						(arc
							(start -0.2794 0.1778)
							(mid -0.249642 0.249642)
							(end -0.1778 0.2794)
						)
						(arc
							(start 0.1778 0.2794)
							(mid 0.249642 0.249642)
							(end 0.2794 0.1778)
						)
						(arc
							(start 0.2794 -0.1778)
							(mid 0.249642 -0.249642)
							(end 0.1778 -0.2794)
						)
					)
					(width 0)
					(fill yes)
				)
			)
		)
		(pad "2" smd custom
			(at 0 0.4445 180)
			(size 0.1397 0.1397)
			(layers "F.Cu" "F.Mask" "F.Paste")
			(net "SSD_PERST#11_R")
			(options
				(clearance outline)
				(anchor circle)
			)
			(primitives
				(gr_poly
					(pts
						(arc
							(start -0.1778 -0.2794)
							(mid -0.249642 -0.249642)
							(end -0.2794 -0.1778)
						)
						(arc
							(start -0.2794 0.1778)
							(mid -0.249642 0.249642)
							(end -0.1778 0.2794)
						)
						(arc
							(start 0.1778 0.2794)
							(mid 0.249642 0.249642)
							(end 0.2794 0.1778)
						)
						(arc
							(start 0.2794 -0.1778)
							(mid 0.249642 -0.249642)
							(end 0.1778 -0.2794)
						)
					)
					(width 0)
					(fill yes)
				)
			)
		)
	)
	(footprint ""
		(layer "F.Cu")
		(at 70.1802 -164.5666 180)
		(property "Reference" "PC20"
			(at 0 0 180)
			(layer "F.SilkS")
			(hide yes)
			(effects
				(font
					(size 1.27 1.27)
				)
			)
		)
		(property "Value" "SC10U10V5KX-6-GP-U"
			(at -0.0762 -6.1214 180)
			(unlocked yes)
			(layer "F.Fab")
			(hide yes)
			(effects
				(font
					(size 1.016 1.016)
					(thickness 0.1524)
				)
			)
		)
		(property "Device Type" "C805H58"
			(at -0.0762 -8.1534 180)
			(unlocked yes)
			(layer "F.Fab")
			(hide yes)
			(effects
				(font
					(size 1.016 1.016)
					(thickness 0.1524)
				)
			)
		)
		(duplicate_pad_numbers_are_jumpers no)
		(fp_line
			(start 0.635 0)
			(end -0.635 0)
			(stroke
				(width 0.508)
				(type default)
			)
			(layer "F.SilkS")
		)
		(fp_rect
			(start -0.9652 1.778)
			(end 0.9652 -1.778)
			(stroke
				(width 0)
				(type default)
			)
			(fill no)
			(layer "F.CrtYd")
		)
		(fp_poly
			(pts
				(xy -0.9652 -1.778) (xy 0.9652 -1.778) (xy 0.9652 1.778) (xy -0.9652 1.778)
			)
			(stroke
				(width 0)
				(type default)
			)
			(fill no)
			(layer "F.Fab")
		)
		(pad "1" smd rect
			(at 0 -0.9652 180)
			(size 1.397 1.143)
			(layers "F.Cu" "F.Mask" "F.Paste")
			(net "VR_P1V538_STBY_BIAS")
		)
		(pad "2" smd rect
			(at 0 0.9652 180)
			(size 1.397 1.143)
			(layers "F.Cu" "F.Mask" "F.Paste")
			(net "GND")
		)
	)
	(footprint ""
		(layer "F.Cu")
		(at 70.1802 -161.2646 90)
		(property "Reference" "PC76"
			(at 0 0 90)
			(layer "F.SilkS")
			(hide yes)
			(effects
				(font
					(size 1.27 1.27)
				)
			)
		)
		(property "Value" "SC1KP50V2KX-1GP"
			(at 1.1811 -2.7051 90)
			(unlocked yes)
			(layer "F.Fab")
			(hide yes)
			(effects
				(font
					(size 1.016 1.016)
					(thickness 0.1524)
				)
			)
		)
		(property "Device Type" "C402H22"
			(at 1.1811 -4.2291 90)
			(unlocked yes)
			(layer "F.Fab")
			(hide yes)
			(effects
				(font
					(size 1.016 1.016)
					(thickness 0.1524)
				)
			)
		)
		(duplicate_pad_numbers_are_jumpers no)
		(fp_rect
			(start -0.4318 0.9525)
			(end 0.4318 -0.9525)
			(stroke
				(width 0)
				(type default)
			)
			(fill no)
			(layer "F.CrtYd")
		)
		(fp_rect
			(start -0.4318 0.9525)
			(end 0.4318 -0.9525)
			(stroke
				(width 0)
				(type default)
			)
			(fill no)
			(layer "F.Fab")
		)
		(pad "1" smd custom
			(at 0 -0.4445 90)
			(size 0.1524 0.1524)
			(layers "F.Cu" "F.Mask" "F.Paste")
			(net "PWRGD_P1V538_STBY")
			(options
				(clearance outline)
				(anchor circle)
			)
			(primitives
				(gr_poly
					(pts
						(arc
							(start 0.3048 -0.2032)
							(mid 0.275042 -0.275042)
							(end 0.2032 -0.3048)
						)
						(arc
							(start -0.2032 -0.3048)
							(mid -0.275042 -0.275042)
							(end -0.3048 -0.2032)
						)
						(arc
							(start -0.3048 0.2032)
							(mid -0.275042 0.275042)
							(end -0.2032 0.3048)
						)
						(arc
							(start 0.2032 0.3048)
							(mid 0.275042 0.275042)
							(end 0.3048 0.2032)
						)
					)
					(width 0)
					(fill yes)
				)
			)
		)
		(pad "2" smd custom
			(at 0 0.4445 90)
			(size 0.1524 0.1524)
			(layers "F.Cu" "F.Mask" "F.Paste")
			(net "GND")
			(options
				(clearance outline)
				(anchor circle)
			)
			(primitives
				(gr_poly
					(pts
						(arc
							(start 0.3048 -0.2032)
							(mid 0.275042 -0.275042)
							(end 0.2032 -0.3048)
						)
						(arc
							(start -0.2032 -0.3048)
							(mid -0.275042 -0.275042)
							(end -0.3048 -0.2032)
						)
						(arc
							(start -0.3048 0.2032)
							(mid -0.275042 0.275042)
							(end -0.2032 0.3048)
						)
						(arc
							(start 0.2032 0.3048)
							(mid 0.275042 0.275042)
							(end 0.3048 0.2032)
						)
					)
					(width 0)
					(fill yes)
				)
			)
		)
	)
	(footprint ""
		(layer "F.Cu")
		(at 122.023124 -208.889092 180)
		(property "Reference" "C3208"
			(at 0 0 180)
			(layer "F.SilkS")
			(hide yes)
			(effects
				(font
					(size 1.27 1.27)
				)
			)
		)
		(property "Value" "SCD1U25V2KX-2-GP"
			(at 1.1811 -2.7051 180)
			(unlocked yes)
			(layer "F.Fab")
			(hide yes)
			(effects
				(font
					(size 1.016 1.016)
					(thickness 0.1524)
				)
			)
		)
		(property "Device Type" "C402H22"
			(at 1.1811 -4.2291 180)
			(unlocked yes)
			(layer "F.Fab")
			(hide yes)
			(effects
				(font
					(size 1.016 1.016)
					(thickness 0.1524)
				)
			)
		)
		(duplicate_pad_numbers_are_jumpers no)
		(fp_rect
			(start -0.4318 0.9525)
			(end 0.4318 -0.9525)
			(stroke
				(width 0)
				(type default)
			)
			(fill no)
			(layer "F.CrtYd")
		)
		(fp_rect
			(start -0.4318 0.9525)
			(end 0.4318 -0.9525)
			(stroke
				(width 0)
				(type default)
			)
			(fill no)
			(layer "F.Fab")
		)
		(pad "1" smd custom
			(at 0 -0.4445 180)
			(size 0.1524 0.1524)
			(layers "F.Cu" "F.Mask" "F.Paste")
			(net "P3V3_STBY")
			(options
				(clearance outline)
				(anchor circle)
			)
			(primitives
				(gr_poly
					(pts
						(arc
							(start 0.3048 -0.2032)
							(mid 0.275042 -0.275042)
							(end 0.2032 -0.3048)
						)
						(arc
							(start -0.2032 -0.3048)
							(mid -0.275042 -0.275042)
							(end -0.3048 -0.2032)
						)
						(arc
							(start -0.3048 0.2032)
							(mid -0.275042 0.275042)
							(end -0.2032 0.3048)
						)
						(arc
							(start 0.2032 0.3048)
							(mid 0.275042 0.275042)
							(end 0.3048 0.2032)
						)
					)
					(width 0)
					(fill yes)
				)
			)
		)
		(pad "2" smd custom
			(at 0 0.4445 180)
			(size 0.1524 0.1524)
			(layers "F.Cu" "F.Mask" "F.Paste")
			(net "GND")
			(options
				(clearance outline)
				(anchor circle)
			)
			(primitives
				(gr_poly
					(pts
						(arc
							(start 0.3048 -0.2032)
							(mid 0.275042 -0.275042)
							(end 0.2032 -0.3048)
						)
						(arc
							(start -0.2032 -0.3048)
							(mid -0.275042 -0.275042)
							(end -0.3048 -0.2032)
						)
						(arc
							(start -0.3048 0.2032)
							(mid -0.275042 0.275042)
							(end -0.2032 0.3048)
						)
						(arc
							(start 0.2032 0.3048)
							(mid 0.275042 0.275042)
							(end 0.3048 0.2032)
						)
					)
					(width 0)
					(fill yes)
				)
			)
		)
	)
	(footprint ""
		(layer "F.Cu")
		(at 22.4536 -55.118 180)
		(property "Reference" "R612"
			(at 0 0 180)
			(layer "F.SilkS")
			(hide yes)
			(effects
				(font
					(size 1.27 1.27)
				)
			)
		)
		(property "Value" "0R2J-2-GP"
			(at 0.064008 -3.993896 180)
			(unlocked yes)
			(layer "F.Fab")
			(hide yes)
			(effects
				(font
					(size 1.016 1.016)
					(thickness 0.1524)
				)
			)
		)
		(property "Device Type" "R402H16"
			(at 0.064008 -5.517896 180)
			(unlocked yes)
			(layer "F.Fab")
			(hide yes)
			(effects
				(font
					(size 1.016 1.016)
					(thickness 0.1524)
				)
			)
		)
		(duplicate_pad_numbers_are_jumpers no)
		(fp_line
			(start 0.508 -0.9398)
			(end -0.508 -0.9398)
			(stroke
				(width 0.1524)
				(type default)
			)
			(layer "F.SilkS")
		)
		(fp_line
			(start -0.508 -0.9398)
			(end -0.508 0.9398)
			(stroke
				(width 0.1524)
				(type default)
			)
			(layer "F.SilkS")
		)
		(fp_rect
			(start -0.508 0.9398)
			(end 0.508 -0.9398)
			(stroke
				(width 0)
				(type default)
			)
			(fill no)
			(layer "F.CrtYd")
		)
		(fp_rect
			(start -0.508 0.9398)
			(end 0.508 -0.9398)
			(stroke
				(width 0)
				(type default)
			)
			(fill no)
			(layer "F.Fab")
		)
		(pad "1" smd custom
			(at 0 -0.4445 180)
			(size 0.1397 0.1397)
			(layers "F.Cu" "F.Mask" "F.Paste")
			(net "NIC0_MDI0_N3")
			(options
				(clearance outline)
				(anchor circle)
			)
			(primitives
				(gr_poly
					(pts
						(arc
							(start -0.1778 -0.2794)
							(mid -0.249642 -0.249642)
							(end -0.2794 -0.1778)
						)
						(arc
							(start -0.2794 0.1778)
							(mid -0.249642 0.249642)
							(end -0.1778 0.2794)
						)
						(arc
							(start 0.1778 0.2794)
							(mid 0.249642 0.249642)
							(end 0.2794 0.1778)
						)
						(arc
							(start 0.2794 -0.1778)
							(mid 0.249642 -0.249642)
							(end 0.1778 -0.2794)
						)
					)
					(width 0)
					(fill yes)
				)
			)
		)
		(pad "2" smd custom
			(at 0 0.4445 180)
			(size 0.1397 0.1397)
			(layers "F.Cu" "F.Mask" "F.Paste")
			(net "MNG_RX_DN")
			(options
				(clearance outline)
				(anchor circle)
			)
			(primitives
				(gr_poly
					(pts
						(arc
							(start -0.1778 -0.2794)
							(mid -0.249642 -0.249642)
							(end -0.2794 -0.1778)
						)
						(arc
							(start -0.2794 0.1778)
							(mid -0.249642 0.249642)
							(end -0.1778 0.2794)
						)
						(arc
							(start 0.1778 0.2794)
							(mid 0.249642 0.249642)
							(end 0.2794 0.1778)
						)
						(arc
							(start 0.2794 -0.1778)
							(mid 0.249642 -0.249642)
							(end 0.1778 -0.2794)
						)
					)
					(width 0)
					(fill yes)
				)
			)
		)
	)
	(footprint ""
		(layer "F.Cu")
		(at 143.136874 -95.27032)
		(property "Reference" "PR78"
			(at 0 0 0)
			(layer "F.SilkS")
			(hide yes)
			(effects
				(font
					(size 1.27 1.27)
				)
			)
		)
		(property "Value" "10KR2F-2-GP"
			(at 0.064008 -3.993896 0)
			(unlocked yes)
			(layer "F.Fab")
			(hide yes)
			(effects
				(font
					(size 1.016 1.016)
					(thickness 0.1524)
				)
			)
		)
		(property "Device Type" "R402H16"
			(at 0.064008 -5.517896 0)
			(unlocked yes)
			(layer "F.Fab")
			(hide yes)
			(effects
				(font
					(size 1.016 1.016)
					(thickness 0.1524)
				)
			)
		)
		(duplicate_pad_numbers_are_jumpers no)
		(fp_line
			(start -0.508 -0.9398)
			(end -0.508 0.9398)
			(stroke
				(width 0.1524)
				(type default)
			)
			(layer "F.SilkS")
		)
		(fp_line
			(start 0.508 -0.9398)
			(end -0.508 -0.9398)
			(stroke
				(width 0.1524)
				(type default)
			)
			(layer "F.SilkS")
		)
		(fp_rect
			(start -0.508 0.9398)
			(end 0.508 -0.9398)
			(stroke
				(width 0)
				(type default)
			)
			(fill no)
			(layer "F.CrtYd")
		)
		(fp_rect
			(start -0.508 0.9398)
			(end 0.508 -0.9398)
			(stroke
				(width 0)
				(type default)
			)
			(fill no)
			(layer "F.Fab")
		)
		(pad "1" smd custom
			(at 0 -0.4445)
			(size 0.1397 0.1397)
			(layers "F.Cu" "F.Mask" "F.Paste")
			(net "P3V3_STBY")
			(options
				(clearance outline)
				(anchor circle)
			)
			(primitives
				(gr_poly
					(pts
						(arc
							(start -0.1778 -0.2794)
							(mid -0.249642 -0.249642)
							(end -0.2794 -0.1778)
						)
						(arc
							(start -0.2794 0.1778)
							(mid -0.249642 0.249642)
							(end -0.1778 0.2794)
						)
						(arc
							(start 0.1778 0.2794)
							(mid 0.249642 0.249642)
							(end 0.2794 0.1778)
						)
						(arc
							(start 0.2794 -0.1778)
							(mid 0.249642 -0.249642)
							(end 0.1778 -0.2794)
						)
					)
					(width 0)
					(fill yes)
				)
			)
		)
		(pad "2" smd custom
			(at 0 0.4445)
			(size 0.1397 0.1397)
			(layers "F.Cu" "F.Mask" "F.Paste")
			(net "PWRGD_P1V8_STBY")
			(options
				(clearance outline)
				(anchor circle)
			)
			(primitives
				(gr_poly
					(pts
						(arc
							(start -0.1778 -0.2794)
							(mid -0.249642 -0.249642)
							(end -0.2794 -0.1778)
						)
						(arc
							(start -0.2794 0.1778)
							(mid -0.249642 0.249642)
							(end -0.1778 0.2794)
						)
						(arc
							(start 0.1778 0.2794)
							(mid 0.249642 0.249642)
							(end 0.2794 0.1778)
						)
						(arc
							(start 0.2794 -0.1778)
							(mid 0.249642 -0.249642)
							(end 0.1778 -0.2794)
						)
					)
					(width 0)
					(fill yes)
				)
			)
		)
	)
	(footprint ""
		(layer "F.Cu")
		(at 12.2936 -68.834)
		(property "Reference" "C620"
			(at 0 0 0)
			(layer "F.SilkS")
			(hide yes)
			(effects
				(font
					(size 1.27 1.27)
				)
			)
		)
		(property "Value" "SCD1U16V2KX-3GP"
			(at 1.1811 -2.7051 0)
			(unlocked yes)
			(layer "F.Fab")
			(hide yes)
			(effects
				(font
					(size 1.016 1.016)
					(thickness 0.1524)
				)
			)
		)
		(property "Device Type" "C402H22"
			(at 1.1811 -4.2291 0)
			(unlocked yes)
			(layer "F.Fab")
			(hide yes)
			(effects
				(font
					(size 1.016 1.016)
					(thickness 0.1524)
				)
			)
		)
		(duplicate_pad_numbers_are_jumpers no)
		(fp_rect
			(start -0.4318 0.9525)
			(end 0.4318 -0.9525)
			(stroke
				(width 0)
				(type default)
			)
			(fill no)
			(layer "F.CrtYd")
		)
		(fp_rect
			(start -0.4318 0.9525)
			(end 0.4318 -0.9525)
			(stroke
				(width 0)
				(type default)
			)
			(fill no)
			(layer "F.Fab")
		)
		(pad "1" smd custom
			(at 0 -0.4445)
			(size 0.1524 0.1524)
			(layers "F.Cu" "F.Mask" "F.Paste")
			(net "P1V5_I210")
			(options
				(clearance outline)
				(anchor circle)
			)
			(primitives
				(gr_poly
					(pts
						(arc
							(start 0.3048 -0.2032)
							(mid 0.275042 -0.275042)
							(end 0.2032 -0.3048)
						)
						(arc
							(start -0.2032 -0.3048)
							(mid -0.275042 -0.275042)
							(end -0.3048 -0.2032)
						)
						(arc
							(start -0.3048 0.2032)
							(mid -0.275042 0.275042)
							(end -0.2032 0.3048)
						)
						(arc
							(start 0.2032 0.3048)
							(mid 0.275042 0.275042)
							(end 0.3048 0.2032)
						)
					)
					(width 0)
					(fill yes)
				)
			)
		)
		(pad "2" smd custom
			(at 0 0.4445)
			(size 0.1524 0.1524)
			(layers "F.Cu" "F.Mask" "F.Paste")
			(net "GND")
			(options
				(clearance outline)
				(anchor circle)
			)
			(primitives
				(gr_poly
					(pts
						(arc
							(start 0.3048 -0.2032)
							(mid 0.275042 -0.275042)
							(end 0.2032 -0.3048)
						)
						(arc
							(start -0.2032 -0.3048)
							(mid -0.275042 -0.275042)
							(end -0.3048 -0.2032)
						)
						(arc
							(start -0.3048 0.2032)
							(mid -0.275042 0.275042)
							(end -0.2032 0.3048)
						)
						(arc
							(start 0.2032 0.3048)
							(mid 0.275042 0.275042)
							(end 0.3048 0.2032)
						)
					)
					(width 0)
					(fill yes)
				)
			)
		)
	)
	(footprint ""
		(layer "F.Cu")
		(at 156.718 -95.9104)
		(property "Reference" "R97"
			(at 0 0 0)
			(layer "F.SilkS")
			(hide yes)
			(effects
				(font
					(size 1.27 1.27)
				)
			)
		)
		(property "Value" "10KR2F-2-GP"
			(at 0.064008 -3.993896 0)
			(unlocked yes)
			(layer "F.Fab")
			(hide yes)
			(effects
				(font
					(size 1.016 1.016)
					(thickness 0.1524)
				)
			)
		)
		(property "Device Type" "R402H16"
			(at 0.064008 -5.517896 0)
			(unlocked yes)
			(layer "F.Fab")
			(hide yes)
			(effects
				(font
					(size 1.016 1.016)
					(thickness 0.1524)
				)
			)
		)
		(duplicate_pad_numbers_are_jumpers no)
		(fp_line
			(start -0.508 -0.9398)
			(end -0.508 0.9398)
			(stroke
				(width 0.1524)
				(type default)
			)
			(layer "F.SilkS")
		)
		(fp_line
			(start 0.508 -0.9398)
			(end -0.508 -0.9398)
			(stroke
				(width 0.1524)
				(type default)
			)
			(layer "F.SilkS")
		)
		(fp_rect
			(start -0.508 0.9398)
			(end 0.508 -0.9398)
			(stroke
				(width 0)
				(type default)
			)
			(fill no)
			(layer "F.CrtYd")
		)
		(fp_rect
			(start -0.508 0.9398)
			(end 0.508 -0.9398)
			(stroke
				(width 0)
				(type default)
			)
			(fill no)
			(layer "F.Fab")
		)
		(pad "1" smd custom
			(at 0 -0.4445)
			(size 0.1397 0.1397)
			(layers "F.Cu" "F.Mask" "F.Paste")
			(net "GND")
			(options
				(clearance outline)
				(anchor circle)
			)
			(primitives
				(gr_poly
					(pts
						(arc
							(start -0.1778 -0.2794)
							(mid -0.249642 -0.249642)
							(end -0.2794 -0.1778)
						)
						(arc
							(start -0.2794 0.1778)
							(mid -0.249642 0.249642)
							(end -0.1778 0.2794)
						)
						(arc
							(start 0.1778 0.2794)
							(mid 0.249642 0.249642)
							(end 0.2794 0.1778)
						)
						(arc
							(start 0.2794 -0.1778)
							(mid 0.249642 -0.249642)
							(end 0.1778 -0.2794)
						)
					)
					(width 0)
					(fill yes)
				)
			)
		)
		(pad "2" smd custom
			(at 0 0.4445)
			(size 0.1397 0.1397)
			(layers "F.Cu" "F.Mask" "F.Paste")
			(net "CLKGNE_SS_EN")
			(options
				(clearance outline)
				(anchor circle)
			)
			(primitives
				(gr_poly
					(pts
						(arc
							(start -0.1778 -0.2794)
							(mid -0.249642 -0.249642)
							(end -0.2794 -0.1778)
						)
						(arc
							(start -0.2794 0.1778)
							(mid -0.249642 0.249642)
							(end -0.1778 0.2794)
						)
						(arc
							(start 0.1778 0.2794)
							(mid 0.249642 0.249642)
							(end 0.2794 0.1778)
						)
						(arc
							(start 0.2794 -0.1778)
							(mid 0.249642 -0.249642)
							(end 0.1778 -0.2794)
						)
					)
					(width 0)
					(fill yes)
				)
			)
		)
	)
	(footprint ""
		(layer "F.Cu")
		(at 20.574 -148.336)
		(property "Reference" "C187"
			(at 0 0 0)
			(layer "F.SilkS")
			(hide yes)
			(effects
				(font
					(size 1.27 1.27)
				)
			)
		)
		(property "Value" "SCD1U16V2KX-3GP"
			(at 1.1811 -2.7051 0)
			(unlocked yes)
			(layer "F.Fab")
			(hide yes)
			(effects
				(font
					(size 1.016 1.016)
					(thickness 0.1524)
				)
			)
		)
		(property "Device Type" "C402H22"
			(at 1.1811 -4.2291 0)
			(unlocked yes)
			(layer "F.Fab")
			(hide yes)
			(effects
				(font
					(size 1.016 1.016)
					(thickness 0.1524)
				)
			)
		)
		(duplicate_pad_numbers_are_jumpers no)
		(fp_rect
			(start -0.4318 0.9525)
			(end 0.4318 -0.9525)
			(stroke
				(width 0)
				(type default)
			)
			(fill no)
			(layer "F.CrtYd")
		)
		(fp_rect
			(start -0.4318 0.9525)
			(end 0.4318 -0.9525)
			(stroke
				(width 0)
				(type default)
			)
			(fill no)
			(layer "F.Fab")
		)
		(pad "1" smd custom
			(at 0 -0.4445)
			(size 0.1524 0.1524)
			(layers "F.Cu" "F.Mask" "F.Paste")
			(net "P3V3_STBY")
			(options
				(clearance outline)
				(anchor circle)
			)
			(primitives
				(gr_poly
					(pts
						(arc
							(start 0.3048 -0.2032)
							(mid 0.275042 -0.275042)
							(end 0.2032 -0.3048)
						)
						(arc
							(start -0.2032 -0.3048)
							(mid -0.275042 -0.275042)
							(end -0.3048 -0.2032)
						)
						(arc
							(start -0.3048 0.2032)
							(mid -0.275042 0.275042)
							(end -0.2032 0.3048)
						)
						(arc
							(start 0.2032 0.3048)
							(mid 0.275042 0.275042)
							(end 0.3048 0.2032)
						)
					)
					(width 0)
					(fill yes)
				)
			)
		)
		(pad "2" smd custom
			(at 0 0.4445)
			(size 0.1524 0.1524)
			(layers "F.Cu" "F.Mask" "F.Paste")
			(net "GND")
			(options
				(clearance outline)
				(anchor circle)
			)
			(primitives
				(gr_poly
					(pts
						(arc
							(start 0.3048 -0.2032)
							(mid 0.275042 -0.275042)
							(end 0.2032 -0.3048)
						)
						(arc
							(start -0.2032 -0.3048)
							(mid -0.275042 -0.275042)
							(end -0.3048 -0.2032)
						)
						(arc
							(start -0.3048 0.2032)
							(mid -0.275042 0.275042)
							(end -0.2032 0.3048)
						)
						(arc
							(start 0.2032 0.3048)
							(mid 0.275042 0.275042)
							(end 0.3048 0.2032)
						)
					)
					(width 0)
					(fill yes)
				)
			)
		)
	)
	(footprint ""
		(layer "F.Cu")
		(at 83.081368 -75.1586 90)
		(property "Reference" "C283"
			(at 0 0 90)
			(layer "F.SilkS")
			(hide yes)
			(effects
				(font
					(size 1.27 1.27)
				)
			)
		)
		(property "Value" "SCD01U16V2KX-3GP"
			(at 1.1811 -2.7051 90)
			(unlocked yes)
			(layer "F.Fab")
			(hide yes)
			(effects
				(font
					(size 1.016 1.016)
					(thickness 0.1524)
				)
			)
		)
		(property "Device Type" "C402H22"
			(at 1.1811 -4.2291 90)
			(unlocked yes)
			(layer "F.Fab")
			(hide yes)
			(effects
				(font
					(size 1.016 1.016)
					(thickness 0.1524)
				)
			)
		)
		(duplicate_pad_numbers_are_jumpers no)
		(fp_rect
			(start -0.4318 0.9525)
			(end 0.4318 -0.9525)
			(stroke
				(width 0)
				(type default)
			)
			(fill no)
			(layer "F.CrtYd")
		)
		(fp_rect
			(start -0.4318 0.9525)
			(end 0.4318 -0.9525)
			(stroke
				(width 0)
				(type default)
			)
			(fill no)
			(layer "F.Fab")
		)
		(pad "1" smd custom
			(at 0 -0.4445 90)
			(size 0.1524 0.1524)
			(layers "F.Cu" "F.Mask" "F.Paste")
			(net "P3V3_STBY")
			(options
				(clearance outline)
				(anchor circle)
			)
			(primitives
				(gr_poly
					(pts
						(arc
							(start 0.3048 -0.2032)
							(mid 0.275042 -0.275042)
							(end 0.2032 -0.3048)
						)
						(arc
							(start -0.2032 -0.3048)
							(mid -0.275042 -0.275042)
							(end -0.3048 -0.2032)
						)
						(arc
							(start -0.3048 0.2032)
							(mid -0.275042 0.275042)
							(end -0.2032 0.3048)
						)
						(arc
							(start 0.2032 0.3048)
							(mid 0.275042 0.275042)
							(end 0.3048 0.2032)
						)
					)
					(width 0)
					(fill yes)
				)
			)
		)
		(pad "2" smd custom
			(at 0 0.4445 90)
			(size 0.1524 0.1524)
			(layers "F.Cu" "F.Mask" "F.Paste")
			(net "GND")
			(options
				(clearance outline)
				(anchor circle)
			)
			(primitives
				(gr_poly
					(pts
						(arc
							(start 0.3048 -0.2032)
							(mid 0.275042 -0.275042)
							(end 0.2032 -0.3048)
						)
						(arc
							(start -0.2032 -0.3048)
							(mid -0.275042 -0.275042)
							(end -0.3048 -0.2032)
						)
						(arc
							(start -0.3048 0.2032)
							(mid -0.275042 0.275042)
							(end -0.2032 0.3048)
						)
						(arc
							(start 0.2032 0.3048)
							(mid 0.275042 0.275042)
							(end 0.3048 0.2032)
						)
					)
					(width 0)
					(fill yes)
				)
			)
		)
	)
	(footprint ""
		(layer "F.Cu")
		(at 61.2902 -161.8996 180)
		(property "Reference" "PC18"
			(at 0 0 180)
			(layer "F.SilkS")
			(hide yes)
			(effects
				(font
					(size 1.27 1.27)
				)
			)
		)
		(property "Value" "SCD01U25V2KX-3GP"
			(at 1.1811 -2.7051 180)
			(unlocked yes)
			(layer "F.Fab")
			(hide yes)
			(effects
				(font
					(size 1.016 1.016)
					(thickness 0.1524)
				)
			)
		)
		(property "Device Type" "C402H22"
			(at 1.1811 -4.2291 180)
			(unlocked yes)
			(layer "F.Fab")
			(hide yes)
			(effects
				(font
					(size 1.016 1.016)
					(thickness 0.1524)
				)
			)
		)
		(duplicate_pad_numbers_are_jumpers no)
		(fp_rect
			(start -0.4318 0.9525)
			(end 0.4318 -0.9525)
			(stroke
				(width 0)
				(type default)
			)
			(fill no)
			(layer "F.CrtYd")
		)
		(fp_rect
			(start -0.4318 0.9525)
			(end 0.4318 -0.9525)
			(stroke
				(width 0)
				(type default)
			)
			(fill no)
			(layer "F.Fab")
		)
		(pad "1" smd custom
			(at 0 -0.4445 180)
			(size 0.1524 0.1524)
			(layers "F.Cu" "F.Mask" "F.Paste")
			(net "P1V53_PWR")
			(options
				(clearance outline)
				(anchor circle)
			)
			(primitives
				(gr_poly
					(pts
						(arc
							(start 0.3048 -0.2032)
							(mid 0.275042 -0.275042)
							(end 0.2032 -0.3048)
						)
						(arc
							(start -0.2032 -0.3048)
							(mid -0.275042 -0.275042)
							(end -0.3048 -0.2032)
						)
						(arc
							(start -0.3048 0.2032)
							(mid -0.275042 0.275042)
							(end -0.2032 0.3048)
						)
						(arc
							(start 0.2032 0.3048)
							(mid 0.275042 0.275042)
							(end 0.3048 0.2032)
						)
					)
					(width 0)
					(fill yes)
				)
			)
		)
		(pad "2" smd custom
			(at 0 0.4445 180)
			(size 0.1524 0.1524)
			(layers "F.Cu" "F.Mask" "F.Paste")
			(net "VR_P1V538_STBY_FB")
			(options
				(clearance outline)
				(anchor circle)
			)
			(primitives
				(gr_poly
					(pts
						(arc
							(start 0.3048 -0.2032)
							(mid 0.275042 -0.275042)
							(end 0.2032 -0.3048)
						)
						(arc
							(start -0.2032 -0.3048)
							(mid -0.275042 -0.275042)
							(end -0.3048 -0.2032)
						)
						(arc
							(start -0.3048 0.2032)
							(mid -0.275042 0.275042)
							(end -0.2032 0.3048)
						)
						(arc
							(start 0.2032 0.3048)
							(mid 0.275042 0.275042)
							(end 0.3048 0.2032)
						)
					)
					(width 0)
					(fill yes)
				)
			)
		)
	)
	(footprint ""
		(layer "F.Cu")
		(at 257.670554 -10.999724 180)
		(property "Reference" "C42"
			(at 0 0 180)
			(layer "F.SilkS")
			(hide yes)
			(effects
				(font
					(size 1.27 1.27)
				)
			)
		)
		(property "Value" "SCD1U10V2KX-5GP"
			(at 1.1811 -2.7051 180)
			(unlocked yes)
			(layer "F.Fab")
			(hide yes)
			(effects
				(font
					(size 1.016 1.016)
					(thickness 0.1524)
				)
			)
		)
		(property "Device Type" "C402H22"
			(at 1.1811 -4.2291 180)
			(unlocked yes)
			(layer "F.Fab")
			(hide yes)
			(effects
				(font
					(size 1.016 1.016)
					(thickness 0.1524)
				)
			)
		)
		(duplicate_pad_numbers_are_jumpers no)
		(fp_rect
			(start -0.4318 0.9525)
			(end 0.4318 -0.9525)
			(stroke
				(width 0)
				(type default)
			)
			(fill no)
			(layer "F.CrtYd")
		)
		(fp_rect
			(start -0.4318 0.9525)
			(end 0.4318 -0.9525)
			(stroke
				(width 0)
				(type default)
			)
			(fill no)
			(layer "F.Fab")
		)
		(pad "1" smd custom
			(at 0 -0.4445 180)
			(size 0.1524 0.1524)
			(layers "F.Cu" "F.Mask" "F.Paste")
			(net "P3V3_STBY")
			(options
				(clearance outline)
				(anchor circle)
			)
			(primitives
				(gr_poly
					(pts
						(arc
							(start 0.3048 -0.2032)
							(mid 0.275042 -0.275042)
							(end 0.2032 -0.3048)
						)
						(arc
							(start -0.2032 -0.3048)
							(mid -0.275042 -0.275042)
							(end -0.3048 -0.2032)
						)
						(arc
							(start -0.3048 0.2032)
							(mid -0.275042 0.275042)
							(end -0.2032 0.3048)
						)
						(arc
							(start 0.2032 0.3048)
							(mid 0.275042 0.275042)
							(end 0.3048 0.2032)
						)
					)
					(width 0)
					(fill yes)
				)
			)
		)
		(pad "2" smd custom
			(at 0 0.4445 180)
			(size 0.1524 0.1524)
			(layers "F.Cu" "F.Mask" "F.Paste")
			(net "GND")
			(options
				(clearance outline)
				(anchor circle)
			)
			(primitives
				(gr_poly
					(pts
						(arc
							(start 0.3048 -0.2032)
							(mid 0.275042 -0.275042)
							(end 0.2032 -0.3048)
						)
						(arc
							(start -0.2032 -0.3048)
							(mid -0.275042 -0.275042)
							(end -0.3048 -0.2032)
						)
						(arc
							(start -0.3048 0.2032)
							(mid -0.275042 0.275042)
							(end -0.2032 0.3048)
						)
						(arc
							(start 0.2032 0.3048)
							(mid 0.275042 0.275042)
							(end 0.3048 0.2032)
						)
					)
					(width 0)
					(fill yes)
				)
			)
		)
	)
	(footprint ""
		(layer "F.Cu")
		(at 276.50948 -5.82676 90)
		(property "Reference" "R2904"
			(at 0 0 90)
			(layer "F.SilkS")
			(hide yes)
			(effects
				(font
					(size 1.27 1.27)
				)
			)
		)
		(property "Value" "0R2J-2-GP"
			(at 0.064008 -3.993896 90)
			(unlocked yes)
			(layer "F.Fab")
			(hide yes)
			(effects
				(font
					(size 1.016 1.016)
					(thickness 0.1524)
				)
			)
		)
		(property "Device Type" "R402H16"
			(at 0.064008 -5.517896 90)
			(unlocked yes)
			(layer "F.Fab")
			(hide yes)
			(effects
				(font
					(size 1.016 1.016)
					(thickness 0.1524)
				)
			)
		)
		(duplicate_pad_numbers_are_jumpers no)
		(fp_line
			(start 0.508 -0.9398)
			(end -0.508 -0.9398)
			(stroke
				(width 0.1524)
				(type default)
			)
			(layer "F.SilkS")
		)
		(fp_line
			(start -0.508 -0.9398)
			(end -0.508 0.9398)
			(stroke
				(width 0.1524)
				(type default)
			)
			(layer "F.SilkS")
		)
		(fp_rect
			(start -0.508 0.9398)
			(end 0.508 -0.9398)
			(stroke
				(width 0)
				(type default)
			)
			(fill no)
			(layer "F.CrtYd")
		)
		(fp_rect
			(start -0.508 0.9398)
			(end 0.508 -0.9398)
			(stroke
				(width 0)
				(type default)
			)
			(fill no)
			(layer "F.Fab")
		)
		(pad "1" smd custom
			(at 0 -0.4445 90)
			(size 0.1397 0.1397)
			(layers "F.Cu" "F.Mask" "F.Paste")
			(net "CBL_PRSNT_N_6")
			(options
				(clearance outline)
				(anchor circle)
			)
			(primitives
				(gr_poly
					(pts
						(arc
							(start -0.1778 -0.2794)
							(mid -0.249642 -0.249642)
							(end -0.2794 -0.1778)
						)
						(arc
							(start -0.2794 0.1778)
							(mid -0.249642 0.249642)
							(end -0.1778 0.2794)
						)
						(arc
							(start 0.1778 0.2794)
							(mid 0.249642 0.249642)
							(end 0.2794 0.1778)
						)
						(arc
							(start 0.2794 -0.1778)
							(mid 0.249642 -0.249642)
							(end 0.1778 -0.2794)
						)
					)
					(width 0)
					(fill yes)
				)
			)
		)
		(pad "2" smd custom
			(at 0 0.4445 90)
			(size 0.1397 0.1397)
			(layers "F.Cu" "F.Mask" "F.Paste")
			(net "8644_CBL_PRSNT_R_6")
			(options
				(clearance outline)
				(anchor circle)
			)
			(primitives
				(gr_poly
					(pts
						(arc
							(start -0.1778 -0.2794)
							(mid -0.249642 -0.249642)
							(end -0.2794 -0.1778)
						)
						(arc
							(start -0.2794 0.1778)
							(mid -0.249642 0.249642)
							(end -0.1778 0.2794)
						)
						(arc
							(start 0.1778 0.2794)
							(mid 0.249642 0.249642)
							(end 0.2794 0.1778)
						)
						(arc
							(start 0.2794 -0.1778)
							(mid 0.249642 -0.249642)
							(end 0.1778 -0.2794)
						)
					)
					(width 0)
					(fill yes)
				)
			)
		)
	)
	(footprint ""
		(layer "F.Cu")
		(at 262.255 -26.289 180)
		(property "Reference" "R744"
			(at 0 0 180)
			(layer "F.SilkS")
			(hide yes)
			(effects
				(font
					(size 1.27 1.27)
				)
			)
		)
		(property "Value" "4K7R2F-GP"
			(at 0.064008 -3.993896 180)
			(unlocked yes)
			(layer "F.Fab")
			(hide yes)
			(effects
				(font
					(size 1.016 1.016)
					(thickness 0.1524)
				)
			)
		)
		(property "Device Type" "R402H16"
			(at 0.064008 -5.517896 180)
			(unlocked yes)
			(layer "F.Fab")
			(hide yes)
			(effects
				(font
					(size 1.016 1.016)
					(thickness 0.1524)
				)
			)
		)
		(duplicate_pad_numbers_are_jumpers no)
		(fp_line
			(start 0.508 -0.9398)
			(end -0.508 -0.9398)
			(stroke
				(width 0.1524)
				(type default)
			)
			(layer "F.SilkS")
		)
		(fp_line
			(start -0.508 -0.9398)
			(end -0.508 0.9398)
			(stroke
				(width 0.1524)
				(type default)
			)
			(layer "F.SilkS")
		)
		(fp_rect
			(start -0.508 0.9398)
			(end 0.508 -0.9398)
			(stroke
				(width 0)
				(type default)
			)
			(fill no)
			(layer "F.CrtYd")
		)
		(fp_rect
			(start -0.508 0.9398)
			(end 0.508 -0.9398)
			(stroke
				(width 0)
				(type default)
			)
			(fill no)
			(layer "F.Fab")
		)
		(pad "1" smd custom
			(at 0 -0.4445 180)
			(size 0.1397 0.1397)
			(layers "F.Cu" "F.Mask" "F.Paste")
			(net "P3V3_GPIO")
			(options
				(clearance outline)
				(anchor circle)
			)
			(primitives
				(gr_poly
					(pts
						(arc
							(start -0.1778 -0.2794)
							(mid -0.249642 -0.249642)
							(end -0.2794 -0.1778)
						)
						(arc
							(start -0.2794 0.1778)
							(mid -0.249642 0.249642)
							(end -0.1778 0.2794)
						)
						(arc
							(start 0.1778 0.2794)
							(mid 0.249642 0.249642)
							(end 0.2794 0.1778)
						)
						(arc
							(start 0.2794 -0.1778)
							(mid 0.249642 -0.249642)
							(end 0.1778 -0.2794)
						)
					)
					(width 0)
					(fill yes)
				)
			)
		)
		(pad "2" smd custom
			(at 0 0.4445 180)
			(size 0.1397 0.1397)
			(layers "F.Cu" "F.Mask" "F.Paste")
			(net "IOEXP_INT#_3")
			(options
				(clearance outline)
				(anchor circle)
			)
			(primitives
				(gr_poly
					(pts
						(arc
							(start -0.1778 -0.2794)
							(mid -0.249642 -0.249642)
							(end -0.2794 -0.1778)
						)
						(arc
							(start -0.2794 0.1778)
							(mid -0.249642 0.249642)
							(end -0.1778 0.2794)
						)
						(arc
							(start 0.1778 0.2794)
							(mid 0.249642 0.249642)
							(end 0.2794 0.1778)
						)
						(arc
							(start 0.2794 -0.1778)
							(mid 0.249642 -0.249642)
							(end 0.1778 -0.2794)
						)
					)
					(width 0)
					(fill yes)
				)
			)
		)
	)
	(footprint ""
		(layer "F.Cu")
		(at 52.197 -199.39 -90)
		(property "Reference" "R888"
			(at 0 0 270)
			(layer "F.SilkS")
			(hide yes)
			(effects
				(font
					(size 1.27 1.27)
				)
			)
		)
		(property "Value" "4K7R2J-2-GP"
			(at 0.064008 -3.993896 270)
			(unlocked yes)
			(layer "F.Fab")
			(hide yes)
			(effects
				(font
					(size 1.016 1.016)
					(thickness 0.1524)
				)
			)
		)
		(property "Device Type" "R402H16"
			(at 0.064008 -5.517896 270)
			(unlocked yes)
			(layer "F.Fab")
			(hide yes)
			(effects
				(font
					(size 1.016 1.016)
					(thickness 0.1524)
				)
			)
		)
		(duplicate_pad_numbers_are_jumpers no)
		(fp_line
			(start -0.508 -0.9398)
			(end -0.508 0.9398)
			(stroke
				(width 0.1524)
				(type default)
			)
			(layer "F.SilkS")
		)
		(fp_line
			(start 0.508 -0.9398)
			(end -0.508 -0.9398)
			(stroke
				(width 0.1524)
				(type default)
			)
			(layer "F.SilkS")
		)
		(fp_rect
			(start -0.508 0.9398)
			(end 0.508 -0.9398)
			(stroke
				(width 0)
				(type default)
			)
			(fill no)
			(layer "F.CrtYd")
		)
		(fp_rect
			(start -0.508 0.9398)
			(end 0.508 -0.9398)
			(stroke
				(width 0)
				(type default)
			)
			(fill no)
			(layer "F.Fab")
		)
		(pad "1" smd custom
			(at 0 -0.4445 270)
			(size 0.1397 0.1397)
			(layers "F.Cu" "F.Mask" "F.Paste")
			(net "P3V3_STBY")
			(options
				(clearance outline)
				(anchor circle)
			)
			(primitives
				(gr_poly
					(pts
						(arc
							(start -0.1778 -0.2794)
							(mid -0.249642 -0.249642)
							(end -0.2794 -0.1778)
						)
						(arc
							(start -0.2794 0.1778)
							(mid -0.249642 0.249642)
							(end -0.1778 0.2794)
						)
						(arc
							(start 0.1778 0.2794)
							(mid 0.249642 0.249642)
							(end 0.2794 0.1778)
						)
						(arc
							(start 0.2794 -0.1778)
							(mid 0.249642 -0.249642)
							(end 0.1778 -0.2794)
						)
					)
					(width 0)
					(fill yes)
				)
			)
		)
		(pad "2" smd custom
			(at 0 0.4445 270)
			(size 0.1397 0.1397)
			(layers "F.Cu" "F.Mask" "F.Paste")
			(net "BUF_I2C7_B_DBP_SCL_R")
			(options
				(clearance outline)
				(anchor circle)
			)
			(primitives
				(gr_poly
					(pts
						(arc
							(start -0.1778 -0.2794)
							(mid -0.249642 -0.249642)
							(end -0.2794 -0.1778)
						)
						(arc
							(start -0.2794 0.1778)
							(mid -0.249642 0.249642)
							(end -0.1778 0.2794)
						)
						(arc
							(start 0.1778 0.2794)
							(mid 0.249642 0.249642)
							(end 0.2794 0.1778)
						)
						(arc
							(start 0.2794 -0.1778)
							(mid 0.249642 -0.249642)
							(end 0.1778 -0.2794)
						)
					)
					(width 0)
					(fill yes)
				)
			)
		)
	)
	(footprint ""
		(layer "F.Cu")
		(at 126.5936 -50.8508 180)
		(property "Reference" "R931"
			(at 0 0 180)
			(layer "F.SilkS")
			(hide yes)
			(effects
				(font
					(size 1.27 1.27)
				)
			)
		)
		(property "Value" "4K7R2F-GP"
			(at 0.064008 -3.993896 180)
			(unlocked yes)
			(layer "F.Fab")
			(hide yes)
			(effects
				(font
					(size 1.016 1.016)
					(thickness 0.1524)
				)
			)
		)
		(property "Device Type" "R402H16"
			(at 0.064008 -5.517896 180)
			(unlocked yes)
			(layer "F.Fab")
			(hide yes)
			(effects
				(font
					(size 1.016 1.016)
					(thickness 0.1524)
				)
			)
		)
		(duplicate_pad_numbers_are_jumpers no)
		(fp_line
			(start 0.508 -0.9398)
			(end -0.508 -0.9398)
			(stroke
				(width 0.1524)
				(type default)
			)
			(layer "F.SilkS")
		)
		(fp_line
			(start -0.508 -0.9398)
			(end -0.508 0.9398)
			(stroke
				(width 0.1524)
				(type default)
			)
			(layer "F.SilkS")
		)
		(fp_rect
			(start -0.508 0.9398)
			(end 0.508 -0.9398)
			(stroke
				(width 0)
				(type default)
			)
			(fill no)
			(layer "F.CrtYd")
		)
		(fp_rect
			(start -0.508 0.9398)
			(end 0.508 -0.9398)
			(stroke
				(width 0)
				(type default)
			)
			(fill no)
			(layer "F.Fab")
		)
		(pad "1" smd custom
			(at 0 -0.4445 180)
			(size 0.1397 0.1397)
			(layers "F.Cu" "F.Mask" "F.Paste")
			(net "P3V3_STBY")
			(options
				(clearance outline)
				(anchor circle)
			)
			(primitives
				(gr_poly
					(pts
						(arc
							(start -0.1778 -0.2794)
							(mid -0.249642 -0.249642)
							(end -0.2794 -0.1778)
						)
						(arc
							(start -0.2794 0.1778)
							(mid -0.249642 0.249642)
							(end -0.1778 0.2794)
						)
						(arc
							(start 0.1778 0.2794)
							(mid 0.249642 0.249642)
							(end 0.2794 0.1778)
						)
						(arc
							(start 0.2794 -0.1778)
							(mid 0.249642 -0.249642)
							(end 0.1778 -0.2794)
						)
					)
					(width 0)
					(fill yes)
				)
			)
		)
		(pad "2" smd custom
			(at 0 0.4445 180)
			(size 0.1397 0.1397)
			(layers "F.Cu" "F.Mask" "F.Paste")
			(net "BMC_ADD1_PWR")
			(options
				(clearance outline)
				(anchor circle)
			)
			(primitives
				(gr_poly
					(pts
						(arc
							(start -0.1778 -0.2794)
							(mid -0.249642 -0.249642)
							(end -0.2794 -0.1778)
						)
						(arc
							(start -0.2794 0.1778)
							(mid -0.249642 0.249642)
							(end -0.1778 0.2794)
						)
						(arc
							(start 0.1778 0.2794)
							(mid 0.249642 0.249642)
							(end 0.2794 0.1778)
						)
						(arc
							(start 0.2794 -0.1778)
							(mid 0.249642 -0.249642)
							(end 0.1778 -0.2794)
						)
					)
					(width 0)
					(fill yes)
				)
			)
		)
	)
	(footprint ""
		(layer "F.Cu")
		(at 26.289 -116.713 180)
		(property "Reference" "R235"
			(at 0 0 180)
			(layer "F.SilkS")
			(hide yes)
			(effects
				(font
					(size 1.27 1.27)
				)
			)
		)
		(property "Value" "100KR2F-L1-GP"
			(at 0.064008 -3.993896 180)
			(unlocked yes)
			(layer "F.Fab")
			(hide yes)
			(effects
				(font
					(size 1.016 1.016)
					(thickness 0.1524)
				)
			)
		)
		(property "Device Type" "R402H16"
			(at 0.064008 -5.517896 180)
			(unlocked yes)
			(layer "F.Fab")
			(hide yes)
			(effects
				(font
					(size 1.016 1.016)
					(thickness 0.1524)
				)
			)
		)
		(duplicate_pad_numbers_are_jumpers no)
		(fp_line
			(start 0.508 -0.9398)
			(end -0.508 -0.9398)
			(stroke
				(width 0.1524)
				(type default)
			)
			(layer "F.SilkS")
		)
		(fp_line
			(start -0.508 -0.9398)
			(end -0.508 0.9398)
			(stroke
				(width 0.1524)
				(type default)
			)
			(layer "F.SilkS")
		)
		(fp_rect
			(start -0.508 0.9398)
			(end 0.508 -0.9398)
			(stroke
				(width 0)
				(type default)
			)
			(fill no)
			(layer "F.CrtYd")
		)
		(fp_rect
			(start -0.508 0.9398)
			(end 0.508 -0.9398)
			(stroke
				(width 0)
				(type default)
			)
			(fill no)
			(layer "F.Fab")
		)
		(pad "1" smd custom
			(at 0 -0.4445 180)
			(size 0.1397 0.1397)
			(layers "F.Cu" "F.Mask" "F.Paste")
			(net "GND")
			(options
				(clearance outline)
				(anchor circle)
			)
			(primitives
				(gr_poly
					(pts
						(arc
							(start -0.1778 -0.2794)
							(mid -0.249642 -0.249642)
							(end -0.2794 -0.1778)
						)
						(arc
							(start -0.2794 0.1778)
							(mid -0.249642 0.249642)
							(end -0.1778 0.2794)
						)
						(arc
							(start 0.1778 0.2794)
							(mid 0.249642 0.249642)
							(end 0.2794 0.1778)
						)
						(arc
							(start 0.2794 -0.1778)
							(mid 0.249642 -0.249642)
							(end 0.1778 -0.2794)
						)
					)
					(width 0)
					(fill yes)
				)
			)
		)
		(pad "2" smd custom
			(at 0 0.4445 180)
			(size 0.1397 0.1397)
			(layers "F.Cu" "F.Mask" "F.Paste")
			(net "TP_BMC0_LPC_LAD1")
			(options
				(clearance outline)
				(anchor circle)
			)
			(primitives
				(gr_poly
					(pts
						(arc
							(start -0.1778 -0.2794)
							(mid -0.249642 -0.249642)
							(end -0.2794 -0.1778)
						)
						(arc
							(start -0.2794 0.1778)
							(mid -0.249642 0.249642)
							(end -0.1778 0.2794)
						)
						(arc
							(start 0.1778 0.2794)
							(mid 0.249642 0.249642)
							(end 0.2794 0.1778)
						)
						(arc
							(start 0.2794 -0.1778)
							(mid 0.249642 -0.249642)
							(end 0.1778 -0.2794)
						)
					)
					(width 0)
					(fill yes)
				)
			)
		)
	)
	(footprint ""
		(layer "F.Cu")
		(at 200.4314 -0.2794 -90)
		(property "Reference" "R543"
			(at 0 0 270)
			(layer "F.SilkS")
			(hide yes)
			(effects
				(font
					(size 1.27 1.27)
				)
			)
		)
		(property "Value" "330R1210J-GP"
			(at 0.0889 -6.9977 270)
			(unlocked yes)
			(layer "F.Fab")
			(hide yes)
			(effects
				(font
					(size 1.016 1.016)
					(thickness 0.1524)
				)
			)
		)
		(property "Device Type" "R1210H24"
			(at 0.0635 -8.636 270)
			(unlocked yes)
			(layer "F.Fab")
			(hide yes)
			(effects
				(font
					(size 1.016 1.016)
					(thickness 0.1524)
				)
			)
		)
		(duplicate_pad_numbers_are_jumpers no)
		(fp_line
			(start -1.651 2.413)
			(end -1.651 -2.413)
			(stroke
				(width 0.1524)
				(type default)
			)
			(layer "F.SilkS")
		)
		(fp_line
			(start 1.651 2.413)
			(end -1.651 2.413)
			(stroke
				(width 0.1524)
				(type default)
			)
			(layer "F.SilkS")
		)
		(fp_line
			(start -1.651 -2.413)
			(end 1.651 -2.413)
			(stroke
				(width 0.1524)
				(type default)
			)
			(layer "F.SilkS")
		)
		(fp_line
			(start 1.651 -2.413)
			(end 1.651 2.413)
			(stroke
				(width 0.1524)
				(type default)
			)
			(layer "F.SilkS")
		)
		(fp_poly
			(pts
				(xy -1.651 -2.413) (xy 1.651 -2.413) (xy 1.651 2.413) (xy -1.651 2.413)
			)
			(stroke
				(width 0)
				(type default)
			)
			(fill no)
			(layer "F.CrtYd")
		)
		(fp_poly
			(pts
				(xy -1.651 -2.413) (xy 1.651 -2.413) (xy 1.651 2.413) (xy -1.651 2.413)
			)
			(stroke
				(width 0)
				(type default)
			)
			(fill no)
			(layer "F.Fab")
		)
		(pad "1" smd rect
			(at 0 -1.4732 270)
			(size 2.794 1.397)
			(layers "F.Cu" "F.Mask" "F.Paste")
			(net "P5V_STBY")
		)
		(pad "2" smd rect
			(at 0 1.4732 270)
			(size 2.794 1.397)
			(layers "F.Cu" "F.Mask" "F.Paste")
			(net "ENCLO_LED_RED_R")
		)
	)
	(footprint ""
		(layer "F.Cu")
		(at 335.8896 -170.5102)
		(property "Reference" "R9033"
			(at 0 0 0)
			(layer "F.SilkS")
			(hide yes)
			(effects
				(font
					(size 1.27 1.27)
				)
			)
		)
		(property "Value" "4K7R2F-GP"
			(at 0.064008 -3.993896 0)
			(unlocked yes)
			(layer "F.Fab")
			(hide yes)
			(effects
				(font
					(size 1.016 1.016)
					(thickness 0.1524)
				)
			)
		)
		(property "Device Type" "R402H16"
			(at 0.064008 -5.517896 0)
			(unlocked yes)
			(layer "F.Fab")
			(hide yes)
			(effects
				(font
					(size 1.016 1.016)
					(thickness 0.1524)
				)
			)
		)
		(duplicate_pad_numbers_are_jumpers no)
		(fp_line
			(start -0.508 -0.9398)
			(end -0.508 0.9398)
			(stroke
				(width 0.1524)
				(type default)
			)
			(layer "F.SilkS")
		)
		(fp_line
			(start 0.508 -0.9398)
			(end -0.508 -0.9398)
			(stroke
				(width 0.1524)
				(type default)
			)
			(layer "F.SilkS")
		)
		(fp_rect
			(start -0.508 0.9398)
			(end 0.508 -0.9398)
			(stroke
				(width 0)
				(type default)
			)
			(fill no)
			(layer "F.CrtYd")
		)
		(fp_rect
			(start -0.508 0.9398)
			(end 0.508 -0.9398)
			(stroke
				(width 0)
				(type default)
			)
			(fill no)
			(layer "F.Fab")
		)
		(pad "1" smd custom
			(at 0 -0.4445)
			(size 0.1397 0.1397)
			(layers "F.Cu" "F.Mask" "F.Paste")
			(net "SSD_PERST#4")
			(options
				(clearance outline)
				(anchor circle)
			)
			(primitives
				(gr_poly
					(pts
						(arc
							(start -0.1778 -0.2794)
							(mid -0.249642 -0.249642)
							(end -0.2794 -0.1778)
						)
						(arc
							(start -0.2794 0.1778)
							(mid -0.249642 0.249642)
							(end -0.1778 0.2794)
						)
						(arc
							(start 0.1778 0.2794)
							(mid 0.249642 0.249642)
							(end 0.2794 0.1778)
						)
						(arc
							(start 0.2794 -0.1778)
							(mid 0.249642 -0.249642)
							(end 0.1778 -0.2794)
						)
					)
					(width 0)
					(fill yes)
				)
			)
		)
		(pad "2" smd custom
			(at 0 0.4445)
			(size 0.1397 0.1397)
			(layers "F.Cu" "F.Mask" "F.Paste")
			(net "GND")
			(options
				(clearance outline)
				(anchor circle)
			)
			(primitives
				(gr_poly
					(pts
						(arc
							(start -0.1778 -0.2794)
							(mid -0.249642 -0.249642)
							(end -0.2794 -0.1778)
						)
						(arc
							(start -0.2794 0.1778)
							(mid -0.249642 0.249642)
							(end -0.1778 0.2794)
						)
						(arc
							(start 0.1778 0.2794)
							(mid 0.249642 0.249642)
							(end 0.2794 0.1778)
						)
						(arc
							(start 0.2794 -0.1778)
							(mid 0.249642 -0.249642)
							(end 0.1778 -0.2794)
						)
					)
					(width 0)
					(fill yes)
				)
			)
		)
	)
	(footprint ""
		(layer "F.Cu")
		(at 42.75328 -115.640612)
		(property "Reference" "TP302"
			(at 0 0 0)
			(layer "F.SilkS")
			(hide yes)
			(effects
				(font
					(size 1.27 1.27)
				)
			)
		)
		(property "Value" "TPAD28-2-GP"
			(at -0.0127 -1.6637 0)
			(unlocked yes)
			(layer "F.Fab")
			(hide yes)
			(effects
				(font
					(size 1.016 1.016)
					(thickness 0.1524)
				)
			)
		)
		(property "Device Type" "TPAD28"
			(at -0.0127 -3.1877 0)
			(unlocked yes)
			(layer "F.Fab")
			(hide yes)
			(effects
				(font
					(size 1.016 1.016)
					(thickness 0.1524)
				)
			)
		)
		(duplicate_pad_numbers_are_jumpers no)
		(fp_poly
			(pts
				(arc
					(start 0.3556 0)
					(mid -0.3556 0)
					(end 0.3556 0)
				)
			)
			(stroke
				(width 0)
				(type default)
			)
			(fill no)
			(layer "F.CrtYd")
		)
		(fp_poly
			(pts
				(arc
					(start 0.6096 0)
					(mid -0.6096 0)
					(end 0.6096 0)
				)
			)
			(stroke
				(width 0)
				(type default)
			)
			(fill no)
			(layer "F.Fab")
		)
		(pad "1" smd circle
			(at 0 0)
			(size 0.7112 0.7112)
			(layers "F.Cu" "F.Mask" "F.Paste")
			(net "TP_RGMIICK")
		)
	)
	(footprint ""
		(layer "F.Cu")
		(at 242.824 -23.241)
		(property "Reference" "R793"
			(at 0 0 0)
			(layer "F.SilkS")
			(hide yes)
			(effects
				(font
					(size 1.27 1.27)
				)
			)
		)
		(property "Value" "4K7R2F-GP"
			(at 0.064008 -3.993896 0)
			(unlocked yes)
			(layer "F.Fab")
			(hide yes)
			(effects
				(font
					(size 1.016 1.016)
					(thickness 0.1524)
				)
			)
		)
		(property "Device Type" "R402H16"
			(at 0.064008 -5.517896 0)
			(unlocked yes)
			(layer "F.Fab")
			(hide yes)
			(effects
				(font
					(size 1.016 1.016)
					(thickness 0.1524)
				)
			)
		)
		(duplicate_pad_numbers_are_jumpers no)
		(fp_line
			(start -0.508 -0.9398)
			(end -0.508 0.9398)
			(stroke
				(width 0.1524)
				(type default)
			)
			(layer "F.SilkS")
		)
		(fp_line
			(start 0.508 -0.9398)
			(end -0.508 -0.9398)
			(stroke
				(width 0.1524)
				(type default)
			)
			(layer "F.SilkS")
		)
		(fp_rect
			(start -0.508 0.9398)
			(end 0.508 -0.9398)
			(stroke
				(width 0)
				(type default)
			)
			(fill no)
			(layer "F.CrtYd")
		)
		(fp_rect
			(start -0.508 0.9398)
			(end 0.508 -0.9398)
			(stroke
				(width 0)
				(type default)
			)
			(fill no)
			(layer "F.Fab")
		)
		(pad "1" smd custom
			(at 0 -0.4445)
			(size 0.1397 0.1397)
			(layers "F.Cu" "F.Mask" "F.Paste")
			(net "GND")
			(options
				(clearance outline)
				(anchor circle)
			)
			(primitives
				(gr_poly
					(pts
						(arc
							(start -0.1778 -0.2794)
							(mid -0.249642 -0.249642)
							(end -0.2794 -0.1778)
						)
						(arc
							(start -0.2794 0.1778)
							(mid -0.249642 0.249642)
							(end -0.1778 0.2794)
						)
						(arc
							(start 0.1778 0.2794)
							(mid 0.249642 0.249642)
							(end 0.2794 0.1778)
						)
						(arc
							(start 0.2794 -0.1778)
							(mid 0.249642 -0.249642)
							(end 0.1778 -0.2794)
						)
					)
					(width 0)
					(fill yes)
				)
			)
		)
		(pad "2" smd custom
			(at 0 0.4445)
			(size 0.1397 0.1397)
			(layers "F.Cu" "F.Mask" "F.Paste")
			(net "BOOTSTRAP0")
			(options
				(clearance outline)
				(anchor circle)
			)
			(primitives
				(gr_poly
					(pts
						(arc
							(start -0.1778 -0.2794)
							(mid -0.249642 -0.249642)
							(end -0.2794 -0.1778)
						)
						(arc
							(start -0.2794 0.1778)
							(mid -0.249642 0.249642)
							(end -0.1778 0.2794)
						)
						(arc
							(start 0.1778 0.2794)
							(mid 0.249642 0.249642)
							(end 0.2794 0.1778)
						)
						(arc
							(start 0.2794 -0.1778)
							(mid 0.249642 -0.249642)
							(end 0.1778 -0.2794)
						)
					)
					(width 0)
					(fill yes)
				)
			)
		)
	)
	(footprint ""
		(layer "F.Cu")
		(at 14.5034 -181.102 90)
		(property "Reference" "R1226"
			(at 0 0 90)
			(layer "F.SilkS")
			(hide yes)
			(effects
				(font
					(size 1.27 1.27)
				)
			)
		)
		(property "Value" "11KR2F-L-GP"
			(at 0.064008 -3.993896 90)
			(unlocked yes)
			(layer "F.Fab")
			(hide yes)
			(effects
				(font
					(size 1.016 1.016)
					(thickness 0.1524)
				)
			)
		)
		(property "Device Type" "R402H16"
			(at 0.064008 -5.517896 90)
			(unlocked yes)
			(layer "F.Fab")
			(hide yes)
			(effects
				(font
					(size 1.016 1.016)
					(thickness 0.1524)
				)
			)
		)
		(duplicate_pad_numbers_are_jumpers no)
		(fp_line
			(start 0.508 -0.9398)
			(end -0.508 -0.9398)
			(stroke
				(width 0.1524)
				(type default)
			)
			(layer "F.SilkS")
		)
		(fp_line
			(start -0.508 -0.9398)
			(end -0.508 0.9398)
			(stroke
				(width 0.1524)
				(type default)
			)
			(layer "F.SilkS")
		)
		(fp_rect
			(start -0.508 0.9398)
			(end 0.508 -0.9398)
			(stroke
				(width 0)
				(type default)
			)
			(fill no)
			(layer "F.CrtYd")
		)
		(fp_rect
			(start -0.508 0.9398)
			(end 0.508 -0.9398)
			(stroke
				(width 0)
				(type default)
			)
			(fill no)
			(layer "F.Fab")
		)
		(pad "1" smd custom
			(at 0 -0.4445 90)
			(size 0.1397 0.1397)
			(layers "F.Cu" "F.Mask" "F.Paste")
			(net "MB0_P12V_PWGIN_R")
			(options
				(clearance outline)
				(anchor circle)
			)
			(primitives
				(gr_poly
					(pts
						(arc
							(start -0.1778 -0.2794)
							(mid -0.249642 -0.249642)
							(end -0.2794 -0.1778)
						)
						(arc
							(start -0.2794 0.1778)
							(mid -0.249642 0.249642)
							(end -0.1778 0.2794)
						)
						(arc
							(start 0.1778 0.2794)
							(mid 0.249642 0.249642)
							(end 0.2794 0.1778)
						)
						(arc
							(start 0.2794 -0.1778)
							(mid 0.249642 -0.249642)
							(end 0.1778 -0.2794)
						)
					)
					(width 0)
					(fill yes)
				)
			)
		)
		(pad "2" smd custom
			(at 0 0.4445 90)
			(size 0.1397 0.1397)
			(layers "F.Cu" "F.Mask" "F.Paste")
			(net "AGND_CURRENT_MON")
			(options
				(clearance outline)
				(anchor circle)
			)
			(primitives
				(gr_poly
					(pts
						(arc
							(start -0.1778 -0.2794)
							(mid -0.249642 -0.249642)
							(end -0.2794 -0.1778)
						)
						(arc
							(start -0.2794 0.1778)
							(mid -0.249642 0.249642)
							(end -0.1778 0.2794)
						)
						(arc
							(start 0.1778 0.2794)
							(mid 0.249642 0.249642)
							(end 0.2794 0.1778)
						)
						(arc
							(start 0.2794 -0.1778)
							(mid 0.249642 -0.249642)
							(end 0.1778 -0.2794)
						)
					)
					(width 0)
					(fill yes)
				)
			)
		)
	)
	(footprint ""
		(layer "F.Cu")
		(at 24.394922 -109.840522 180)
		(property "Reference" "R9046"
			(at 0 0 180)
			(layer "F.SilkS")
			(hide yes)
			(effects
				(font
					(size 1.27 1.27)
				)
			)
		)
		(property "Value" "56R2F"
			(at 0.064008 -3.993896 180)
			(unlocked yes)
			(layer "F.Fab")
			(hide yes)
			(effects
				(font
					(size 1.016 1.016)
					(thickness 0.1524)
				)
			)
		)
		(property "Device Type" "R402H14"
			(at 0.064008 -5.517896 180)
			(unlocked yes)
			(layer "F.Fab")
			(hide yes)
			(effects
				(font
					(size 1.016 1.016)
					(thickness 0.1524)
				)
			)
		)
		(duplicate_pad_numbers_are_jumpers no)
		(fp_line
			(start 0.508 -0.9398)
			(end -0.508 -0.9398)
			(stroke
				(width 0.1524)
				(type default)
			)
			(layer "F.SilkS")
		)
		(fp_line
			(start -0.508 -0.9398)
			(end -0.508 0.9398)
			(stroke
				(width 0.1524)
				(type default)
			)
			(layer "F.SilkS")
		)
		(fp_rect
			(start -0.508 0.9398)
			(end 0.508 -0.9398)
			(stroke
				(width 0)
				(type default)
			)
			(fill no)
			(layer "F.CrtYd")
		)
		(fp_rect
			(start -0.508 0.9398)
			(end 0.508 -0.9398)
			(stroke
				(width 0)
				(type default)
			)
			(fill no)
			(layer "F.Fab")
		)
		(pad "1" smd custom
			(at 0 -0.4445 180)
			(size 0.1397 0.1397)
			(layers "F.Cu" "F.Mask" "F.Paste")
			(net "BMC_REFCLK_P")
			(options
				(clearance outline)
				(anchor circle)
			)
			(primitives
				(gr_poly
					(pts
						(arc
							(start -0.1778 -0.2794)
							(mid -0.249642 -0.249642)
							(end -0.2794 -0.1778)
						)
						(arc
							(start -0.2794 0.1778)
							(mid -0.249642 0.249642)
							(end -0.1778 0.2794)
						)
						(arc
							(start 0.1778 0.2794)
							(mid 0.249642 0.249642)
							(end 0.2794 0.1778)
						)
						(arc
							(start 0.2794 -0.1778)
							(mid 0.249642 -0.249642)
							(end 0.1778 -0.2794)
						)
					)
					(width 0)
					(fill yes)
				)
			)
		)
		(pad "2" smd custom
			(at 0 0.4445 180)
			(size 0.1397 0.1397)
			(layers "F.Cu" "F.Mask" "F.Paste")
			(net "GND")
			(options
				(clearance outline)
				(anchor circle)
			)
			(primitives
				(gr_poly
					(pts
						(arc
							(start -0.1778 -0.2794)
							(mid -0.249642 -0.249642)
							(end -0.2794 -0.1778)
						)
						(arc
							(start -0.2794 0.1778)
							(mid -0.249642 0.249642)
							(end -0.1778 0.2794)
						)
						(arc
							(start 0.1778 0.2794)
							(mid 0.249642 0.249642)
							(end 0.2794 0.1778)
						)
						(arc
							(start 0.2794 -0.1778)
							(mid 0.249642 -0.249642)
							(end 0.1778 -0.2794)
						)
					)
					(width 0)
					(fill yes)
				)
			)
		)
	)
	(footprint ""
		(layer "F.Cu")
		(at 8.89 -194.3354 180)
		(property "Reference" "R2172"
			(at 0 0 180)
			(layer "F.SilkS")
			(hide yes)
			(effects
				(font
					(size 1.27 1.27)
				)
			)
		)
		(property "Value" "0R2J-2-GP"
			(at 0.064008 -3.993896 180)
			(unlocked yes)
			(layer "F.Fab")
			(hide yes)
			(effects
				(font
					(size 1.016 1.016)
					(thickness 0.1524)
				)
			)
		)
		(property "Device Type" "R402H16"
			(at 0.064008 -5.517896 180)
			(unlocked yes)
			(layer "F.Fab")
			(hide yes)
			(effects
				(font
					(size 1.016 1.016)
					(thickness 0.1524)
				)
			)
		)
		(duplicate_pad_numbers_are_jumpers no)
		(fp_line
			(start 0.508 -0.9398)
			(end -0.508 -0.9398)
			(stroke
				(width 0.1524)
				(type default)
			)
			(layer "F.SilkS")
		)
		(fp_line
			(start -0.508 -0.9398)
			(end -0.508 0.9398)
			(stroke
				(width 0.1524)
				(type default)
			)
			(layer "F.SilkS")
		)
		(fp_rect
			(start -0.508 0.9398)
			(end 0.508 -0.9398)
			(stroke
				(width 0)
				(type default)
			)
			(fill no)
			(layer "F.CrtYd")
		)
		(fp_rect
			(start -0.508 0.9398)
			(end 0.508 -0.9398)
			(stroke
				(width 0)
				(type default)
			)
			(fill no)
			(layer "F.Fab")
		)
		(pad "1" smd custom
			(at 0 -0.4445 180)
			(size 0.1397 0.1397)
			(layers "F.Cu" "F.Mask" "F.Paste")
			(net "MB0_CM_ADR2_R")
			(options
				(clearance outline)
				(anchor circle)
			)
			(primitives
				(gr_poly
					(pts
						(arc
							(start -0.1778 -0.2794)
							(mid -0.249642 -0.249642)
							(end -0.2794 -0.1778)
						)
						(arc
							(start -0.2794 0.1778)
							(mid -0.249642 0.249642)
							(end -0.1778 0.2794)
						)
						(arc
							(start 0.1778 0.2794)
							(mid 0.249642 0.249642)
							(end 0.2794 0.1778)
						)
						(arc
							(start 0.2794 -0.1778)
							(mid 0.249642 -0.249642)
							(end 0.1778 -0.2794)
						)
					)
					(width 0)
					(fill yes)
				)
			)
		)
		(pad "2" smd custom
			(at 0 0.4445 180)
			(size 0.1397 0.1397)
			(layers "F.Cu" "F.Mask" "F.Paste")
			(net "AGND_CURRENT_MON")
			(options
				(clearance outline)
				(anchor circle)
			)
			(primitives
				(gr_poly
					(pts
						(arc
							(start -0.1778 -0.2794)
							(mid -0.249642 -0.249642)
							(end -0.2794 -0.1778)
						)
						(arc
							(start -0.2794 0.1778)
							(mid -0.249642 0.249642)
							(end -0.1778 0.2794)
						)
						(arc
							(start 0.1778 0.2794)
							(mid 0.249642 0.249642)
							(end 0.2794 0.1778)
						)
						(arc
							(start 0.2794 -0.1778)
							(mid 0.249642 -0.249642)
							(end 0.1778 -0.2794)
						)
					)
					(width 0)
					(fill yes)
				)
			)
		)
	)
	(footprint ""
		(layer "F.Cu")
		(at 306.819046 -33.51022)
		(property "Reference" "C18"
			(at 0 0 0)
			(layer "F.SilkS")
			(hide yes)
			(effects
				(font
					(size 1.27 1.27)
				)
			)
		)
		(property "Value" "SCD22U10V2KX-1GP"
			(at 1.1811 -2.7051 0)
			(unlocked yes)
			(layer "F.Fab")
			(hide yes)
			(effects
				(font
					(size 1.016 1.016)
					(thickness 0.1524)
				)
			)
		)
		(property "Device Type" "C402H22"
			(at 1.1811 -4.2291 0)
			(unlocked yes)
			(layer "F.Fab")
			(hide yes)
			(effects
				(font
					(size 1.016 1.016)
					(thickness 0.1524)
				)
			)
		)
		(duplicate_pad_numbers_are_jumpers no)
		(fp_rect
			(start -0.4318 0.9525)
			(end 0.4318 -0.9525)
			(stroke
				(width 0)
				(type default)
			)
			(fill no)
			(layer "F.CrtYd")
		)
		(fp_rect
			(start -0.4318 0.9525)
			(end 0.4318 -0.9525)
			(stroke
				(width 0)
				(type default)
			)
			(fill no)
			(layer "F.Fab")
		)
		(pad "1" smd custom
			(at 0 -0.4445)
			(size 0.1524 0.1524)
			(layers "F.Cu" "F.Mask" "F.Paste")
			(net "PCIE_TX_CAP_N8")
			(options
				(clearance outline)
				(anchor circle)
			)
			(primitives
				(gr_poly
					(pts
						(arc
							(start 0.3048 -0.2032)
							(mid 0.275042 -0.275042)
							(end 0.2032 -0.3048)
						)
						(arc
							(start -0.2032 -0.3048)
							(mid -0.275042 -0.275042)
							(end -0.3048 -0.2032)
						)
						(arc
							(start -0.3048 0.2032)
							(mid -0.275042 0.275042)
							(end -0.2032 0.3048)
						)
						(arc
							(start 0.2032 0.3048)
							(mid 0.275042 0.275042)
							(end 0.3048 0.2032)
						)
					)
					(width 0)
					(fill yes)
				)
			)
		)
		(pad "2" smd custom
			(at 0 0.4445)
			(size 0.1524 0.1524)
			(layers "F.Cu" "F.Mask" "F.Paste")
			(net "PCIE_TX_N8")
			(options
				(clearance outline)
				(anchor circle)
			)
			(primitives
				(gr_poly
					(pts
						(arc
							(start 0.3048 -0.2032)
							(mid 0.275042 -0.275042)
							(end 0.2032 -0.3048)
						)
						(arc
							(start -0.2032 -0.3048)
							(mid -0.275042 -0.275042)
							(end -0.3048 -0.2032)
						)
						(arc
							(start -0.3048 0.2032)
							(mid -0.275042 0.275042)
							(end -0.2032 0.3048)
						)
						(arc
							(start 0.2032 0.3048)
							(mid 0.275042 0.275042)
							(end 0.3048 0.2032)
						)
					)
					(width 0)
					(fill yes)
				)
			)
		)
	)
	(footprint ""
		(layer "F.Cu")
		(at 41.275 -56.388)
		(property "Reference" "TP147"
			(at 0 0 0)
			(layer "F.SilkS")
			(hide yes)
			(effects
				(font
					(size 1.27 1.27)
				)
			)
		)
		(property "Value" "TPAD28-2-GP"
			(at -0.0127 -1.6637 0)
			(unlocked yes)
			(layer "F.Fab")
			(hide yes)
			(effects
				(font
					(size 1.016 1.016)
					(thickness 0.1524)
				)
			)
		)
		(property "Device Type" "TPAD28"
			(at -0.0127 -3.1877 0)
			(unlocked yes)
			(layer "F.Fab")
			(hide yes)
			(effects
				(font
					(size 1.016 1.016)
					(thickness 0.1524)
				)
			)
		)
		(duplicate_pad_numbers_are_jumpers no)
		(fp_poly
			(pts
				(arc
					(start 0.3556 0)
					(mid -0.3556 0)
					(end 0.3556 0)
				)
			)
			(stroke
				(width 0)
				(type default)
			)
			(fill no)
			(layer "F.CrtYd")
		)
		(fp_poly
			(pts
				(arc
					(start 0.6096 0)
					(mid -0.6096 0)
					(end 0.6096 0)
				)
			)
			(stroke
				(width 0)
				(type default)
			)
			(fill no)
			(layer "F.Fab")
		)
		(pad "1" smd circle
			(at 0 0)
			(size 0.7112 0.7112)
			(layers "F.Cu" "F.Mask" "F.Paste")
			(net "USB_OC#")
		)
	)
	(footprint ""
		(layer "F.Cu")
		(at 300.268894 -33.560258)
		(property "Reference" "C14"
			(at 0 0 0)
			(layer "F.SilkS")
			(hide yes)
			(effects
				(font
					(size 1.27 1.27)
				)
			)
		)
		(property "Value" "SCD22U10V2KX-1GP"
			(at 1.1811 -2.7051 0)
			(unlocked yes)
			(layer "F.Fab")
			(hide yes)
			(effects
				(font
					(size 1.016 1.016)
					(thickness 0.1524)
				)
			)
		)
		(property "Device Type" "C402H22"
			(at 1.1811 -4.2291 0)
			(unlocked yes)
			(layer "F.Fab")
			(hide yes)
			(effects
				(font
					(size 1.016 1.016)
					(thickness 0.1524)
				)
			)
		)
		(duplicate_pad_numbers_are_jumpers no)
		(fp_rect
			(start -0.4318 0.9525)
			(end 0.4318 -0.9525)
			(stroke
				(width 0)
				(type default)
			)
			(fill no)
			(layer "F.CrtYd")
		)
		(fp_rect
			(start -0.4318 0.9525)
			(end 0.4318 -0.9525)
			(stroke
				(width 0)
				(type default)
			)
			(fill no)
			(layer "F.Fab")
		)
		(pad "1" smd custom
			(at 0 -0.4445)
			(size 0.1524 0.1524)
			(layers "F.Cu" "F.Mask" "F.Paste")
			(net "PCIE_TX_CAP_N5")
			(options
				(clearance outline)
				(anchor circle)
			)
			(primitives
				(gr_poly
					(pts
						(arc
							(start 0.3048 -0.2032)
							(mid 0.275042 -0.275042)
							(end 0.2032 -0.3048)
						)
						(arc
							(start -0.2032 -0.3048)
							(mid -0.275042 -0.275042)
							(end -0.3048 -0.2032)
						)
						(arc
							(start -0.3048 0.2032)
							(mid -0.275042 0.275042)
							(end -0.2032 0.3048)
						)
						(arc
							(start 0.2032 0.3048)
							(mid 0.275042 0.275042)
							(end 0.3048 0.2032)
						)
					)
					(width 0)
					(fill yes)
				)
			)
		)
		(pad "2" smd custom
			(at 0 0.4445)
			(size 0.1524 0.1524)
			(layers "F.Cu" "F.Mask" "F.Paste")
			(net "PCIE_TX_N5")
			(options
				(clearance outline)
				(anchor circle)
			)
			(primitives
				(gr_poly
					(pts
						(arc
							(start 0.3048 -0.2032)
							(mid 0.275042 -0.275042)
							(end 0.2032 -0.3048)
						)
						(arc
							(start -0.2032 -0.3048)
							(mid -0.275042 -0.275042)
							(end -0.3048 -0.2032)
						)
						(arc
							(start -0.3048 0.2032)
							(mid -0.275042 0.275042)
							(end -0.2032 0.3048)
						)
						(arc
							(start 0.2032 0.3048)
							(mid 0.275042 0.275042)
							(end 0.3048 0.2032)
						)
					)
					(width 0)
					(fill yes)
				)
			)
		)
	)
	(footprint ""
		(layer "F.Cu")
		(at 225.114104 -203.720192 180)
		(property "Reference" "R7977"
			(at 0 0 180)
			(layer "F.SilkS")
			(hide yes)
			(effects
				(font
					(size 1.27 1.27)
				)
			)
		)
		(property "Value" "0R2J-2-GP"
			(at 0.064008 -3.993896 180)
			(unlocked yes)
			(layer "F.Fab")
			(hide yes)
			(effects
				(font
					(size 1.016 1.016)
					(thickness 0.1524)
				)
			)
		)
		(property "Device Type" "R402H16"
			(at 0.064008 -5.517896 180)
			(unlocked yes)
			(layer "F.Fab")
			(hide yes)
			(effects
				(font
					(size 1.016 1.016)
					(thickness 0.1524)
				)
			)
		)
		(duplicate_pad_numbers_are_jumpers no)
		(fp_line
			(start 0.508 -0.9398)
			(end -0.508 -0.9398)
			(stroke
				(width 0.1524)
				(type default)
			)
			(layer "F.SilkS")
		)
		(fp_line
			(start -0.508 -0.9398)
			(end -0.508 0.9398)
			(stroke
				(width 0.1524)
				(type default)
			)
			(layer "F.SilkS")
		)
		(fp_rect
			(start -0.508 0.9398)
			(end 0.508 -0.9398)
			(stroke
				(width 0)
				(type default)
			)
			(fill no)
			(layer "F.CrtYd")
		)
		(fp_rect
			(start -0.508 0.9398)
			(end 0.508 -0.9398)
			(stroke
				(width 0)
				(type default)
			)
			(fill no)
			(layer "F.Fab")
		)
		(pad "1" smd custom
			(at 0 -0.4445 180)
			(size 0.1397 0.1397)
			(layers "F.Cu" "F.Mask" "F.Paste")
			(net "SSD_PERST#12")
			(options
				(clearance outline)
				(anchor circle)
			)
			(primitives
				(gr_poly
					(pts
						(arc
							(start -0.1778 -0.2794)
							(mid -0.249642 -0.249642)
							(end -0.2794 -0.1778)
						)
						(arc
							(start -0.2794 0.1778)
							(mid -0.249642 0.249642)
							(end -0.1778 0.2794)
						)
						(arc
							(start 0.1778 0.2794)
							(mid 0.249642 0.249642)
							(end 0.2794 0.1778)
						)
						(arc
							(start 0.2794 -0.1778)
							(mid 0.249642 -0.249642)
							(end 0.1778 -0.2794)
						)
					)
					(width 0)
					(fill yes)
				)
			)
		)
		(pad "2" smd custom
			(at 0 0.4445 180)
			(size 0.1397 0.1397)
			(layers "F.Cu" "F.Mask" "F.Paste")
			(net "SSD_PERST#12_R")
			(options
				(clearance outline)
				(anchor circle)
			)
			(primitives
				(gr_poly
					(pts
						(arc
							(start -0.1778 -0.2794)
							(mid -0.249642 -0.249642)
							(end -0.2794 -0.1778)
						)
						(arc
							(start -0.2794 0.1778)
							(mid -0.249642 0.249642)
							(end -0.1778 0.2794)
						)
						(arc
							(start 0.1778 0.2794)
							(mid 0.249642 0.249642)
							(end 0.2794 0.1778)
						)
						(arc
							(start 0.2794 -0.1778)
							(mid 0.249642 -0.249642)
							(end 0.1778 -0.2794)
						)
					)
					(width 0)
					(fill yes)
				)
			)
		)
	)
	(footprint ""
		(layer "F.Cu")
		(at 331.216 -21.59)
		(property "Reference" "SR714"
			(at 0 0 0)
			(layer "F.SilkS")
			(hide yes)
			(effects
				(font
					(size 1.27 1.27)
				)
			)
		)
		(property "Value" "150R2F-1-GP"
			(at 0.064008 -3.993896 0)
			(unlocked yes)
			(layer "F.Fab")
			(hide yes)
			(effects
				(font
					(size 1.016 1.016)
					(thickness 0.1524)
				)
			)
		)
		(property "Device Type" "R402H16"
			(at 0.064008 -5.517896 0)
			(unlocked yes)
			(layer "F.Fab")
			(hide yes)
			(effects
				(font
					(size 1.016 1.016)
					(thickness 0.1524)
				)
			)
		)
		(duplicate_pad_numbers_are_jumpers no)
		(fp_line
			(start -0.508 -0.9398)
			(end -0.508 0.9398)
			(stroke
				(width 0.1524)
				(type default)
			)
			(layer "F.SilkS")
		)
		(fp_line
			(start 0.508 -0.9398)
			(end -0.508 -0.9398)
			(stroke
				(width 0.1524)
				(type default)
			)
			(layer "F.SilkS")
		)
		(fp_rect
			(start -0.508 0.9398)
			(end 0.508 -0.9398)
			(stroke
				(width 0)
				(type default)
			)
			(fill no)
			(layer "F.CrtYd")
		)
		(fp_rect
			(start -0.508 0.9398)
			(end 0.508 -0.9398)
			(stroke
				(width 0)
				(type default)
			)
			(fill no)
			(layer "F.Fab")
		)
		(pad "1" smd custom
			(at 0 -0.4445)
			(size 0.1397 0.1397)
			(layers "F.Cu" "F.Mask" "F.Paste")
			(net "P3V3_STBY")
			(options
				(clearance outline)
				(anchor circle)
			)
			(primitives
				(gr_poly
					(pts
						(arc
							(start -0.1778 -0.2794)
							(mid -0.249642 -0.249642)
							(end -0.2794 -0.1778)
						)
						(arc
							(start -0.2794 0.1778)
							(mid -0.249642 0.249642)
							(end -0.1778 0.2794)
						)
						(arc
							(start 0.1778 0.2794)
							(mid 0.249642 0.249642)
							(end 0.2794 0.1778)
						)
						(arc
							(start 0.2794 -0.1778)
							(mid 0.249642 -0.249642)
							(end 0.1778 -0.2794)
						)
					)
					(width 0)
					(fill yes)
				)
			)
		)
		(pad "2" smd custom
			(at 0 0.4445)
			(size 0.1397 0.1397)
			(layers "F.Cu" "F.Mask" "F.Paste")
			(net "LED_R_5")
			(options
				(clearance outline)
				(anchor circle)
			)
			(primitives
				(gr_poly
					(pts
						(arc
							(start -0.1778 -0.2794)
							(mid -0.249642 -0.249642)
							(end -0.2794 -0.1778)
						)
						(arc
							(start -0.2794 0.1778)
							(mid -0.249642 0.249642)
							(end -0.1778 0.2794)
						)
						(arc
							(start 0.1778 0.2794)
							(mid 0.249642 0.249642)
							(end 0.2794 0.1778)
						)
						(arc
							(start 0.2794 -0.1778)
							(mid 0.249642 -0.249642)
							(end 0.1778 -0.2794)
						)
					)
					(width 0)
					(fill yes)
				)
			)
		)
	)
	(footprint ""
		(layer "F.Cu")
		(at 234.6706 -13.1064 180)
		(property "Reference" "C465"
			(at 0 0 180)
			(layer "F.SilkS")
			(hide yes)
			(effects
				(font
					(size 1.27 1.27)
				)
			)
		)
		(property "Value" "SC47U4V5MX-2-GP"
			(at -0.0762 -6.1214 180)
			(unlocked yes)
			(layer "F.Fab")
			(hide yes)
			(effects
				(font
					(size 1.016 1.016)
					(thickness 0.1524)
				)
			)
		)
		(property "Device Type" "C805H58"
			(at -0.0762 -8.1534 180)
			(unlocked yes)
			(layer "F.Fab")
			(hide yes)
			(effects
				(font
					(size 1.016 1.016)
					(thickness 0.1524)
				)
			)
		)
		(duplicate_pad_numbers_are_jumpers no)
		(fp_line
			(start 0.635 0)
			(end -0.635 0)
			(stroke
				(width 0.508)
				(type default)
			)
			(layer "F.SilkS")
		)
		(fp_rect
			(start -0.9652 1.778)
			(end 0.9652 -1.778)
			(stroke
				(width 0)
				(type default)
			)
			(fill no)
			(layer "F.CrtYd")
		)
		(fp_poly
			(pts
				(xy -0.9652 -1.778) (xy 0.9652 -1.778) (xy 0.9652 1.778) (xy -0.9652 1.778)
			)
			(stroke
				(width 0)
				(type default)
			)
			(fill no)
			(layer "F.Fab")
		)
		(pad "1" smd rect
			(at 0 -0.9652 180)
			(size 1.397 1.143)
			(layers "F.Cu" "F.Mask" "F.Paste")
			(net "DUT_VDDO_REF")
		)
		(pad "2" smd rect
			(at 0 0.9652 180)
			(size 1.397 1.143)
			(layers "F.Cu" "F.Mask" "F.Paste")
			(net "GND")
		)
	)
	(footprint ""
		(layer "F.Cu")
		(at 213.424008 -10.287 180)
		(property "Reference" "U6"
			(at 0 0 180)
			(layer "F.SilkS")
			(hide yes)
			(effects
				(font
					(size 1.27 1.27)
				)
			)
		)
		(property "Value" "SNLVC8T245DGVR-GP"
			(at 0 -11.1252 180)
			(unlocked yes)
			(layer "F.Fab")
			(hide yes)
			(effects
				(font
					(size 1.016 1.016)
					(thickness 0.1524)
				)
			)
		)
		(property "Device Type" "TVSOP24H48"
			(at 0 -12.6492 180)
			(unlocked yes)
			(layer "F.Fab")
			(hide yes)
			(effects
				(font
					(size 1.016 1.016)
					(thickness 0.1524)
				)
			)
		)
		(duplicate_pad_numbers_are_jumpers no)
		(fp_line
			(start 2.2987 1.397)
			(end 2.2987 -1.397)
			(stroke
				(width 0.1524)
				(type default)
			)
			(layer "F.SilkS")
		)
		(fp_line
			(start 2.2987 -1.397)
			(end -2.9337 -1.397)
			(stroke
				(width 0.1524)
				(type default)
			)
			(layer "F.SilkS")
		)
		(fp_line
			(start -2.5654 0)
			(end -2.9337 0.3683)
			(stroke
				(width 0.1524)
				(type default)
			)
			(layer "F.SilkS")
		)
		(fp_line
			(start -2.7559 1.397)
			(end -2.7559 3.8354)
			(stroke
				(width 0.508)
				(type default)
			)
			(layer "F.SilkS")
		)
		(fp_line
			(start -2.9337 1.397)
			(end 2.2987 1.397)
			(stroke
				(width 0.1524)
				(type default)
			)
			(layer "F.SilkS")
		)
		(fp_line
			(start -2.9337 -0.3683)
			(end -2.5654 0)
			(stroke
				(width 0.1524)
				(type default)
			)
			(layer "F.SilkS")
		)
		(fp_line
			(start -2.9337 -1.397)
			(end -2.9337 1.397)
			(stroke
				(width 0.1524)
				(type default)
			)
			(layer "F.SilkS")
		)
		(fp_rect
			(start -3.0099 4.0894)
			(end 3.0099 -4.0894)
			(stroke
				(width 0)
				(type default)
			)
			(fill no)
			(layer "F.CrtYd")
		)
		(fp_poly
			(pts
				(xy -3.0099 -4.0894) (xy 3.0099 -4.0894) (xy 3.0099 4.0894) (xy -3.0099 4.0894)
			)
			(stroke
				(width 0)
				(type default)
			)
			(fill no)
			(layer "F.Fab")
		)
		(pad "1" smd rect
			(at -2.19964 2.8194 180)
			(size 0.2032 1.524)
			(layers "F.Cu" "F.Mask" "F.Paste")
			(net "DUT_VDDO")
		)
		(pad "2" smd rect
			(at -1.79959 2.8194 180)
			(size 0.2032 1.524)
			(layers "F.Cu" "F.Mask" "F.Paste")
			(net "GND")
		)
		(pad "3" smd rect
			(at -1.39954 2.8194 180)
			(size 0.2032 1.524)
			(layers "F.Cu" "F.Mask" "F.Paste")
			(net "HOST1_RST_N_LS")
		)
		(pad "4" smd rect
			(at -0.99949 2.8194 180)
			(size 0.2032 1.524)
			(layers "F.Cu" "F.Mask" "F.Paste")
			(net "HOST2_RST_N_LS")
		)
		(pad "5" smd rect
			(at -0.59944 2.8194 180)
			(size 0.2032 1.524)
			(layers "F.Cu" "F.Mask" "F.Paste")
			(net "HOST3_RST_N_LS")
		)
		(pad "6" smd rect
			(at -0.19939 2.8194 180)
			(size 0.2032 1.524)
			(layers "F.Cu" "F.Mask" "F.Paste")
			(net "HOST4_RST_N_LS")
		)
		(pad "7" smd rect
			(at 0.19939 2.8194 180)
			(size 0.2032 1.524)
			(layers "F.Cu" "F.Mask" "F.Paste")
			(net "HOST5_RST_N_LS")
		)
		(pad "8" smd rect
			(at 0.59944 2.8194 180)
			(size 0.2032 1.524)
			(layers "F.Cu" "F.Mask" "F.Paste")
			(net "HOST6_RST_N_LS")
		)
		(pad "9" smd rect
			(at 0.99949 2.8194 180)
			(size 0.2032 1.524)
			(layers "F.Cu" "F.Mask" "F.Paste")
			(net "HOST7_RST_N_LS")
		)
		(pad "10" smd rect
			(at 1.39954 2.8194 180)
			(size 0.2032 1.524)
			(layers "F.Cu" "F.Mask" "F.Paste")
			(net "HOST8_RST_N_LS")
		)
		(pad "11" smd rect
			(at 1.79959 2.8194 180)
			(size 0.2032 1.524)
			(layers "F.Cu" "F.Mask" "F.Paste")
			(net "GND")
		)
		(pad "12" smd rect
			(at 2.19964 2.8194 180)
			(size 0.2032 1.524)
			(layers "F.Cu" "F.Mask" "F.Paste")
			(net "GND")
		)
		(pad "13" smd rect
			(at 2.19964 -2.8194 180)
			(size 0.2032 1.524)
			(layers "F.Cu" "F.Mask" "F.Paste")
			(net "GND")
		)
		(pad "14" smd rect
			(at 1.79959 -2.8194 180)
			(size 0.2032 1.524)
			(layers "F.Cu" "F.Mask" "F.Paste")
			(net "HOST8_RST_N")
		)
		(pad "15" smd rect
			(at 1.39954 -2.8194 180)
			(size 0.2032 1.524)
			(layers "F.Cu" "F.Mask" "F.Paste")
			(net "HOST7_RST_N")
		)
		(pad "16" smd rect
			(at 0.99949 -2.8194 180)
			(size 0.2032 1.524)
			(layers "F.Cu" "F.Mask" "F.Paste")
			(net "HOST6_RST_N")
		)
		(pad "17" smd rect
			(at 0.59944 -2.8194 180)
			(size 0.2032 1.524)
			(layers "F.Cu" "F.Mask" "F.Paste")
			(net "HOST5_RST_N")
		)
		(pad "18" smd rect
			(at 0.19939 -2.8194 180)
			(size 0.2032 1.524)
			(layers "F.Cu" "F.Mask" "F.Paste")
			(net "HOST4_RST_N")
		)
		(pad "19" smd rect
			(at -0.19939 -2.8194 180)
			(size 0.2032 1.524)
			(layers "F.Cu" "F.Mask" "F.Paste")
			(net "HOST3_RST_N")
		)
		(pad "20" smd rect
			(at -0.59944 -2.8194 180)
			(size 0.2032 1.524)
			(layers "F.Cu" "F.Mask" "F.Paste")
			(net "HOST2_RST_N")
		)
		(pad "21" smd rect
			(at -0.99949 -2.8194 180)
			(size 0.2032 1.524)
			(layers "F.Cu" "F.Mask" "F.Paste")
			(net "HOST1_RST_N_R")
		)
		(pad "22" smd rect
			(at -1.39954 -2.8194 180)
			(size 0.2032 1.524)
			(layers "F.Cu" "F.Mask" "F.Paste")
			(net "Q3202_D")
		)
		(pad "23" smd rect
			(at -1.79959 -2.8194 180)
			(size 0.2032 1.524)
			(layers "F.Cu" "F.Mask" "F.Paste")
			(net "P3V3_STBY")
		)
		(pad "24" smd rect
			(at -2.19964 -2.8194 180)
			(size 0.2032 1.524)
			(layers "F.Cu" "F.Mask" "F.Paste")
			(net "P3V3_STBY")
		)
	)
	(footprint ""
		(layer "F.Cu")
		(at 35.941 -117.1956 90)
		(property "Reference" "TP241"
			(at 0 0 90)
			(layer "F.SilkS")
			(hide yes)
			(effects
				(font
					(size 1.27 1.27)
				)
			)
		)
		(property "Value" "TPAD28-2-GP"
			(at -0.0127 -1.6637 90)
			(unlocked yes)
			(layer "F.Fab")
			(hide yes)
			(effects
				(font
					(size 1.016 1.016)
					(thickness 0.1524)
				)
			)
		)
		(property "Device Type" "TPAD28"
			(at -0.0127 -3.1877 90)
			(unlocked yes)
			(layer "F.Fab")
			(hide yes)
			(effects
				(font
					(size 1.016 1.016)
					(thickness 0.1524)
				)
			)
		)
		(duplicate_pad_numbers_are_jumpers no)
		(fp_poly
			(pts
				(arc
					(start 0 0.3556)
					(mid 0 -0.3556)
					(end 0 0.3556)
				)
			)
			(stroke
				(width 0)
				(type default)
			)
			(fill no)
			(layer "F.CrtYd")
		)
		(fp_poly
			(pts
				(arc
					(start 0 0.6096)
					(mid 0 -0.6096)
					(end 0 0.6096)
				)
			)
			(stroke
				(width 0)
				(type default)
			)
			(fill no)
			(layer "F.Fab")
		)
		(pad "1" smd circle
			(at 0 0 90)
			(size 0.7112 0.7112)
			(layers "F.Cu" "F.Mask" "F.Paste")
			(net "TP_GPIOE7")
		)
	)
	(footprint ""
		(layer "F.Cu")
		(at 286.4866 -32.9692 90)
		(property "Reference" "C9"
			(at 0 0 90)
			(layer "F.SilkS")
			(hide yes)
			(effects
				(font
					(size 1.27 1.27)
				)
			)
		)
		(property "Value" "SCD22U10V2KX-1GP"
			(at 1.1811 -2.7051 90)
			(unlocked yes)
			(layer "F.Fab")
			(hide yes)
			(effects
				(font
					(size 1.016 1.016)
					(thickness 0.1524)
				)
			)
		)
		(property "Device Type" "C402H22"
			(at 1.1811 -4.2291 90)
			(unlocked yes)
			(layer "F.Fab")
			(hide yes)
			(effects
				(font
					(size 1.016 1.016)
					(thickness 0.1524)
				)
			)
		)
		(duplicate_pad_numbers_are_jumpers no)
		(fp_rect
			(start -0.4318 0.9525)
			(end 0.4318 -0.9525)
			(stroke
				(width 0)
				(type default)
			)
			(fill no)
			(layer "F.CrtYd")
		)
		(fp_rect
			(start -0.4318 0.9525)
			(end 0.4318 -0.9525)
			(stroke
				(width 0)
				(type default)
			)
			(fill no)
			(layer "F.Fab")
		)
		(pad "1" smd custom
			(at 0 -0.4445 90)
			(size 0.1524 0.1524)
			(layers "F.Cu" "F.Mask" "F.Paste")
			(net "PCIE_TX_CAP_P2")
			(options
				(clearance outline)
				(anchor circle)
			)
			(primitives
				(gr_poly
					(pts
						(arc
							(start 0.3048 -0.2032)
							(mid 0.275042 -0.275042)
							(end 0.2032 -0.3048)
						)
						(arc
							(start -0.2032 -0.3048)
							(mid -0.275042 -0.275042)
							(end -0.3048 -0.2032)
						)
						(arc
							(start -0.3048 0.2032)
							(mid -0.275042 0.275042)
							(end -0.2032 0.3048)
						)
						(arc
							(start 0.2032 0.3048)
							(mid 0.275042 0.275042)
							(end 0.3048 0.2032)
						)
					)
					(width 0)
					(fill yes)
				)
			)
		)
		(pad "2" smd custom
			(at 0 0.4445 90)
			(size 0.1524 0.1524)
			(layers "F.Cu" "F.Mask" "F.Paste")
			(net "PCIE_TX_P2")
			(options
				(clearance outline)
				(anchor circle)
			)
			(primitives
				(gr_poly
					(pts
						(arc
							(start 0.3048 -0.2032)
							(mid 0.275042 -0.275042)
							(end 0.2032 -0.3048)
						)
						(arc
							(start -0.2032 -0.3048)
							(mid -0.275042 -0.275042)
							(end -0.3048 -0.2032)
						)
						(arc
							(start -0.3048 0.2032)
							(mid -0.275042 0.275042)
							(end -0.2032 0.3048)
						)
						(arc
							(start 0.2032 0.3048)
							(mid 0.275042 0.275042)
							(end 0.3048 0.2032)
						)
					)
					(width 0)
					(fill yes)
				)
			)
		)
	)
	(footprint ""
		(layer "F.Cu")
		(at 36.432998 -103.386636 -90)
		(property "Reference" "C371"
			(at 0 0 270)
			(layer "F.SilkS")
			(hide yes)
			(effects
				(font
					(size 1.27 1.27)
				)
			)
		)
		(property "Value" "SCD1U16V2KX-3GP"
			(at 1.1811 -2.7051 270)
			(unlocked yes)
			(layer "F.Fab")
			(hide yes)
			(effects
				(font
					(size 1.016 1.016)
					(thickness 0.1524)
				)
			)
		)
		(property "Device Type" "C402H22"
			(at 1.1811 -4.2291 270)
			(unlocked yes)
			(layer "F.Fab")
			(hide yes)
			(effects
				(font
					(size 1.016 1.016)
					(thickness 0.1524)
				)
			)
		)
		(duplicate_pad_numbers_are_jumpers no)
		(fp_rect
			(start -0.4318 0.9525)
			(end 0.4318 -0.9525)
			(stroke
				(width 0)
				(type default)
			)
			(fill no)
			(layer "F.CrtYd")
		)
		(fp_rect
			(start -0.4318 0.9525)
			(end 0.4318 -0.9525)
			(stroke
				(width 0)
				(type default)
			)
			(fill no)
			(layer "F.Fab")
		)
		(pad "1" smd custom
			(at 0 -0.4445 270)
			(size 0.1524 0.1524)
			(layers "F.Cu" "F.Mask" "F.Paste")
			(net "P3V3_STBY")
			(options
				(clearance outline)
				(anchor circle)
			)
			(primitives
				(gr_poly
					(pts
						(arc
							(start 0.3048 -0.2032)
							(mid 0.275042 -0.275042)
							(end 0.2032 -0.3048)
						)
						(arc
							(start -0.2032 -0.3048)
							(mid -0.275042 -0.275042)
							(end -0.3048 -0.2032)
						)
						(arc
							(start -0.3048 0.2032)
							(mid -0.275042 0.275042)
							(end -0.2032 0.3048)
						)
						(arc
							(start 0.2032 0.3048)
							(mid 0.275042 0.275042)
							(end 0.3048 0.2032)
						)
					)
					(width 0)
					(fill yes)
				)
			)
		)
		(pad "2" smd custom
			(at 0 0.4445 270)
			(size 0.1524 0.1524)
			(layers "F.Cu" "F.Mask" "F.Paste")
			(net "GND")
			(options
				(clearance outline)
				(anchor circle)
			)
			(primitives
				(gr_poly
					(pts
						(arc
							(start 0.3048 -0.2032)
							(mid 0.275042 -0.275042)
							(end 0.2032 -0.3048)
						)
						(arc
							(start -0.2032 -0.3048)
							(mid -0.275042 -0.275042)
							(end -0.3048 -0.2032)
						)
						(arc
							(start -0.3048 0.2032)
							(mid -0.275042 0.275042)
							(end -0.2032 0.3048)
						)
						(arc
							(start 0.2032 0.3048)
							(mid 0.275042 0.275042)
							(end 0.3048 0.2032)
						)
					)
					(width 0)
					(fill yes)
				)
			)
		)
	)
	(footprint ""
		(layer "F.Cu")
		(at 237.109 -23.241)
		(property "Reference" "R814"
			(at 0 0 0)
			(layer "F.SilkS")
			(hide yes)
			(effects
				(font
					(size 1.27 1.27)
				)
			)
		)
		(property "Value" "4K7R2F-GP"
			(at 0.064008 -3.993896 0)
			(unlocked yes)
			(layer "F.Fab")
			(hide yes)
			(effects
				(font
					(size 1.016 1.016)
					(thickness 0.1524)
				)
			)
		)
		(property "Device Type" "R402H16"
			(at 0.064008 -5.517896 0)
			(unlocked yes)
			(layer "F.Fab")
			(hide yes)
			(effects
				(font
					(size 1.016 1.016)
					(thickness 0.1524)
				)
			)
		)
		(duplicate_pad_numbers_are_jumpers no)
		(fp_line
			(start -0.508 -0.9398)
			(end -0.508 0.9398)
			(stroke
				(width 0.1524)
				(type default)
			)
			(layer "F.SilkS")
		)
		(fp_line
			(start 0.508 -0.9398)
			(end -0.508 -0.9398)
			(stroke
				(width 0.1524)
				(type default)
			)
			(layer "F.SilkS")
		)
		(fp_rect
			(start -0.508 0.9398)
			(end 0.508 -0.9398)
			(stroke
				(width 0)
				(type default)
			)
			(fill no)
			(layer "F.CrtYd")
		)
		(fp_rect
			(start -0.508 0.9398)
			(end 0.508 -0.9398)
			(stroke
				(width 0)
				(type default)
			)
			(fill no)
			(layer "F.Fab")
		)
		(pad "1" smd custom
			(at 0 -0.4445)
			(size 0.1397 0.1397)
			(layers "F.Cu" "F.Mask" "F.Paste")
			(net "GND")
			(options
				(clearance outline)
				(anchor circle)
			)
			(primitives
				(gr_poly
					(pts
						(arc
							(start -0.1778 -0.2794)
							(mid -0.249642 -0.249642)
							(end -0.2794 -0.1778)
						)
						(arc
							(start -0.2794 0.1778)
							(mid -0.249642 0.249642)
							(end -0.1778 0.2794)
						)
						(arc
							(start 0.1778 0.2794)
							(mid 0.249642 0.249642)
							(end 0.2794 0.1778)
						)
						(arc
							(start 0.2794 -0.1778)
							(mid 0.249642 -0.249642)
							(end 0.1778 -0.2794)
						)
					)
					(width 0)
					(fill yes)
				)
			)
		)
		(pad "2" smd custom
			(at 0 0.4445)
			(size 0.1397 0.1397)
			(layers "F.Cu" "F.Mask" "F.Paste")
			(net "BOOTSTRAP7")
			(options
				(clearance outline)
				(anchor circle)
			)
			(primitives
				(gr_poly
					(pts
						(arc
							(start -0.1778 -0.2794)
							(mid -0.249642 -0.249642)
							(end -0.2794 -0.1778)
						)
						(arc
							(start -0.2794 0.1778)
							(mid -0.249642 0.249642)
							(end -0.1778 0.2794)
						)
						(arc
							(start 0.1778 0.2794)
							(mid 0.249642 0.249642)
							(end 0.2794 0.1778)
						)
						(arc
							(start 0.2794 -0.1778)
							(mid 0.249642 -0.249642)
							(end 0.1778 -0.2794)
						)
					)
					(width 0)
					(fill yes)
				)
			)
		)
	)
	(footprint ""
		(layer "F.Cu")
		(at 81.364836 -67.109594)
		(property "Reference" "SKT5"
			(at 0 0 0)
			(layer "F.SilkS")
			(hide yes)
			(effects
				(font
					(size 1.27 1.27)
				)
			)
		)
		(property "Value" "SKT-SPI16P-GP-U"
			(at -8.9916 4.641596 0)
			(unlocked yes)
			(layer "F.Fab")
			(hide yes)
			(effects
				(font
					(size 1.016 1.016)
					(thickness 0.1524)
				)
			)
		)
		(property "Device Type" "SKT-SOIC16-153139H258"
			(at -8.9916 3.117596 0)
			(unlocked yes)
			(layer "F.Fab")
			(hide yes)
			(effects
				(font
					(size 1.016 1.016)
					(thickness 0.1524)
				)
			)
		)
		(duplicate_pad_numbers_are_jumpers no)
		(fp_line
			(start -7.8994 -6.4008)
			(end -7.8994 6.4008)
			(stroke
				(width 0.1524)
				(type default)
			)
			(layer "F.SilkS")
		)
		(fp_line
			(start -7.8994 6.4008)
			(end 7.8994 6.4008)
			(stroke
				(width 0.1524)
				(type default)
			)
			(layer "F.SilkS")
		)
		(fp_line
			(start 6.7183 0.0762)
			(end 7.8994 1.2573)
			(stroke
				(width 0.1524)
				(type default)
			)
			(layer "F.SilkS")
		)
		(fp_line
			(start 7.7216 -6.223)
			(end 7.7216 -3.6576)
			(stroke
				(width 0.508)
				(type default)
			)
			(layer "F.SilkS")
		)
		(fp_line
			(start 7.8867 -1.0922)
			(end 6.7183 0.0762)
			(stroke
				(width 0.1524)
				(type default)
			)
			(layer "F.SilkS")
		)
		(fp_line
			(start 7.8994 -6.4008)
			(end -7.8994 -6.4008)
			(stroke
				(width 0.1524)
				(type default)
			)
			(layer "F.SilkS")
		)
		(fp_line
			(start 7.8994 6.4008)
			(end 7.8994 -6.4008)
			(stroke
				(width 0.1524)
				(type default)
			)
			(layer "F.SilkS")
		)
		(fp_poly
			(pts
				(xy -4.699 -3.855466) (xy -4.699 3.855466) (xy 4.699 3.855466) (xy 4.699 -3.855466)
			)
			(stroke
				(width 0)
				(type default)
			)
			(fill yes)
			(layer "F.SilkS")
		)
		(fp_rect
			(start -8.1534 -6.4008)
			(end 8.1534 -12.5222)
			(stroke
				(width 0)
				(type default)
			)
			(fill no)
			(layer "F.CrtYd")
		)
		(fp_rect
			(start -8.1534 11.6078)
			(end 8.1534 6.4008)
			(stroke
				(width 0)
				(type default)
			)
			(fill no)
			(layer "F.CrtYd")
		)
		(fp_poly
			(pts
				(xy -8.1534 6.4008) (xy -8.1534 -6.4008) (xy -6.2484 -6.4008) (xy -6.2484 -2.6416) (xy -7.6454 -2.6416)
				(xy -7.6454 2.6416) (xy -6.2484 2.6416) (xy -6.2484 6.4008)
			)
			(stroke
				(width 0)
				(type default)
			)
			(fill no)
			(layer "F.CrtYd")
		)
		(fp_poly
			(pts
				(xy 6.2484 -6.4008) (xy 8.1534 -6.4008) (xy 8.1534 6.4008) (xy 6.2484 6.4008) (xy 6.2484 2.6416)
				(xy 7.6454 2.6416) (xy 7.6454 -2.6416) (xy 6.2484 -2.6416)
			)
			(stroke
				(width 0)
				(type default)
			)
			(fill no)
			(layer "F.CrtYd")
		)
		(fp_poly
			(pts
				(xy 6.2484 -6.4008) (xy -6.2484 -6.4008) (xy -6.2484 -2.6416) (xy -7.6454 -2.6416) (xy -7.6454 2.6416)
				(xy -6.2484 2.6416) (xy -6.2484 6.4008) (xy 6.2484 6.4008) (xy 6.2484 2.6416) (xy 7.6454 2.6416)
				(xy 7.6454 -2.6416) (xy 6.2484 -2.6416)
			)
			(stroke
				(width 0)
				(type default)
			)
			(fill no)
			(layer "F.CrtYd")
		)
		(fp_rect
			(start -8.1534 11.6078)
			(end 8.1534 -12.5222)
			(stroke
				(width 0)
				(type default)
			)
			(fill no)
			(layer "F.Fab")
		)
		(pad "1" smd rect
			(at 4.445 -4.896866)
			(size 0.508 1.6764)
			(layers "F.Cu" "F.Mask" "F.Paste")
			(net "SEC_SPI_HOLD_N")
		)
		(pad "2" smd rect
			(at 3.175 -4.896866)
			(size 0.508 1.6764)
			(layers "F.Cu" "F.Mask" "F.Paste")
			(net "P3V3_STBY")
		)
		(pad "3" smd rect
			(at 1.905 -4.896866)
			(size 0.508 1.6764)
			(layers "F.Cu" "F.Mask" "F.Paste")
			(net "SEC_RST_N_R")
		)
		(pad "4" smd rect
			(at 0.635 -4.896866)
			(size 0.508 1.6764)
			(layers "F.Cu" "F.Mask" "F.Paste")
			(net "Net_288")
		)
		(pad "5" smd rect
			(at -0.635 -4.896866)
			(size 0.508 1.6764)
			(layers "F.Cu" "F.Mask" "F.Paste")
			(net "Net_287")
		)
		(pad "6" smd rect
			(at -1.905 -4.896866)
			(size 0.508 1.6764)
			(layers "F.Cu" "F.Mask" "F.Paste")
			(net "Net_286")
		)
		(pad "7" smd rect
			(at -3.175 -4.896866)
			(size 0.508 1.6764)
			(layers "F.Cu" "F.Mask" "F.Paste")
			(net "FLA_CS_R")
		)
		(pad "8" smd rect
			(at -4.445 -4.896866)
			(size 0.508 1.6764)
			(layers "F.Cu" "F.Mask" "F.Paste")
			(net "ROMD2_SEC")
		)
		(pad "9" smd rect
			(at -4.445 4.896866)
			(size 0.508 1.6764)
			(layers "F.Cu" "F.Mask" "F.Paste")
			(net "FLA1_WPN")
		)
		(pad "10" smd rect
			(at -3.175 4.896866)
			(size 0.508 1.6764)
			(layers "F.Cu" "F.Mask" "F.Paste")
			(net "GND")
		)
		(pad "11" smd rect
			(at -1.905 4.896866)
			(size 0.508 1.6764)
			(layers "F.Cu" "F.Mask" "F.Paste")
			(net "Net_292")
		)
		(pad "12" smd rect
			(at -0.635 4.896866)
			(size 0.508 1.6764)
			(layers "F.Cu" "F.Mask" "F.Paste")
			(net "Net_291")
		)
		(pad "13" smd rect
			(at 0.635 4.896866)
			(size 0.508 1.6764)
			(layers "F.Cu" "F.Mask" "F.Paste")
			(net "Net_290")
		)
		(pad "14" smd rect
			(at 1.905 4.896866)
			(size 0.508 1.6764)
			(layers "F.Cu" "F.Mask" "F.Paste")
			(net "Net_289")
		)
		(pad "15" smd rect
			(at 3.175 4.896866)
			(size 0.508 1.6764)
			(layers "F.Cu" "F.Mask" "F.Paste")
			(net "ROMD1_R")
		)
		(pad "16" smd rect
			(at 4.445 4.896866)
			(size 0.508 1.6764)
			(layers "F.Cu" "F.Mask" "F.Paste")
			(net "ROMD0_R")
		)
	)
	(footprint ""
		(layer "F.Cu")
		(at 30.544008 -112.281208 180)
		(property "Reference" "R731"
			(at 0 0 180)
			(layer "F.SilkS")
			(hide yes)
			(effects
				(font
					(size 1.27 1.27)
				)
			)
		)
		(property "Value" "0R2J-2-GP"
			(at 0.064008 -3.993896 180)
			(unlocked yes)
			(layer "F.Fab")
			(hide yes)
			(effects
				(font
					(size 1.016 1.016)
					(thickness 0.1524)
				)
			)
		)
		(property "Device Type" "R402H16"
			(at 0.064008 -5.517896 180)
			(unlocked yes)
			(layer "F.Fab")
			(hide yes)
			(effects
				(font
					(size 1.016 1.016)
					(thickness 0.1524)
				)
			)
		)
		(duplicate_pad_numbers_are_jumpers no)
		(fp_line
			(start 0.508 -0.9398)
			(end -0.508 -0.9398)
			(stroke
				(width 0.1524)
				(type default)
			)
			(layer "F.SilkS")
		)
		(fp_line
			(start -0.508 -0.9398)
			(end -0.508 0.9398)
			(stroke
				(width 0.1524)
				(type default)
			)
			(layer "F.SilkS")
		)
		(fp_rect
			(start -0.508 0.9398)
			(end 0.508 -0.9398)
			(stroke
				(width 0)
				(type default)
			)
			(fill no)
			(layer "F.CrtYd")
		)
		(fp_rect
			(start -0.508 0.9398)
			(end 0.508 -0.9398)
			(stroke
				(width 0)
				(type default)
			)
			(fill no)
			(layer "F.Fab")
		)
		(pad "1" smd custom
			(at 0 -0.4445 180)
			(size 0.1397 0.1397)
			(layers "F.Cu" "F.Mask" "F.Paste")
			(net "LAN_SMB_ALERT_N")
			(options
				(clearance outline)
				(anchor circle)
			)
			(primitives
				(gr_poly
					(pts
						(arc
							(start -0.1778 -0.2794)
							(mid -0.249642 -0.249642)
							(end -0.2794 -0.1778)
						)
						(arc
							(start -0.2794 0.1778)
							(mid -0.249642 0.249642)
							(end -0.1778 0.2794)
						)
						(arc
							(start 0.1778 0.2794)
							(mid 0.249642 0.249642)
							(end 0.2794 0.1778)
						)
						(arc
							(start 0.2794 -0.1778)
							(mid 0.249642 -0.249642)
							(end 0.1778 -0.2794)
						)
					)
					(width 0)
					(fill yes)
				)
			)
		)
		(pad "2" smd custom
			(at 0 0.4445 180)
			(size 0.1397 0.1397)
			(layers "F.Cu" "F.Mask" "F.Paste")
			(net "LAN_SMB_ALERT_N_R")
			(options
				(clearance outline)
				(anchor circle)
			)
			(primitives
				(gr_poly
					(pts
						(arc
							(start -0.1778 -0.2794)
							(mid -0.249642 -0.249642)
							(end -0.2794 -0.1778)
						)
						(arc
							(start -0.2794 0.1778)
							(mid -0.249642 0.249642)
							(end -0.1778 0.2794)
						)
						(arc
							(start 0.1778 0.2794)
							(mid 0.249642 0.249642)
							(end 0.2794 0.1778)
						)
						(arc
							(start 0.2794 -0.1778)
							(mid 0.249642 -0.249642)
							(end 0.1778 -0.2794)
						)
					)
					(width 0)
					(fill yes)
				)
			)
		)
	)
	(footprint ""
		(layer "F.Cu")
		(at 167.6654 -87.5284 90)
		(property "Reference" "TP71"
			(at 0 0 90)
			(layer "F.SilkS")
			(hide yes)
			(effects
				(font
					(size 1.27 1.27)
				)
			)
		)
		(property "Value" "TPAD28-2-GP"
			(at -0.0127 -1.6637 90)
			(unlocked yes)
			(layer "F.Fab")
			(hide yes)
			(effects
				(font
					(size 1.016 1.016)
					(thickness 0.1524)
				)
			)
		)
		(property "Device Type" "TPAD28"
			(at -0.0127 -3.1877 90)
			(unlocked yes)
			(layer "F.Fab")
			(hide yes)
			(effects
				(font
					(size 1.016 1.016)
					(thickness 0.1524)
				)
			)
		)
		(duplicate_pad_numbers_are_jumpers no)
		(fp_poly
			(pts
				(arc
					(start 0 0.3556)
					(mid 0 -0.3556)
					(end 0 0.3556)
				)
			)
			(stroke
				(width 0)
				(type default)
			)
			(fill no)
			(layer "F.CrtYd")
		)
		(fp_poly
			(pts
				(arc
					(start 0 0.6096)
					(mid 0 -0.6096)
					(end 0 0.6096)
				)
			)
			(stroke
				(width 0)
				(type default)
			)
			(fill no)
			(layer "F.Fab")
		)
		(pad "1" smd circle
			(at 0 0 90)
			(size 0.7112 0.7112)
			(layers "F.Cu" "F.Mask" "F.Paste")
			(net "CLKGEN_OE1")
		)
	)
	(footprint ""
		(layer "F.Cu")
		(at 226.695 -5.842)
		(property "Reference" "LED14"
			(at 0 0 0)
			(layer "F.SilkS")
			(hide yes)
			(effects
				(font
					(size 1.27 1.27)
				)
			)
		)
		(property "Value" "LED-Y-11-GP"
			(at -0.1016 -8.1788 0)
			(unlocked yes)
			(layer "F.Fab")
			(hide yes)
			(effects
				(font
					(size 1.016 1.016)
					(thickness 0.1524)
				)
			)
		)
		(property "Device Type" "19-21UBC-1"
			(at -0.0508 -9.8552 0)
			(unlocked yes)
			(layer "F.Fab")
			(hide yes)
			(effects
				(font
					(size 1.016 1.016)
					(thickness 0.1524)
				)
			)
		)
		(duplicate_pad_numbers_are_jumpers no)
		(fp_line
			(start -1.7653 -0.7747)
			(end -1.7653 0.7747)
			(stroke
				(width 0.508)
				(type default)
			)
			(layer "F.SilkS")
		)
		(fp_line
			(start -1.4351 -0.7747)
			(end 1.4351 -0.7747)
			(stroke
				(width 0.1524)
				(type default)
			)
			(layer "F.SilkS")
		)
		(fp_line
			(start -1.4351 0.7747)
			(end -1.4351 -0.7747)
			(stroke
				(width 0.1524)
				(type default)
			)
			(layer "F.SilkS")
		)
		(fp_line
			(start 1.4351 -0.7747)
			(end 1.4351 0.7747)
			(stroke
				(width 0.1524)
				(type default)
			)
			(layer "F.SilkS")
		)
		(fp_line
			(start 1.4351 0.7747)
			(end -1.4351 0.7747)
			(stroke
				(width 0.1524)
				(type default)
			)
			(layer "F.SilkS")
		)
		(fp_rect
			(start -2.0193 1.0287)
			(end 1.6891 -1.0287)
			(stroke
				(width 0)
				(type default)
			)
			(fill no)
			(layer "F.CrtYd")
		)
		(fp_poly
			(pts
				(xy -2.0193 -1.0287) (xy -2.0193 1.0287) (xy 1.6891 1.0287) (xy 1.6891 -1.0287)
			)
			(stroke
				(width 0)
				(type default)
			)
			(fill no)
			(layer "F.Fab")
		)
		(pad "1" smd rect
			(at -0.7112 0)
			(size 0.9398 1.0668)
			(layers "F.Cu" "F.Mask" "F.Paste")
			(net "DEBUG_CONSOLE_LED_0")
		)
		(pad "2" smd rect
			(at 0.7112 0)
			(size 0.9398 1.0668)
			(layers "F.Cu" "F.Mask" "F.Paste")
			(net "CONSOLE_LED_0")
		)
	)
	(footprint ""
		(layer "F.Cu")
		(at 215.361774 -1.396746 -90)
		(property "Reference" "R3725"
			(at 0 0 270)
			(layer "F.SilkS")
			(hide yes)
			(effects
				(font
					(size 1.27 1.27)
				)
			)
		)
		(property "Value" "1KR2F-3-GP"
			(at 0.064008 -3.993896 270)
			(unlocked yes)
			(layer "F.Fab")
			(hide yes)
			(effects
				(font
					(size 1.016 1.016)
					(thickness 0.1524)
				)
			)
		)
		(property "Device Type" "R402H16"
			(at 0.064008 -5.517896 270)
			(unlocked yes)
			(layer "F.Fab")
			(hide yes)
			(effects
				(font
					(size 1.016 1.016)
					(thickness 0.1524)
				)
			)
		)
		(duplicate_pad_numbers_are_jumpers no)
		(fp_line
			(start -0.508 -0.9398)
			(end -0.508 0.9398)
			(stroke
				(width 0.1524)
				(type default)
			)
			(layer "F.SilkS")
		)
		(fp_line
			(start 0.508 -0.9398)
			(end -0.508 -0.9398)
			(stroke
				(width 0.1524)
				(type default)
			)
			(layer "F.SilkS")
		)
		(fp_rect
			(start -0.508 0.9398)
			(end 0.508 -0.9398)
			(stroke
				(width 0)
				(type default)
			)
			(fill no)
			(layer "F.CrtYd")
		)
		(fp_rect
			(start -0.508 0.9398)
			(end 0.508 -0.9398)
			(stroke
				(width 0)
				(type default)
			)
			(fill no)
			(layer "F.Fab")
		)
		(pad "1" smd custom
			(at 0 -0.4445 270)
			(size 0.1397 0.1397)
			(layers "F.Cu" "F.Mask" "F.Paste")
			(net "HOST1_RST_N_R")
			(options
				(clearance outline)
				(anchor circle)
			)
			(primitives
				(gr_poly
					(pts
						(arc
							(start -0.1778 -0.2794)
							(mid -0.249642 -0.249642)
							(end -0.2794 -0.1778)
						)
						(arc
							(start -0.2794 0.1778)
							(mid -0.249642 0.249642)
							(end -0.1778 0.2794)
						)
						(arc
							(start 0.1778 0.2794)
							(mid 0.249642 0.249642)
							(end 0.2794 0.1778)
						)
						(arc
							(start 0.2794 -0.1778)
							(mid 0.249642 -0.249642)
							(end 0.1778 -0.2794)
						)
					)
					(width 0)
					(fill yes)
				)
			)
		)
		(pad "2" smd custom
			(at 0 0.4445 270)
			(size 0.1397 0.1397)
			(layers "F.Cu" "F.Mask" "F.Paste")
			(net "P3V3_STBY")
			(options
				(clearance outline)
				(anchor circle)
			)
			(primitives
				(gr_poly
					(pts
						(arc
							(start -0.1778 -0.2794)
							(mid -0.249642 -0.249642)
							(end -0.2794 -0.1778)
						)
						(arc
							(start -0.2794 0.1778)
							(mid -0.249642 0.249642)
							(end -0.1778 0.2794)
						)
						(arc
							(start 0.1778 0.2794)
							(mid 0.249642 0.249642)
							(end 0.2794 0.1778)
						)
						(arc
							(start 0.2794 -0.1778)
							(mid 0.249642 -0.249642)
							(end 0.1778 -0.2794)
						)
					)
					(width 0)
					(fill yes)
				)
			)
		)
	)
	(footprint ""
		(layer "F.Cu")
		(at 221.742 -13.4112 90)
		(property "Reference" "R7910"
			(at 0 0 90)
			(layer "F.SilkS")
			(hide yes)
			(effects
				(font
					(size 1.27 1.27)
				)
			)
		)
		(property "Value" "0R2J-2-GP"
			(at 0.064008 -3.993896 90)
			(unlocked yes)
			(layer "F.Fab")
			(hide yes)
			(effects
				(font
					(size 1.016 1.016)
					(thickness 0.1524)
				)
			)
		)
		(property "Device Type" "R402H16"
			(at 0.064008 -5.517896 90)
			(unlocked yes)
			(layer "F.Fab")
			(hide yes)
			(effects
				(font
					(size 1.016 1.016)
					(thickness 0.1524)
				)
			)
		)
		(duplicate_pad_numbers_are_jumpers no)
		(fp_line
			(start 0.508 -0.9398)
			(end -0.508 -0.9398)
			(stroke
				(width 0.1524)
				(type default)
			)
			(layer "F.SilkS")
		)
		(fp_line
			(start -0.508 -0.9398)
			(end -0.508 0.9398)
			(stroke
				(width 0.1524)
				(type default)
			)
			(layer "F.SilkS")
		)
		(fp_rect
			(start -0.508 0.9398)
			(end 0.508 -0.9398)
			(stroke
				(width 0)
				(type default)
			)
			(fill no)
			(layer "F.CrtYd")
		)
		(fp_rect
			(start -0.508 0.9398)
			(end 0.508 -0.9398)
			(stroke
				(width 0)
				(type default)
			)
			(fill no)
			(layer "F.Fab")
		)
		(pad "1" smd custom
			(at 0 -0.4445 90)
			(size 0.1397 0.1397)
			(layers "F.Cu" "F.Mask" "F.Paste")
			(net "U81_Y")
			(options
				(clearance outline)
				(anchor circle)
			)
			(primitives
				(gr_poly
					(pts
						(arc
							(start -0.1778 -0.2794)
							(mid -0.249642 -0.249642)
							(end -0.2794 -0.1778)
						)
						(arc
							(start -0.2794 0.1778)
							(mid -0.249642 0.249642)
							(end -0.1778 0.2794)
						)
						(arc
							(start 0.1778 0.2794)
							(mid 0.249642 0.249642)
							(end 0.2794 0.1778)
						)
						(arc
							(start 0.2794 -0.1778)
							(mid 0.249642 -0.249642)
							(end 0.1778 -0.2794)
						)
					)
					(width 0)
					(fill yes)
				)
			)
		)
		(pad "2" smd custom
			(at 0 0.4445 90)
			(size 0.1397 0.1397)
			(layers "F.Cu" "F.Mask" "F.Paste")
			(net "U82_MR#")
			(options
				(clearance outline)
				(anchor circle)
			)
			(primitives
				(gr_poly
					(pts
						(arc
							(start -0.1778 -0.2794)
							(mid -0.249642 -0.249642)
							(end -0.2794 -0.1778)
						)
						(arc
							(start -0.2794 0.1778)
							(mid -0.249642 0.249642)
							(end -0.1778 0.2794)
						)
						(arc
							(start 0.1778 0.2794)
							(mid 0.249642 0.249642)
							(end 0.2794 0.1778)
						)
						(arc
							(start 0.2794 -0.1778)
							(mid 0.249642 -0.249642)
							(end 0.1778 -0.2794)
						)
					)
					(width 0)
					(fill yes)
				)
			)
		)
	)
	(footprint ""
		(layer "F.Cu")
		(at 262.971534 -6.837934 90)
		(property "Reference" "R697"
			(at 0 0 90)
			(layer "F.SilkS")
			(hide yes)
			(effects
				(font
					(size 1.27 1.27)
				)
			)
		)
		(property "Value" "4K7R2F-GP"
			(at 0.064008 -3.993896 90)
			(unlocked yes)
			(layer "F.Fab")
			(hide yes)
			(effects
				(font
					(size 1.016 1.016)
					(thickness 0.1524)
				)
			)
		)
		(property "Device Type" "R402H16"
			(at 0.064008 -5.517896 90)
			(unlocked yes)
			(layer "F.Fab")
			(hide yes)
			(effects
				(font
					(size 1.016 1.016)
					(thickness 0.1524)
				)
			)
		)
		(duplicate_pad_numbers_are_jumpers no)
		(fp_line
			(start 0.508 -0.9398)
			(end -0.508 -0.9398)
			(stroke
				(width 0.1524)
				(type default)
			)
			(layer "F.SilkS")
		)
		(fp_line
			(start -0.508 -0.9398)
			(end -0.508 0.9398)
			(stroke
				(width 0.1524)
				(type default)
			)
			(layer "F.SilkS")
		)
		(fp_rect
			(start -0.508 0.9398)
			(end 0.508 -0.9398)
			(stroke
				(width 0)
				(type default)
			)
			(fill no)
			(layer "F.CrtYd")
		)
		(fp_rect
			(start -0.508 0.9398)
			(end 0.508 -0.9398)
			(stroke
				(width 0)
				(type default)
			)
			(fill no)
			(layer "F.Fab")
		)
		(pad "1" smd custom
			(at 0 -0.4445 90)
			(size 0.1397 0.1397)
			(layers "F.Cu" "F.Mask" "F.Paste")
			(net "PQ22_G")
			(options
				(clearance outline)
				(anchor circle)
			)
			(primitives
				(gr_poly
					(pts
						(arc
							(start -0.1778 -0.2794)
							(mid -0.249642 -0.249642)
							(end -0.2794 -0.1778)
						)
						(arc
							(start -0.2794 0.1778)
							(mid -0.249642 0.249642)
							(end -0.1778 0.2794)
						)
						(arc
							(start 0.1778 0.2794)
							(mid 0.249642 0.249642)
							(end 0.2794 0.1778)
						)
						(arc
							(start 0.2794 -0.1778)
							(mid 0.249642 -0.249642)
							(end 0.1778 -0.2794)
						)
					)
					(width 0)
					(fill yes)
				)
			)
		)
		(pad "2" smd custom
			(at 0 0.4445 90)
			(size 0.1397 0.1397)
			(layers "F.Cu" "F.Mask" "F.Paste")
			(net "P3V3_STBY")
			(options
				(clearance outline)
				(anchor circle)
			)
			(primitives
				(gr_poly
					(pts
						(arc
							(start -0.1778 -0.2794)
							(mid -0.249642 -0.249642)
							(end -0.2794 -0.1778)
						)
						(arc
							(start -0.2794 0.1778)
							(mid -0.249642 0.249642)
							(end -0.1778 0.2794)
						)
						(arc
							(start 0.1778 0.2794)
							(mid 0.249642 0.249642)
							(end 0.2794 0.1778)
						)
						(arc
							(start 0.2794 -0.1778)
							(mid 0.249642 -0.249642)
							(end 0.1778 -0.2794)
						)
					)
					(width 0)
					(fill yes)
				)
			)
		)
	)
	(footprint ""
		(layer "F.Cu")
		(at 46.355 -194.564)
		(property "Reference" "C706"
			(at 0 0 0)
			(layer "F.SilkS")
			(hide yes)
			(effects
				(font
					(size 1.27 1.27)
				)
			)
		)
		(property "Value" "SCD1U16V2KX-3GP"
			(at 1.1811 -2.7051 0)
			(unlocked yes)
			(layer "F.Fab")
			(hide yes)
			(effects
				(font
					(size 1.016 1.016)
					(thickness 0.1524)
				)
			)
		)
		(property "Device Type" "C402H22"
			(at 1.1811 -4.2291 0)
			(unlocked yes)
			(layer "F.Fab")
			(hide yes)
			(effects
				(font
					(size 1.016 1.016)
					(thickness 0.1524)
				)
			)
		)
		(duplicate_pad_numbers_are_jumpers no)
		(fp_rect
			(start -0.4318 0.9525)
			(end 0.4318 -0.9525)
			(stroke
				(width 0)
				(type default)
			)
			(fill no)
			(layer "F.CrtYd")
		)
		(fp_rect
			(start -0.4318 0.9525)
			(end 0.4318 -0.9525)
			(stroke
				(width 0)
				(type default)
			)
			(fill no)
			(layer "F.Fab")
		)
		(pad "1" smd custom
			(at 0 -0.4445)
			(size 0.1524 0.1524)
			(layers "F.Cu" "F.Mask" "F.Paste")
			(net "P3V3_STBY")
			(options
				(clearance outline)
				(anchor circle)
			)
			(primitives
				(gr_poly
					(pts
						(arc
							(start 0.3048 -0.2032)
							(mid 0.275042 -0.275042)
							(end 0.2032 -0.3048)
						)
						(arc
							(start -0.2032 -0.3048)
							(mid -0.275042 -0.275042)
							(end -0.3048 -0.2032)
						)
						(arc
							(start -0.3048 0.2032)
							(mid -0.275042 0.275042)
							(end -0.2032 0.3048)
						)
						(arc
							(start 0.2032 0.3048)
							(mid 0.275042 0.275042)
							(end 0.3048 0.2032)
						)
					)
					(width 0)
					(fill yes)
				)
			)
		)
		(pad "2" smd custom
			(at 0 0.4445)
			(size 0.1524 0.1524)
			(layers "F.Cu" "F.Mask" "F.Paste")
			(net "GND")
			(options
				(clearance outline)
				(anchor circle)
			)
			(primitives
				(gr_poly
					(pts
						(arc
							(start 0.3048 -0.2032)
							(mid 0.275042 -0.275042)
							(end 0.2032 -0.3048)
						)
						(arc
							(start -0.2032 -0.3048)
							(mid -0.275042 -0.275042)
							(end -0.3048 -0.2032)
						)
						(arc
							(start -0.3048 0.2032)
							(mid -0.275042 0.275042)
							(end -0.2032 0.3048)
						)
						(arc
							(start 0.2032 0.3048)
							(mid 0.275042 0.275042)
							(end 0.3048 0.2032)
						)
					)
					(width 0)
					(fill yes)
				)
			)
		)
	)
	(footprint ""
		(layer "F.Cu")
		(at 31.623 -49.657 -90)
		(property "Reference" "TC10"
			(at 0 0 270)
			(layer "F.SilkS")
			(hide yes)
			(effects
				(font
					(size 1.27 1.27)
				)
			)
		)
		(property "Value" "SC10U16V5KX-1-GP"
			(at -0.0762 -6.1214 270)
			(unlocked yes)
			(layer "F.Fab")
			(hide yes)
			(effects
				(font
					(size 1.016 1.016)
					(thickness 0.1524)
				)
			)
		)
		(property "Device Type" "C805H54"
			(at -0.0762 -8.1534 270)
			(unlocked yes)
			(layer "F.Fab")
			(hide yes)
			(effects
				(font
					(size 1.016 1.016)
					(thickness 0.1524)
				)
			)
		)
		(duplicate_pad_numbers_are_jumpers no)
		(fp_line
			(start 0.635 0)
			(end -0.635 0)
			(stroke
				(width 0.508)
				(type default)
			)
			(layer "F.SilkS")
		)
		(fp_rect
			(start -0.9652 1.778)
			(end 0.9652 -1.778)
			(stroke
				(width 0)
				(type default)
			)
			(fill no)
			(layer "F.CrtYd")
		)
		(fp_poly
			(pts
				(xy -0.9652 -1.778) (xy 0.9652 -1.778) (xy 0.9652 1.778) (xy -0.9652 1.778)
			)
			(stroke
				(width 0)
				(type default)
			)
			(fill no)
			(layer "F.Fab")
		)
		(pad "1" smd rect
			(at 0 -0.9652 270)
			(size 1.397 1.143)
			(layers "F.Cu" "F.Mask" "F.Paste")
			(net "P5V_USB")
		)
		(pad "2" smd rect
			(at 0 0.9652 270)
			(size 1.397 1.143)
			(layers "F.Cu" "F.Mask" "F.Paste")
			(net "GND")
		)
	)
	(footprint ""
		(layer "F.Cu")
		(at 127.0254 -208.8896 180)
		(property "Reference" "R9036"
			(at 0 0 180)
			(layer "F.SilkS")
			(hide yes)
			(effects
				(font
					(size 1.27 1.27)
				)
			)
		)
		(property "Value" "4K7R2F-GP"
			(at 0.064008 -3.993896 180)
			(unlocked yes)
			(layer "F.Fab")
			(hide yes)
			(effects
				(font
					(size 1.016 1.016)
					(thickness 0.1524)
				)
			)
		)
		(property "Device Type" "R402H16"
			(at 0.064008 -5.517896 180)
			(unlocked yes)
			(layer "F.Fab")
			(hide yes)
			(effects
				(font
					(size 1.016 1.016)
					(thickness 0.1524)
				)
			)
		)
		(duplicate_pad_numbers_are_jumpers no)
		(fp_line
			(start 0.508 -0.9398)
			(end -0.508 -0.9398)
			(stroke
				(width 0.1524)
				(type default)
			)
			(layer "F.SilkS")
		)
		(fp_line
			(start -0.508 -0.9398)
			(end -0.508 0.9398)
			(stroke
				(width 0.1524)
				(type default)
			)
			(layer "F.SilkS")
		)
		(fp_rect
			(start -0.508 0.9398)
			(end 0.508 -0.9398)
			(stroke
				(width 0)
				(type default)
			)
			(fill no)
			(layer "F.CrtYd")
		)
		(fp_rect
			(start -0.508 0.9398)
			(end 0.508 -0.9398)
			(stroke
				(width 0)
				(type default)
			)
			(fill no)
			(layer "F.Fab")
		)
		(pad "1" smd custom
			(at 0 -0.4445 180)
			(size 0.1397 0.1397)
			(layers "F.Cu" "F.Mask" "F.Paste")
			(net "SSD_PERST#7")
			(options
				(clearance outline)
				(anchor circle)
			)
			(primitives
				(gr_poly
					(pts
						(arc
							(start -0.1778 -0.2794)
							(mid -0.249642 -0.249642)
							(end -0.2794 -0.1778)
						)
						(arc
							(start -0.2794 0.1778)
							(mid -0.249642 0.249642)
							(end -0.1778 0.2794)
						)
						(arc
							(start 0.1778 0.2794)
							(mid 0.249642 0.249642)
							(end 0.2794 0.1778)
						)
						(arc
							(start 0.2794 -0.1778)
							(mid 0.249642 -0.249642)
							(end 0.1778 -0.2794)
						)
					)
					(width 0)
					(fill yes)
				)
			)
		)
		(pad "2" smd custom
			(at 0 0.4445 180)
			(size 0.1397 0.1397)
			(layers "F.Cu" "F.Mask" "F.Paste")
			(net "GND")
			(options
				(clearance outline)
				(anchor circle)
			)
			(primitives
				(gr_poly
					(pts
						(arc
							(start -0.1778 -0.2794)
							(mid -0.249642 -0.249642)
							(end -0.2794 -0.1778)
						)
						(arc
							(start -0.2794 0.1778)
							(mid -0.249642 0.249642)
							(end -0.1778 0.2794)
						)
						(arc
							(start 0.1778 0.2794)
							(mid 0.249642 0.249642)
							(end 0.2794 0.1778)
						)
						(arc
							(start 0.2794 -0.1778)
							(mid 0.249642 -0.249642)
							(end 0.1778 -0.2794)
						)
					)
					(width 0)
					(fill yes)
				)
			)
		)
	)
	(footprint ""
		(layer "F.Cu")
		(at 29.9466 -181.4322 -90)
		(property "Reference" "R503"
			(at 0 0 270)
			(layer "F.SilkS")
			(hide yes)
			(effects
				(font
					(size 1.27 1.27)
				)
			)
		)
		(property "Value" "10KR2F-2-GP"
			(at 0.064008 -3.993896 270)
			(unlocked yes)
			(layer "F.Fab")
			(hide yes)
			(effects
				(font
					(size 1.016 1.016)
					(thickness 0.1524)
				)
			)
		)
		(property "Device Type" "R402H16"
			(at 0.064008 -5.517896 270)
			(unlocked yes)
			(layer "F.Fab")
			(hide yes)
			(effects
				(font
					(size 1.016 1.016)
					(thickness 0.1524)
				)
			)
		)
		(duplicate_pad_numbers_are_jumpers no)
		(fp_line
			(start -0.508 -0.9398)
			(end -0.508 0.9398)
			(stroke
				(width 0.1524)
				(type default)
			)
			(layer "F.SilkS")
		)
		(fp_line
			(start 0.508 -0.9398)
			(end -0.508 -0.9398)
			(stroke
				(width 0.1524)
				(type default)
			)
			(layer "F.SilkS")
		)
		(fp_rect
			(start -0.508 0.9398)
			(end 0.508 -0.9398)
			(stroke
				(width 0)
				(type default)
			)
			(fill no)
			(layer "F.CrtYd")
		)
		(fp_rect
			(start -0.508 0.9398)
			(end 0.508 -0.9398)
			(stroke
				(width 0)
				(type default)
			)
			(fill no)
			(layer "F.Fab")
		)
		(pad "1" smd custom
			(at 0 -0.4445 270)
			(size 0.1397 0.1397)
			(layers "F.Cu" "F.Mask" "F.Paste")
			(net "BMC_I2C5_BUF_READY")
			(options
				(clearance outline)
				(anchor circle)
			)
			(primitives
				(gr_poly
					(pts
						(arc
							(start -0.1778 -0.2794)
							(mid -0.249642 -0.249642)
							(end -0.2794 -0.1778)
						)
						(arc
							(start -0.2794 0.1778)
							(mid -0.249642 0.249642)
							(end -0.1778 0.2794)
						)
						(arc
							(start 0.1778 0.2794)
							(mid 0.249642 0.249642)
							(end 0.2794 0.1778)
						)
						(arc
							(start 0.2794 -0.1778)
							(mid 0.249642 -0.249642)
							(end 0.1778 -0.2794)
						)
					)
					(width 0)
					(fill yes)
				)
			)
		)
		(pad "2" smd custom
			(at 0 0.4445 270)
			(size 0.1397 0.1397)
			(layers "F.Cu" "F.Mask" "F.Paste")
			(net "P3V3_STBY")
			(options
				(clearance outline)
				(anchor circle)
			)
			(primitives
				(gr_poly
					(pts
						(arc
							(start -0.1778 -0.2794)
							(mid -0.249642 -0.249642)
							(end -0.2794 -0.1778)
						)
						(arc
							(start -0.2794 0.1778)
							(mid -0.249642 0.249642)
							(end -0.1778 0.2794)
						)
						(arc
							(start 0.1778 0.2794)
							(mid 0.249642 0.249642)
							(end 0.2794 0.1778)
						)
						(arc
							(start 0.2794 -0.1778)
							(mid 0.249642 -0.249642)
							(end 0.1778 -0.2794)
						)
					)
					(width 0)
					(fill yes)
				)
			)
		)
	)
	(footprint ""
		(layer "F.Cu")
		(at 52.197 -145.415 180)
		(property "Reference" "R311"
			(at 0 0 180)
			(layer "F.SilkS")
			(hide yes)
			(effects
				(font
					(size 1.27 1.27)
				)
			)
		)
		(property "Value" "0R2J-2-GP"
			(at 0.064008 -3.993896 180)
			(unlocked yes)
			(layer "F.Fab")
			(hide yes)
			(effects
				(font
					(size 1.016 1.016)
					(thickness 0.1524)
				)
			)
		)
		(property "Device Type" "R402H16"
			(at 0.064008 -5.517896 180)
			(unlocked yes)
			(layer "F.Fab")
			(hide yes)
			(effects
				(font
					(size 1.016 1.016)
					(thickness 0.1524)
				)
			)
		)
		(duplicate_pad_numbers_are_jumpers no)
		(fp_line
			(start 0.508 -0.9398)
			(end -0.508 -0.9398)
			(stroke
				(width 0.1524)
				(type default)
			)
			(layer "F.SilkS")
		)
		(fp_line
			(start -0.508 -0.9398)
			(end -0.508 0.9398)
			(stroke
				(width 0.1524)
				(type default)
			)
			(layer "F.SilkS")
		)
		(fp_rect
			(start -0.508 0.9398)
			(end 0.508 -0.9398)
			(stroke
				(width 0)
				(type default)
			)
			(fill no)
			(layer "F.CrtYd")
		)
		(fp_rect
			(start -0.508 0.9398)
			(end 0.508 -0.9398)
			(stroke
				(width 0)
				(type default)
			)
			(fill no)
			(layer "F.Fab")
		)
		(pad "1" smd custom
			(at 0 -0.4445 180)
			(size 0.1397 0.1397)
			(layers "F.Cu" "F.Mask" "F.Paste")
			(net "BMC0_LED_DR_R_LED0")
			(options
				(clearance outline)
				(anchor circle)
			)
			(primitives
				(gr_poly
					(pts
						(arc
							(start -0.1778 -0.2794)
							(mid -0.249642 -0.249642)
							(end -0.2794 -0.1778)
						)
						(arc
							(start -0.2794 0.1778)
							(mid -0.249642 0.249642)
							(end -0.1778 0.2794)
						)
						(arc
							(start 0.1778 0.2794)
							(mid 0.249642 0.249642)
							(end 0.2794 0.1778)
						)
						(arc
							(start 0.2794 -0.1778)
							(mid 0.249642 -0.249642)
							(end 0.1778 -0.2794)
						)
					)
					(width 0)
					(fill yes)
				)
			)
		)
		(pad "2" smd custom
			(at 0 0.4445 180)
			(size 0.1397 0.1397)
			(layers "F.Cu" "F.Mask" "F.Paste")
			(net "LED_DR_LED0")
			(options
				(clearance outline)
				(anchor circle)
			)
			(primitives
				(gr_poly
					(pts
						(arc
							(start -0.1778 -0.2794)
							(mid -0.249642 -0.249642)
							(end -0.2794 -0.1778)
						)
						(arc
							(start -0.2794 0.1778)
							(mid -0.249642 0.249642)
							(end -0.1778 0.2794)
						)
						(arc
							(start 0.1778 0.2794)
							(mid 0.249642 0.249642)
							(end 0.2794 0.1778)
						)
						(arc
							(start 0.2794 -0.1778)
							(mid 0.249642 -0.249642)
							(end 0.1778 -0.2794)
						)
					)
					(width 0)
					(fill yes)
				)
			)
		)
	)
	(footprint ""
		(layer "F.Cu")
		(at 36.322 -200.533)
		(property "Reference" "C694"
			(at 0 0 0)
			(layer "F.SilkS")
			(hide yes)
			(effects
				(font
					(size 1.27 1.27)
				)
			)
		)
		(property "Value" "SCD1U16V2KX-3GP"
			(at 1.1811 -2.7051 0)
			(unlocked yes)
			(layer "F.Fab")
			(hide yes)
			(effects
				(font
					(size 1.016 1.016)
					(thickness 0.1524)
				)
			)
		)
		(property "Device Type" "C402H22"
			(at 1.1811 -4.2291 0)
			(unlocked yes)
			(layer "F.Fab")
			(hide yes)
			(effects
				(font
					(size 1.016 1.016)
					(thickness 0.1524)
				)
			)
		)
		(duplicate_pad_numbers_are_jumpers no)
		(fp_rect
			(start -0.4318 0.9525)
			(end 0.4318 -0.9525)
			(stroke
				(width 0)
				(type default)
			)
			(fill no)
			(layer "F.CrtYd")
		)
		(fp_rect
			(start -0.4318 0.9525)
			(end 0.4318 -0.9525)
			(stroke
				(width 0)
				(type default)
			)
			(fill no)
			(layer "F.Fab")
		)
		(pad "1" smd custom
			(at 0 -0.4445)
			(size 0.1524 0.1524)
			(layers "F.Cu" "F.Mask" "F.Paste")
			(net "P3V3_STBY")
			(options
				(clearance outline)
				(anchor circle)
			)
			(primitives
				(gr_poly
					(pts
						(arc
							(start 0.3048 -0.2032)
							(mid 0.275042 -0.275042)
							(end 0.2032 -0.3048)
						)
						(arc
							(start -0.2032 -0.3048)
							(mid -0.275042 -0.275042)
							(end -0.3048 -0.2032)
						)
						(arc
							(start -0.3048 0.2032)
							(mid -0.275042 0.275042)
							(end -0.2032 0.3048)
						)
						(arc
							(start 0.2032 0.3048)
							(mid 0.275042 0.275042)
							(end 0.3048 0.2032)
						)
					)
					(width 0)
					(fill yes)
				)
			)
		)
		(pad "2" smd custom
			(at 0 0.4445)
			(size 0.1524 0.1524)
			(layers "F.Cu" "F.Mask" "F.Paste")
			(net "GND")
			(options
				(clearance outline)
				(anchor circle)
			)
			(primitives
				(gr_poly
					(pts
						(arc
							(start 0.3048 -0.2032)
							(mid 0.275042 -0.275042)
							(end 0.2032 -0.3048)
						)
						(arc
							(start -0.2032 -0.3048)
							(mid -0.275042 -0.275042)
							(end -0.3048 -0.2032)
						)
						(arc
							(start -0.3048 0.2032)
							(mid -0.275042 0.275042)
							(end -0.2032 0.3048)
						)
						(arc
							(start 0.2032 0.3048)
							(mid 0.275042 0.275042)
							(end 0.3048 0.2032)
						)
					)
					(width 0)
					(fill yes)
				)
			)
		)
	)
	(footprint ""
		(layer "F.Cu")
		(at 197.808088 -212.420454 180)
		(property "Reference" "C118"
			(at 0 0 180)
			(layer "F.SilkS")
			(hide yes)
			(effects
				(font
					(size 1.27 1.27)
				)
			)
		)
		(property "Value" "SCD22U10V2KX-1GP"
			(at 1.1811 -2.7051 180)
			(unlocked yes)
			(layer "F.Fab")
			(hide yes)
			(effects
				(font
					(size 1.016 1.016)
					(thickness 0.1524)
				)
			)
		)
		(property "Device Type" "C402H22"
			(at 1.1811 -4.2291 180)
			(unlocked yes)
			(layer "F.Fab")
			(hide yes)
			(effects
				(font
					(size 1.016 1.016)
					(thickness 0.1524)
				)
			)
		)
		(duplicate_pad_numbers_are_jumpers no)
		(fp_rect
			(start -0.4318 0.9525)
			(end 0.4318 -0.9525)
			(stroke
				(width 0)
				(type default)
			)
			(fill no)
			(layer "F.CrtYd")
		)
		(fp_rect
			(start -0.4318 0.9525)
			(end 0.4318 -0.9525)
			(stroke
				(width 0)
				(type default)
			)
			(fill no)
			(layer "F.Fab")
		)
		(pad "1" smd custom
			(at 0 -0.4445 180)
			(size 0.1524 0.1524)
			(layers "F.Cu" "F.Mask" "F.Paste")
			(net "PCIE_TX_CAP_N43")
			(options
				(clearance outline)
				(anchor circle)
			)
			(primitives
				(gr_poly
					(pts
						(arc
							(start 0.3048 -0.2032)
							(mid 0.275042 -0.275042)
							(end 0.2032 -0.3048)
						)
						(arc
							(start -0.2032 -0.3048)
							(mid -0.275042 -0.275042)
							(end -0.3048 -0.2032)
						)
						(arc
							(start -0.3048 0.2032)
							(mid -0.275042 0.275042)
							(end -0.2032 0.3048)
						)
						(arc
							(start 0.2032 0.3048)
							(mid 0.275042 0.275042)
							(end 0.3048 0.2032)
						)
					)
					(width 0)
					(fill yes)
				)
			)
		)
		(pad "2" smd custom
			(at 0 0.4445 180)
			(size 0.1524 0.1524)
			(layers "F.Cu" "F.Mask" "F.Paste")
			(net "PCIE_TX_N43")
			(options
				(clearance outline)
				(anchor circle)
			)
			(primitives
				(gr_poly
					(pts
						(arc
							(start 0.3048 -0.2032)
							(mid 0.275042 -0.275042)
							(end 0.2032 -0.3048)
						)
						(arc
							(start -0.2032 -0.3048)
							(mid -0.275042 -0.275042)
							(end -0.3048 -0.2032)
						)
						(arc
							(start -0.3048 0.2032)
							(mid -0.275042 0.275042)
							(end -0.2032 0.3048)
						)
						(arc
							(start 0.2032 0.3048)
							(mid 0.275042 0.275042)
							(end 0.3048 0.2032)
						)
					)
					(width 0)
					(fill yes)
				)
			)
		)
	)
	(footprint ""
		(layer "F.Cu")
		(at 56.98998 -144.27708 -90)
		(property "Reference" "R414"
			(at 0 0 270)
			(layer "F.SilkS")
			(hide yes)
			(effects
				(font
					(size 1.27 1.27)
				)
			)
		)
		(property "Value" "10KR2F-2-GP"
			(at 0.064008 -3.993896 270)
			(unlocked yes)
			(layer "F.Fab")
			(hide yes)
			(effects
				(font
					(size 1.016 1.016)
					(thickness 0.1524)
				)
			)
		)
		(property "Device Type" "R402H16"
			(at 0.064008 -5.517896 270)
			(unlocked yes)
			(layer "F.Fab")
			(hide yes)
			(effects
				(font
					(size 1.016 1.016)
					(thickness 0.1524)
				)
			)
		)
		(duplicate_pad_numbers_are_jumpers no)
		(fp_line
			(start -0.508 -0.9398)
			(end -0.508 0.9398)
			(stroke
				(width 0.1524)
				(type default)
			)
			(layer "F.SilkS")
		)
		(fp_line
			(start 0.508 -0.9398)
			(end -0.508 -0.9398)
			(stroke
				(width 0.1524)
				(type default)
			)
			(layer "F.SilkS")
		)
		(fp_rect
			(start -0.508 0.9398)
			(end 0.508 -0.9398)
			(stroke
				(width 0)
				(type default)
			)
			(fill no)
			(layer "F.CrtYd")
		)
		(fp_rect
			(start -0.508 0.9398)
			(end 0.508 -0.9398)
			(stroke
				(width 0)
				(type default)
			)
			(fill no)
			(layer "F.Fab")
		)
		(pad "1" smd custom
			(at 0 -0.4445 270)
			(size 0.1397 0.1397)
			(layers "F.Cu" "F.Mask" "F.Paste")
			(net "BMC_I210_PERST_N")
			(options
				(clearance outline)
				(anchor circle)
			)
			(primitives
				(gr_poly
					(pts
						(arc
							(start -0.1778 -0.2794)
							(mid -0.249642 -0.249642)
							(end -0.2794 -0.1778)
						)
						(arc
							(start -0.2794 0.1778)
							(mid -0.249642 0.249642)
							(end -0.1778 0.2794)
						)
						(arc
							(start 0.1778 0.2794)
							(mid 0.249642 0.249642)
							(end 0.2794 0.1778)
						)
						(arc
							(start 0.2794 -0.1778)
							(mid 0.249642 -0.249642)
							(end 0.1778 -0.2794)
						)
					)
					(width 0)
					(fill yes)
				)
			)
		)
		(pad "2" smd custom
			(at 0 0.4445 270)
			(size 0.1397 0.1397)
			(layers "F.Cu" "F.Mask" "F.Paste")
			(net "GND")
			(options
				(clearance outline)
				(anchor circle)
			)
			(primitives
				(gr_poly
					(pts
						(arc
							(start -0.1778 -0.2794)
							(mid -0.249642 -0.249642)
							(end -0.2794 -0.1778)
						)
						(arc
							(start -0.2794 0.1778)
							(mid -0.249642 0.249642)
							(end -0.1778 0.2794)
						)
						(arc
							(start 0.1778 0.2794)
							(mid 0.249642 0.249642)
							(end 0.2794 0.1778)
						)
						(arc
							(start 0.2794 -0.1778)
							(mid 0.249642 -0.249642)
							(end 0.1778 -0.2794)
						)
					)
					(width 0)
					(fill yes)
				)
			)
		)
	)
	(footprint ""
		(layer "F.Cu")
		(at 39.0398 -188.5696 180)
		(property "Reference" "R874"
			(at 0 0 180)
			(layer "F.SilkS")
			(hide yes)
			(effects
				(font
					(size 1.27 1.27)
				)
			)
		)
		(property "Value" "10KR2F-2-GP"
			(at 0.064008 -3.993896 180)
			(unlocked yes)
			(layer "F.Fab")
			(hide yes)
			(effects
				(font
					(size 1.016 1.016)
					(thickness 0.1524)
				)
			)
		)
		(property "Device Type" "R402H16"
			(at 0.064008 -5.517896 180)
			(unlocked yes)
			(layer "F.Fab")
			(hide yes)
			(effects
				(font
					(size 1.016 1.016)
					(thickness 0.1524)
				)
			)
		)
		(duplicate_pad_numbers_are_jumpers no)
		(fp_line
			(start 0.508 -0.9398)
			(end -0.508 -0.9398)
			(stroke
				(width 0.1524)
				(type default)
			)
			(layer "F.SilkS")
		)
		(fp_line
			(start -0.508 -0.9398)
			(end -0.508 0.9398)
			(stroke
				(width 0.1524)
				(type default)
			)
			(layer "F.SilkS")
		)
		(fp_rect
			(start -0.508 0.9398)
			(end 0.508 -0.9398)
			(stroke
				(width 0)
				(type default)
			)
			(fill no)
			(layer "F.CrtYd")
		)
		(fp_rect
			(start -0.508 0.9398)
			(end 0.508 -0.9398)
			(stroke
				(width 0)
				(type default)
			)
			(fill no)
			(layer "F.Fab")
		)
		(pad "1" smd custom
			(at 0 -0.4445 180)
			(size 0.1397 0.1397)
			(layers "F.Cu" "F.Mask" "F.Paste")
			(net "I2C9_BUF_READY")
			(options
				(clearance outline)
				(anchor circle)
			)
			(primitives
				(gr_poly
					(pts
						(arc
							(start -0.1778 -0.2794)
							(mid -0.249642 -0.249642)
							(end -0.2794 -0.1778)
						)
						(arc
							(start -0.2794 0.1778)
							(mid -0.249642 0.249642)
							(end -0.1778 0.2794)
						)
						(arc
							(start 0.1778 0.2794)
							(mid 0.249642 0.249642)
							(end 0.2794 0.1778)
						)
						(arc
							(start 0.2794 -0.1778)
							(mid 0.249642 -0.249642)
							(end 0.1778 -0.2794)
						)
					)
					(width 0)
					(fill yes)
				)
			)
		)
		(pad "2" smd custom
			(at 0 0.4445 180)
			(size 0.1397 0.1397)
			(layers "F.Cu" "F.Mask" "F.Paste")
			(net "P3V3_STBY")
			(options
				(clearance outline)
				(anchor circle)
			)
			(primitives
				(gr_poly
					(pts
						(arc
							(start -0.1778 -0.2794)
							(mid -0.249642 -0.249642)
							(end -0.2794 -0.1778)
						)
						(arc
							(start -0.2794 0.1778)
							(mid -0.249642 0.249642)
							(end -0.1778 0.2794)
						)
						(arc
							(start 0.1778 0.2794)
							(mid 0.249642 0.249642)
							(end 0.2794 0.1778)
						)
						(arc
							(start 0.2794 -0.1778)
							(mid 0.249642 -0.249642)
							(end 0.1778 -0.2794)
						)
					)
					(width 0)
					(fill yes)
				)
			)
		)
	)
	(footprint ""
		(layer "F.Cu")
		(at 147.365212 -59.936126)
		(property "Reference" "PC193"
			(at 0 0 0)
			(layer "F.SilkS")
			(hide yes)
			(effects
				(font
					(size 1.27 1.27)
				)
			)
		)
		(property "Value" "SC1U16V3KX-5GP"
			(at 0 -2.8194 0)
			(unlocked yes)
			(layer "F.Fab")
			(hide yes)
			(effects
				(font
					(size 1.016 1.016)
					(thickness 0.1524)
				)
			)
		)
		(property "Device Type" "C603H36"
			(at 0 -4.3434 0)
			(unlocked yes)
			(layer "F.Fab")
			(hide yes)
			(effects
				(font
					(size 1.016 1.016)
					(thickness 0.1524)
				)
			)
		)
		(duplicate_pad_numbers_are_jumpers no)
		(fp_line
			(start 0.508 0)
			(end -0.508 0)
			(stroke
				(width 0.2032)
				(type default)
			)
			(layer "F.SilkS")
		)
		(fp_rect
			(start -0.5842 1.3335)
			(end 0.5842 -1.3335)
			(stroke
				(width 0)
				(type default)
			)
			(fill no)
			(layer "F.CrtYd")
		)
		(fp_rect
			(start -0.5842 1.3335)
			(end 0.5842 -1.3335)
			(stroke
				(width 0)
				(type default)
			)
			(fill no)
			(layer "F.Fab")
		)
		(pad "1" smd custom
			(at 0 -0.762)
			(size 0.2159 0.2159)
			(layers "F.Cu" "F.Mask" "F.Paste")
			(net "P0V9_VREG")
			(options
				(clearance outline)
				(anchor circle)
			)
			(primitives
				(gr_poly
					(pts
						(arc
							(start -0.3302 -0.4318)
							(mid -0.402042 -0.402042)
							(end -0.4318 -0.3302)
						)
						(arc
							(start -0.4318 0.3302)
							(mid -0.402042 0.402042)
							(end -0.3302 0.4318)
						)
						(arc
							(start 0.3302 0.4318)
							(mid 0.402042 0.402042)
							(end 0.4318 0.3302)
						)
						(arc
							(start 0.4318 -0.3302)
							(mid 0.402042 -0.402042)
							(end 0.3302 -0.4318)
						)
					)
					(width 0)
					(fill yes)
				)
			)
		)
		(pad "2" smd custom
			(at 0 0.762)
			(size 0.2159 0.2159)
			(layers "F.Cu" "F.Mask" "F.Paste")
			(net "GND")
			(options
				(clearance outline)
				(anchor circle)
			)
			(primitives
				(gr_poly
					(pts
						(arc
							(start -0.3302 -0.4318)
							(mid -0.402042 -0.402042)
							(end -0.4318 -0.3302)
						)
						(arc
							(start -0.4318 0.3302)
							(mid -0.402042 0.402042)
							(end -0.3302 0.4318)
						)
						(arc
							(start 0.3302 0.4318)
							(mid 0.402042 0.402042)
							(end 0.4318 0.3302)
						)
						(arc
							(start 0.4318 -0.3302)
							(mid 0.402042 -0.402042)
							(end 0.3302 -0.4318)
						)
					)
					(width 0)
					(fill yes)
				)
			)
		)
	)
	(footprint ""
		(layer "F.Cu")
		(at 151.527002 -72.823832 90)
		(property "Reference" "PC211"
			(at 0 0 90)
			(layer "F.SilkS")
			(hide yes)
			(effects
				(font
					(size 1.27 1.27)
				)
			)
		)
		(property "Value" "SC22U25V6KX-GP-U"
			(at -2.860802 -5.279644 90)
			(unlocked yes)
			(layer "F.Fab")
			(hide yes)
			(effects
				(font
					(size 1.016 1.016)
					(thickness 0.1524)
				)
			)
		)
		(property "Device Type" "C1206-TO0D3H75"
			(at -2.860802 -6.803644 90)
			(unlocked yes)
			(layer "F.Fab")
			(hide yes)
			(effects
				(font
					(size 1.016 1.016)
					(thickness 0.1524)
				)
			)
		)
		(duplicate_pad_numbers_are_jumpers no)
		(fp_line
			(start 1.3081 -2.3749)
			(end 1.3081 2.3749)
			(stroke
				(width 0.1524)
				(type default)
			)
			(layer "F.SilkS")
		)
		(fp_line
			(start -1.3081 -2.3749)
			(end 1.3081 -2.3749)
			(stroke
				(width 0.1524)
				(type default)
			)
			(layer "F.SilkS")
		)
		(fp_line
			(start 1.3081 2.3749)
			(end -1.3081 2.3749)
			(stroke
				(width 0.1524)
				(type default)
			)
			(layer "F.SilkS")
		)
		(fp_line
			(start -1.3081 2.3749)
			(end -1.3081 -2.3749)
			(stroke
				(width 0.1524)
				(type default)
			)
			(layer "F.SilkS")
		)
		(fp_rect
			(start -0.8001 1.6002)
			(end 0.8001 -1.6002)
			(stroke
				(width 0)
				(type default)
			)
			(fill no)
			(layer "F.CrtYd")
		)
		(fp_poly
			(pts
				(xy -1.5621 2.4511) (xy -1.5621 1.6002) (xy 0.8001 1.6002) (xy 0.8001 -1.6002) (xy -0.8001 -1.6002)
				(xy -0.8001 1.5875) (xy -1.5621 1.5875) (xy -1.5621 -2.4511) (xy 1.5621 -2.4511) (xy 1.5621 2.4511)
			)
			(stroke
				(width 0)
				(type default)
			)
			(fill no)
			(layer "F.CrtYd")
		)
		(fp_rect
			(start -1.5621 2.4511)
			(end 1.5621 -2.4511)
			(stroke
				(width 0)
				(type default)
			)
			(fill no)
			(layer "F.Fab")
		)
		(pad "1" smd rect
			(at 0 -1.392936 90)
			(size 2.1082 1.4478)
			(layers "F.Cu" "F.Mask" "F.Paste")
			(net "P0V9_VIN")
		)
		(pad "2" smd rect
			(at 0 1.392936 90)
			(size 2.1082 1.4478)
			(layers "F.Cu" "F.Mask" "F.Paste")
			(net "GND")
		)
	)
	(footprint ""
		(layer "F.Cu")
		(at 224.893124 -190.601092)
		(property "Reference" "R7942"
			(at 0 0 0)
			(layer "F.SilkS")
			(hide yes)
			(effects
				(font
					(size 1.27 1.27)
				)
			)
		)
		(property "Value" "0R2J-2-GP"
			(at 0.064008 -3.993896 0)
			(unlocked yes)
			(layer "F.Fab")
			(hide yes)
			(effects
				(font
					(size 1.016 1.016)
					(thickness 0.1524)
				)
			)
		)
		(property "Device Type" "R402H16"
			(at 0.064008 -5.517896 0)
			(unlocked yes)
			(layer "F.Fab")
			(hide yes)
			(effects
				(font
					(size 1.016 1.016)
					(thickness 0.1524)
				)
			)
		)
		(duplicate_pad_numbers_are_jumpers no)
		(fp_line
			(start -0.508 -0.9398)
			(end -0.508 0.9398)
			(stroke
				(width 0.1524)
				(type default)
			)
			(layer "F.SilkS")
		)
		(fp_line
			(start 0.508 -0.9398)
			(end -0.508 -0.9398)
			(stroke
				(width 0.1524)
				(type default)
			)
			(layer "F.SilkS")
		)
		(fp_rect
			(start -0.508 0.9398)
			(end 0.508 -0.9398)
			(stroke
				(width 0)
				(type default)
			)
			(fill no)
			(layer "F.CrtYd")
		)
		(fp_rect
			(start -0.508 0.9398)
			(end 0.508 -0.9398)
			(stroke
				(width 0)
				(type default)
			)
			(fill no)
			(layer "F.Fab")
		)
		(pad "1" smd custom
			(at 0 -0.4445)
			(size 0.1397 0.1397)
			(layers "F.Cu" "F.Mask" "F.Paste")
			(net "SSD_ATNLED#8")
			(options
				(clearance outline)
				(anchor circle)
			)
			(primitives
				(gr_poly
					(pts
						(arc
							(start -0.1778 -0.2794)
							(mid -0.249642 -0.249642)
							(end -0.2794 -0.1778)
						)
						(arc
							(start -0.2794 0.1778)
							(mid -0.249642 0.249642)
							(end -0.1778 0.2794)
						)
						(arc
							(start 0.1778 0.2794)
							(mid 0.249642 0.249642)
							(end 0.2794 0.1778)
						)
						(arc
							(start 0.2794 -0.1778)
							(mid 0.249642 -0.249642)
							(end 0.1778 -0.2794)
						)
					)
					(width 0)
					(fill yes)
				)
			)
		)
		(pad "2" smd custom
			(at 0 0.4445)
			(size 0.1397 0.1397)
			(layers "F.Cu" "F.Mask" "F.Paste")
			(net "SSD_ATNLED#8_R")
			(options
				(clearance outline)
				(anchor circle)
			)
			(primitives
				(gr_poly
					(pts
						(arc
							(start -0.1778 -0.2794)
							(mid -0.249642 -0.249642)
							(end -0.2794 -0.1778)
						)
						(arc
							(start -0.2794 0.1778)
							(mid -0.249642 0.249642)
							(end -0.1778 0.2794)
						)
						(arc
							(start 0.1778 0.2794)
							(mid 0.249642 0.249642)
							(end 0.2794 0.1778)
						)
						(arc
							(start 0.2794 -0.1778)
							(mid 0.249642 -0.249642)
							(end 0.1778 -0.2794)
						)
					)
					(width 0)
					(fill yes)
				)
			)
		)
	)
	(footprint ""
		(layer "F.Cu")
		(at 26.318718 -84.96681)
		(property "Reference" "R646"
			(at 0 0 0)
			(layer "F.SilkS")
			(hide yes)
			(effects
				(font
					(size 1.27 1.27)
				)
			)
		)
		(property "Value" "10KR2F-2-GP"
			(at 0.064008 -3.993896 0)
			(unlocked yes)
			(layer "F.Fab")
			(hide yes)
			(effects
				(font
					(size 1.016 1.016)
					(thickness 0.1524)
				)
			)
		)
		(property "Device Type" "R402H16"
			(at 0.064008 -5.517896 0)
			(unlocked yes)
			(layer "F.Fab")
			(hide yes)
			(effects
				(font
					(size 1.016 1.016)
					(thickness 0.1524)
				)
			)
		)
		(duplicate_pad_numbers_are_jumpers no)
		(fp_line
			(start -0.508 -0.9398)
			(end -0.508 0.9398)
			(stroke
				(width 0.1524)
				(type default)
			)
			(layer "F.SilkS")
		)
		(fp_line
			(start 0.508 -0.9398)
			(end -0.508 -0.9398)
			(stroke
				(width 0.1524)
				(type default)
			)
			(layer "F.SilkS")
		)
		(fp_rect
			(start -0.508 0.9398)
			(end 0.508 -0.9398)
			(stroke
				(width 0)
				(type default)
			)
			(fill no)
			(layer "F.CrtYd")
		)
		(fp_rect
			(start -0.508 0.9398)
			(end 0.508 -0.9398)
			(stroke
				(width 0)
				(type default)
			)
			(fill no)
			(layer "F.Fab")
		)
		(pad "1" smd custom
			(at 0 -0.4445)
			(size 0.1397 0.1397)
			(layers "F.Cu" "F.Mask" "F.Paste")
			(net "P3V3_STBY")
			(options
				(clearance outline)
				(anchor circle)
			)
			(primitives
				(gr_poly
					(pts
						(arc
							(start -0.1778 -0.2794)
							(mid -0.249642 -0.249642)
							(end -0.2794 -0.1778)
						)
						(arc
							(start -0.2794 0.1778)
							(mid -0.249642 0.249642)
							(end -0.1778 0.2794)
						)
						(arc
							(start 0.1778 0.2794)
							(mid 0.249642 0.249642)
							(end 0.2794 0.1778)
						)
						(arc
							(start 0.2794 -0.1778)
							(mid 0.249642 -0.249642)
							(end 0.1778 -0.2794)
						)
					)
					(width 0)
					(fill yes)
				)
			)
		)
		(pad "2" smd custom
			(at 0 0.4445)
			(size 0.1397 0.1397)
			(layers "F.Cu" "F.Mask" "F.Paste")
			(net "PHY_WAKE_N")
			(options
				(clearance outline)
				(anchor circle)
			)
			(primitives
				(gr_poly
					(pts
						(arc
							(start -0.1778 -0.2794)
							(mid -0.249642 -0.249642)
							(end -0.2794 -0.1778)
						)
						(arc
							(start -0.2794 0.1778)
							(mid -0.249642 0.249642)
							(end -0.1778 0.2794)
						)
						(arc
							(start 0.1778 0.2794)
							(mid 0.249642 0.249642)
							(end 0.2794 0.1778)
						)
						(arc
							(start 0.2794 -0.1778)
							(mid 0.249642 -0.249642)
							(end 0.1778 -0.2794)
						)
					)
					(width 0)
					(fill yes)
				)
			)
		)
	)
	(footprint ""
		(layer "F.Cu")
		(at 99.008184 -212.420454 180)
		(property "Reference" "C157"
			(at 0 0 180)
			(layer "F.SilkS")
			(hide yes)
			(effects
				(font
					(size 1.27 1.27)
				)
			)
		)
		(property "Value" "SCD22U10V2KX-1GP"
			(at 1.1811 -2.7051 180)
			(unlocked yes)
			(layer "F.Fab")
			(hide yes)
			(effects
				(font
					(size 1.016 1.016)
					(thickness 0.1524)
				)
			)
		)
		(property "Device Type" "C402H22"
			(at 1.1811 -4.2291 180)
			(unlocked yes)
			(layer "F.Fab")
			(hide yes)
			(effects
				(font
					(size 1.016 1.016)
					(thickness 0.1524)
				)
			)
		)
		(duplicate_pad_numbers_are_jumpers no)
		(fp_rect
			(start -0.4318 0.9525)
			(end 0.4318 -0.9525)
			(stroke
				(width 0)
				(type default)
			)
			(fill no)
			(layer "F.CrtYd")
		)
		(fp_rect
			(start -0.4318 0.9525)
			(end 0.4318 -0.9525)
			(stroke
				(width 0)
				(type default)
			)
			(fill no)
			(layer "F.Fab")
		)
		(pad "1" smd custom
			(at 0 -0.4445 180)
			(size 0.1524 0.1524)
			(layers "F.Cu" "F.Mask" "F.Paste")
			(net "PCIE_TX_CAP_N63")
			(options
				(clearance outline)
				(anchor circle)
			)
			(primitives
				(gr_poly
					(pts
						(arc
							(start 0.3048 -0.2032)
							(mid 0.275042 -0.275042)
							(end 0.2032 -0.3048)
						)
						(arc
							(start -0.2032 -0.3048)
							(mid -0.275042 -0.275042)
							(end -0.3048 -0.2032)
						)
						(arc
							(start -0.3048 0.2032)
							(mid -0.275042 0.275042)
							(end -0.2032 0.3048)
						)
						(arc
							(start 0.2032 0.3048)
							(mid 0.275042 0.275042)
							(end 0.3048 0.2032)
						)
					)
					(width 0)
					(fill yes)
				)
			)
		)
		(pad "2" smd custom
			(at 0 0.4445 180)
			(size 0.1524 0.1524)
			(layers "F.Cu" "F.Mask" "F.Paste")
			(net "PCIE_TX_N63")
			(options
				(clearance outline)
				(anchor circle)
			)
			(primitives
				(gr_poly
					(pts
						(arc
							(start 0.3048 -0.2032)
							(mid 0.275042 -0.275042)
							(end 0.2032 -0.3048)
						)
						(arc
							(start -0.2032 -0.3048)
							(mid -0.275042 -0.275042)
							(end -0.3048 -0.2032)
						)
						(arc
							(start -0.3048 0.2032)
							(mid -0.275042 0.275042)
							(end -0.2032 0.3048)
						)
						(arc
							(start 0.2032 0.3048)
							(mid 0.275042 0.275042)
							(end 0.3048 0.2032)
						)
					)
					(width 0)
					(fill yes)
				)
			)
		)
	)
	(footprint ""
		(layer "F.Cu")
		(at 182.448708 -1.276096)
		(property "Reference" "R671"
			(at 0 0 0)
			(layer "F.SilkS")
			(hide yes)
			(effects
				(font
					(size 1.27 1.27)
				)
			)
		)
		(property "Value" "0R2J-2-GP"
			(at 0.064008 -3.993896 0)
			(unlocked yes)
			(layer "F.Fab")
			(hide yes)
			(effects
				(font
					(size 1.016 1.016)
					(thickness 0.1524)
				)
			)
		)
		(property "Device Type" "R402H16"
			(at 0.064008 -5.517896 0)
			(unlocked yes)
			(layer "F.Fab")
			(hide yes)
			(effects
				(font
					(size 1.016 1.016)
					(thickness 0.1524)
				)
			)
		)
		(duplicate_pad_numbers_are_jumpers no)
		(fp_line
			(start -0.508 -0.9398)
			(end -0.508 0.9398)
			(stroke
				(width 0.1524)
				(type default)
			)
			(layer "F.SilkS")
		)
		(fp_line
			(start 0.508 -0.9398)
			(end -0.508 -0.9398)
			(stroke
				(width 0.1524)
				(type default)
			)
			(layer "F.SilkS")
		)
		(fp_rect
			(start -0.508 0.9398)
			(end 0.508 -0.9398)
			(stroke
				(width 0)
				(type default)
			)
			(fill no)
			(layer "F.CrtYd")
		)
		(fp_rect
			(start -0.508 0.9398)
			(end 0.508 -0.9398)
			(stroke
				(width 0)
				(type default)
			)
			(fill no)
			(layer "F.Fab")
		)
		(pad "1" smd custom
			(at 0 -0.4445)
			(size 0.1397 0.1397)
			(layers "F.Cu" "F.Mask" "F.Paste")
			(net "HOST2_RST_N_C")
			(options
				(clearance outline)
				(anchor circle)
			)
			(primitives
				(gr_poly
					(pts
						(arc
							(start -0.1778 -0.2794)
							(mid -0.249642 -0.249642)
							(end -0.2794 -0.1778)
						)
						(arc
							(start -0.2794 0.1778)
							(mid -0.249642 0.249642)
							(end -0.1778 0.2794)
						)
						(arc
							(start 0.1778 0.2794)
							(mid 0.249642 0.249642)
							(end 0.2794 0.1778)
						)
						(arc
							(start 0.2794 -0.1778)
							(mid 0.249642 -0.249642)
							(end 0.1778 -0.2794)
						)
					)
					(width 0)
					(fill yes)
				)
			)
		)
		(pad "2" smd custom
			(at 0 0.4445)
			(size 0.1397 0.1397)
			(layers "F.Cu" "F.Mask" "F.Paste")
			(net "P3V3_STBY")
			(options
				(clearance outline)
				(anchor circle)
			)
			(primitives
				(gr_poly
					(pts
						(arc
							(start -0.1778 -0.2794)
							(mid -0.249642 -0.249642)
							(end -0.2794 -0.1778)
						)
						(arc
							(start -0.2794 0.1778)
							(mid -0.249642 0.249642)
							(end -0.1778 0.2794)
						)
						(arc
							(start 0.1778 0.2794)
							(mid 0.249642 0.249642)
							(end 0.2794 0.1778)
						)
						(arc
							(start 0.2794 -0.1778)
							(mid 0.249642 -0.249642)
							(end 0.1778 -0.2794)
						)
					)
					(width 0)
					(fill yes)
				)
			)
		)
	)
	(footprint ""
		(layer "F.Cu")
		(at 67.794124 -195.681092 180)
		(property "Reference" "C370"
			(at 0 0 180)
			(layer "F.SilkS")
			(hide yes)
			(effects
				(font
					(size 1.27 1.27)
				)
			)
		)
		(property "Value" "SCD1U25V2KX-2-GP"
			(at 1.1811 -2.7051 180)
			(unlocked yes)
			(layer "F.Fab")
			(hide yes)
			(effects
				(font
					(size 1.016 1.016)
					(thickness 0.1524)
				)
			)
		)
		(property "Device Type" "C402H22"
			(at 1.1811 -4.2291 180)
			(unlocked yes)
			(layer "F.Fab")
			(hide yes)
			(effects
				(font
					(size 1.016 1.016)
					(thickness 0.1524)
				)
			)
		)
		(duplicate_pad_numbers_are_jumpers no)
		(fp_rect
			(start -0.4318 0.9525)
			(end 0.4318 -0.9525)
			(stroke
				(width 0)
				(type default)
			)
			(fill no)
			(layer "F.CrtYd")
		)
		(fp_rect
			(start -0.4318 0.9525)
			(end 0.4318 -0.9525)
			(stroke
				(width 0)
				(type default)
			)
			(fill no)
			(layer "F.Fab")
		)
		(pad "1" smd custom
			(at 0 -0.4445 180)
			(size 0.1524 0.1524)
			(layers "F.Cu" "F.Mask" "F.Paste")
			(net "P3V3_STBY")
			(options
				(clearance outline)
				(anchor circle)
			)
			(primitives
				(gr_poly
					(pts
						(arc
							(start 0.3048 -0.2032)
							(mid 0.275042 -0.275042)
							(end 0.2032 -0.3048)
						)
						(arc
							(start -0.2032 -0.3048)
							(mid -0.275042 -0.275042)
							(end -0.3048 -0.2032)
						)
						(arc
							(start -0.3048 0.2032)
							(mid -0.275042 0.275042)
							(end -0.2032 0.3048)
						)
						(arc
							(start 0.2032 0.3048)
							(mid 0.275042 0.275042)
							(end 0.3048 0.2032)
						)
					)
					(width 0)
					(fill yes)
				)
			)
		)
		(pad "2" smd custom
			(at 0 0.4445 180)
			(size 0.1524 0.1524)
			(layers "F.Cu" "F.Mask" "F.Paste")
			(net "GND")
			(options
				(clearance outline)
				(anchor circle)
			)
			(primitives
				(gr_poly
					(pts
						(arc
							(start 0.3048 -0.2032)
							(mid 0.275042 -0.275042)
							(end 0.2032 -0.3048)
						)
						(arc
							(start -0.2032 -0.3048)
							(mid -0.275042 -0.275042)
							(end -0.3048 -0.2032)
						)
						(arc
							(start -0.3048 0.2032)
							(mid -0.275042 0.275042)
							(end -0.2032 0.3048)
						)
						(arc
							(start 0.2032 0.3048)
							(mid 0.275042 0.275042)
							(end 0.3048 0.2032)
						)
					)
					(width 0)
					(fill yes)
				)
			)
		)
	)
	(footprint ""
		(layer "F.Cu")
		(at 135.361934 -74.375518 180)
		(property "Reference" "R447"
			(at 0 0 180)
			(layer "F.SilkS")
			(hide yes)
			(effects
				(font
					(size 1.27 1.27)
				)
			)
		)
		(property "Value" "100KR2F-L1-GP"
			(at 0.064008 -3.993896 180)
			(unlocked yes)
			(layer "F.Fab")
			(hide yes)
			(effects
				(font
					(size 1.016 1.016)
					(thickness 0.1524)
				)
			)
		)
		(property "Device Type" "R402H16"
			(at 0.064008 -5.517896 180)
			(unlocked yes)
			(layer "F.Fab")
			(hide yes)
			(effects
				(font
					(size 1.016 1.016)
					(thickness 0.1524)
				)
			)
		)
		(duplicate_pad_numbers_are_jumpers no)
		(fp_line
			(start 0.508 -0.9398)
			(end -0.508 -0.9398)
			(stroke
				(width 0.1524)
				(type default)
			)
			(layer "F.SilkS")
		)
		(fp_line
			(start -0.508 -0.9398)
			(end -0.508 0.9398)
			(stroke
				(width 0.1524)
				(type default)
			)
			(layer "F.SilkS")
		)
		(fp_rect
			(start -0.508 0.9398)
			(end 0.508 -0.9398)
			(stroke
				(width 0)
				(type default)
			)
			(fill no)
			(layer "F.CrtYd")
		)
		(fp_rect
			(start -0.508 0.9398)
			(end 0.508 -0.9398)
			(stroke
				(width 0)
				(type default)
			)
			(fill no)
			(layer "F.Fab")
		)
		(pad "1" smd custom
			(at 0 -0.4445 180)
			(size 0.1397 0.1397)
			(layers "F.Cu" "F.Mask" "F.Paste")
			(net "SPI_CLK0_R")
			(options
				(clearance outline)
				(anchor circle)
			)
			(primitives
				(gr_poly
					(pts
						(arc
							(start -0.1778 -0.2794)
							(mid -0.249642 -0.249642)
							(end -0.2794 -0.1778)
						)
						(arc
							(start -0.2794 0.1778)
							(mid -0.249642 0.249642)
							(end -0.1778 0.2794)
						)
						(arc
							(start 0.1778 0.2794)
							(mid 0.249642 0.249642)
							(end 0.2794 0.1778)
						)
						(arc
							(start 0.2794 -0.1778)
							(mid 0.249642 -0.249642)
							(end 0.1778 -0.2794)
						)
					)
					(width 0)
					(fill yes)
				)
			)
		)
		(pad "2" smd custom
			(at 0 0.4445 180)
			(size 0.1397 0.1397)
			(layers "F.Cu" "F.Mask" "F.Paste")
			(net "GND")
			(options
				(clearance outline)
				(anchor circle)
			)
			(primitives
				(gr_poly
					(pts
						(arc
							(start -0.1778 -0.2794)
							(mid -0.249642 -0.249642)
							(end -0.2794 -0.1778)
						)
						(arc
							(start -0.2794 0.1778)
							(mid -0.249642 0.249642)
							(end -0.1778 0.2794)
						)
						(arc
							(start 0.1778 0.2794)
							(mid 0.249642 0.249642)
							(end 0.2794 0.1778)
						)
						(arc
							(start 0.2794 -0.1778)
							(mid 0.249642 -0.249642)
							(end 0.1778 -0.2794)
						)
					)
					(width 0)
					(fill yes)
				)
			)
		)
	)
	(footprint ""
		(layer "F.Cu")
		(at 132.056124 -196.443092)
		(property "Reference" "R7959"
			(at 0 0 0)
			(layer "F.SilkS")
			(hide yes)
			(effects
				(font
					(size 1.27 1.27)
				)
			)
		)
		(property "Value" "0R2J-2-GP"
			(at 0.064008 -3.993896 0)
			(unlocked yes)
			(layer "F.Fab")
			(hide yes)
			(effects
				(font
					(size 1.016 1.016)
					(thickness 0.1524)
				)
			)
		)
		(property "Device Type" "R402H16"
			(at 0.064008 -5.517896 0)
			(unlocked yes)
			(layer "F.Fab")
			(hide yes)
			(effects
				(font
					(size 1.016 1.016)
					(thickness 0.1524)
				)
			)
		)
		(duplicate_pad_numbers_are_jumpers no)
		(fp_line
			(start -0.508 -0.9398)
			(end -0.508 0.9398)
			(stroke
				(width 0.1524)
				(type default)
			)
			(layer "F.SilkS")
		)
		(fp_line
			(start 0.508 -0.9398)
			(end -0.508 -0.9398)
			(stroke
				(width 0.1524)
				(type default)
			)
			(layer "F.SilkS")
		)
		(fp_rect
			(start -0.508 0.9398)
			(end 0.508 -0.9398)
			(stroke
				(width 0)
				(type default)
			)
			(fill no)
			(layer "F.CrtYd")
		)
		(fp_rect
			(start -0.508 0.9398)
			(end 0.508 -0.9398)
			(stroke
				(width 0)
				(type default)
			)
			(fill no)
			(layer "F.Fab")
		)
		(pad "1" smd custom
			(at 0 -0.4445)
			(size 0.1397 0.1397)
			(layers "F.Cu" "F.Mask" "F.Paste")
			(net "SSD_PWREN2")
			(options
				(clearance outline)
				(anchor circle)
			)
			(primitives
				(gr_poly
					(pts
						(arc
							(start -0.1778 -0.2794)
							(mid -0.249642 -0.249642)
							(end -0.2794 -0.1778)
						)
						(arc
							(start -0.2794 0.1778)
							(mid -0.249642 0.249642)
							(end -0.1778 0.2794)
						)
						(arc
							(start 0.1778 0.2794)
							(mid 0.249642 0.249642)
							(end 0.2794 0.1778)
						)
						(arc
							(start 0.2794 -0.1778)
							(mid 0.249642 -0.249642)
							(end 0.1778 -0.2794)
						)
					)
					(width 0)
					(fill yes)
				)
			)
		)
		(pad "2" smd custom
			(at 0 0.4445)
			(size 0.1397 0.1397)
			(layers "F.Cu" "F.Mask" "F.Paste")
			(net "SSD_PWREN2_R")
			(options
				(clearance outline)
				(anchor circle)
			)
			(primitives
				(gr_poly
					(pts
						(arc
							(start -0.1778 -0.2794)
							(mid -0.249642 -0.249642)
							(end -0.2794 -0.1778)
						)
						(arc
							(start -0.2794 0.1778)
							(mid -0.249642 0.249642)
							(end -0.1778 0.2794)
						)
						(arc
							(start 0.1778 0.2794)
							(mid 0.249642 0.249642)
							(end 0.2794 0.1778)
						)
						(arc
							(start 0.2794 -0.1778)
							(mid 0.249642 -0.249642)
							(end 0.1778 -0.2794)
						)
					)
					(width 0)
					(fill yes)
				)
			)
		)
	)
	(footprint ""
		(layer "F.Cu")
		(at 27.559 -73.3806 180)
		(property "Reference" "R395"
			(at 0 0 180)
			(layer "F.SilkS")
			(hide yes)
			(effects
				(font
					(size 1.27 1.27)
				)
			)
		)
		(property "Value" "10KR2F-2-GP"
			(at 0.064008 -3.993896 180)
			(unlocked yes)
			(layer "F.Fab")
			(hide yes)
			(effects
				(font
					(size 1.016 1.016)
					(thickness 0.1524)
				)
			)
		)
		(property "Device Type" "R402H16"
			(at 0.064008 -5.517896 180)
			(unlocked yes)
			(layer "F.Fab")
			(hide yes)
			(effects
				(font
					(size 1.016 1.016)
					(thickness 0.1524)
				)
			)
		)
		(duplicate_pad_numbers_are_jumpers no)
		(fp_line
			(start 0.508 -0.9398)
			(end -0.508 -0.9398)
			(stroke
				(width 0.1524)
				(type default)
			)
			(layer "F.SilkS")
		)
		(fp_line
			(start -0.508 -0.9398)
			(end -0.508 0.9398)
			(stroke
				(width 0.1524)
				(type default)
			)
			(layer "F.SilkS")
		)
		(fp_rect
			(start -0.508 0.9398)
			(end 0.508 -0.9398)
			(stroke
				(width 0)
				(type default)
			)
			(fill no)
			(layer "F.CrtYd")
		)
		(fp_rect
			(start -0.508 0.9398)
			(end 0.508 -0.9398)
			(stroke
				(width 0)
				(type default)
			)
			(fill no)
			(layer "F.Fab")
		)
		(pad "1" smd custom
			(at 0 -0.4445 180)
			(size 0.1397 0.1397)
			(layers "F.Cu" "F.Mask" "F.Paste")
			(net "P3V3_STBY")
			(options
				(clearance outline)
				(anchor circle)
			)
			(primitives
				(gr_poly
					(pts
						(arc
							(start -0.1778 -0.2794)
							(mid -0.249642 -0.249642)
							(end -0.2794 -0.1778)
						)
						(arc
							(start -0.2794 0.1778)
							(mid -0.249642 0.249642)
							(end -0.1778 0.2794)
						)
						(arc
							(start 0.1778 0.2794)
							(mid 0.249642 0.249642)
							(end 0.2794 0.1778)
						)
						(arc
							(start 0.2794 -0.1778)
							(mid 0.249642 -0.249642)
							(end 0.1778 -0.2794)
						)
					)
					(width 0)
					(fill yes)
				)
			)
		)
		(pad "2" smd custom
			(at 0 0.4445 180)
			(size 0.1397 0.1397)
			(layers "F.Cu" "F.Mask" "F.Paste")
			(net "RMII_PHY_BMC_RXD1")
			(options
				(clearance outline)
				(anchor circle)
			)
			(primitives
				(gr_poly
					(pts
						(arc
							(start -0.1778 -0.2794)
							(mid -0.249642 -0.249642)
							(end -0.2794 -0.1778)
						)
						(arc
							(start -0.2794 0.1778)
							(mid -0.249642 0.249642)
							(end -0.1778 0.2794)
						)
						(arc
							(start 0.1778 0.2794)
							(mid 0.249642 0.249642)
							(end 0.2794 0.1778)
						)
						(arc
							(start 0.2794 -0.1778)
							(mid 0.249642 -0.249642)
							(end 0.1778 -0.2794)
						)
					)
					(width 0)
					(fill yes)
				)
			)
		)
	)
	(footprint ""
		(layer "F.Cu")
		(at 266.827 -26.289 180)
		(property "Reference" "R766"
			(at 0 0 180)
			(layer "F.SilkS")
			(hide yes)
			(effects
				(font
					(size 1.27 1.27)
				)
			)
		)
		(property "Value" "1KR2F-3-GP"
			(at 0.064008 -3.993896 180)
			(unlocked yes)
			(layer "F.Fab")
			(hide yes)
			(effects
				(font
					(size 1.016 1.016)
					(thickness 0.1524)
				)
			)
		)
		(property "Device Type" "R402H16"
			(at 0.064008 -5.517896 180)
			(unlocked yes)
			(layer "F.Fab")
			(hide yes)
			(effects
				(font
					(size 1.016 1.016)
					(thickness 0.1524)
				)
			)
		)
		(duplicate_pad_numbers_are_jumpers no)
		(fp_line
			(start 0.508 -0.9398)
			(end -0.508 -0.9398)
			(stroke
				(width 0.1524)
				(type default)
			)
			(layer "F.SilkS")
		)
		(fp_line
			(start -0.508 -0.9398)
			(end -0.508 0.9398)
			(stroke
				(width 0.1524)
				(type default)
			)
			(layer "F.SilkS")
		)
		(fp_rect
			(start -0.508 0.9398)
			(end 0.508 -0.9398)
			(stroke
				(width 0)
				(type default)
			)
			(fill no)
			(layer "F.CrtYd")
		)
		(fp_rect
			(start -0.508 0.9398)
			(end 0.508 -0.9398)
			(stroke
				(width 0)
				(type default)
			)
			(fill no)
			(layer "F.Fab")
		)
		(pad "1" smd custom
			(at 0 -0.4445 180)
			(size 0.1397 0.1397)
			(layers "F.Cu" "F.Mask" "F.Paste")
			(net "P3V3_GPIO")
			(options
				(clearance outline)
				(anchor circle)
			)
			(primitives
				(gr_poly
					(pts
						(arc
							(start -0.1778 -0.2794)
							(mid -0.249642 -0.249642)
							(end -0.2794 -0.1778)
						)
						(arc
							(start -0.2794 0.1778)
							(mid -0.249642 0.249642)
							(end -0.1778 0.2794)
						)
						(arc
							(start 0.1778 0.2794)
							(mid 0.249642 0.249642)
							(end 0.2794 0.1778)
						)
						(arc
							(start 0.2794 -0.1778)
							(mid 0.249642 -0.249642)
							(end 0.1778 -0.2794)
						)
					)
					(width 0)
					(fill yes)
				)
			)
		)
		(pad "2" smd custom
			(at 0 0.4445 180)
			(size 0.1397 0.1397)
			(layers "F.Cu" "F.Mask" "F.Paste")
			(net "TWI_SCL1")
			(options
				(clearance outline)
				(anchor circle)
			)
			(primitives
				(gr_poly
					(pts
						(arc
							(start -0.1778 -0.2794)
							(mid -0.249642 -0.249642)
							(end -0.2794 -0.1778)
						)
						(arc
							(start -0.2794 0.1778)
							(mid -0.249642 0.249642)
							(end -0.1778 0.2794)
						)
						(arc
							(start 0.1778 0.2794)
							(mid 0.249642 0.249642)
							(end 0.2794 0.1778)
						)
						(arc
							(start 0.2794 -0.1778)
							(mid 0.249642 -0.249642)
							(end 0.1778 -0.2794)
						)
					)
					(width 0)
					(fill yes)
				)
			)
		)
	)
	(footprint ""
		(layer "F.Cu")
		(at 78.613 -180.9496 -90)
		(property "Reference" "C4108"
			(at 0 0 270)
			(layer "F.SilkS")
			(hide yes)
			(effects
				(font
					(size 1.27 1.27)
				)
			)
		)
		(property "Value" "SCD1U25V3KX-GP"
			(at 0 -2.8194 270)
			(unlocked yes)
			(layer "F.Fab")
			(hide yes)
			(effects
				(font
					(size 1.016 1.016)
					(thickness 0.1524)
				)
			)
		)
		(property "Device Type" "C603H36"
			(at 0 -4.3434 270)
			(unlocked yes)
			(layer "F.Fab")
			(hide yes)
			(effects
				(font
					(size 1.016 1.016)
					(thickness 0.1524)
				)
			)
		)
		(duplicate_pad_numbers_are_jumpers no)
		(fp_line
			(start 0.508 0)
			(end -0.508 0)
			(stroke
				(width 0.2032)
				(type default)
			)
			(layer "F.SilkS")
		)
		(fp_rect
			(start -0.5842 1.3335)
			(end 0.5842 -1.3335)
			(stroke
				(width 0)
				(type default)
			)
			(fill no)
			(layer "F.CrtYd")
		)
		(fp_rect
			(start -0.5842 1.3335)
			(end 0.5842 -1.3335)
			(stroke
				(width 0)
				(type default)
			)
			(fill no)
			(layer "F.Fab")
		)
		(pad "1" smd custom
			(at 0 -0.762 270)
			(size 0.2159 0.2159)
			(layers "F.Cu" "F.Mask" "F.Paste")
			(net "GND")
			(options
				(clearance outline)
				(anchor circle)
			)
			(primitives
				(gr_poly
					(pts
						(arc
							(start -0.3302 -0.4318)
							(mid -0.402042 -0.402042)
							(end -0.4318 -0.3302)
						)
						(arc
							(start -0.4318 0.3302)
							(mid -0.402042 0.402042)
							(end -0.3302 0.4318)
						)
						(arc
							(start 0.3302 0.4318)
							(mid 0.402042 0.402042)
							(end 0.4318 0.3302)
						)
						(arc
							(start 0.4318 -0.3302)
							(mid 0.402042 -0.402042)
							(end 0.3302 -0.4318)
						)
					)
					(width 0)
					(fill yes)
				)
			)
		)
		(pad "2" smd custom
			(at 0 0.762 270)
			(size 0.2159 0.2159)
			(layers "F.Cu" "F.Mask" "F.Paste")
			(net "SSD_PWREN5_R")
			(options
				(clearance outline)
				(anchor circle)
			)
			(primitives
				(gr_poly
					(pts
						(arc
							(start -0.3302 -0.4318)
							(mid -0.402042 -0.402042)
							(end -0.4318 -0.3302)
						)
						(arc
							(start -0.4318 0.3302)
							(mid -0.402042 0.402042)
							(end -0.3302 0.4318)
						)
						(arc
							(start 0.3302 0.4318)
							(mid 0.402042 0.402042)
							(end 0.4318 0.3302)
						)
						(arc
							(start 0.4318 -0.3302)
							(mid 0.402042 -0.402042)
							(end 0.3302 -0.4318)
						)
					)
					(width 0)
					(fill yes)
				)
			)
		)
	)
	(footprint ""
		(layer "F.Cu")
		(at 143.898874 -97.55632 90)
		(property "Reference" "PR77"
			(at 0 0 90)
			(layer "F.SilkS")
			(hide yes)
			(effects
				(font
					(size 1.27 1.27)
				)
			)
		)
		(property "Value" "0R3J-0-U-GP"
			(at -0.0254 -2.5146 90)
			(unlocked yes)
			(layer "F.Fab")
			(hide yes)
			(effects
				(font
					(size 1.016 1.016)
					(thickness 0.1524)
				)
			)
		)
		(property "Device Type" "R603H22"
			(at -0.0254 -4.0386 90)
			(unlocked yes)
			(layer "F.Fab")
			(hide yes)
			(effects
				(font
					(size 1.016 1.016)
					(thickness 0.1524)
				)
			)
		)
		(duplicate_pad_numbers_are_jumpers no)
		(fp_line
			(start 0.2032 0)
			(end 0.4826 0)
			(stroke
				(width 0.2032)
				(type default)
			)
			(layer "F.SilkS")
		)
		(fp_line
			(start -0.4826 0)
			(end -0.2032 0)
			(stroke
				(width 0.2032)
				(type default)
			)
			(layer "F.SilkS")
		)
		(fp_rect
			(start -0.5842 1.3335)
			(end 0.5842 -1.3335)
			(stroke
				(width 0)
				(type default)
			)
			(fill no)
			(layer "F.CrtYd")
		)
		(fp_rect
			(start -0.5842 1.3335)
			(end 0.5842 -1.3335)
			(stroke
				(width 0)
				(type default)
			)
			(fill no)
			(layer "F.Fab")
		)
		(pad "1" smd custom
			(at 0 -0.762 90)
			(size 0.2159 0.2159)
			(layers "F.Cu" "F.Mask" "F.Paste")
			(net "P3V3_STBY")
			(options
				(clearance outline)
				(anchor circle)
			)
			(primitives
				(gr_poly
					(pts
						(arc
							(start -0.3302 -0.4318)
							(mid -0.402042 -0.402042)
							(end -0.4318 -0.3302)
						)
						(arc
							(start -0.4318 0.3302)
							(mid -0.402042 0.402042)
							(end -0.3302 0.4318)
						)
						(arc
							(start 0.3302 0.4318)
							(mid 0.402042 0.402042)
							(end 0.4318 0.3302)
						)
						(arc
							(start 0.4318 -0.3302)
							(mid 0.402042 -0.402042)
							(end 0.3302 -0.4318)
						)
					)
					(width 0)
					(fill yes)
				)
			)
		)
		(pad "2" smd custom
			(at 0 0.762 90)
			(size 0.2159 0.2159)
			(layers "F.Cu" "F.Mask" "F.Paste")
			(net "VR_P1V8_STBY_IN")
			(options
				(clearance outline)
				(anchor circle)
			)
			(primitives
				(gr_poly
					(pts
						(arc
							(start -0.3302 -0.4318)
							(mid -0.402042 -0.402042)
							(end -0.4318 -0.3302)
						)
						(arc
							(start -0.4318 0.3302)
							(mid -0.402042 0.402042)
							(end -0.3302 0.4318)
						)
						(arc
							(start 0.3302 0.4318)
							(mid 0.402042 0.402042)
							(end 0.4318 0.3302)
						)
						(arc
							(start 0.4318 -0.3302)
							(mid 0.402042 -0.402042)
							(end 0.3302 -0.4318)
						)
					)
					(width 0)
					(fill yes)
				)
			)
		)
	)
	(footprint ""
		(layer "F.Cu")
		(at 330.740512 -172.432218 180)
		(property "Reference" "R575"
			(at 0 0 180)
			(layer "F.SilkS")
			(hide yes)
			(effects
				(font
					(size 1.27 1.27)
				)
			)
		)
		(property "Value" "10KR2F-2-GP"
			(at 0.064008 -3.993896 180)
			(unlocked yes)
			(layer "F.Fab")
			(hide yes)
			(effects
				(font
					(size 1.016 1.016)
					(thickness 0.1524)
				)
			)
		)
		(property "Device Type" "R402H16"
			(at 0.064008 -5.517896 180)
			(unlocked yes)
			(layer "F.Fab")
			(hide yes)
			(effects
				(font
					(size 1.016 1.016)
					(thickness 0.1524)
				)
			)
		)
		(duplicate_pad_numbers_are_jumpers no)
		(fp_line
			(start 0.508 -0.9398)
			(end -0.508 -0.9398)
			(stroke
				(width 0.1524)
				(type default)
			)
			(layer "F.SilkS")
		)
		(fp_line
			(start -0.508 -0.9398)
			(end -0.508 0.9398)
			(stroke
				(width 0.1524)
				(type default)
			)
			(layer "F.SilkS")
		)
		(fp_rect
			(start -0.508 0.9398)
			(end 0.508 -0.9398)
			(stroke
				(width 0)
				(type default)
			)
			(fill no)
			(layer "F.CrtYd")
		)
		(fp_rect
			(start -0.508 0.9398)
			(end 0.508 -0.9398)
			(stroke
				(width 0)
				(type default)
			)
			(fill no)
			(layer "F.Fab")
		)
		(pad "1" smd custom
			(at 0 -0.4445 180)
			(size 0.1397 0.1397)
			(layers "F.Cu" "F.Mask" "F.Paste")
			(net "GND")
			(options
				(clearance outline)
				(anchor circle)
			)
			(primitives
				(gr_poly
					(pts
						(arc
							(start -0.1778 -0.2794)
							(mid -0.249642 -0.249642)
							(end -0.2794 -0.1778)
						)
						(arc
							(start -0.2794 0.1778)
							(mid -0.249642 0.249642)
							(end -0.1778 0.2794)
						)
						(arc
							(start 0.1778 0.2794)
							(mid 0.249642 0.249642)
							(end 0.2794 0.1778)
						)
						(arc
							(start 0.2794 -0.1778)
							(mid 0.249642 -0.249642)
							(end 0.1778 -0.2794)
						)
					)
					(width 0)
					(fill yes)
				)
			)
		)
		(pad "2" smd custom
			(at 0 0.4445 180)
			(size 0.1397 0.1397)
			(layers "F.Cu" "F.Mask" "F.Paste")
			(net "IOEXP4_AD1")
			(options
				(clearance outline)
				(anchor circle)
			)
			(primitives
				(gr_poly
					(pts
						(arc
							(start -0.1778 -0.2794)
							(mid -0.249642 -0.249642)
							(end -0.2794 -0.1778)
						)
						(arc
							(start -0.2794 0.1778)
							(mid -0.249642 0.249642)
							(end -0.1778 0.2794)
						)
						(arc
							(start 0.1778 0.2794)
							(mid 0.249642 0.249642)
							(end 0.2794 0.1778)
						)
						(arc
							(start 0.2794 -0.1778)
							(mid 0.249642 -0.249642)
							(end 0.1778 -0.2794)
						)
					)
					(width 0)
					(fill yes)
				)
			)
		)
	)
	(footprint ""
		(layer "F.Cu")
		(at 345.188794 -45.893736)
		(property "Reference" "R7902"
			(at 0 0 0)
			(layer "F.SilkS")
			(hide yes)
			(effects
				(font
					(size 1.27 1.27)
				)
			)
		)
		(property "Value" "0R2J-2-GP"
			(at 0.064008 -3.993896 0)
			(unlocked yes)
			(layer "F.Fab")
			(hide yes)
			(effects
				(font
					(size 1.016 1.016)
					(thickness 0.1524)
				)
			)
		)
		(property "Device Type" "R402H16"
			(at 0.064008 -5.517896 0)
			(unlocked yes)
			(layer "F.Fab")
			(hide yes)
			(effects
				(font
					(size 1.016 1.016)
					(thickness 0.1524)
				)
			)
		)
		(duplicate_pad_numbers_are_jumpers no)
		(fp_line
			(start -0.508 -0.9398)
			(end -0.508 0.9398)
			(stroke
				(width 0.1524)
				(type default)
			)
			(layer "F.SilkS")
		)
		(fp_line
			(start 0.508 -0.9398)
			(end -0.508 -0.9398)
			(stroke
				(width 0.1524)
				(type default)
			)
			(layer "F.SilkS")
		)
		(fp_rect
			(start -0.508 0.9398)
			(end 0.508 -0.9398)
			(stroke
				(width 0)
				(type default)
			)
			(fill no)
			(layer "F.CrtYd")
		)
		(fp_rect
			(start -0.508 0.9398)
			(end 0.508 -0.9398)
			(stroke
				(width 0)
				(type default)
			)
			(fill no)
			(layer "F.Fab")
		)
		(pad "1" smd custom
			(at 0 -0.4445)
			(size 0.1397 0.1397)
			(layers "F.Cu" "F.Mask" "F.Paste")
			(net "PM8536_RST#_AND")
			(options
				(clearance outline)
				(anchor circle)
			)
			(primitives
				(gr_poly
					(pts
						(arc
							(start -0.1778 -0.2794)
							(mid -0.249642 -0.249642)
							(end -0.2794 -0.1778)
						)
						(arc
							(start -0.2794 0.1778)
							(mid -0.249642 0.249642)
							(end -0.1778 0.2794)
						)
						(arc
							(start 0.1778 0.2794)
							(mid 0.249642 0.249642)
							(end 0.2794 0.1778)
						)
						(arc
							(start 0.2794 -0.1778)
							(mid 0.249642 -0.249642)
							(end 0.1778 -0.2794)
						)
					)
					(width 0)
					(fill yes)
				)
			)
		)
		(pad "2" smd custom
			(at 0 0.4445)
			(size 0.1397 0.1397)
			(layers "F.Cu" "F.Mask" "F.Paste")
			(net "PM8536_RST#_LS")
			(options
				(clearance outline)
				(anchor circle)
			)
			(primitives
				(gr_poly
					(pts
						(arc
							(start -0.1778 -0.2794)
							(mid -0.249642 -0.249642)
							(end -0.2794 -0.1778)
						)
						(arc
							(start -0.2794 0.1778)
							(mid -0.249642 0.249642)
							(end -0.1778 0.2794)
						)
						(arc
							(start 0.1778 0.2794)
							(mid 0.249642 0.249642)
							(end 0.2794 0.1778)
						)
						(arc
							(start 0.2794 -0.1778)
							(mid 0.249642 -0.249642)
							(end 0.1778 -0.2794)
						)
					)
					(width 0)
					(fill yes)
				)
			)
		)
	)
	(footprint ""
		(layer "F.Cu")
		(at 68.8594 -118.6942 -90)
		(property "Reference" "R307"
			(at 0 0 270)
			(layer "F.SilkS")
			(hide yes)
			(effects
				(font
					(size 1.27 1.27)
				)
			)
		)
		(property "Value" "4K7R2F-GP"
			(at 0.064008 -3.993896 270)
			(unlocked yes)
			(layer "F.Fab")
			(hide yes)
			(effects
				(font
					(size 1.016 1.016)
					(thickness 0.1524)
				)
			)
		)
		(property "Device Type" "R402H16"
			(at 0.064008 -5.517896 270)
			(unlocked yes)
			(layer "F.Fab")
			(hide yes)
			(effects
				(font
					(size 1.016 1.016)
					(thickness 0.1524)
				)
			)
		)
		(duplicate_pad_numbers_are_jumpers no)
		(fp_line
			(start -0.508 -0.9398)
			(end -0.508 0.9398)
			(stroke
				(width 0.1524)
				(type default)
			)
			(layer "F.SilkS")
		)
		(fp_line
			(start 0.508 -0.9398)
			(end -0.508 -0.9398)
			(stroke
				(width 0.1524)
				(type default)
			)
			(layer "F.SilkS")
		)
		(fp_rect
			(start -0.508 0.9398)
			(end 0.508 -0.9398)
			(stroke
				(width 0)
				(type default)
			)
			(fill no)
			(layer "F.CrtYd")
		)
		(fp_rect
			(start -0.508 0.9398)
			(end 0.508 -0.9398)
			(stroke
				(width 0)
				(type default)
			)
			(fill no)
			(layer "F.Fab")
		)
		(pad "1" smd custom
			(at 0 -0.4445 270)
			(size 0.1397 0.1397)
			(layers "F.Cu" "F.Mask" "F.Paste")
			(net "P3V3_STBY")
			(options
				(clearance outline)
				(anchor circle)
			)
			(primitives
				(gr_poly
					(pts
						(arc
							(start -0.1778 -0.2794)
							(mid -0.249642 -0.249642)
							(end -0.2794 -0.1778)
						)
						(arc
							(start -0.2794 0.1778)
							(mid -0.249642 0.249642)
							(end -0.1778 0.2794)
						)
						(arc
							(start 0.1778 0.2794)
							(mid 0.249642 0.249642)
							(end 0.2794 0.1778)
						)
						(arc
							(start 0.2794 -0.1778)
							(mid 0.249642 -0.249642)
							(end 0.1778 -0.2794)
						)
					)
					(width 0)
					(fill yes)
				)
			)
		)
		(pad "2" smd custom
			(at 0 0.4445 270)
			(size 0.1397 0.1397)
			(layers "F.Cu" "F.Mask" "F.Paste")
			(net "I2C4_LS_G2")
			(options
				(clearance outline)
				(anchor circle)
			)
			(primitives
				(gr_poly
					(pts
						(arc
							(start -0.1778 -0.2794)
							(mid -0.249642 -0.249642)
							(end -0.2794 -0.1778)
						)
						(arc
							(start -0.2794 0.1778)
							(mid -0.249642 0.249642)
							(end -0.1778 0.2794)
						)
						(arc
							(start 0.1778 0.2794)
							(mid 0.249642 0.249642)
							(end 0.2794 0.1778)
						)
						(arc
							(start 0.2794 -0.1778)
							(mid 0.249642 -0.249642)
							(end 0.1778 -0.2794)
						)
					)
					(width 0)
					(fill yes)
				)
			)
		)
	)
	(footprint ""
		(layer "F.Cu")
		(at 181.864 -16.256 -90)
		(property "Reference" "SR718"
			(at 0 0 270)
			(layer "F.SilkS")
			(hide yes)
			(effects
				(font
					(size 1.27 1.27)
				)
			)
		)
		(property "Value" "150R2F-1-GP"
			(at 0.064008 -3.993896 270)
			(unlocked yes)
			(layer "F.Fab")
			(hide yes)
			(effects
				(font
					(size 1.016 1.016)
					(thickness 0.1524)
				)
			)
		)
		(property "Device Type" "R402H16"
			(at 0.064008 -5.517896 270)
			(unlocked yes)
			(layer "F.Fab")
			(hide yes)
			(effects
				(font
					(size 1.016 1.016)
					(thickness 0.1524)
				)
			)
		)
		(duplicate_pad_numbers_are_jumpers no)
		(fp_line
			(start -0.508 -0.9398)
			(end -0.508 0.9398)
			(stroke
				(width 0.1524)
				(type default)
			)
			(layer "F.SilkS")
		)
		(fp_line
			(start 0.508 -0.9398)
			(end -0.508 -0.9398)
			(stroke
				(width 0.1524)
				(type default)
			)
			(layer "F.SilkS")
		)
		(fp_rect
			(start -0.508 0.9398)
			(end 0.508 -0.9398)
			(stroke
				(width 0)
				(type default)
			)
			(fill no)
			(layer "F.CrtYd")
		)
		(fp_rect
			(start -0.508 0.9398)
			(end 0.508 -0.9398)
			(stroke
				(width 0)
				(type default)
			)
			(fill no)
			(layer "F.Fab")
		)
		(pad "1" smd custom
			(at 0 -0.4445 270)
			(size 0.1397 0.1397)
			(layers "F.Cu" "F.Mask" "F.Paste")
			(net "P3V3_STBY")
			(options
				(clearance outline)
				(anchor circle)
			)
			(primitives
				(gr_poly
					(pts
						(arc
							(start -0.1778 -0.2794)
							(mid -0.249642 -0.249642)
							(end -0.2794 -0.1778)
						)
						(arc
							(start -0.2794 0.1778)
							(mid -0.249642 0.249642)
							(end -0.1778 0.2794)
						)
						(arc
							(start 0.1778 0.2794)
							(mid 0.249642 0.249642)
							(end 0.2794 0.1778)
						)
						(arc
							(start 0.2794 -0.1778)
							(mid 0.249642 -0.249642)
							(end 0.1778 -0.2794)
						)
					)
					(width 0)
					(fill yes)
				)
			)
		)
		(pad "2" smd custom
			(at 0 0.4445 270)
			(size 0.1397 0.1397)
			(layers "F.Cu" "F.Mask" "F.Paste")
			(net "LED_R_9")
			(options
				(clearance outline)
				(anchor circle)
			)
			(primitives
				(gr_poly
					(pts
						(arc
							(start -0.1778 -0.2794)
							(mid -0.249642 -0.249642)
							(end -0.2794 -0.1778)
						)
						(arc
							(start -0.2794 0.1778)
							(mid -0.249642 0.249642)
							(end -0.1778 0.2794)
						)
						(arc
							(start 0.1778 0.2794)
							(mid 0.249642 0.249642)
							(end 0.2794 0.1778)
						)
						(arc
							(start 0.2794 -0.1778)
							(mid 0.249642 -0.249642)
							(end 0.1778 -0.2794)
						)
					)
					(width 0)
					(fill yes)
				)
			)
		)
	)
	(footprint ""
		(layer "F.Cu")
		(at 47.244 -180.467)
		(property "Reference" "C265"
			(at 0 0 0)
			(layer "F.SilkS")
			(hide yes)
			(effects
				(font
					(size 1.27 1.27)
				)
			)
		)
		(property "Value" "SCD01U50V2KX-1GP"
			(at 1.1811 -2.7051 0)
			(unlocked yes)
			(layer "F.Fab")
			(hide yes)
			(effects
				(font
					(size 1.016 1.016)
					(thickness 0.1524)
				)
			)
		)
		(property "Device Type" "C402H22"
			(at 1.1811 -4.2291 0)
			(unlocked yes)
			(layer "F.Fab")
			(hide yes)
			(effects
				(font
					(size 1.016 1.016)
					(thickness 0.1524)
				)
			)
		)
		(duplicate_pad_numbers_are_jumpers no)
		(fp_rect
			(start -0.4318 0.9525)
			(end 0.4318 -0.9525)
			(stroke
				(width 0)
				(type default)
			)
			(fill no)
			(layer "F.CrtYd")
		)
		(fp_rect
			(start -0.4318 0.9525)
			(end 0.4318 -0.9525)
			(stroke
				(width 0)
				(type default)
			)
			(fill no)
			(layer "F.Fab")
		)
		(pad "1" smd custom
			(at 0 -0.4445)
			(size 0.1524 0.1524)
			(layers "F.Cu" "F.Mask" "F.Paste")
			(net "P3V3_STBY")
			(options
				(clearance outline)
				(anchor circle)
			)
			(primitives
				(gr_poly
					(pts
						(arc
							(start 0.3048 -0.2032)
							(mid 0.275042 -0.275042)
							(end 0.2032 -0.3048)
						)
						(arc
							(start -0.2032 -0.3048)
							(mid -0.275042 -0.275042)
							(end -0.3048 -0.2032)
						)
						(arc
							(start -0.3048 0.2032)
							(mid -0.275042 0.275042)
							(end -0.2032 0.3048)
						)
						(arc
							(start 0.2032 0.3048)
							(mid 0.275042 0.275042)
							(end 0.3048 0.2032)
						)
					)
					(width 0)
					(fill yes)
				)
			)
		)
		(pad "2" smd custom
			(at 0 0.4445)
			(size 0.1524 0.1524)
			(layers "F.Cu" "F.Mask" "F.Paste")
			(net "GND")
			(options
				(clearance outline)
				(anchor circle)
			)
			(primitives
				(gr_poly
					(pts
						(arc
							(start 0.3048 -0.2032)
							(mid 0.275042 -0.275042)
							(end 0.2032 -0.3048)
						)
						(arc
							(start -0.2032 -0.3048)
							(mid -0.275042 -0.275042)
							(end -0.3048 -0.2032)
						)
						(arc
							(start -0.3048 0.2032)
							(mid -0.275042 0.275042)
							(end -0.2032 0.3048)
						)
						(arc
							(start 0.2032 0.3048)
							(mid 0.275042 0.275042)
							(end 0.3048 0.2032)
						)
					)
					(width 0)
					(fill yes)
				)
			)
		)
	)
	(footprint ""
		(layer "F.Cu")
		(at 67.749166 -90.33256 180)
		(property "Reference" "R483"
			(at 0 0 180)
			(layer "F.SilkS")
			(hide yes)
			(effects
				(font
					(size 1.27 1.27)
				)
			)
		)
		(property "Value" "0R2J-2-GP"
			(at 0.064008 -3.993896 180)
			(unlocked yes)
			(layer "F.Fab")
			(hide yes)
			(effects
				(font
					(size 1.016 1.016)
					(thickness 0.1524)
				)
			)
		)
		(property "Device Type" "R402H16"
			(at 0.064008 -5.517896 180)
			(unlocked yes)
			(layer "F.Fab")
			(hide yes)
			(effects
				(font
					(size 1.016 1.016)
					(thickness 0.1524)
				)
			)
		)
		(duplicate_pad_numbers_are_jumpers no)
		(fp_line
			(start 0.508 -0.9398)
			(end -0.508 -0.9398)
			(stroke
				(width 0.1524)
				(type default)
			)
			(layer "F.SilkS")
		)
		(fp_line
			(start -0.508 -0.9398)
			(end -0.508 0.9398)
			(stroke
				(width 0.1524)
				(type default)
			)
			(layer "F.SilkS")
		)
		(fp_rect
			(start -0.508 0.9398)
			(end 0.508 -0.9398)
			(stroke
				(width 0)
				(type default)
			)
			(fill no)
			(layer "F.CrtYd")
		)
		(fp_rect
			(start -0.508 0.9398)
			(end 0.508 -0.9398)
			(stroke
				(width 0)
				(type default)
			)
			(fill no)
			(layer "F.Fab")
		)
		(pad "1" smd custom
			(at 0 -0.4445 180)
			(size 0.1397 0.1397)
			(layers "F.Cu" "F.Mask" "F.Paste")
			(net "HB_A_OUT")
			(options
				(clearance outline)
				(anchor circle)
			)
			(primitives
				(gr_poly
					(pts
						(arc
							(start -0.1778 -0.2794)
							(mid -0.249642 -0.249642)
							(end -0.2794 -0.1778)
						)
						(arc
							(start -0.2794 0.1778)
							(mid -0.249642 0.249642)
							(end -0.1778 0.2794)
						)
						(arc
							(start 0.1778 0.2794)
							(mid 0.249642 0.249642)
							(end 0.2794 0.1778)
						)
						(arc
							(start 0.2794 -0.1778)
							(mid 0.249642 -0.249642)
							(end 0.1778 -0.2794)
						)
					)
					(width 0)
					(fill yes)
				)
			)
		)
		(pad "2" smd custom
			(at 0 0.4445 180)
			(size 0.1397 0.1397)
			(layers "F.Cu" "F.Mask" "F.Paste")
			(net "HB_OUT")
			(options
				(clearance outline)
				(anchor circle)
			)
			(primitives
				(gr_poly
					(pts
						(arc
							(start -0.1778 -0.2794)
							(mid -0.249642 -0.249642)
							(end -0.2794 -0.1778)
						)
						(arc
							(start -0.2794 0.1778)
							(mid -0.249642 0.249642)
							(end -0.1778 0.2794)
						)
						(arc
							(start 0.1778 0.2794)
							(mid 0.249642 0.249642)
							(end 0.2794 0.1778)
						)
						(arc
							(start 0.2794 -0.1778)
							(mid 0.249642 -0.249642)
							(end 0.1778 -0.2794)
						)
					)
					(width 0)
					(fill yes)
				)
			)
		)
	)
	(footprint ""
		(layer "F.Cu")
		(at 275.008086 -212.420454 180)
		(property "Reference" "C100"
			(at 0 0 180)
			(layer "F.SilkS")
			(hide yes)
			(effects
				(font
					(size 1.27 1.27)
				)
			)
		)
		(property "Value" "SCD22U10V2KX-1GP"
			(at 1.1811 -2.7051 180)
			(unlocked yes)
			(layer "F.Fab")
			(hide yes)
			(effects
				(font
					(size 1.016 1.016)
					(thickness 0.1524)
				)
			)
		)
		(property "Device Type" "C402H22"
			(at 1.1811 -4.2291 180)
			(unlocked yes)
			(layer "F.Fab")
			(hide yes)
			(effects
				(font
					(size 1.016 1.016)
					(thickness 0.1524)
				)
			)
		)
		(duplicate_pad_numbers_are_jumpers no)
		(fp_rect
			(start -0.4318 0.9525)
			(end 0.4318 -0.9525)
			(stroke
				(width 0)
				(type default)
			)
			(fill no)
			(layer "F.CrtYd")
		)
		(fp_rect
			(start -0.4318 0.9525)
			(end 0.4318 -0.9525)
			(stroke
				(width 0)
				(type default)
			)
			(fill no)
			(layer "F.Fab")
		)
		(pad "1" smd custom
			(at 0 -0.4445 180)
			(size 0.1524 0.1524)
			(layers "F.Cu" "F.Mask" "F.Paste")
			(net "PCIE_TX_CAP_N34")
			(options
				(clearance outline)
				(anchor circle)
			)
			(primitives
				(gr_poly
					(pts
						(arc
							(start 0.3048 -0.2032)
							(mid 0.275042 -0.275042)
							(end 0.2032 -0.3048)
						)
						(arc
							(start -0.2032 -0.3048)
							(mid -0.275042 -0.275042)
							(end -0.3048 -0.2032)
						)
						(arc
							(start -0.3048 0.2032)
							(mid -0.275042 0.275042)
							(end -0.2032 0.3048)
						)
						(arc
							(start 0.2032 0.3048)
							(mid 0.275042 0.275042)
							(end 0.3048 0.2032)
						)
					)
					(width 0)
					(fill yes)
				)
			)
		)
		(pad "2" smd custom
			(at 0 0.4445 180)
			(size 0.1524 0.1524)
			(layers "F.Cu" "F.Mask" "F.Paste")
			(net "PCIE_TX_N34")
			(options
				(clearance outline)
				(anchor circle)
			)
			(primitives
				(gr_poly
					(pts
						(arc
							(start 0.3048 -0.2032)
							(mid 0.275042 -0.275042)
							(end 0.2032 -0.3048)
						)
						(arc
							(start -0.2032 -0.3048)
							(mid -0.275042 -0.275042)
							(end -0.3048 -0.2032)
						)
						(arc
							(start -0.3048 0.2032)
							(mid -0.275042 0.275042)
							(end -0.2032 0.3048)
						)
						(arc
							(start 0.2032 0.3048)
							(mid 0.275042 0.275042)
							(end 0.3048 0.2032)
						)
					)
					(width 0)
					(fill yes)
				)
			)
		)
	)
	(footprint ""
		(layer "F.Cu")
		(at 46.186852 -32.819594)
		(property "Reference" "R545"
			(at 0 0 0)
			(layer "F.SilkS")
			(hide yes)
			(effects
				(font
					(size 1.27 1.27)
				)
			)
		)
		(property "Value" "0R3J-0-U-GP"
			(at -0.0254 -2.5146 0)
			(unlocked yes)
			(layer "F.Fab")
			(hide yes)
			(effects
				(font
					(size 1.016 1.016)
					(thickness 0.1524)
				)
			)
		)
		(property "Device Type" "R603H22"
			(at -0.0254 -4.0386 0)
			(unlocked yes)
			(layer "F.Fab")
			(hide yes)
			(effects
				(font
					(size 1.016 1.016)
					(thickness 0.1524)
				)
			)
		)
		(duplicate_pad_numbers_are_jumpers no)
		(fp_line
			(start -0.4826 0)
			(end -0.2032 0)
			(stroke
				(width 0.2032)
				(type default)
			)
			(layer "F.SilkS")
		)
		(fp_line
			(start 0.2032 0)
			(end 0.4826 0)
			(stroke
				(width 0.2032)
				(type default)
			)
			(layer "F.SilkS")
		)
		(fp_rect
			(start -0.5842 1.3335)
			(end 0.5842 -1.3335)
			(stroke
				(width 0)
				(type default)
			)
			(fill no)
			(layer "F.CrtYd")
		)
		(fp_rect
			(start -0.5842 1.3335)
			(end 0.5842 -1.3335)
			(stroke
				(width 0)
				(type default)
			)
			(fill no)
			(layer "F.Fab")
		)
		(pad "1" smd custom
			(at 0 -0.762)
			(size 0.2159 0.2159)
			(layers "F.Cu" "F.Mask" "F.Paste")
			(net "AGND_USB")
			(options
				(clearance outline)
				(anchor circle)
			)
			(primitives
				(gr_poly
					(pts
						(arc
							(start -0.3302 -0.4318)
							(mid -0.402042 -0.402042)
							(end -0.4318 -0.3302)
						)
						(arc
							(start -0.4318 0.3302)
							(mid -0.402042 0.402042)
							(end -0.3302 0.4318)
						)
						(arc
							(start 0.3302 0.4318)
							(mid 0.402042 0.402042)
							(end 0.4318 0.3302)
						)
						(arc
							(start 0.4318 -0.3302)
							(mid 0.402042 -0.402042)
							(end 0.3302 -0.4318)
						)
					)
					(width 0)
					(fill yes)
				)
			)
		)
		(pad "2" smd custom
			(at 0 0.762)
			(size 0.2159 0.2159)
			(layers "F.Cu" "F.Mask" "F.Paste")
			(net "GND")
			(options
				(clearance outline)
				(anchor circle)
			)
			(primitives
				(gr_poly
					(pts
						(arc
							(start -0.3302 -0.4318)
							(mid -0.402042 -0.402042)
							(end -0.4318 -0.3302)
						)
						(arc
							(start -0.4318 0.3302)
							(mid -0.402042 0.402042)
							(end -0.3302 0.4318)
						)
						(arc
							(start 0.3302 0.4318)
							(mid 0.402042 0.402042)
							(end 0.4318 0.3302)
						)
						(arc
							(start 0.4318 -0.3302)
							(mid 0.402042 -0.402042)
							(end 0.3302 -0.4318)
						)
					)
					(width 0)
					(fill yes)
				)
			)
		)
	)
	(footprint ""
		(layer "F.Cu")
		(at 337.852512 -172.432218)
		(property "Reference" "R7939"
			(at 0 0 0)
			(layer "F.SilkS")
			(hide yes)
			(effects
				(font
					(size 1.27 1.27)
				)
			)
		)
		(property "Value" "0R2J-2-GP"
			(at 0.064008 -3.993896 0)
			(unlocked yes)
			(layer "F.Fab")
			(hide yes)
			(effects
				(font
					(size 1.016 1.016)
					(thickness 0.1524)
				)
			)
		)
		(property "Device Type" "R402H16"
			(at 0.064008 -5.517896 0)
			(unlocked yes)
			(layer "F.Fab")
			(hide yes)
			(effects
				(font
					(size 1.016 1.016)
					(thickness 0.1524)
				)
			)
		)
		(duplicate_pad_numbers_are_jumpers no)
		(fp_line
			(start -0.508 -0.9398)
			(end -0.508 0.9398)
			(stroke
				(width 0.1524)
				(type default)
			)
			(layer "F.SilkS")
		)
		(fp_line
			(start 0.508 -0.9398)
			(end -0.508 -0.9398)
			(stroke
				(width 0.1524)
				(type default)
			)
			(layer "F.SilkS")
		)
		(fp_rect
			(start -0.508 0.9398)
			(end 0.508 -0.9398)
			(stroke
				(width 0)
				(type default)
			)
			(fill no)
			(layer "F.CrtYd")
		)
		(fp_rect
			(start -0.508 0.9398)
			(end 0.508 -0.9398)
			(stroke
				(width 0)
				(type default)
			)
			(fill no)
			(layer "F.Fab")
		)
		(pad "1" smd custom
			(at 0 -0.4445)
			(size 0.1397 0.1397)
			(layers "F.Cu" "F.Mask" "F.Paste")
			(net "SSD_ATNLED#9")
			(options
				(clearance outline)
				(anchor circle)
			)
			(primitives
				(gr_poly
					(pts
						(arc
							(start -0.1778 -0.2794)
							(mid -0.249642 -0.249642)
							(end -0.2794 -0.1778)
						)
						(arc
							(start -0.2794 0.1778)
							(mid -0.249642 0.249642)
							(end -0.1778 0.2794)
						)
						(arc
							(start 0.1778 0.2794)
							(mid 0.249642 0.249642)
							(end 0.2794 0.1778)
						)
						(arc
							(start 0.2794 -0.1778)
							(mid 0.249642 -0.249642)
							(end 0.1778 -0.2794)
						)
					)
					(width 0)
					(fill yes)
				)
			)
		)
		(pad "2" smd custom
			(at 0 0.4445)
			(size 0.1397 0.1397)
			(layers "F.Cu" "F.Mask" "F.Paste")
			(net "SSD_ATNLED#9_R")
			(options
				(clearance outline)
				(anchor circle)
			)
			(primitives
				(gr_poly
					(pts
						(arc
							(start -0.1778 -0.2794)
							(mid -0.249642 -0.249642)
							(end -0.2794 -0.1778)
						)
						(arc
							(start -0.2794 0.1778)
							(mid -0.249642 0.249642)
							(end -0.1778 0.2794)
						)
						(arc
							(start 0.1778 0.2794)
							(mid 0.249642 0.249642)
							(end 0.2794 0.1778)
						)
						(arc
							(start 0.2794 -0.1778)
							(mid 0.249642 -0.249642)
							(end 0.1778 -0.2794)
						)
					)
					(width 0)
					(fill yes)
				)
			)
		)
	)
	(footprint ""
		(layer "F.Cu")
		(at 10.287 -105.156 90)
		(property "Reference" "PR72"
			(at 0 0 90)
			(layer "F.SilkS")
			(hide yes)
			(effects
				(font
					(size 1.27 1.27)
				)
			)
		)
		(property "Value" "0R3J-0-U-GP"
			(at -0.0254 -2.5146 90)
			(unlocked yes)
			(layer "F.Fab")
			(hide yes)
			(effects
				(font
					(size 1.016 1.016)
					(thickness 0.1524)
				)
			)
		)
		(property "Device Type" "R603H22"
			(at -0.0254 -4.0386 90)
			(unlocked yes)
			(layer "F.Fab")
			(hide yes)
			(effects
				(font
					(size 1.016 1.016)
					(thickness 0.1524)
				)
			)
		)
		(duplicate_pad_numbers_are_jumpers no)
		(fp_line
			(start 0.2032 0)
			(end 0.4826 0)
			(stroke
				(width 0.2032)
				(type default)
			)
			(layer "F.SilkS")
		)
		(fp_line
			(start -0.4826 0)
			(end -0.2032 0)
			(stroke
				(width 0.2032)
				(type default)
			)
			(layer "F.SilkS")
		)
		(fp_rect
			(start -0.5842 1.3335)
			(end 0.5842 -1.3335)
			(stroke
				(width 0)
				(type default)
			)
			(fill no)
			(layer "F.CrtYd")
		)
		(fp_rect
			(start -0.5842 1.3335)
			(end 0.5842 -1.3335)
			(stroke
				(width 0)
				(type default)
			)
			(fill no)
			(layer "F.Fab")
		)
		(pad "1" smd custom
			(at 0 -0.762 90)
			(size 0.2159 0.2159)
			(layers "F.Cu" "F.Mask" "F.Paste")
			(net "PWRGD_P1V538_STBY")
			(options
				(clearance outline)
				(anchor circle)
			)
			(primitives
				(gr_poly
					(pts
						(arc
							(start -0.3302 -0.4318)
							(mid -0.402042 -0.402042)
							(end -0.4318 -0.3302)
						)
						(arc
							(start -0.4318 0.3302)
							(mid -0.402042 0.402042)
							(end -0.3302 0.4318)
						)
						(arc
							(start 0.3302 0.4318)
							(mid 0.402042 0.402042)
							(end 0.4318 0.3302)
						)
						(arc
							(start 0.4318 -0.3302)
							(mid 0.402042 -0.402042)
							(end 0.3302 -0.4318)
						)
					)
					(width 0)
					(fill yes)
				)
			)
		)
		(pad "2" smd custom
			(at 0 0.762 90)
			(size 0.2159 0.2159)
			(layers "F.Cu" "F.Mask" "F.Paste")
			(net "VR_P1V26_STBY_EN_R")
			(options
				(clearance outline)
				(anchor circle)
			)
			(primitives
				(gr_poly
					(pts
						(arc
							(start -0.3302 -0.4318)
							(mid -0.402042 -0.402042)
							(end -0.4318 -0.3302)
						)
						(arc
							(start -0.4318 0.3302)
							(mid -0.402042 0.402042)
							(end -0.3302 0.4318)
						)
						(arc
							(start 0.3302 0.4318)
							(mid 0.402042 0.402042)
							(end 0.4318 0.3302)
						)
						(arc
							(start 0.4318 -0.3302)
							(mid 0.402042 -0.402042)
							(end 0.3302 -0.4318)
						)
					)
					(width 0)
					(fill yes)
				)
			)
		)
	)
	(footprint ""
		(layer "F.Cu")
		(at 199.6186 -18.8214 90)
		(property "Reference" "R706"
			(at 0 0 90)
			(layer "F.SilkS")
			(hide yes)
			(effects
				(font
					(size 1.27 1.27)
				)
			)
		)
		(property "Value" "4K7R2F-GP"
			(at 0.064008 -3.993896 90)
			(unlocked yes)
			(layer "F.Fab")
			(hide yes)
			(effects
				(font
					(size 1.016 1.016)
					(thickness 0.1524)
				)
			)
		)
		(property "Device Type" "R402H16"
			(at 0.064008 -5.517896 90)
			(unlocked yes)
			(layer "F.Fab")
			(hide yes)
			(effects
				(font
					(size 1.016 1.016)
					(thickness 0.1524)
				)
			)
		)
		(duplicate_pad_numbers_are_jumpers no)
		(fp_line
			(start 0.508 -0.9398)
			(end -0.508 -0.9398)
			(stroke
				(width 0.1524)
				(type default)
			)
			(layer "F.SilkS")
		)
		(fp_line
			(start -0.508 -0.9398)
			(end -0.508 0.9398)
			(stroke
				(width 0.1524)
				(type default)
			)
			(layer "F.SilkS")
		)
		(fp_rect
			(start -0.508 0.9398)
			(end 0.508 -0.9398)
			(stroke
				(width 0)
				(type default)
			)
			(fill no)
			(layer "F.CrtYd")
		)
		(fp_rect
			(start -0.508 0.9398)
			(end 0.508 -0.9398)
			(stroke
				(width 0)
				(type default)
			)
			(fill no)
			(layer "F.Fab")
		)
		(pad "1" smd custom
			(at 0 -0.4445 90)
			(size 0.1397 0.1397)
			(layers "F.Cu" "F.Mask" "F.Paste")
			(net "MINISAS_CN16_B_I2C_INT#")
			(options
				(clearance outline)
				(anchor circle)
			)
			(primitives
				(gr_poly
					(pts
						(arc
							(start -0.1778 -0.2794)
							(mid -0.249642 -0.249642)
							(end -0.2794 -0.1778)
						)
						(arc
							(start -0.2794 0.1778)
							(mid -0.249642 0.249642)
							(end -0.1778 0.2794)
						)
						(arc
							(start 0.1778 0.2794)
							(mid 0.249642 0.249642)
							(end 0.2794 0.1778)
						)
						(arc
							(start 0.2794 -0.1778)
							(mid 0.249642 -0.249642)
							(end 0.1778 -0.2794)
						)
					)
					(width 0)
					(fill yes)
				)
			)
		)
		(pad "2" smd custom
			(at 0 0.4445 90)
			(size 0.1397 0.1397)
			(layers "F.Cu" "F.Mask" "F.Paste")
			(net "P3V3_STBY")
			(options
				(clearance outline)
				(anchor circle)
			)
			(primitives
				(gr_poly
					(pts
						(arc
							(start -0.1778 -0.2794)
							(mid -0.249642 -0.249642)
							(end -0.2794 -0.1778)
						)
						(arc
							(start -0.2794 0.1778)
							(mid -0.249642 0.249642)
							(end -0.1778 0.2794)
						)
						(arc
							(start 0.1778 0.2794)
							(mid 0.249642 0.249642)
							(end 0.2794 0.1778)
						)
						(arc
							(start 0.2794 -0.1778)
							(mid 0.249642 -0.249642)
							(end 0.1778 -0.2794)
						)
					)
					(width 0)
					(fill yes)
				)
			)
		)
	)
	(footprint ""
		(layer "F.Cu")
		(at 50.165 -145.296128)
		(property "Reference" "SR853"
			(at 0 0 0)
			(layer "F.SilkS")
			(hide yes)
			(effects
				(font
					(size 1.27 1.27)
				)
			)
		)
		(property "Value" "4K75R2F-1-GP"
			(at 0.064008 -3.993896 0)
			(unlocked yes)
			(layer "F.Fab")
			(hide yes)
			(effects
				(font
					(size 1.016 1.016)
					(thickness 0.1524)
				)
			)
		)
		(property "Device Type" "R402H16"
			(at 0.064008 -5.517896 0)
			(unlocked yes)
			(layer "F.Fab")
			(hide yes)
			(effects
				(font
					(size 1.016 1.016)
					(thickness 0.1524)
				)
			)
		)
		(duplicate_pad_numbers_are_jumpers no)
		(fp_line
			(start -0.508 -0.9398)
			(end -0.508 0.9398)
			(stroke
				(width 0.1524)
				(type default)
			)
			(layer "F.SilkS")
		)
		(fp_line
			(start 0.508 -0.9398)
			(end -0.508 -0.9398)
			(stroke
				(width 0.1524)
				(type default)
			)
			(layer "F.SilkS")
		)
		(fp_rect
			(start -0.508 0.9398)
			(end 0.508 -0.9398)
			(stroke
				(width 0)
				(type default)
			)
			(fill no)
			(layer "F.CrtYd")
		)
		(fp_rect
			(start -0.508 0.9398)
			(end 0.508 -0.9398)
			(stroke
				(width 0)
				(type default)
			)
			(fill no)
			(layer "F.Fab")
		)
		(pad "1" smd custom
			(at 0 -0.4445)
			(size 0.1397 0.1397)
			(layers "F.Cu" "F.Mask" "F.Paste")
			(net "P3V3_STBY")
			(options
				(clearance outline)
				(anchor circle)
			)
			(primitives
				(gr_poly
					(pts
						(arc
							(start -0.1778 -0.2794)
							(mid -0.249642 -0.249642)
							(end -0.2794 -0.1778)
						)
						(arc
							(start -0.2794 0.1778)
							(mid -0.249642 0.249642)
							(end -0.1778 0.2794)
						)
						(arc
							(start 0.1778 0.2794)
							(mid 0.249642 0.249642)
							(end 0.2794 0.1778)
						)
						(arc
							(start 0.2794 -0.1778)
							(mid 0.249642 -0.249642)
							(end 0.1778 -0.2794)
						)
					)
					(width 0)
					(fill yes)
				)
			)
		)
		(pad "2" smd custom
			(at 0 0.4445)
			(size 0.1397 0.1397)
			(layers "F.Cu" "F.Mask" "F.Paste")
			(net "BMC_FW_DET_BOARD_VER_2")
			(options
				(clearance outline)
				(anchor circle)
			)
			(primitives
				(gr_poly
					(pts
						(arc
							(start -0.1778 -0.2794)
							(mid -0.249642 -0.249642)
							(end -0.2794 -0.1778)
						)
						(arc
							(start -0.2794 0.1778)
							(mid -0.249642 0.249642)
							(end -0.1778 0.2794)
						)
						(arc
							(start 0.1778 0.2794)
							(mid 0.249642 0.249642)
							(end 0.2794 0.1778)
						)
						(arc
							(start 0.2794 -0.1778)
							(mid 0.249642 -0.249642)
							(end 0.1778 -0.2794)
						)
					)
					(width 0)
					(fill yes)
				)
			)
		)
	)
	(footprint ""
		(layer "F.Cu")
		(at 131.252468 -54.760876 180)
		(property "Reference" "SCN9"
			(at 0 0 180)
			(layer "F.SilkS")
			(hide yes)
			(effects
				(font
					(size 1.27 1.27)
				)
			)
		)
		(property "Value" "JWT-CON4-S24-GP"
			(at -7.3787 1.4351 180)
			(unlocked yes)
			(layer "F.Fab")
			(hide yes)
			(effects
				(font
					(size 1.016 1.016)
					(thickness 0.1524)
				)
			)
		)
		(property "Device Type" "A2541WV0-1QX4PA-6T"
			(at -7.3787 -0.0889 180)
			(unlocked yes)
			(layer "F.Fab")
			(hide yes)
			(effects
				(font
					(size 1.016 1.016)
					(thickness 0.1524)
				)
			)
		)
		(duplicate_pad_numbers_are_jumpers no)
		(fp_line
			(start 5.334 1.524)
			(end 5.334 -1.524)
			(stroke
				(width 0.1524)
				(type default)
			)
			(layer "F.SilkS")
		)
		(fp_line
			(start 5.334 -1.524)
			(end -5.334 -1.524)
			(stroke
				(width 0.1524)
				(type default)
			)
			(layer "F.SilkS")
		)
		(fp_line
			(start -4.191 -1.651)
			(end -5.461 -1.651)
			(stroke
				(width 0.4064)
				(type default)
			)
			(layer "F.SilkS")
		)
		(fp_line
			(start -5.334 1.524)
			(end 5.334 1.524)
			(stroke
				(width 0.1524)
				(type default)
			)
			(layer "F.SilkS")
		)
		(fp_line
			(start -5.334 -1.524)
			(end -5.334 1.524)
			(stroke
				(width 0.1524)
				(type default)
			)
			(layer "F.SilkS")
		)
		(fp_line
			(start -5.461 -1.651)
			(end -5.461 -0.381)
			(stroke
				(width 0.4064)
				(type default)
			)
			(layer "F.SilkS")
		)
		(fp_circle
			(center 3.81 0)
			(end 2.7432 0)
			(stroke
				(width 0.3048)
				(type default)
			)
			(fill no)
			(layer "F.SilkS")
		)
		(fp_circle
			(center 1.27 0)
			(end 0.2032 0)
			(stroke
				(width 0.3048)
				(type default)
			)
			(fill no)
			(layer "F.SilkS")
		)
		(fp_circle
			(center -1.27 0)
			(end -2.3368 0)
			(stroke
				(width 0.3048)
				(type default)
			)
			(fill no)
			(layer "F.SilkS")
		)
		(fp_circle
			(center -3.81 0)
			(end -4.8768 0)
			(stroke
				(width 0.3048)
				(type default)
			)
			(fill no)
			(layer "F.SilkS")
		)
		(fp_rect
			(start -5.08 1.27)
			(end 5.08 -1.27)
			(stroke
				(width 0)
				(type default)
			)
			(fill no)
			(layer "F.CrtYd")
		)
		(fp_poly
			(pts
				(xy -5.588 1.778) (xy -5.588 -1.778) (xy 5.588 -1.778) (xy 5.588 1.2573) (xy 5.08 1.2573) (xy 5.08 -1.27)
				(xy -5.08 -1.27) (xy -5.08 1.27) (xy 5.588 1.27) (xy 5.588 1.778)
			)
			(stroke
				(width 0)
				(type default)
			)
			(fill no)
			(layer "F.CrtYd")
		)
		(fp_rect
			(start -5.588 1.778)
			(end 5.588 -1.778)
			(stroke
				(width 0)
				(type default)
			)
			(fill no)
			(layer "F.Fab")
		)
		(pad "1" thru_hole circle
			(at -3.81 0 180)
			(size 1.4224 1.4224)
			(drill 1.016)
			(layers "*.Cu" "*.Mask")
			(remove_unused_layers no)
			(net "P5V_STBY")
			(clearance 0.1524)
			(thermal_gap 0.1524)
		)
		(pad "2" thru_hole circle
			(at -1.27 0 180)
			(size 1.4224 1.4224)
			(drill 1.016)
			(layers "*.Cu" "*.Mask")
			(remove_unused_layers no)
			(net "PMC_R_TXD5")
			(clearance 0.1524)
			(thermal_gap 0.1524)
		)
		(pad "3" thru_hole circle
			(at 1.27 0 180)
			(size 1.4224 1.4224)
			(drill 1.016)
			(layers "*.Cu" "*.Mask")
			(remove_unused_layers no)
			(net "PMC_R_RXD5")
			(clearance 0.1524)
			(thermal_gap 0.1524)
		)
		(pad "4" thru_hole circle
			(at 3.81 0 180)
			(size 1.4224 1.4224)
			(drill 1.016)
			(layers "*.Cu" "*.Mask")
			(remove_unused_layers no)
			(net "GND")
			(clearance 0.1524)
			(thermal_gap 0.1524)
		)
	)
	(footprint ""
		(layer "F.Cu")
		(at 139.408154 -212.420454 180)
		(property "Reference" "C343"
			(at 0 0 180)
			(layer "F.SilkS")
			(hide yes)
			(effects
				(font
					(size 1.27 1.27)
				)
			)
		)
		(property "Value" "SCD22U10V2KX-1GP"
			(at 1.1811 -2.7051 180)
			(unlocked yes)
			(layer "F.Fab")
			(hide yes)
			(effects
				(font
					(size 1.016 1.016)
					(thickness 0.1524)
				)
			)
		)
		(property "Device Type" "C402H22"
			(at 1.1811 -4.2291 180)
			(unlocked yes)
			(layer "F.Fab")
			(hide yes)
			(effects
				(font
					(size 1.016 1.016)
					(thickness 0.1524)
				)
			)
		)
		(duplicate_pad_numbers_are_jumpers no)
		(fp_rect
			(start -0.4318 0.9525)
			(end 0.4318 -0.9525)
			(stroke
				(width 0)
				(type default)
			)
			(fill no)
			(layer "F.CrtYd")
		)
		(fp_rect
			(start -0.4318 0.9525)
			(end 0.4318 -0.9525)
			(stroke
				(width 0)
				(type default)
			)
			(fill no)
			(layer "F.Fab")
		)
		(pad "1" smd custom
			(at 0 -0.4445 180)
			(size 0.1524 0.1524)
			(layers "F.Cu" "F.Mask" "F.Paste")
			(net "PCIE_TX_CAP_N59")
			(options
				(clearance outline)
				(anchor circle)
			)
			(primitives
				(gr_poly
					(pts
						(arc
							(start 0.3048 -0.2032)
							(mid 0.275042 -0.275042)
							(end 0.2032 -0.3048)
						)
						(arc
							(start -0.2032 -0.3048)
							(mid -0.275042 -0.275042)
							(end -0.3048 -0.2032)
						)
						(arc
							(start -0.3048 0.2032)
							(mid -0.275042 0.275042)
							(end -0.2032 0.3048)
						)
						(arc
							(start 0.2032 0.3048)
							(mid 0.275042 0.275042)
							(end 0.3048 0.2032)
						)
					)
					(width 0)
					(fill yes)
				)
			)
		)
		(pad "2" smd custom
			(at 0 0.4445 180)
			(size 0.1524 0.1524)
			(layers "F.Cu" "F.Mask" "F.Paste")
			(net "PCIE_TX_N59")
			(options
				(clearance outline)
				(anchor circle)
			)
			(primitives
				(gr_poly
					(pts
						(arc
							(start 0.3048 -0.2032)
							(mid 0.275042 -0.275042)
							(end 0.2032 -0.3048)
						)
						(arc
							(start -0.2032 -0.3048)
							(mid -0.275042 -0.275042)
							(end -0.3048 -0.2032)
						)
						(arc
							(start -0.3048 0.2032)
							(mid -0.275042 0.275042)
							(end -0.2032 0.3048)
						)
						(arc
							(start 0.2032 0.3048)
							(mid 0.275042 0.275042)
							(end 0.3048 0.2032)
						)
					)
					(width 0)
					(fill yes)
				)
			)
		)
	)
	(footprint ""
		(layer "F.Cu")
		(at 153.4922 -33.5026)
		(property "Reference" "C395"
			(at 0 0 0)
			(layer "F.SilkS")
			(hide yes)
			(effects
				(font
					(size 1.27 1.27)
				)
			)
		)
		(property "Value" "SCD22U10V2KX-1GP"
			(at 1.1811 -2.7051 0)
			(unlocked yes)
			(layer "F.Fab")
			(hide yes)
			(effects
				(font
					(size 1.016 1.016)
					(thickness 0.1524)
				)
			)
		)
		(property "Device Type" "C402H22"
			(at 1.1811 -4.2291 0)
			(unlocked yes)
			(layer "F.Fab")
			(hide yes)
			(effects
				(font
					(size 1.016 1.016)
					(thickness 0.1524)
				)
			)
		)
		(duplicate_pad_numbers_are_jumpers no)
		(fp_rect
			(start -0.4318 0.9525)
			(end 0.4318 -0.9525)
			(stroke
				(width 0)
				(type default)
			)
			(fill no)
			(layer "F.CrtYd")
		)
		(fp_rect
			(start -0.4318 0.9525)
			(end 0.4318 -0.9525)
			(stroke
				(width 0)
				(type default)
			)
			(fill no)
			(layer "F.Fab")
		)
		(pad "1" smd custom
			(at 0 -0.4445)
			(size 0.1524 0.1524)
			(layers "F.Cu" "F.Mask" "F.Paste")
			(net "PCIE_TX_CAP_N87")
			(options
				(clearance outline)
				(anchor circle)
			)
			(primitives
				(gr_poly
					(pts
						(arc
							(start 0.3048 -0.2032)
							(mid 0.275042 -0.275042)
							(end 0.2032 -0.3048)
						)
						(arc
							(start -0.2032 -0.3048)
							(mid -0.275042 -0.275042)
							(end -0.3048 -0.2032)
						)
						(arc
							(start -0.3048 0.2032)
							(mid -0.275042 0.275042)
							(end -0.2032 0.3048)
						)
						(arc
							(start 0.2032 0.3048)
							(mid 0.275042 0.275042)
							(end 0.3048 0.2032)
						)
					)
					(width 0)
					(fill yes)
				)
			)
		)
		(pad "2" smd custom
			(at 0 0.4445)
			(size 0.1524 0.1524)
			(layers "F.Cu" "F.Mask" "F.Paste")
			(net "PCIE_TX_N87")
			(options
				(clearance outline)
				(anchor circle)
			)
			(primitives
				(gr_poly
					(pts
						(arc
							(start 0.3048 -0.2032)
							(mid 0.275042 -0.275042)
							(end 0.2032 -0.3048)
						)
						(arc
							(start -0.2032 -0.3048)
							(mid -0.275042 -0.275042)
							(end -0.3048 -0.2032)
						)
						(arc
							(start -0.3048 0.2032)
							(mid -0.275042 0.275042)
							(end -0.2032 0.3048)
						)
						(arc
							(start 0.2032 0.3048)
							(mid 0.275042 0.275042)
							(end 0.3048 0.2032)
						)
					)
					(width 0)
					(fill yes)
				)
			)
		)
	)
	(footprint ""
		(layer "F.Cu")
		(at 22.479 -163.068 -90)
		(property "Reference" "R505"
			(at 0 0 270)
			(layer "F.SilkS")
			(hide yes)
			(effects
				(font
					(size 1.27 1.27)
				)
			)
		)
		(property "Value" "4K7R2F-GP"
			(at 0.064008 -3.993896 270)
			(unlocked yes)
			(layer "F.Fab")
			(hide yes)
			(effects
				(font
					(size 1.016 1.016)
					(thickness 0.1524)
				)
			)
		)
		(property "Device Type" "R402H16"
			(at 0.064008 -5.517896 270)
			(unlocked yes)
			(layer "F.Fab")
			(hide yes)
			(effects
				(font
					(size 1.016 1.016)
					(thickness 0.1524)
				)
			)
		)
		(duplicate_pad_numbers_are_jumpers no)
		(fp_line
			(start -0.508 -0.9398)
			(end -0.508 0.9398)
			(stroke
				(width 0.1524)
				(type default)
			)
			(layer "F.SilkS")
		)
		(fp_line
			(start 0.508 -0.9398)
			(end -0.508 -0.9398)
			(stroke
				(width 0.1524)
				(type default)
			)
			(layer "F.SilkS")
		)
		(fp_rect
			(start -0.508 0.9398)
			(end 0.508 -0.9398)
			(stroke
				(width 0)
				(type default)
			)
			(fill no)
			(layer "F.CrtYd")
		)
		(fp_rect
			(start -0.508 0.9398)
			(end 0.508 -0.9398)
			(stroke
				(width 0)
				(type default)
			)
			(fill no)
			(layer "F.Fab")
		)
		(pad "1" smd custom
			(at 0 -0.4445 270)
			(size 0.1397 0.1397)
			(layers "F.Cu" "F.Mask" "F.Paste")
			(net "BMC_RESET#_DDR3")
			(options
				(clearance outline)
				(anchor circle)
			)
			(primitives
				(gr_poly
					(pts
						(arc
							(start -0.1778 -0.2794)
							(mid -0.249642 -0.249642)
							(end -0.2794 -0.1778)
						)
						(arc
							(start -0.2794 0.1778)
							(mid -0.249642 0.249642)
							(end -0.1778 0.2794)
						)
						(arc
							(start 0.1778 0.2794)
							(mid 0.249642 0.249642)
							(end 0.2794 0.1778)
						)
						(arc
							(start 0.2794 -0.1778)
							(mid 0.249642 -0.249642)
							(end 0.1778 -0.2794)
						)
					)
					(width 0)
					(fill yes)
				)
			)
		)
		(pad "2" smd custom
			(at 0 0.4445 270)
			(size 0.1397 0.1397)
			(layers "F.Cu" "F.Mask" "F.Paste")
			(net "P3V3_STBY")
			(options
				(clearance outline)
				(anchor circle)
			)
			(primitives
				(gr_poly
					(pts
						(arc
							(start -0.1778 -0.2794)
							(mid -0.249642 -0.249642)
							(end -0.2794 -0.1778)
						)
						(arc
							(start -0.2794 0.1778)
							(mid -0.249642 0.249642)
							(end -0.1778 0.2794)
						)
						(arc
							(start 0.1778 0.2794)
							(mid 0.249642 0.249642)
							(end 0.2794 0.1778)
						)
						(arc
							(start 0.2794 -0.1778)
							(mid 0.249642 -0.249642)
							(end 0.1778 -0.2794)
						)
					)
					(width 0)
					(fill yes)
				)
			)
		)
	)
	(footprint ""
		(layer "F.Cu")
		(at 34.429954 -163.559744 90)
		(property "Reference" "C177"
			(at 0 0 90)
			(layer "F.SilkS")
			(hide yes)
			(effects
				(font
					(size 1.27 1.27)
				)
			)
		)
		(property "Value" "SCD01U25V2KX-3GP"
			(at 1.1811 -2.7051 90)
			(unlocked yes)
			(layer "F.Fab")
			(hide yes)
			(effects
				(font
					(size 1.016 1.016)
					(thickness 0.1524)
				)
			)
		)
		(property "Device Type" "C402H22"
			(at 1.1811 -4.2291 90)
			(unlocked yes)
			(layer "F.Fab")
			(hide yes)
			(effects
				(font
					(size 1.016 1.016)
					(thickness 0.1524)
				)
			)
		)
		(duplicate_pad_numbers_are_jumpers no)
		(fp_rect
			(start -0.4318 0.9525)
			(end 0.4318 -0.9525)
			(stroke
				(width 0)
				(type default)
			)
			(fill no)
			(layer "F.CrtYd")
		)
		(fp_rect
			(start -0.4318 0.9525)
			(end 0.4318 -0.9525)
			(stroke
				(width 0)
				(type default)
			)
			(fill no)
			(layer "F.Fab")
		)
		(pad "1" smd custom
			(at 0 -0.4445 90)
			(size 0.1524 0.1524)
			(layers "F.Cu" "F.Mask" "F.Paste")
			(net "P1V53_STBY")
			(options
				(clearance outline)
				(anchor circle)
			)
			(primitives
				(gr_poly
					(pts
						(arc
							(start 0.3048 -0.2032)
							(mid 0.275042 -0.275042)
							(end 0.2032 -0.3048)
						)
						(arc
							(start -0.2032 -0.3048)
							(mid -0.275042 -0.275042)
							(end -0.3048 -0.2032)
						)
						(arc
							(start -0.3048 0.2032)
							(mid -0.275042 0.275042)
							(end -0.2032 0.3048)
						)
						(arc
							(start 0.2032 0.3048)
							(mid 0.275042 0.275042)
							(end 0.3048 0.2032)
						)
					)
					(width 0)
					(fill yes)
				)
			)
		)
		(pad "2" smd custom
			(at 0 0.4445 90)
			(size 0.1524 0.1524)
			(layers "F.Cu" "F.Mask" "F.Paste")
			(net "DDR_VREF")
			(options
				(clearance outline)
				(anchor circle)
			)
			(primitives
				(gr_poly
					(pts
						(arc
							(start 0.3048 -0.2032)
							(mid 0.275042 -0.275042)
							(end 0.2032 -0.3048)
						)
						(arc
							(start -0.2032 -0.3048)
							(mid -0.275042 -0.275042)
							(end -0.3048 -0.2032)
						)
						(arc
							(start -0.3048 0.2032)
							(mid -0.275042 0.275042)
							(end -0.2032 0.3048)
						)
						(arc
							(start 0.2032 0.3048)
							(mid 0.275042 0.275042)
							(end 0.3048 0.2032)
						)
					)
					(width 0)
					(fill yes)
				)
			)
		)
	)
	(footprint ""
		(layer "F.Cu")
		(at 14.351 -94.7166 90)
		(property "Reference" "TP134"
			(at 0 0 90)
			(layer "F.SilkS")
			(hide yes)
			(effects
				(font
					(size 1.27 1.27)
				)
			)
		)
		(property "Value" "TPAD28-2-GP"
			(at -0.0127 -1.6637 90)
			(unlocked yes)
			(layer "F.Fab")
			(hide yes)
			(effects
				(font
					(size 1.016 1.016)
					(thickness 0.1524)
				)
			)
		)
		(property "Device Type" "TPAD28"
			(at -0.0127 -3.1877 90)
			(unlocked yes)
			(layer "F.Fab")
			(hide yes)
			(effects
				(font
					(size 1.016 1.016)
					(thickness 0.1524)
				)
			)
		)
		(duplicate_pad_numbers_are_jumpers no)
		(fp_poly
			(pts
				(arc
					(start 0 0.3556)
					(mid 0 -0.3556)
					(end 0 0.3556)
				)
			)
			(stroke
				(width 0)
				(type default)
			)
			(fill no)
			(layer "F.CrtYd")
		)
		(fp_poly
			(pts
				(arc
					(start 0 0.6096)
					(mid 0 -0.6096)
					(end 0 0.6096)
				)
			)
			(stroke
				(width 0)
				(type default)
			)
			(fill no)
			(layer "F.Fab")
		)
		(pad "1" smd circle
			(at 0 0 90)
			(size 0.7112 0.7112)
			(layers "F.Cu" "F.Mask" "F.Paste")
			(net "NCSI_10G_RCLK")
		)
	)
	(footprint ""
		(layer "F.Cu")
		(at 21.336 -143.383)
		(property "Reference" "C203"
			(at 0 0 0)
			(layer "F.SilkS")
			(hide yes)
			(effects
				(font
					(size 1.27 1.27)
				)
			)
		)
		(property "Value" "SC100P50V2JN-3GP"
			(at 1.1811 -2.7051 0)
			(unlocked yes)
			(layer "F.Fab")
			(hide yes)
			(effects
				(font
					(size 1.016 1.016)
					(thickness 0.1524)
				)
			)
		)
		(property "Device Type" "C402H22"
			(at 1.1811 -4.2291 0)
			(unlocked yes)
			(layer "F.Fab")
			(hide yes)
			(effects
				(font
					(size 1.016 1.016)
					(thickness 0.1524)
				)
			)
		)
		(duplicate_pad_numbers_are_jumpers no)
		(fp_rect
			(start -0.4318 0.9525)
			(end 0.4318 -0.9525)
			(stroke
				(width 0)
				(type default)
			)
			(fill no)
			(layer "F.CrtYd")
		)
		(fp_rect
			(start -0.4318 0.9525)
			(end 0.4318 -0.9525)
			(stroke
				(width 0)
				(type default)
			)
			(fill no)
			(layer "F.Fab")
		)
		(pad "1" smd custom
			(at 0 -0.4445)
			(size 0.1524 0.1524)
			(layers "F.Cu" "F.Mask" "F.Paste")
			(net "V1PLLAV12")
			(options
				(clearance outline)
				(anchor circle)
			)
			(primitives
				(gr_poly
					(pts
						(arc
							(start 0.3048 -0.2032)
							(mid 0.275042 -0.275042)
							(end 0.2032 -0.3048)
						)
						(arc
							(start -0.2032 -0.3048)
							(mid -0.275042 -0.275042)
							(end -0.3048 -0.2032)
						)
						(arc
							(start -0.3048 0.2032)
							(mid -0.275042 0.275042)
							(end -0.2032 0.3048)
						)
						(arc
							(start 0.2032 0.3048)
							(mid 0.275042 0.275042)
							(end 0.3048 0.2032)
						)
					)
					(width 0)
					(fill yes)
				)
			)
		)
		(pad "2" smd custom
			(at 0 0.4445)
			(size 0.1524 0.1524)
			(layers "F.Cu" "F.Mask" "F.Paste")
			(net "GND")
			(options
				(clearance outline)
				(anchor circle)
			)
			(primitives
				(gr_poly
					(pts
						(arc
							(start 0.3048 -0.2032)
							(mid 0.275042 -0.275042)
							(end 0.2032 -0.3048)
						)
						(arc
							(start -0.2032 -0.3048)
							(mid -0.275042 -0.275042)
							(end -0.3048 -0.2032)
						)
						(arc
							(start -0.3048 0.2032)
							(mid -0.275042 0.275042)
							(end -0.2032 0.3048)
						)
						(arc
							(start 0.2032 0.3048)
							(mid 0.275042 0.275042)
							(end 0.3048 0.2032)
						)
					)
					(width 0)
					(fill yes)
				)
			)
		)
	)
	(footprint ""
		(layer "F.Cu")
		(at 23.1902 -84.2264 -90)
		(property "Reference" "TP158"
			(at 0 0 270)
			(layer "F.SilkS")
			(hide yes)
			(effects
				(font
					(size 1.27 1.27)
				)
			)
		)
		(property "Value" "TPAD28-2-GP"
			(at -0.0127 -1.6637 270)
			(unlocked yes)
			(layer "F.Fab")
			(hide yes)
			(effects
				(font
					(size 1.016 1.016)
					(thickness 0.1524)
				)
			)
		)
		(property "Device Type" "TPAD28"
			(at -0.0127 -3.1877 270)
			(unlocked yes)
			(layer "F.Fab")
			(hide yes)
			(effects
				(font
					(size 1.016 1.016)
					(thickness 0.1524)
				)
			)
		)
		(duplicate_pad_numbers_are_jumpers no)
		(fp_poly
			(pts
				(arc
					(start 0 -0.3556)
					(mid 0 0.3556)
					(end 0 -0.3556)
				)
			)
			(stroke
				(width 0)
				(type default)
			)
			(fill no)
			(layer "F.CrtYd")
		)
		(fp_poly
			(pts
				(arc
					(start 0 -0.6096)
					(mid 0 0.6096)
					(end 0 -0.6096)
				)
			)
			(stroke
				(width 0)
				(type default)
			)
			(fill no)
			(layer "F.Fab")
		)
		(pad "1" smd circle
			(at 0 0 270)
			(size 0.7112 0.7112)
			(layers "F.Cu" "F.Mask" "F.Paste")
			(net "NIC_JTCK")
		)
	)
	(footprint ""
		(layer "F.Cu")
		(at 230.251 -11.43 90)
		(property "Reference" "C728"
			(at 0 0 90)
			(layer "F.SilkS")
			(hide yes)
			(effects
				(font
					(size 1.27 1.27)
				)
			)
		)
		(property "Value" "SCD01U25V2KX-3GP"
			(at 1.1811 -2.7051 90)
			(unlocked yes)
			(layer "F.Fab")
			(hide yes)
			(effects
				(font
					(size 1.016 1.016)
					(thickness 0.1524)
				)
			)
		)
		(property "Device Type" "C402H22"
			(at 1.1811 -4.2291 90)
			(unlocked yes)
			(layer "F.Fab")
			(hide yes)
			(effects
				(font
					(size 1.016 1.016)
					(thickness 0.1524)
				)
			)
		)
		(duplicate_pad_numbers_are_jumpers no)
		(fp_rect
			(start -0.4318 0.9525)
			(end 0.4318 -0.9525)
			(stroke
				(width 0)
				(type default)
			)
			(fill no)
			(layer "F.CrtYd")
		)
		(fp_rect
			(start -0.4318 0.9525)
			(end 0.4318 -0.9525)
			(stroke
				(width 0)
				(type default)
			)
			(fill no)
			(layer "F.Fab")
		)
		(pad "1" smd custom
			(at 0 -0.4445 90)
			(size 0.1524 0.1524)
			(layers "F.Cu" "F.Mask" "F.Paste")
			(net "P3V3_STBY")
			(options
				(clearance outline)
				(anchor circle)
			)
			(primitives
				(gr_poly
					(pts
						(arc
							(start 0.3048 -0.2032)
							(mid 0.275042 -0.275042)
							(end 0.2032 -0.3048)
						)
						(arc
							(start -0.2032 -0.3048)
							(mid -0.275042 -0.275042)
							(end -0.3048 -0.2032)
						)
						(arc
							(start -0.3048 0.2032)
							(mid -0.275042 0.275042)
							(end -0.2032 0.3048)
						)
						(arc
							(start 0.2032 0.3048)
							(mid 0.275042 0.275042)
							(end 0.3048 0.2032)
						)
					)
					(width 0)
					(fill yes)
				)
			)
		)
		(pad "2" smd custom
			(at 0 0.4445 90)
			(size 0.1524 0.1524)
			(layers "F.Cu" "F.Mask" "F.Paste")
			(net "GND")
			(options
				(clearance outline)
				(anchor circle)
			)
			(primitives
				(gr_poly
					(pts
						(arc
							(start 0.3048 -0.2032)
							(mid 0.275042 -0.275042)
							(end 0.2032 -0.3048)
						)
						(arc
							(start -0.2032 -0.3048)
							(mid -0.275042 -0.275042)
							(end -0.3048 -0.2032)
						)
						(arc
							(start -0.3048 0.2032)
							(mid -0.275042 0.275042)
							(end -0.2032 0.3048)
						)
						(arc
							(start 0.2032 0.3048)
							(mid 0.275042 0.275042)
							(end 0.3048 0.2032)
						)
					)
					(width 0)
					(fill yes)
				)
			)
		)
	)
	(footprint ""
		(layer "F.Cu")
		(at 58.166 -132.1054 180)
		(property "Reference" "R5769"
			(at 0 0 180)
			(layer "F.SilkS")
			(hide yes)
			(effects
				(font
					(size 1.27 1.27)
				)
			)
		)
		(property "Value" "1KR2F-3-GP"
			(at 0.064008 -3.993896 180)
			(unlocked yes)
			(layer "F.Fab")
			(hide yes)
			(effects
				(font
					(size 1.016 1.016)
					(thickness 0.1524)
				)
			)
		)
		(property "Device Type" "R402H16"
			(at 0.064008 -5.517896 180)
			(unlocked yes)
			(layer "F.Fab")
			(hide yes)
			(effects
				(font
					(size 1.016 1.016)
					(thickness 0.1524)
				)
			)
		)
		(duplicate_pad_numbers_are_jumpers no)
		(fp_line
			(start 0.508 -0.9398)
			(end -0.508 -0.9398)
			(stroke
				(width 0.1524)
				(type default)
			)
			(layer "F.SilkS")
		)
		(fp_line
			(start -0.508 -0.9398)
			(end -0.508 0.9398)
			(stroke
				(width 0.1524)
				(type default)
			)
			(layer "F.SilkS")
		)
		(fp_rect
			(start -0.508 0.9398)
			(end 0.508 -0.9398)
			(stroke
				(width 0)
				(type default)
			)
			(fill no)
			(layer "F.CrtYd")
		)
		(fp_rect
			(start -0.508 0.9398)
			(end 0.508 -0.9398)
			(stroke
				(width 0)
				(type default)
			)
			(fill no)
			(layer "F.Fab")
		)
		(pad "1" smd custom
			(at 0 -0.4445 180)
			(size 0.1397 0.1397)
			(layers "F.Cu" "F.Mask" "F.Paste")
			(net "P1V53_STBY")
			(options
				(clearance outline)
				(anchor circle)
			)
			(primitives
				(gr_poly
					(pts
						(arc
							(start -0.1778 -0.2794)
							(mid -0.249642 -0.249642)
							(end -0.2794 -0.1778)
						)
						(arc
							(start -0.2794 0.1778)
							(mid -0.249642 0.249642)
							(end -0.1778 0.2794)
						)
						(arc
							(start 0.1778 0.2794)
							(mid 0.249642 0.249642)
							(end 0.2794 0.1778)
						)
						(arc
							(start 0.2794 -0.1778)
							(mid 0.249642 -0.249642)
							(end 0.1778 -0.2794)
						)
					)
					(width 0)
					(fill yes)
				)
			)
		)
		(pad "2" smd custom
			(at 0 0.4445 180)
			(size 0.1397 0.1397)
			(layers "F.Cu" "F.Mask" "F.Paste")
			(net "ADC_P1V53V")
			(options
				(clearance outline)
				(anchor circle)
			)
			(primitives
				(gr_poly
					(pts
						(arc
							(start -0.1778 -0.2794)
							(mid -0.249642 -0.249642)
							(end -0.2794 -0.1778)
						)
						(arc
							(start -0.2794 0.1778)
							(mid -0.249642 0.249642)
							(end -0.1778 0.2794)
						)
						(arc
							(start 0.1778 0.2794)
							(mid 0.249642 0.249642)
							(end 0.2794 0.1778)
						)
						(arc
							(start 0.2794 -0.1778)
							(mid 0.249642 -0.249642)
							(end 0.1778 -0.2794)
						)
					)
					(width 0)
					(fill yes)
				)
			)
		)
	)
	(footprint ""
		(layer "F.Cu")
		(at 21.5646 -148.336 180)
		(property "Reference" "R3604"
			(at 0 0 180)
			(layer "F.SilkS")
			(hide yes)
			(effects
				(font
					(size 1.27 1.27)
				)
			)
		)
		(property "Value" "0R2J-2-GP"
			(at 0.064008 -3.993896 180)
			(unlocked yes)
			(layer "F.Fab")
			(hide yes)
			(effects
				(font
					(size 1.016 1.016)
					(thickness 0.1524)
				)
			)
		)
		(property "Device Type" "R402H16"
			(at 0.064008 -5.517896 180)
			(unlocked yes)
			(layer "F.Fab")
			(hide yes)
			(effects
				(font
					(size 1.016 1.016)
					(thickness 0.1524)
				)
			)
		)
		(duplicate_pad_numbers_are_jumpers no)
		(fp_line
			(start 0.508 -0.9398)
			(end -0.508 -0.9398)
			(stroke
				(width 0.1524)
				(type default)
			)
			(layer "F.SilkS")
		)
		(fp_line
			(start -0.508 -0.9398)
			(end -0.508 0.9398)
			(stroke
				(width 0.1524)
				(type default)
			)
			(layer "F.SilkS")
		)
		(fp_rect
			(start -0.508 0.9398)
			(end 0.508 -0.9398)
			(stroke
				(width 0)
				(type default)
			)
			(fill no)
			(layer "F.CrtYd")
		)
		(fp_rect
			(start -0.508 0.9398)
			(end 0.508 -0.9398)
			(stroke
				(width 0)
				(type default)
			)
			(fill no)
			(layer "F.Fab")
		)
		(pad "1" smd custom
			(at 0 -0.4445 180)
			(size 0.1397 0.1397)
			(layers "F.Cu" "F.Mask" "F.Paste")
			(net "PWRGD_P1V26_STBY")
			(options
				(clearance outline)
				(anchor circle)
			)
			(primitives
				(gr_poly
					(pts
						(arc
							(start -0.1778 -0.2794)
							(mid -0.249642 -0.249642)
							(end -0.2794 -0.1778)
						)
						(arc
							(start -0.2794 0.1778)
							(mid -0.249642 0.249642)
							(end -0.1778 0.2794)
						)
						(arc
							(start 0.1778 0.2794)
							(mid 0.249642 0.249642)
							(end 0.2794 0.1778)
						)
						(arc
							(start 0.2794 -0.1778)
							(mid 0.249642 -0.249642)
							(end 0.1778 -0.2794)
						)
					)
					(width 0)
					(fill yes)
				)
			)
		)
		(pad "2" smd custom
			(at 0 0.4445 180)
			(size 0.1397 0.1397)
			(layers "F.Cu" "F.Mask" "F.Paste")
			(net "U80_B")
			(options
				(clearance outline)
				(anchor circle)
			)
			(primitives
				(gr_poly
					(pts
						(arc
							(start -0.1778 -0.2794)
							(mid -0.249642 -0.249642)
							(end -0.2794 -0.1778)
						)
						(arc
							(start -0.2794 0.1778)
							(mid -0.249642 0.249642)
							(end -0.1778 0.2794)
						)
						(arc
							(start 0.1778 0.2794)
							(mid 0.249642 0.249642)
							(end 0.2794 0.1778)
						)
						(arc
							(start 0.2794 -0.1778)
							(mid 0.249642 -0.249642)
							(end 0.1778 -0.2794)
						)
					)
					(width 0)
					(fill yes)
				)
			)
		)
	)
	(footprint ""
		(layer "F.Cu")
		(at 76.8858 -75.250548)
		(property "Reference" "R740"
			(at 0 0 0)
			(layer "F.SilkS")
			(hide yes)
			(effects
				(font
					(size 1.27 1.27)
				)
			)
		)
		(property "Value" "0R2J-2-GP"
			(at 0.064008 -3.993896 0)
			(unlocked yes)
			(layer "F.Fab")
			(hide yes)
			(effects
				(font
					(size 1.016 1.016)
					(thickness 0.1524)
				)
			)
		)
		(property "Device Type" "R402H16"
			(at 0.064008 -5.517896 0)
			(unlocked yes)
			(layer "F.Fab")
			(hide yes)
			(effects
				(font
					(size 1.016 1.016)
					(thickness 0.1524)
				)
			)
		)
		(duplicate_pad_numbers_are_jumpers no)
		(fp_line
			(start -0.508 -0.9398)
			(end -0.508 0.9398)
			(stroke
				(width 0.1524)
				(type default)
			)
			(layer "F.SilkS")
		)
		(fp_line
			(start 0.508 -0.9398)
			(end -0.508 -0.9398)
			(stroke
				(width 0.1524)
				(type default)
			)
			(layer "F.SilkS")
		)
		(fp_rect
			(start -0.508 0.9398)
			(end 0.508 -0.9398)
			(stroke
				(width 0)
				(type default)
			)
			(fill no)
			(layer "F.CrtYd")
		)
		(fp_rect
			(start -0.508 0.9398)
			(end 0.508 -0.9398)
			(stroke
				(width 0)
				(type default)
			)
			(fill no)
			(layer "F.Fab")
		)
		(pad "1" smd custom
			(at 0 -0.4445)
			(size 0.1397 0.1397)
			(layers "F.Cu" "F.Mask" "F.Paste")
			(net "ROMD2")
			(options
				(clearance outline)
				(anchor circle)
			)
			(primitives
				(gr_poly
					(pts
						(arc
							(start -0.1778 -0.2794)
							(mid -0.249642 -0.249642)
							(end -0.2794 -0.1778)
						)
						(arc
							(start -0.2794 0.1778)
							(mid -0.249642 0.249642)
							(end -0.1778 0.2794)
						)
						(arc
							(start 0.1778 0.2794)
							(mid 0.249642 0.249642)
							(end 0.2794 0.1778)
						)
						(arc
							(start 0.2794 -0.1778)
							(mid 0.249642 -0.249642)
							(end 0.1778 -0.2794)
						)
					)
					(width 0)
					(fill yes)
				)
			)
		)
		(pad "2" smd custom
			(at 0 0.4445)
			(size 0.1397 0.1397)
			(layers "F.Cu" "F.Mask" "F.Paste")
			(net "ROMD2_SEC")
			(options
				(clearance outline)
				(anchor circle)
			)
			(primitives
				(gr_poly
					(pts
						(arc
							(start -0.1778 -0.2794)
							(mid -0.249642 -0.249642)
							(end -0.2794 -0.1778)
						)
						(arc
							(start -0.2794 0.1778)
							(mid -0.249642 0.249642)
							(end -0.1778 0.2794)
						)
						(arc
							(start 0.1778 0.2794)
							(mid 0.249642 0.249642)
							(end 0.2794 0.1778)
						)
						(arc
							(start 0.2794 -0.1778)
							(mid 0.249642 -0.249642)
							(end 0.1778 -0.2794)
						)
					)
					(width 0)
					(fill yes)
				)
			)
		)
	)
	(footprint ""
		(layer "F.Cu")
		(at 227.33 -78.1304 180)
		(property "Reference" "R588"
			(at 0 0 180)
			(layer "F.SilkS")
			(hide yes)
			(effects
				(font
					(size 1.27 1.27)
				)
			)
		)
		(property "Value" "0R2J-2-GP"
			(at 0.064008 -3.993896 180)
			(unlocked yes)
			(layer "F.Fab")
			(hide yes)
			(effects
				(font
					(size 1.016 1.016)
					(thickness 0.1524)
				)
			)
		)
		(property "Device Type" "R402H16"
			(at 0.064008 -5.517896 180)
			(unlocked yes)
			(layer "F.Fab")
			(hide yes)
			(effects
				(font
					(size 1.016 1.016)
					(thickness 0.1524)
				)
			)
		)
		(duplicate_pad_numbers_are_jumpers no)
		(fp_line
			(start 0.508 -0.9398)
			(end -0.508 -0.9398)
			(stroke
				(width 0.1524)
				(type default)
			)
			(layer "F.SilkS")
		)
		(fp_line
			(start -0.508 -0.9398)
			(end -0.508 0.9398)
			(stroke
				(width 0.1524)
				(type default)
			)
			(layer "F.SilkS")
		)
		(fp_rect
			(start -0.508 0.9398)
			(end 0.508 -0.9398)
			(stroke
				(width 0)
				(type default)
			)
			(fill no)
			(layer "F.CrtYd")
		)
		(fp_rect
			(start -0.508 0.9398)
			(end 0.508 -0.9398)
			(stroke
				(width 0)
				(type default)
			)
			(fill no)
			(layer "F.Fab")
		)
		(pad "1" smd custom
			(at 0 -0.4445 180)
			(size 0.1397 0.1397)
			(layers "F.Cu" "F.Mask" "F.Paste")
			(net "BMC_I2C5_D_PEB_SCL")
			(options
				(clearance outline)
				(anchor circle)
			)
			(primitives
				(gr_poly
					(pts
						(arc
							(start -0.1778 -0.2794)
							(mid -0.249642 -0.249642)
							(end -0.2794 -0.1778)
						)
						(arc
							(start -0.2794 0.1778)
							(mid -0.249642 0.249642)
							(end -0.1778 0.2794)
						)
						(arc
							(start 0.1778 0.2794)
							(mid 0.249642 0.249642)
							(end 0.2794 0.1778)
						)
						(arc
							(start 0.2794 -0.1778)
							(mid 0.249642 -0.249642)
							(end 0.1778 -0.2794)
						)
					)
					(width 0)
					(fill yes)
				)
			)
		)
		(pad "2" smd custom
			(at 0 0.4445 180)
			(size 0.1397 0.1397)
			(layers "F.Cu" "F.Mask" "F.Paste")
			(net "TEMP_3_SCL")
			(options
				(clearance outline)
				(anchor circle)
			)
			(primitives
				(gr_poly
					(pts
						(arc
							(start -0.1778 -0.2794)
							(mid -0.249642 -0.249642)
							(end -0.2794 -0.1778)
						)
						(arc
							(start -0.2794 0.1778)
							(mid -0.249642 0.249642)
							(end -0.1778 0.2794)
						)
						(arc
							(start 0.1778 0.2794)
							(mid 0.249642 0.249642)
							(end 0.2794 0.1778)
						)
						(arc
							(start 0.2794 -0.1778)
							(mid 0.249642 -0.249642)
							(end 0.1778 -0.2794)
						)
					)
					(width 0)
					(fill yes)
				)
			)
		)
	)
	(footprint ""
		(layer "F.Cu")
		(at 80.645 -135.763 90)
		(property "Reference" "C8089"
			(at 0 0 90)
			(layer "F.SilkS")
			(hide yes)
			(effects
				(font
					(size 1.27 1.27)
				)
			)
		)
		(property "Value" "SCD1U25V2KX-2-GP"
			(at 1.1811 -2.7051 90)
			(unlocked yes)
			(layer "F.Fab")
			(hide yes)
			(effects
				(font
					(size 1.016 1.016)
					(thickness 0.1524)
				)
			)
		)
		(property "Device Type" "C402H22"
			(at 1.1811 -4.2291 90)
			(unlocked yes)
			(layer "F.Fab")
			(hide yes)
			(effects
				(font
					(size 1.016 1.016)
					(thickness 0.1524)
				)
			)
		)
		(duplicate_pad_numbers_are_jumpers no)
		(fp_rect
			(start -0.4318 0.9525)
			(end 0.4318 -0.9525)
			(stroke
				(width 0)
				(type default)
			)
			(fill no)
			(layer "F.CrtYd")
		)
		(fp_rect
			(start -0.4318 0.9525)
			(end 0.4318 -0.9525)
			(stroke
				(width 0)
				(type default)
			)
			(fill no)
			(layer "F.Fab")
		)
		(pad "1" smd custom
			(at 0 -0.4445 90)
			(size 0.1524 0.1524)
			(layers "F.Cu" "F.Mask" "F.Paste")
			(net "ADC_P1V26")
			(options
				(clearance outline)
				(anchor circle)
			)
			(primitives
				(gr_poly
					(pts
						(arc
							(start 0.3048 -0.2032)
							(mid 0.275042 -0.275042)
							(end 0.2032 -0.3048)
						)
						(arc
							(start -0.2032 -0.3048)
							(mid -0.275042 -0.275042)
							(end -0.3048 -0.2032)
						)
						(arc
							(start -0.3048 0.2032)
							(mid -0.275042 0.275042)
							(end -0.2032 0.3048)
						)
						(arc
							(start 0.2032 0.3048)
							(mid 0.275042 0.275042)
							(end 0.3048 0.2032)
						)
					)
					(width 0)
					(fill yes)
				)
			)
		)
		(pad "2" smd custom
			(at 0 0.4445 90)
			(size 0.1524 0.1524)
			(layers "F.Cu" "F.Mask" "F.Paste")
			(net "GND")
			(options
				(clearance outline)
				(anchor circle)
			)
			(primitives
				(gr_poly
					(pts
						(arc
							(start 0.3048 -0.2032)
							(mid 0.275042 -0.275042)
							(end 0.2032 -0.3048)
						)
						(arc
							(start -0.2032 -0.3048)
							(mid -0.275042 -0.275042)
							(end -0.3048 -0.2032)
						)
						(arc
							(start -0.3048 0.2032)
							(mid -0.275042 0.275042)
							(end -0.2032 0.3048)
						)
						(arc
							(start 0.2032 0.3048)
							(mid 0.275042 0.275042)
							(end 0.3048 0.2032)
						)
					)
					(width 0)
					(fill yes)
				)
			)
		)
	)
	(footprint ""
		(layer "F.Cu")
		(at 22.72919 -124.334016 90)
		(property "Reference" "C367"
			(at 0 0 90)
			(layer "F.SilkS")
			(hide yes)
			(effects
				(font
					(size 1.27 1.27)
				)
			)
		)
		(property "Value" "SCD22U10V2KX-1GP"
			(at 1.1811 -2.7051 90)
			(unlocked yes)
			(layer "F.Fab")
			(hide yes)
			(effects
				(font
					(size 1.016 1.016)
					(thickness 0.1524)
				)
			)
		)
		(property "Device Type" "C402H22"
			(at 1.1811 -4.2291 90)
			(unlocked yes)
			(layer "F.Fab")
			(hide yes)
			(effects
				(font
					(size 1.016 1.016)
					(thickness 0.1524)
				)
			)
		)
		(duplicate_pad_numbers_are_jumpers no)
		(fp_rect
			(start -0.4318 0.9525)
			(end 0.4318 -0.9525)
			(stroke
				(width 0)
				(type default)
			)
			(fill no)
			(layer "F.CrtYd")
		)
		(fp_rect
			(start -0.4318 0.9525)
			(end 0.4318 -0.9525)
			(stroke
				(width 0)
				(type default)
			)
			(fill no)
			(layer "F.Fab")
		)
		(pad "1" smd custom
			(at 0 -0.4445 90)
			(size 0.1524 0.1524)
			(layers "F.Cu" "F.Mask" "F.Paste")
			(net "PCIE_TX_CAP_P76")
			(options
				(clearance outline)
				(anchor circle)
			)
			(primitives
				(gr_poly
					(pts
						(arc
							(start 0.3048 -0.2032)
							(mid 0.275042 -0.275042)
							(end 0.2032 -0.3048)
						)
						(arc
							(start -0.2032 -0.3048)
							(mid -0.275042 -0.275042)
							(end -0.3048 -0.2032)
						)
						(arc
							(start -0.3048 0.2032)
							(mid -0.275042 0.275042)
							(end -0.2032 0.3048)
						)
						(arc
							(start 0.2032 0.3048)
							(mid 0.275042 0.275042)
							(end 0.3048 0.2032)
						)
					)
					(width 0)
					(fill yes)
				)
			)
		)
		(pad "2" smd custom
			(at 0 0.4445 90)
			(size 0.1524 0.1524)
			(layers "F.Cu" "F.Mask" "F.Paste")
			(net "PCIE_TX_P76")
			(options
				(clearance outline)
				(anchor circle)
			)
			(primitives
				(gr_poly
					(pts
						(arc
							(start 0.3048 -0.2032)
							(mid 0.275042 -0.275042)
							(end 0.2032 -0.3048)
						)
						(arc
							(start -0.2032 -0.3048)
							(mid -0.275042 -0.275042)
							(end -0.3048 -0.2032)
						)
						(arc
							(start -0.3048 0.2032)
							(mid -0.275042 0.275042)
							(end -0.2032 0.3048)
						)
						(arc
							(start 0.2032 0.3048)
							(mid 0.275042 0.275042)
							(end 0.3048 0.2032)
						)
					)
					(width 0)
					(fill yes)
				)
			)
		)
	)
	(footprint ""
		(layer "F.Cu")
		(at 16.75511 -94.083632 180)
		(property "Reference" "C41"
			(at 0 0 180)
			(layer "F.SilkS")
			(hide yes)
			(effects
				(font
					(size 1.27 1.27)
				)
			)
		)
		(property "Value" "SC1U16V3KX-5GP"
			(at 0 -2.8194 180)
			(unlocked yes)
			(layer "F.Fab")
			(hide yes)
			(effects
				(font
					(size 1.016 1.016)
					(thickness 0.1524)
				)
			)
		)
		(property "Device Type" "C603H36"
			(at 0 -4.3434 180)
			(unlocked yes)
			(layer "F.Fab")
			(hide yes)
			(effects
				(font
					(size 1.016 1.016)
					(thickness 0.1524)
				)
			)
		)
		(duplicate_pad_numbers_are_jumpers no)
		(fp_line
			(start 0.508 0)
			(end -0.508 0)
			(stroke
				(width 0.2032)
				(type default)
			)
			(layer "F.SilkS")
		)
		(fp_rect
			(start -0.5842 1.3335)
			(end 0.5842 -1.3335)
			(stroke
				(width 0)
				(type default)
			)
			(fill no)
			(layer "F.CrtYd")
		)
		(fp_rect
			(start -0.5842 1.3335)
			(end 0.5842 -1.3335)
			(stroke
				(width 0)
				(type default)
			)
			(fill no)
			(layer "F.Fab")
		)
		(pad "1" smd custom
			(at 0 -0.762 180)
			(size 0.2159 0.2159)
			(layers "F.Cu" "F.Mask" "F.Paste")
			(net "BMC_TPM_RST")
			(options
				(clearance outline)
				(anchor circle)
			)
			(primitives
				(gr_poly
					(pts
						(arc
							(start -0.3302 -0.4318)
							(mid -0.402042 -0.402042)
							(end -0.4318 -0.3302)
						)
						(arc
							(start -0.4318 0.3302)
							(mid -0.402042 0.402042)
							(end -0.3302 0.4318)
						)
						(arc
							(start 0.3302 0.4318)
							(mid 0.402042 0.402042)
							(end 0.4318 0.3302)
						)
						(arc
							(start 0.4318 -0.3302)
							(mid 0.402042 -0.402042)
							(end 0.3302 -0.4318)
						)
					)
					(width 0)
					(fill yes)
				)
			)
		)
		(pad "2" smd custom
			(at 0 0.762 180)
			(size 0.2159 0.2159)
			(layers "F.Cu" "F.Mask" "F.Paste")
			(net "Q20_G")
			(options
				(clearance outline)
				(anchor circle)
			)
			(primitives
				(gr_poly
					(pts
						(arc
							(start -0.3302 -0.4318)
							(mid -0.402042 -0.402042)
							(end -0.4318 -0.3302)
						)
						(arc
							(start -0.4318 0.3302)
							(mid -0.402042 0.402042)
							(end -0.3302 0.4318)
						)
						(arc
							(start 0.3302 0.4318)
							(mid 0.402042 0.402042)
							(end 0.4318 0.3302)
						)
						(arc
							(start 0.4318 -0.3302)
							(mid 0.402042 -0.402042)
							(end 0.3302 -0.4318)
						)
					)
					(width 0)
					(fill yes)
				)
			)
		)
	)
	(footprint ""
		(layer "F.Cu")
		(at 27.4447 -33.89884 180)
		(property "Reference" "R540"
			(at 0 0 180)
			(layer "F.SilkS")
			(hide yes)
			(effects
				(font
					(size 1.27 1.27)
				)
			)
		)
		(property "Value" "0R2J-2-GP"
			(at 0.064008 -3.993896 180)
			(unlocked yes)
			(layer "F.Fab")
			(hide yes)
			(effects
				(font
					(size 1.016 1.016)
					(thickness 0.1524)
				)
			)
		)
		(property "Device Type" "R402H16"
			(at 0.064008 -5.517896 180)
			(unlocked yes)
			(layer "F.Fab")
			(hide yes)
			(effects
				(font
					(size 1.016 1.016)
					(thickness 0.1524)
				)
			)
		)
		(duplicate_pad_numbers_are_jumpers no)
		(fp_line
			(start 0.508 -0.9398)
			(end -0.508 -0.9398)
			(stroke
				(width 0.1524)
				(type default)
			)
			(layer "F.SilkS")
		)
		(fp_line
			(start -0.508 -0.9398)
			(end -0.508 0.9398)
			(stroke
				(width 0.1524)
				(type default)
			)
			(layer "F.SilkS")
		)
		(fp_rect
			(start -0.508 0.9398)
			(end 0.508 -0.9398)
			(stroke
				(width 0)
				(type default)
			)
			(fill no)
			(layer "F.CrtYd")
		)
		(fp_rect
			(start -0.508 0.9398)
			(end 0.508 -0.9398)
			(stroke
				(width 0)
				(type default)
			)
			(fill no)
			(layer "F.Fab")
		)
		(pad "1" smd custom
			(at 0 -0.4445 180)
			(size 0.1397 0.1397)
			(layers "F.Cu" "F.Mask" "F.Paste")
			(net "LED_MDI0_100M_N")
			(options
				(clearance outline)
				(anchor circle)
			)
			(primitives
				(gr_poly
					(pts
						(arc
							(start -0.1778 -0.2794)
							(mid -0.249642 -0.249642)
							(end -0.2794 -0.1778)
						)
						(arc
							(start -0.2794 0.1778)
							(mid -0.249642 0.249642)
							(end -0.1778 0.2794)
						)
						(arc
							(start 0.1778 0.2794)
							(mid 0.249642 0.249642)
							(end 0.2794 0.1778)
						)
						(arc
							(start 0.2794 -0.1778)
							(mid 0.249642 -0.249642)
							(end 0.1778 -0.2794)
						)
					)
					(width 0)
					(fill yes)
				)
			)
		)
		(pad "2" smd custom
			(at 0 0.4445 180)
			(size 0.1397 0.1397)
			(layers "F.Cu" "F.Mask" "F.Paste")
			(net "LED_MDI0_100M_N_R")
			(options
				(clearance outline)
				(anchor circle)
			)
			(primitives
				(gr_poly
					(pts
						(arc
							(start -0.1778 -0.2794)
							(mid -0.249642 -0.249642)
							(end -0.2794 -0.1778)
						)
						(arc
							(start -0.2794 0.1778)
							(mid -0.249642 0.249642)
							(end -0.1778 0.2794)
						)
						(arc
							(start 0.1778 0.2794)
							(mid 0.249642 0.249642)
							(end 0.2794 0.1778)
						)
						(arc
							(start 0.2794 -0.1778)
							(mid 0.249642 -0.249642)
							(end 0.1778 -0.2794)
						)
					)
					(width 0)
					(fill yes)
				)
			)
		)
	)
	(footprint ""
		(layer "F.Cu")
		(at 126.976124 -196.443092)
		(property "Reference" "R7938"
			(at 0 0 0)
			(layer "F.SilkS")
			(hide yes)
			(effects
				(font
					(size 1.27 1.27)
				)
			)
		)
		(property "Value" "0R2J-2-GP"
			(at 0.064008 -3.993896 0)
			(unlocked yes)
			(layer "F.Fab")
			(hide yes)
			(effects
				(font
					(size 1.016 1.016)
					(thickness 0.1524)
				)
			)
		)
		(property "Device Type" "R402H16"
			(at 0.064008 -5.517896 0)
			(unlocked yes)
			(layer "F.Fab")
			(hide yes)
			(effects
				(font
					(size 1.016 1.016)
					(thickness 0.1524)
				)
			)
		)
		(duplicate_pad_numbers_are_jumpers no)
		(fp_line
			(start -0.508 -0.9398)
			(end -0.508 0.9398)
			(stroke
				(width 0.1524)
				(type default)
			)
			(layer "F.SilkS")
		)
		(fp_line
			(start 0.508 -0.9398)
			(end -0.508 -0.9398)
			(stroke
				(width 0.1524)
				(type default)
			)
			(layer "F.SilkS")
		)
		(fp_rect
			(start -0.508 0.9398)
			(end 0.508 -0.9398)
			(stroke
				(width 0)
				(type default)
			)
			(fill no)
			(layer "F.CrtYd")
		)
		(fp_rect
			(start -0.508 0.9398)
			(end 0.508 -0.9398)
			(stroke
				(width 0)
				(type default)
			)
			(fill no)
			(layer "F.Fab")
		)
		(pad "1" smd custom
			(at 0 -0.4445)
			(size 0.1397 0.1397)
			(layers "F.Cu" "F.Mask" "F.Paste")
			(net "SSD_ATNLED#1")
			(options
				(clearance outline)
				(anchor circle)
			)
			(primitives
				(gr_poly
					(pts
						(arc
							(start -0.1778 -0.2794)
							(mid -0.249642 -0.249642)
							(end -0.2794 -0.1778)
						)
						(arc
							(start -0.2794 0.1778)
							(mid -0.249642 0.249642)
							(end -0.1778 0.2794)
						)
						(arc
							(start 0.1778 0.2794)
							(mid 0.249642 0.249642)
							(end 0.2794 0.1778)
						)
						(arc
							(start 0.2794 -0.1778)
							(mid 0.249642 -0.249642)
							(end 0.1778 -0.2794)
						)
					)
					(width 0)
					(fill yes)
				)
			)
		)
		(pad "2" smd custom
			(at 0 0.4445)
			(size 0.1397 0.1397)
			(layers "F.Cu" "F.Mask" "F.Paste")
			(net "SSD_ATNLED#1_R")
			(options
				(clearance outline)
				(anchor circle)
			)
			(primitives
				(gr_poly
					(pts
						(arc
							(start -0.1778 -0.2794)
							(mid -0.249642 -0.249642)
							(end -0.2794 -0.1778)
						)
						(arc
							(start -0.2794 0.1778)
							(mid -0.249642 0.249642)
							(end -0.1778 0.2794)
						)
						(arc
							(start 0.1778 0.2794)
							(mid 0.249642 0.249642)
							(end 0.2794 0.1778)
						)
						(arc
							(start 0.2794 -0.1778)
							(mid 0.249642 -0.249642)
							(end 0.1778 -0.2794)
						)
					)
					(width 0)
					(fill yes)
				)
			)
		)
	)
	(footprint ""
		(layer "F.Cu")
		(at 128.391158 -74.60996 180)
		(property "Reference" "C724"
			(at 0 0 180)
			(layer "F.SilkS")
			(hide yes)
			(effects
				(font
					(size 1.27 1.27)
				)
			)
		)
		(property "Value" "SCD1U10V2KX-5GP"
			(at 1.1811 -2.7051 180)
			(unlocked yes)
			(layer "F.Fab")
			(hide yes)
			(effects
				(font
					(size 1.016 1.016)
					(thickness 0.1524)
				)
			)
		)
		(property "Device Type" "C402H22"
			(at 1.1811 -4.2291 180)
			(unlocked yes)
			(layer "F.Fab")
			(hide yes)
			(effects
				(font
					(size 1.016 1.016)
					(thickness 0.1524)
				)
			)
		)
		(duplicate_pad_numbers_are_jumpers no)
		(fp_rect
			(start -0.4318 0.9525)
			(end 0.4318 -0.9525)
			(stroke
				(width 0)
				(type default)
			)
			(fill no)
			(layer "F.CrtYd")
		)
		(fp_rect
			(start -0.4318 0.9525)
			(end 0.4318 -0.9525)
			(stroke
				(width 0)
				(type default)
			)
			(fill no)
			(layer "F.Fab")
		)
		(pad "1" smd custom
			(at 0 -0.4445 180)
			(size 0.1524 0.1524)
			(layers "F.Cu" "F.Mask" "F.Paste")
			(net "P1V8_STBY")
			(options
				(clearance outline)
				(anchor circle)
			)
			(primitives
				(gr_poly
					(pts
						(arc
							(start 0.3048 -0.2032)
							(mid 0.275042 -0.275042)
							(end 0.2032 -0.3048)
						)
						(arc
							(start -0.2032 -0.3048)
							(mid -0.275042 -0.275042)
							(end -0.3048 -0.2032)
						)
						(arc
							(start -0.3048 0.2032)
							(mid -0.275042 0.275042)
							(end -0.2032 0.3048)
						)
						(arc
							(start 0.2032 0.3048)
							(mid 0.275042 0.275042)
							(end 0.3048 0.2032)
						)
					)
					(width 0)
					(fill yes)
				)
			)
		)
		(pad "2" smd custom
			(at 0 0.4445 180)
			(size 0.1524 0.1524)
			(layers "F.Cu" "F.Mask" "F.Paste")
			(net "GND")
			(options
				(clearance outline)
				(anchor circle)
			)
			(primitives
				(gr_poly
					(pts
						(arc
							(start 0.3048 -0.2032)
							(mid 0.275042 -0.275042)
							(end 0.2032 -0.3048)
						)
						(arc
							(start -0.2032 -0.3048)
							(mid -0.275042 -0.275042)
							(end -0.3048 -0.2032)
						)
						(arc
							(start -0.3048 0.2032)
							(mid -0.275042 0.275042)
							(end -0.2032 0.3048)
						)
						(arc
							(start 0.2032 0.3048)
							(mid 0.275042 0.275042)
							(end 0.3048 0.2032)
						)
					)
					(width 0)
					(fill yes)
				)
			)
		)
	)
	(footprint ""
		(layer "F.Cu")
		(at 338.868512 -184.878218 180)
		(property "Reference" "R7946"
			(at 0 0 180)
			(layer "F.SilkS")
			(hide yes)
			(effects
				(font
					(size 1.27 1.27)
				)
			)
		)
		(property "Value" "0R2J-2-GP"
			(at 0.064008 -3.993896 180)
			(unlocked yes)
			(layer "F.Fab")
			(hide yes)
			(effects
				(font
					(size 1.016 1.016)
					(thickness 0.1524)
				)
			)
		)
		(property "Device Type" "R402H16"
			(at 0.064008 -5.517896 180)
			(unlocked yes)
			(layer "F.Fab")
			(hide yes)
			(effects
				(font
					(size 1.016 1.016)
					(thickness 0.1524)
				)
			)
		)
		(duplicate_pad_numbers_are_jumpers no)
		(fp_line
			(start 0.508 -0.9398)
			(end -0.508 -0.9398)
			(stroke
				(width 0.1524)
				(type default)
			)
			(layer "F.SilkS")
		)
		(fp_line
			(start -0.508 -0.9398)
			(end -0.508 0.9398)
			(stroke
				(width 0.1524)
				(type default)
			)
			(layer "F.SilkS")
		)
		(fp_rect
			(start -0.508 0.9398)
			(end 0.508 -0.9398)
			(stroke
				(width 0)
				(type default)
			)
			(fill no)
			(layer "F.CrtYd")
		)
		(fp_rect
			(start -0.508 0.9398)
			(end 0.508 -0.9398)
			(stroke
				(width 0)
				(type default)
			)
			(fill no)
			(layer "F.Fab")
		)
		(pad "1" smd custom
			(at 0 -0.4445 180)
			(size 0.1397 0.1397)
			(layers "F.Cu" "F.Mask" "F.Paste")
			(net "SSD_ATNLED#14")
			(options
				(clearance outline)
				(anchor circle)
			)
			(primitives
				(gr_poly
					(pts
						(arc
							(start -0.1778 -0.2794)
							(mid -0.249642 -0.249642)
							(end -0.2794 -0.1778)
						)
						(arc
							(start -0.2794 0.1778)
							(mid -0.249642 0.249642)
							(end -0.1778 0.2794)
						)
						(arc
							(start 0.1778 0.2794)
							(mid 0.249642 0.249642)
							(end 0.2794 0.1778)
						)
						(arc
							(start 0.2794 -0.1778)
							(mid 0.249642 -0.249642)
							(end 0.1778 -0.2794)
						)
					)
					(width 0)
					(fill yes)
				)
			)
		)
		(pad "2" smd custom
			(at 0 0.4445 180)
			(size 0.1397 0.1397)
			(layers "F.Cu" "F.Mask" "F.Paste")
			(net "SSD_ATNLED#14_R")
			(options
				(clearance outline)
				(anchor circle)
			)
			(primitives
				(gr_poly
					(pts
						(arc
							(start -0.1778 -0.2794)
							(mid -0.249642 -0.249642)
							(end -0.2794 -0.1778)
						)
						(arc
							(start -0.2794 0.1778)
							(mid -0.249642 0.249642)
							(end -0.1778 0.2794)
						)
						(arc
							(start 0.1778 0.2794)
							(mid 0.249642 0.249642)
							(end 0.2794 0.1778)
						)
						(arc
							(start 0.2794 -0.1778)
							(mid 0.249642 -0.249642)
							(end 0.1778 -0.2794)
						)
					)
					(width 0)
					(fill yes)
				)
			)
		)
	)
	(footprint ""
		(layer "F.Cu")
		(at 73.763124 -183.235092)
		(property "Reference" "R7952"
			(at 0 0 0)
			(layer "F.SilkS")
			(hide yes)
			(effects
				(font
					(size 1.27 1.27)
				)
			)
		)
		(property "Value" "0R2J-2-GP"
			(at 0.064008 -3.993896 0)
			(unlocked yes)
			(layer "F.Fab")
			(hide yes)
			(effects
				(font
					(size 1.016 1.016)
					(thickness 0.1524)
				)
			)
		)
		(property "Device Type" "R402H16"
			(at 0.064008 -5.517896 0)
			(unlocked yes)
			(layer "F.Fab")
			(hide yes)
			(effects
				(font
					(size 1.016 1.016)
					(thickness 0.1524)
				)
			)
		)
		(duplicate_pad_numbers_are_jumpers no)
		(fp_line
			(start -0.508 -0.9398)
			(end -0.508 0.9398)
			(stroke
				(width 0.1524)
				(type default)
			)
			(layer "F.SilkS")
		)
		(fp_line
			(start 0.508 -0.9398)
			(end -0.508 -0.9398)
			(stroke
				(width 0.1524)
				(type default)
			)
			(layer "F.SilkS")
		)
		(fp_rect
			(start -0.508 0.9398)
			(end 0.508 -0.9398)
			(stroke
				(width 0)
				(type default)
			)
			(fill no)
			(layer "F.CrtYd")
		)
		(fp_rect
			(start -0.508 0.9398)
			(end 0.508 -0.9398)
			(stroke
				(width 0)
				(type default)
			)
			(fill no)
			(layer "F.Fab")
		)
		(pad "1" smd custom
			(at 0 -0.4445)
			(size 0.1397 0.1397)
			(layers "F.Cu" "F.Mask" "F.Paste")
			(net "SSD_PWREN0")
			(options
				(clearance outline)
				(anchor circle)
			)
			(primitives
				(gr_poly
					(pts
						(arc
							(start -0.1778 -0.2794)
							(mid -0.249642 -0.249642)
							(end -0.2794 -0.1778)
						)
						(arc
							(start -0.2794 0.1778)
							(mid -0.249642 0.249642)
							(end -0.1778 0.2794)
						)
						(arc
							(start 0.1778 0.2794)
							(mid 0.249642 0.249642)
							(end 0.2794 0.1778)
						)
						(arc
							(start 0.2794 -0.1778)
							(mid 0.249642 -0.249642)
							(end 0.1778 -0.2794)
						)
					)
					(width 0)
					(fill yes)
				)
			)
		)
		(pad "2" smd custom
			(at 0 0.4445)
			(size 0.1397 0.1397)
			(layers "F.Cu" "F.Mask" "F.Paste")
			(net "SSD_PWREN0_R")
			(options
				(clearance outline)
				(anchor circle)
			)
			(primitives
				(gr_poly
					(pts
						(arc
							(start -0.1778 -0.2794)
							(mid -0.249642 -0.249642)
							(end -0.2794 -0.1778)
						)
						(arc
							(start -0.2794 0.1778)
							(mid -0.249642 0.249642)
							(end -0.1778 0.2794)
						)
						(arc
							(start 0.1778 0.2794)
							(mid 0.249642 0.249642)
							(end 0.2794 0.1778)
						)
						(arc
							(start 0.2794 -0.1778)
							(mid 0.249642 -0.249642)
							(end 0.1778 -0.2794)
						)
					)
					(width 0)
					(fill yes)
				)
			)
		)
	)
	(footprint ""
		(layer "F.Cu")
		(at 267.462 -5.6388 -90)
		(property "Reference" "R7903"
			(at 0 0 270)
			(layer "F.SilkS")
			(hide yes)
			(effects
				(font
					(size 1.27 1.27)
				)
			)
		)
		(property "Value" "0R2J-2-GP"
			(at 0.064008 -3.993896 270)
			(unlocked yes)
			(layer "F.Fab")
			(hide yes)
			(effects
				(font
					(size 1.016 1.016)
					(thickness 0.1524)
				)
			)
		)
		(property "Device Type" "R402H16"
			(at 0.064008 -5.517896 270)
			(unlocked yes)
			(layer "F.Fab")
			(hide yes)
			(effects
				(font
					(size 1.016 1.016)
					(thickness 0.1524)
				)
			)
		)
		(duplicate_pad_numbers_are_jumpers no)
		(fp_line
			(start -0.508 -0.9398)
			(end -0.508 0.9398)
			(stroke
				(width 0.1524)
				(type default)
			)
			(layer "F.SilkS")
		)
		(fp_line
			(start 0.508 -0.9398)
			(end -0.508 -0.9398)
			(stroke
				(width 0.1524)
				(type default)
			)
			(layer "F.SilkS")
		)
		(fp_rect
			(start -0.508 0.9398)
			(end 0.508 -0.9398)
			(stroke
				(width 0)
				(type default)
			)
			(fill no)
			(layer "F.CrtYd")
		)
		(fp_rect
			(start -0.508 0.9398)
			(end 0.508 -0.9398)
			(stroke
				(width 0)
				(type default)
			)
			(fill no)
			(layer "F.Fab")
		)
		(pad "1" smd custom
			(at 0 -0.4445 270)
			(size 0.1397 0.1397)
			(layers "F.Cu" "F.Mask" "F.Paste")
			(net "ADM6315_PM8536_RST#")
			(options
				(clearance outline)
				(anchor circle)
			)
			(primitives
				(gr_poly
					(pts
						(arc
							(start -0.1778 -0.2794)
							(mid -0.249642 -0.249642)
							(end -0.2794 -0.1778)
						)
						(arc
							(start -0.2794 0.1778)
							(mid -0.249642 0.249642)
							(end -0.1778 0.2794)
						)
						(arc
							(start 0.1778 0.2794)
							(mid 0.249642 0.249642)
							(end 0.2794 0.1778)
						)
						(arc
							(start 0.2794 -0.1778)
							(mid 0.249642 -0.249642)
							(end 0.1778 -0.2794)
						)
					)
					(width 0)
					(fill yes)
				)
			)
		)
		(pad "2" smd custom
			(at 0 0.4445 270)
			(size 0.1397 0.1397)
			(layers "F.Cu" "F.Mask" "F.Paste")
			(net "PM8536_RST#")
			(options
				(clearance outline)
				(anchor circle)
			)
			(primitives
				(gr_poly
					(pts
						(arc
							(start -0.1778 -0.2794)
							(mid -0.249642 -0.249642)
							(end -0.2794 -0.1778)
						)
						(arc
							(start -0.2794 0.1778)
							(mid -0.249642 0.249642)
							(end -0.1778 0.2794)
						)
						(arc
							(start 0.1778 0.2794)
							(mid 0.249642 0.249642)
							(end 0.2794 0.1778)
						)
						(arc
							(start 0.2794 -0.1778)
							(mid 0.249642 -0.249642)
							(end 0.1778 -0.2794)
						)
					)
					(width 0)
					(fill yes)
				)
			)
		)
	)
	(footprint ""
		(layer "F.Cu")
		(at 41.724072 -117.597682)
		(property "Reference" "TP295"
			(at 0 0 0)
			(layer "F.SilkS")
			(hide yes)
			(effects
				(font
					(size 1.27 1.27)
				)
			)
		)
		(property "Value" "TPAD28-2-GP"
			(at -0.0127 -1.6637 0)
			(unlocked yes)
			(layer "F.Fab")
			(hide yes)
			(effects
				(font
					(size 1.016 1.016)
					(thickness 0.1524)
				)
			)
		)
		(property "Device Type" "TPAD28"
			(at -0.0127 -3.1877 0)
			(unlocked yes)
			(layer "F.Fab")
			(hide yes)
			(effects
				(font
					(size 1.016 1.016)
					(thickness 0.1524)
				)
			)
		)
		(duplicate_pad_numbers_are_jumpers no)
		(fp_poly
			(pts
				(arc
					(start 0.3556 0)
					(mid -0.3556 0)
					(end 0.3556 0)
				)
			)
			(stroke
				(width 0)
				(type default)
			)
			(fill no)
			(layer "F.CrtYd")
		)
		(fp_poly
			(pts
				(arc
					(start 0.6096 0)
					(mid -0.6096 0)
					(end 0.6096 0)
				)
			)
			(stroke
				(width 0)
				(type default)
			)
			(fill no)
			(layer "F.Fab")
		)
		(pad "1" smd circle
			(at 0 0)
			(size 0.7112 0.7112)
			(layers "F.Cu" "F.Mask" "F.Paste")
			(net "TP_GPIOV5")
		)
	)
	(footprint ""
		(layer "F.Cu")
		(at 49.911 -192.913 -90)
		(property "Reference" "C703"
			(at 0 0 270)
			(layer "F.SilkS")
			(hide yes)
			(effects
				(font
					(size 1.27 1.27)
				)
			)
		)
		(property "Value" "SC220P50V3JN-GP"
			(at 0 -2.8194 270)
			(unlocked yes)
			(layer "F.Fab")
			(hide yes)
			(effects
				(font
					(size 1.016 1.016)
					(thickness 0.1524)
				)
			)
		)
		(property "Device Type" "C603H36"
			(at 0 -4.3434 270)
			(unlocked yes)
			(layer "F.Fab")
			(hide yes)
			(effects
				(font
					(size 1.016 1.016)
					(thickness 0.1524)
				)
			)
		)
		(duplicate_pad_numbers_are_jumpers no)
		(fp_line
			(start 0.508 0)
			(end -0.508 0)
			(stroke
				(width 0.2032)
				(type default)
			)
			(layer "F.SilkS")
		)
		(fp_rect
			(start -0.5842 1.3335)
			(end 0.5842 -1.3335)
			(stroke
				(width 0)
				(type default)
			)
			(fill no)
			(layer "F.CrtYd")
		)
		(fp_rect
			(start -0.5842 1.3335)
			(end 0.5842 -1.3335)
			(stroke
				(width 0)
				(type default)
			)
			(fill no)
			(layer "F.Fab")
		)
		(pad "1" smd custom
			(at 0 -0.762 270)
			(size 0.2159 0.2159)
			(layers "F.Cu" "F.Mask" "F.Paste")
			(net "BMC_I2C7_B_DPB_SDA_R")
			(options
				(clearance outline)
				(anchor circle)
			)
			(primitives
				(gr_poly
					(pts
						(arc
							(start -0.3302 -0.4318)
							(mid -0.402042 -0.402042)
							(end -0.4318 -0.3302)
						)
						(arc
							(start -0.4318 0.3302)
							(mid -0.402042 0.402042)
							(end -0.3302 0.4318)
						)
						(arc
							(start 0.3302 0.4318)
							(mid 0.402042 0.402042)
							(end 0.4318 0.3302)
						)
						(arc
							(start 0.4318 -0.3302)
							(mid 0.402042 -0.402042)
							(end 0.3302 -0.4318)
						)
					)
					(width 0)
					(fill yes)
				)
			)
		)
		(pad "2" smd custom
			(at 0 0.762 270)
			(size 0.2159 0.2159)
			(layers "F.Cu" "F.Mask" "F.Paste")
			(net "GND")
			(options
				(clearance outline)
				(anchor circle)
			)
			(primitives
				(gr_poly
					(pts
						(arc
							(start -0.3302 -0.4318)
							(mid -0.402042 -0.402042)
							(end -0.4318 -0.3302)
						)
						(arc
							(start -0.4318 0.3302)
							(mid -0.402042 0.402042)
							(end -0.3302 0.4318)
						)
						(arc
							(start 0.3302 0.4318)
							(mid 0.402042 0.402042)
							(end 0.4318 0.3302)
						)
						(arc
							(start 0.4318 -0.3302)
							(mid 0.402042 -0.402042)
							(end 0.3302 -0.4318)
						)
					)
					(width 0)
					(fill yes)
				)
			)
		)
	)
	(footprint ""
		(layer "F.Cu")
		(at 25.4 -150.495 -90)
		(property "Reference" "R297"
			(at 0 0 270)
			(layer "F.SilkS")
			(hide yes)
			(effects
				(font
					(size 1.27 1.27)
				)
			)
		)
		(property "Value" "4K7R2F-GP"
			(at 0.064008 -3.993896 270)
			(unlocked yes)
			(layer "F.Fab")
			(hide yes)
			(effects
				(font
					(size 1.016 1.016)
					(thickness 0.1524)
				)
			)
		)
		(property "Device Type" "R402H16"
			(at 0.064008 -5.517896 270)
			(unlocked yes)
			(layer "F.Fab")
			(hide yes)
			(effects
				(font
					(size 1.016 1.016)
					(thickness 0.1524)
				)
			)
		)
		(duplicate_pad_numbers_are_jumpers no)
		(fp_line
			(start -0.508 -0.9398)
			(end -0.508 0.9398)
			(stroke
				(width 0.1524)
				(type default)
			)
			(layer "F.SilkS")
		)
		(fp_line
			(start 0.508 -0.9398)
			(end -0.508 -0.9398)
			(stroke
				(width 0.1524)
				(type default)
			)
			(layer "F.SilkS")
		)
		(fp_rect
			(start -0.508 0.9398)
			(end 0.508 -0.9398)
			(stroke
				(width 0)
				(type default)
			)
			(fill no)
			(layer "F.CrtYd")
		)
		(fp_rect
			(start -0.508 0.9398)
			(end 0.508 -0.9398)
			(stroke
				(width 0)
				(type default)
			)
			(fill no)
			(layer "F.Fab")
		)
		(pad "1" smd custom
			(at 0 -0.4445 270)
			(size 0.1397 0.1397)
			(layers "F.Cu" "F.Mask" "F.Paste")
			(net "P3V3_STBY")
			(options
				(clearance outline)
				(anchor circle)
			)
			(primitives
				(gr_poly
					(pts
						(arc
							(start -0.1778 -0.2794)
							(mid -0.249642 -0.249642)
							(end -0.2794 -0.1778)
						)
						(arc
							(start -0.2794 0.1778)
							(mid -0.249642 0.249642)
							(end -0.1778 0.2794)
						)
						(arc
							(start 0.1778 0.2794)
							(mid 0.249642 0.249642)
							(end 0.2794 0.1778)
						)
						(arc
							(start 0.2794 -0.1778)
							(mid 0.249642 -0.249642)
							(end 0.1778 -0.2794)
						)
					)
					(width 0)
					(fill yes)
				)
			)
		)
		(pad "2" smd custom
			(at 0 0.4445 270)
			(size 0.1397 0.1397)
			(layers "F.Cu" "F.Mask" "F.Paste")
			(net "OSC2_CONT")
			(options
				(clearance outline)
				(anchor circle)
			)
			(primitives
				(gr_poly
					(pts
						(arc
							(start -0.1778 -0.2794)
							(mid -0.249642 -0.249642)
							(end -0.2794 -0.1778)
						)
						(arc
							(start -0.2794 0.1778)
							(mid -0.249642 0.249642)
							(end -0.1778 0.2794)
						)
						(arc
							(start 0.1778 0.2794)
							(mid 0.249642 0.249642)
							(end 0.2794 0.1778)
						)
						(arc
							(start 0.2794 -0.1778)
							(mid 0.249642 -0.249642)
							(end 0.1778 -0.2794)
						)
					)
					(width 0)
					(fill yes)
				)
			)
		)
	)
	(footprint ""
		(layer "F.Cu")
		(at 141.592046 -212.420454 180)
		(property "Reference" "C342"
			(at 0 0 180)
			(layer "F.SilkS")
			(hide yes)
			(effects
				(font
					(size 1.27 1.27)
				)
			)
		)
		(property "Value" "SCD22U10V2KX-1GP"
			(at 1.1811 -2.7051 180)
			(unlocked yes)
			(layer "F.Fab")
			(hide yes)
			(effects
				(font
					(size 1.016 1.016)
					(thickness 0.1524)
				)
			)
		)
		(property "Device Type" "C402H22"
			(at 1.1811 -4.2291 180)
			(unlocked yes)
			(layer "F.Fab")
			(hide yes)
			(effects
				(font
					(size 1.016 1.016)
					(thickness 0.1524)
				)
			)
		)
		(duplicate_pad_numbers_are_jumpers no)
		(fp_rect
			(start -0.4318 0.9525)
			(end 0.4318 -0.9525)
			(stroke
				(width 0)
				(type default)
			)
			(fill no)
			(layer "F.CrtYd")
		)
		(fp_rect
			(start -0.4318 0.9525)
			(end 0.4318 -0.9525)
			(stroke
				(width 0)
				(type default)
			)
			(fill no)
			(layer "F.Fab")
		)
		(pad "1" smd custom
			(at 0 -0.4445 180)
			(size 0.1524 0.1524)
			(layers "F.Cu" "F.Mask" "F.Paste")
			(net "PCIE_TX_CAP_P58")
			(options
				(clearance outline)
				(anchor circle)
			)
			(primitives
				(gr_poly
					(pts
						(arc
							(start 0.3048 -0.2032)
							(mid 0.275042 -0.275042)
							(end 0.2032 -0.3048)
						)
						(arc
							(start -0.2032 -0.3048)
							(mid -0.275042 -0.275042)
							(end -0.3048 -0.2032)
						)
						(arc
							(start -0.3048 0.2032)
							(mid -0.275042 0.275042)
							(end -0.2032 0.3048)
						)
						(arc
							(start 0.2032 0.3048)
							(mid 0.275042 0.275042)
							(end 0.3048 0.2032)
						)
					)
					(width 0)
					(fill yes)
				)
			)
		)
		(pad "2" smd custom
			(at 0 0.4445 180)
			(size 0.1524 0.1524)
			(layers "F.Cu" "F.Mask" "F.Paste")
			(net "PCIE_TX_P58")
			(options
				(clearance outline)
				(anchor circle)
			)
			(primitives
				(gr_poly
					(pts
						(arc
							(start 0.3048 -0.2032)
							(mid 0.275042 -0.275042)
							(end 0.2032 -0.3048)
						)
						(arc
							(start -0.2032 -0.3048)
							(mid -0.275042 -0.275042)
							(end -0.3048 -0.2032)
						)
						(arc
							(start -0.3048 0.2032)
							(mid -0.275042 0.275042)
							(end -0.2032 0.3048)
						)
						(arc
							(start 0.2032 0.3048)
							(mid 0.275042 0.275042)
							(end 0.3048 0.2032)
						)
					)
					(width 0)
					(fill yes)
				)
			)
		)
	)
	(footprint ""
		(layer "F.Cu")
		(at 334.804512 -172.432218)
		(property "Reference" "R7951"
			(at 0 0 0)
			(layer "F.SilkS")
			(hide yes)
			(effects
				(font
					(size 1.27 1.27)
				)
			)
		)
		(property "Value" "0R2J-2-GP"
			(at 0.064008 -3.993896 0)
			(unlocked yes)
			(layer "F.Fab")
			(hide yes)
			(effects
				(font
					(size 1.016 1.016)
					(thickness 0.1524)
				)
			)
		)
		(property "Device Type" "R402H16"
			(at 0.064008 -5.517896 0)
			(unlocked yes)
			(layer "F.Fab")
			(hide yes)
			(effects
				(font
					(size 1.016 1.016)
					(thickness 0.1524)
				)
			)
		)
		(duplicate_pad_numbers_are_jumpers no)
		(fp_line
			(start -0.508 -0.9398)
			(end -0.508 0.9398)
			(stroke
				(width 0.1524)
				(type default)
			)
			(layer "F.SilkS")
		)
		(fp_line
			(start 0.508 -0.9398)
			(end -0.508 -0.9398)
			(stroke
				(width 0.1524)
				(type default)
			)
			(layer "F.SilkS")
		)
		(fp_rect
			(start -0.508 0.9398)
			(end 0.508 -0.9398)
			(stroke
				(width 0)
				(type default)
			)
			(fill no)
			(layer "F.CrtYd")
		)
		(fp_rect
			(start -0.508 0.9398)
			(end 0.508 -0.9398)
			(stroke
				(width 0)
				(type default)
			)
			(fill no)
			(layer "F.Fab")
		)
		(pad "1" smd custom
			(at 0 -0.4445)
			(size 0.1397 0.1397)
			(layers "F.Cu" "F.Mask" "F.Paste")
			(net "SSD_PWREN4")
			(options
				(clearance outline)
				(anchor circle)
			)
			(primitives
				(gr_poly
					(pts
						(arc
							(start -0.1778 -0.2794)
							(mid -0.249642 -0.249642)
							(end -0.2794 -0.1778)
						)
						(arc
							(start -0.2794 0.1778)
							(mid -0.249642 0.249642)
							(end -0.1778 0.2794)
						)
						(arc
							(start 0.1778 0.2794)
							(mid 0.249642 0.249642)
							(end 0.2794 0.1778)
						)
						(arc
							(start 0.2794 -0.1778)
							(mid 0.249642 -0.249642)
							(end 0.1778 -0.2794)
						)
					)
					(width 0)
					(fill yes)
				)
			)
		)
		(pad "2" smd custom
			(at 0 0.4445)
			(size 0.1397 0.1397)
			(layers "F.Cu" "F.Mask" "F.Paste")
			(net "SSD_PWREN4_R")
			(options
				(clearance outline)
				(anchor circle)
			)
			(primitives
				(gr_poly
					(pts
						(arc
							(start -0.1778 -0.2794)
							(mid -0.249642 -0.249642)
							(end -0.2794 -0.1778)
						)
						(arc
							(start -0.2794 0.1778)
							(mid -0.249642 0.249642)
							(end -0.1778 0.2794)
						)
						(arc
							(start 0.1778 0.2794)
							(mid 0.249642 0.249642)
							(end 0.2794 0.1778)
						)
						(arc
							(start 0.2794 -0.1778)
							(mid 0.249642 -0.249642)
							(end 0.1778 -0.2794)
						)
					)
					(width 0)
					(fill yes)
				)
			)
		)
	)
	(footprint ""
		(layer "F.Cu")
		(at 223.774 -0.635 -90)
		(property "Reference" "U27"
			(at 0 0 270)
			(layer "F.SilkS")
			(hide yes)
			(effects
				(font
					(size 1.27 1.27)
				)
			)
		)
		(property "Value" "TS5A23157DGSR-GP"
			(at 0 -11.1252 270)
			(unlocked yes)
			(layer "F.Fab")
			(hide yes)
			(effects
				(font
					(size 1.016 1.016)
					(thickness 0.1524)
				)
			)
		)
		(property "Device Type" "MSOP10H44"
			(at 0 -12.6492 270)
			(unlocked yes)
			(layer "F.Fab")
			(hide yes)
			(effects
				(font
					(size 1.016 1.016)
					(thickness 0.1524)
				)
			)
		)
		(duplicate_pad_numbers_are_jumpers no)
		(fp_line
			(start -2.0066 1.016)
			(end -2.0066 -1.016)
			(stroke
				(width 0.1524)
				(type default)
			)
			(layer "F.SilkS")
		)
		(fp_line
			(start -1.8288 1.016)
			(end -1.8288 3.048)
			(stroke
				(width 0.508)
				(type default)
			)
			(layer "F.SilkS")
		)
		(fp_line
			(start 1.143 1.016)
			(end -2.0066 1.016)
			(stroke
				(width 0.1524)
				(type default)
			)
			(layer "F.SilkS")
		)
		(fp_line
			(start -1.5748 0)
			(end -1.9558 0.381)
			(stroke
				(width 0.1524)
				(type default)
			)
			(layer "F.SilkS")
		)
		(fp_line
			(start -1.5748 0)
			(end -1.9558 -0.381)
			(stroke
				(width 0.1524)
				(type default)
			)
			(layer "F.SilkS")
		)
		(fp_line
			(start -2.0066 -1.016)
			(end 1.143 -1.016)
			(stroke
				(width 0.1524)
				(type default)
			)
			(layer "F.SilkS")
		)
		(fp_line
			(start 1.143 -1.016)
			(end 1.143 1.016)
			(stroke
				(width 0.1524)
				(type default)
			)
			(layer "F.SilkS")
		)
		(fp_poly
			(pts
				(xy -2.0828 3.3401) (xy 2.0828 3.3401) (xy 2.0828 -3.3401) (xy -2.0828 -3.3401)
			)
			(stroke
				(width 0)
				(type default)
			)
			(fill no)
			(layer "F.CrtYd")
		)
		(fp_poly
			(pts
				(xy -2.0828 3.3401) (xy 2.0828 3.3401) (xy 2.0828 -3.3401) (xy -2.0828 -3.3401)
			)
			(stroke
				(width 0)
				(type default)
			)
			(fill no)
			(layer "F.Fab")
		)
		(pad "1" smd rect
			(at -0.99949 2.0701 270)
			(size 0.3048 1.524)
			(layers "F.Cu" "F.Mask" "F.Paste")
			(net "UART_SWITCH_R")
		)
		(pad "2" smd rect
			(at -0.50038 2.0701 270)
			(size 0.3048 1.524)
			(layers "F.Cu" "F.Mask" "F.Paste")
			(net "EXP_UART_TX_R")
		)
		(pad "3" smd rect
			(at 0 2.0701 270)
			(size 0.3048 1.524)
			(layers "F.Cu" "F.Mask" "F.Paste")
			(net "GND")
		)
		(pad "4" smd rect
			(at 0.50038 2.0701 270)
			(size 0.3048 1.524)
			(layers "F.Cu" "F.Mask" "F.Paste")
			(net "EXP_UART_RX_R")
		)
		(pad "5" smd rect
			(at 0.99949 2.0701 270)
			(size 0.3048 1.524)
			(layers "F.Cu" "F.Mask" "F.Paste")
			(net "UART_SWITCH_R")
		)
		(pad "6" smd rect
			(at 0.99949 -2.0701 270)
			(size 0.3048 1.524)
			(layers "F.Cu" "F.Mask" "F.Paste")
			(net "DEBUG_CARD_RX")
		)
		(pad "7" smd rect
			(at 0.50038 -2.0701 270)
			(size 0.3048 1.524)
			(layers "F.Cu" "F.Mask" "F.Paste")
			(net "BMC_RXD5")
		)
		(pad "8" smd rect
			(at 0 -2.0701 270)
			(size 0.3048 1.524)
			(layers "F.Cu" "F.Mask" "F.Paste")
			(net "P3V3_STBY")
		)
		(pad "9" smd rect
			(at -0.50038 -2.0701 270)
			(size 0.3048 1.524)
			(layers "F.Cu" "F.Mask" "F.Paste")
			(net "BMC_TXD5")
		)
		(pad "10" smd rect
			(at -0.99949 -2.0701 270)
			(size 0.3048 1.524)
			(layers "F.Cu" "F.Mask" "F.Paste")
			(net "DEBUG_CARD_TX")
		)
	)
	(footprint ""
		(layer "F.Cu")
		(at 40.576754 -146.465544)
		(property "Reference" "C185"
			(at 0 0 0)
			(layer "F.SilkS")
			(hide yes)
			(effects
				(font
					(size 1.27 1.27)
				)
			)
		)
		(property "Value" "SCD1U16V2KX-3GP"
			(at 1.1811 -2.7051 0)
			(unlocked yes)
			(layer "F.Fab")
			(hide yes)
			(effects
				(font
					(size 1.016 1.016)
					(thickness 0.1524)
				)
			)
		)
		(property "Device Type" "C402H22"
			(at 1.1811 -4.2291 0)
			(unlocked yes)
			(layer "F.Fab")
			(hide yes)
			(effects
				(font
					(size 1.016 1.016)
					(thickness 0.1524)
				)
			)
		)
		(duplicate_pad_numbers_are_jumpers no)
		(fp_rect
			(start -0.4318 0.9525)
			(end 0.4318 -0.9525)
			(stroke
				(width 0)
				(type default)
			)
			(fill no)
			(layer "F.CrtYd")
		)
		(fp_rect
			(start -0.4318 0.9525)
			(end 0.4318 -0.9525)
			(stroke
				(width 0)
				(type default)
			)
			(fill no)
			(layer "F.Fab")
		)
		(pad "1" smd custom
			(at 0 -0.4445)
			(size 0.1524 0.1524)
			(layers "F.Cu" "F.Mask" "F.Paste")
			(net "P1V53_STBY")
			(options
				(clearance outline)
				(anchor circle)
			)
			(primitives
				(gr_poly
					(pts
						(arc
							(start 0.3048 -0.2032)
							(mid 0.275042 -0.275042)
							(end 0.2032 -0.3048)
						)
						(arc
							(start -0.2032 -0.3048)
							(mid -0.275042 -0.275042)
							(end -0.3048 -0.2032)
						)
						(arc
							(start -0.3048 0.2032)
							(mid -0.275042 0.275042)
							(end -0.2032 0.3048)
						)
						(arc
							(start 0.2032 0.3048)
							(mid 0.275042 0.275042)
							(end 0.3048 0.2032)
						)
					)
					(width 0)
					(fill yes)
				)
			)
		)
		(pad "2" smd custom
			(at 0 0.4445)
			(size 0.1524 0.1524)
			(layers "F.Cu" "F.Mask" "F.Paste")
			(net "GND")
			(options
				(clearance outline)
				(anchor circle)
			)
			(primitives
				(gr_poly
					(pts
						(arc
							(start 0.3048 -0.2032)
							(mid 0.275042 -0.275042)
							(end 0.2032 -0.3048)
						)
						(arc
							(start -0.2032 -0.3048)
							(mid -0.275042 -0.275042)
							(end -0.3048 -0.2032)
						)
						(arc
							(start -0.3048 0.2032)
							(mid -0.275042 0.275042)
							(end -0.2032 0.3048)
						)
						(arc
							(start 0.2032 0.3048)
							(mid 0.275042 0.275042)
							(end 0.3048 0.2032)
						)
					)
					(width 0)
					(fill yes)
				)
			)
		)
	)
	(footprint ""
		(layer "F.Cu")
		(at 271.477486 -3.820668)
		(property "Reference" "R216"
			(at 0 0 0)
			(layer "F.SilkS")
			(hide yes)
			(effects
				(font
					(size 1.27 1.27)
				)
			)
		)
		(property "Value" "4K7R2F-GP"
			(at 0.064008 -3.993896 0)
			(unlocked yes)
			(layer "F.Fab")
			(hide yes)
			(effects
				(font
					(size 1.016 1.016)
					(thickness 0.1524)
				)
			)
		)
		(property "Device Type" "R402H16"
			(at 0.064008 -5.517896 0)
			(unlocked yes)
			(layer "F.Fab")
			(hide yes)
			(effects
				(font
					(size 1.016 1.016)
					(thickness 0.1524)
				)
			)
		)
		(duplicate_pad_numbers_are_jumpers no)
		(fp_line
			(start -0.508 -0.9398)
			(end -0.508 0.9398)
			(stroke
				(width 0.1524)
				(type default)
			)
			(layer "F.SilkS")
		)
		(fp_line
			(start 0.508 -0.9398)
			(end -0.508 -0.9398)
			(stroke
				(width 0.1524)
				(type default)
			)
			(layer "F.SilkS")
		)
		(fp_rect
			(start -0.508 0.9398)
			(end 0.508 -0.9398)
			(stroke
				(width 0)
				(type default)
			)
			(fill no)
			(layer "F.CrtYd")
		)
		(fp_rect
			(start -0.508 0.9398)
			(end 0.508 -0.9398)
			(stroke
				(width 0)
				(type default)
			)
			(fill no)
			(layer "F.Fab")
		)
		(pad "1" smd custom
			(at 0 -0.4445)
			(size 0.1397 0.1397)
			(layers "F.Cu" "F.Mask" "F.Paste")
			(net "CLK_P_7_R")
			(options
				(clearance outline)
				(anchor circle)
			)
			(primitives
				(gr_poly
					(pts
						(arc
							(start -0.1778 -0.2794)
							(mid -0.249642 -0.249642)
							(end -0.2794 -0.1778)
						)
						(arc
							(start -0.2794 0.1778)
							(mid -0.249642 0.249642)
							(end -0.1778 0.2794)
						)
						(arc
							(start 0.1778 0.2794)
							(mid 0.249642 0.249642)
							(end 0.2794 0.1778)
						)
						(arc
							(start 0.2794 -0.1778)
							(mid 0.249642 -0.249642)
							(end 0.1778 -0.2794)
						)
					)
					(width 0)
					(fill yes)
				)
			)
		)
		(pad "2" smd custom
			(at 0 0.4445)
			(size 0.1397 0.1397)
			(layers "F.Cu" "F.Mask" "F.Paste")
			(net "GND")
			(options
				(clearance outline)
				(anchor circle)
			)
			(primitives
				(gr_poly
					(pts
						(arc
							(start -0.1778 -0.2794)
							(mid -0.249642 -0.249642)
							(end -0.2794 -0.1778)
						)
						(arc
							(start -0.2794 0.1778)
							(mid -0.249642 0.249642)
							(end -0.1778 0.2794)
						)
						(arc
							(start 0.1778 0.2794)
							(mid 0.249642 0.249642)
							(end 0.2794 0.1778)
						)
						(arc
							(start 0.2794 -0.1778)
							(mid 0.249642 -0.249642)
							(end 0.1778 -0.2794)
						)
					)
					(width 0)
					(fill yes)
				)
			)
		)
	)
	(footprint ""
		(layer "F.Cu")
		(at 44.45 -118.364)
		(property "Reference" "TP92"
			(at 0 0 0)
			(layer "F.SilkS")
			(hide yes)
			(effects
				(font
					(size 1.27 1.27)
				)
			)
		)
		(property "Value" "TPAD28-2-GP"
			(at -0.0127 -1.6637 0)
			(unlocked yes)
			(layer "F.Fab")
			(hide yes)
			(effects
				(font
					(size 1.016 1.016)
					(thickness 0.1524)
				)
			)
		)
		(property "Device Type" "TPAD28"
			(at -0.0127 -3.1877 0)
			(unlocked yes)
			(layer "F.Fab")
			(hide yes)
			(effects
				(font
					(size 1.016 1.016)
					(thickness 0.1524)
				)
			)
		)
		(duplicate_pad_numbers_are_jumpers no)
		(fp_poly
			(pts
				(arc
					(start 0.3556 0)
					(mid -0.3556 0)
					(end 0.3556 0)
				)
			)
			(stroke
				(width 0)
				(type default)
			)
			(fill no)
			(layer "F.CrtYd")
		)
		(fp_poly
			(pts
				(arc
					(start 0.6096 0)
					(mid -0.6096 0)
					(end 0.6096 0)
				)
			)
			(stroke
				(width 0)
				(type default)
			)
			(fill no)
			(layer "F.Fab")
		)
		(pad "1" smd circle
			(at 0 0)
			(size 0.7112 0.7112)
			(layers "F.Cu" "F.Mask" "F.Paste")
			(net "TP_GPIOH3")
		)
	)
	(footprint ""
		(layer "F.Cu")
		(at 205.600046 0 90)
		(property "Reference" "LED5"
			(at 0 0 90)
			(layer "F.SilkS")
			(hide yes)
			(effects
				(font
					(size 1.27 1.27)
				)
			)
		)
		(property "Value" "LED-B-77-GP-U3"
			(at -0.7112 -3.6068 90)
			(unlocked yes)
			(layer "F.Fab")
			(hide yes)
			(effects
				(font
					(size 1.016 1.016)
					(thickness 0.1524)
				)
			)
		)
		(property "Device Type" "LED3020AK-U2H44"
			(at -0.7112 -5.1308 90)
			(unlocked yes)
			(layer "F.Fab")
			(hide yes)
			(effects
				(font
					(size 1.016 1.016)
					(thickness 0.1524)
				)
			)
		)
		(duplicate_pad_numbers_are_jumpers no)
		(fp_line
			(start 0.8382 -2.4003)
			(end -0.8382 -2.4003)
			(stroke
				(width 0.1524)
				(type default)
			)
			(layer "F.SilkS")
		)
		(fp_line
			(start -0.8382 -2.4003)
			(end -0.8382 -1.31445)
			(stroke
				(width 0.1524)
				(type default)
			)
			(layer "F.SilkS")
		)
		(fp_line
			(start -0.8382 1.31445)
			(end -0.8382 2.4003)
			(stroke
				(width 0.1524)
				(type default)
			)
			(layer "F.SilkS")
		)
		(fp_line
			(start 0.8382 2.4003)
			(end 0.8382 -2.4003)
			(stroke
				(width 0.1524)
				(type default)
			)
			(layer "F.SilkS")
		)
		(fp_line
			(start -0.8382 2.4003)
			(end 0.8382 2.4003)
			(stroke
				(width 0.1524)
				(type default)
			)
			(layer "F.SilkS")
		)
		(fp_line
			(start 0.889 2.5273)
			(end -0.889 2.5273)
			(stroke
				(width 0.4064)
				(type default)
			)
			(layer "F.SilkS")
		)
		(fp_arc
			(start -0.8382 1.31445)
			(mid -1.85412 0)
			(end -0.8382 -1.31445)
			(stroke
				(width 0.1524)
				(type default)
			)
			(layer "F.SilkS")
		)
		(fp_poly
			(pts
				(xy -1.0922 2.6543) (xy -1.0922 1.49606) (xy -1.15189 1.4732) (xy -1.27254 1.41351) (xy -1.38557 1.34493)
				(xy -1.49098 1.26873) (xy -1.59258 1.18237) (xy -1.68656 1.08712) (xy -1.77165 0.98552) (xy -1.84785 0.87757)
				(xy -1.91516 0.76454) (xy -1.97358 0.64262) (xy -2.02057 0.5207) (xy -2.05867 0.3937) (xy -2.08534 0.26416)
				(xy -2.10185 0.13335) (xy -2.1082 0) (xy -2.10185 -0.13335) (xy -2.08534 -0.26416) (xy -2.05867 -0.3937)
				(xy -2.02057 -0.5207) (xy -1.97358 -0.64262) (xy -1.91516 -0.76454) (xy -1.84785 -0.87757) (xy -1.77165 -0.98552)
				(xy -1.68656 -1.08712) (xy -1.59258 -1.18237) (xy -1.49098 -1.26873) (xy -1.38557 -1.34493) (xy -1.27254 -1.41351)
				(xy -1.15189 -1.4732) (xy -1.0922 -1.49606) (xy -1.0922 -2.6543) (xy 1.0922 -2.6543) (xy 1.0922 2.6543)
			)
			(stroke
				(width 0)
				(type default)
			)
			(fill no)
			(layer "F.CrtYd")
		)
		(fp_poly
			(pts
				(xy -1.0922 2.6543) (xy -1.0922 1.49606) (xy -1.15189 1.4732) (xy -1.27254 1.41351) (xy -1.38557 1.34493)
				(xy -1.49098 1.26873) (xy -1.59258 1.18237) (xy -1.68656 1.08712) (xy -1.77165 0.98552) (xy -1.84785 0.87757)
				(xy -1.91516 0.76454) (xy -1.97358 0.64262) (xy -2.02057 0.5207) (xy -2.05867 0.3937) (xy -2.08534 0.26416)
				(xy -2.10185 0.13335) (xy -2.1082 0) (xy -2.10185 -0.13335) (xy -2.08534 -0.26416) (xy -2.05867 -0.3937)
				(xy -2.02057 -0.5207) (xy -1.97358 -0.64262) (xy -1.91516 -0.76454) (xy -1.84785 -0.87757) (xy -1.77165 -0.98552)
				(xy -1.68656 -1.08712) (xy -1.59258 -1.18237) (xy -1.49098 -1.26873) (xy -1.38557 -1.34493) (xy -1.27254 -1.41351)
				(xy -1.15189 -1.4732) (xy -1.0922 -1.49606) (xy -1.0922 -2.6543) (xy 1.0922 -2.6543) (xy 1.0922 2.6543)
			)
			(stroke
				(width 0)
				(type default)
			)
			(fill no)
			(layer "F.Fab")
		)
		(pad "A" smd rect
			(at 0 -1.57099 90)
			(size 1.143 1.143)
			(layers "F.Cu" "F.Mask" "F.Paste")
			(net "LED_PWR_N_R")
		)
		(pad "K" smd rect
			(at 0 1.57099 90)
			(size 1.143 1.143)
			(layers "F.Cu" "F.Mask" "F.Paste")
			(net "LED_PWR_N_ON")
		)
	)
	(footprint ""
		(layer "F.Cu")
		(at 260.096 -26.289 180)
		(property "Reference" "R747"
			(at 0 0 180)
			(layer "F.SilkS")
			(hide yes)
			(effects
				(font
					(size 1.27 1.27)
				)
			)
		)
		(property "Value" "4K7R2F-GP"
			(at 0.064008 -3.993896 180)
			(unlocked yes)
			(layer "F.Fab")
			(hide yes)
			(effects
				(font
					(size 1.016 1.016)
					(thickness 0.1524)
				)
			)
		)
		(property "Device Type" "R402H16"
			(at 0.064008 -5.517896 180)
			(unlocked yes)
			(layer "F.Fab")
			(hide yes)
			(effects
				(font
					(size 1.016 1.016)
					(thickness 0.1524)
				)
			)
		)
		(duplicate_pad_numbers_are_jumpers no)
		(fp_line
			(start 0.508 -0.9398)
			(end -0.508 -0.9398)
			(stroke
				(width 0.1524)
				(type default)
			)
			(layer "F.SilkS")
		)
		(fp_line
			(start -0.508 -0.9398)
			(end -0.508 0.9398)
			(stroke
				(width 0.1524)
				(type default)
			)
			(layer "F.SilkS")
		)
		(fp_rect
			(start -0.508 0.9398)
			(end 0.508 -0.9398)
			(stroke
				(width 0)
				(type default)
			)
			(fill no)
			(layer "F.CrtYd")
		)
		(fp_rect
			(start -0.508 0.9398)
			(end 0.508 -0.9398)
			(stroke
				(width 0)
				(type default)
			)
			(fill no)
			(layer "F.Fab")
		)
		(pad "1" smd custom
			(at 0 -0.4445 180)
			(size 0.1397 0.1397)
			(layers "F.Cu" "F.Mask" "F.Paste")
			(net "P3V3_GPIO")
			(options
				(clearance outline)
				(anchor circle)
			)
			(primitives
				(gr_poly
					(pts
						(arc
							(start -0.1778 -0.2794)
							(mid -0.249642 -0.249642)
							(end -0.2794 -0.1778)
						)
						(arc
							(start -0.2794 0.1778)
							(mid -0.249642 0.249642)
							(end -0.1778 0.2794)
						)
						(arc
							(start 0.1778 0.2794)
							(mid 0.249642 0.249642)
							(end 0.2794 0.1778)
						)
						(arc
							(start 0.2794 -0.1778)
							(mid 0.249642 -0.249642)
							(end 0.1778 -0.2794)
						)
					)
					(width 0)
					(fill yes)
				)
			)
		)
		(pad "2" smd custom
			(at 0 0.4445 180)
			(size 0.1397 0.1397)
			(layers "F.Cu" "F.Mask" "F.Paste")
			(net "IOEXP_PMC1_INT#")
			(options
				(clearance outline)
				(anchor circle)
			)
			(primitives
				(gr_poly
					(pts
						(arc
							(start -0.1778 -0.2794)
							(mid -0.249642 -0.249642)
							(end -0.2794 -0.1778)
						)
						(arc
							(start -0.2794 0.1778)
							(mid -0.249642 0.249642)
							(end -0.1778 0.2794)
						)
						(arc
							(start 0.1778 0.2794)
							(mid 0.249642 0.249642)
							(end 0.2794 0.1778)
						)
						(arc
							(start 0.2794 -0.1778)
							(mid 0.249642 -0.249642)
							(end 0.1778 -0.2794)
						)
					)
					(width 0)
					(fill yes)
				)
			)
		)
	)
	(footprint ""
		(layer "F.Cu")
		(at 25.3873 -175.6791)
		(property "Reference" "Q94"
			(at 0 0 0)
			(layer "F.SilkS")
			(hide yes)
			(effects
				(font
					(size 1.27 1.27)
				)
			)
		)
		(property "Value" "2N7002K-1-GP"
			(at 0.127 -8.9662 0)
			(unlocked yes)
			(layer "F.Fab")
			(hide yes)
			(effects
				(font
					(size 1.016 1.016)
					(thickness 0.1524)
				)
			)
		)
		(property "Device Type" "SOT23DGS2D4H44"
			(at 0.127 -10.4902 0)
			(unlocked yes)
			(layer "F.Fab")
			(hide yes)
			(effects
				(font
					(size 1.016 1.016)
					(thickness 0.1524)
				)
			)
		)
		(duplicate_pad_numbers_are_jumpers no)
		(fp_line
			(start -1.651 -1.778)
			(end -1.651 1.778)
			(stroke
				(width 0.1524)
				(type default)
			)
			(layer "F.SilkS")
		)
		(fp_line
			(start -1.651 1.778)
			(end 1.651 1.778)
			(stroke
				(width 0.1524)
				(type default)
			)
			(layer "F.SilkS")
		)
		(fp_line
			(start 1.651 -1.778)
			(end -1.651 -1.778)
			(stroke
				(width 0.1524)
				(type default)
			)
			(layer "F.SilkS")
		)
		(fp_line
			(start 1.651 1.778)
			(end 1.651 -1.778)
			(stroke
				(width 0.1524)
				(type default)
			)
			(layer "F.SilkS")
		)
		(fp_poly
			(pts
				(xy -1.778 1.8796) (xy -1.778 -1.8796) (xy 1.778 -1.8796) (xy 1.778 1.8796)
			)
			(stroke
				(width 0)
				(type default)
			)
			(fill no)
			(layer "F.CrtYd")
		)
		(fp_poly
			(pts
				(xy -1.778 1.8796) (xy -1.778 -1.8796) (xy 1.778 -1.8796) (xy 1.778 1.8796)
			)
			(stroke
				(width 0)
				(type default)
			)
			(fill no)
			(layer "F.Fab")
		)
		(pad "D" smd custom
			(at 0 -0.9525)
			(size 0.1905 0.1905)
			(layers "F.Cu" "F.Mask" "F.Paste")
			(net "MATED_P12V_EN")
			(options
				(clearance outline)
				(anchor circle)
			)
			(primitives
				(gr_poly
					(pts
						(arc
							(start -0.1778 0.5715)
							(mid -0.321484 0.511984)
							(end -0.381 0.3683)
						)
						(arc
							(start -0.381 -0.3683)
							(mid -0.321484 -0.511984)
							(end -0.1778 -0.5715)
						)
						(arc
							(start 0.1778 -0.5715)
							(mid 0.321484 -0.511984)
							(end 0.381 -0.3683)
						)
						(arc
							(start 0.381 0.3683)
							(mid 0.321484 0.511984)
							(end 0.1778 0.5715)
						)
					)
					(width 0)
					(fill yes)
				)
			)
		)
		(pad "G" smd custom
			(at -0.98425 0.9525)
			(size 0.1905 0.1905)
			(layers "F.Cu" "F.Mask" "F.Paste")
			(net "PCIE_MATED#_A")
			(options
				(clearance outline)
				(anchor circle)
			)
			(primitives
				(gr_poly
					(pts
						(arc
							(start -0.1778 0.5715)
							(mid -0.321484 0.511984)
							(end -0.381 0.3683)
						)
						(arc
							(start -0.381 -0.3683)
							(mid -0.321484 -0.511984)
							(end -0.1778 -0.5715)
						)
						(arc
							(start 0.1778 -0.5715)
							(mid 0.321484 -0.511984)
							(end 0.381 -0.3683)
						)
						(arc
							(start 0.381 0.3683)
							(mid 0.321484 0.511984)
							(end 0.1778 0.5715)
						)
					)
					(width 0)
					(fill yes)
				)
			)
		)
		(pad "S" smd custom
			(at 0.98425 0.9525)
			(size 0.1905 0.1905)
			(layers "F.Cu" "F.Mask" "F.Paste")
			(net "GND")
			(options
				(clearance outline)
				(anchor circle)
			)
			(primitives
				(gr_poly
					(pts
						(arc
							(start -0.1778 0.5715)
							(mid -0.321484 0.511984)
							(end -0.381 0.3683)
						)
						(arc
							(start -0.381 -0.3683)
							(mid -0.321484 -0.511984)
							(end -0.1778 -0.5715)
						)
						(arc
							(start 0.1778 -0.5715)
							(mid 0.321484 -0.511984)
							(end 0.381 -0.3683)
						)
						(arc
							(start 0.381 0.3683)
							(mid 0.321484 0.511984)
							(end 0.1778 0.5715)
						)
					)
					(width 0)
					(fill yes)
				)
			)
		)
	)
	(footprint ""
		(layer "F.Cu")
		(at 226.163124 -203.047092 180)
		(property "Reference" "R7962"
			(at 0 0 180)
			(layer "F.SilkS")
			(hide yes)
			(effects
				(font
					(size 1.27 1.27)
				)
			)
		)
		(property "Value" "0R2J-2-GP"
			(at 0.064008 -3.993896 180)
			(unlocked yes)
			(layer "F.Fab")
			(hide yes)
			(effects
				(font
					(size 1.016 1.016)
					(thickness 0.1524)
				)
			)
		)
		(property "Device Type" "R402H16"
			(at 0.064008 -5.517896 180)
			(unlocked yes)
			(layer "F.Fab")
			(hide yes)
			(effects
				(font
					(size 1.016 1.016)
					(thickness 0.1524)
				)
			)
		)
		(duplicate_pad_numbers_are_jumpers no)
		(fp_line
			(start 0.508 -0.9398)
			(end -0.508 -0.9398)
			(stroke
				(width 0.1524)
				(type default)
			)
			(layer "F.SilkS")
		)
		(fp_line
			(start -0.508 -0.9398)
			(end -0.508 0.9398)
			(stroke
				(width 0.1524)
				(type default)
			)
			(layer "F.SilkS")
		)
		(fp_rect
			(start -0.508 0.9398)
			(end 0.508 -0.9398)
			(stroke
				(width 0)
				(type default)
			)
			(fill no)
			(layer "F.CrtYd")
		)
		(fp_rect
			(start -0.508 0.9398)
			(end 0.508 -0.9398)
			(stroke
				(width 0)
				(type default)
			)
			(fill no)
			(layer "F.Fab")
		)
		(pad "1" smd custom
			(at 0 -0.4445 180)
			(size 0.1397 0.1397)
			(layers "F.Cu" "F.Mask" "F.Paste")
			(net "SSD_PWREN12")
			(options
				(clearance outline)
				(anchor circle)
			)
			(primitives
				(gr_poly
					(pts
						(arc
							(start -0.1778 -0.2794)
							(mid -0.249642 -0.249642)
							(end -0.2794 -0.1778)
						)
						(arc
							(start -0.2794 0.1778)
							(mid -0.249642 0.249642)
							(end -0.1778 0.2794)
						)
						(arc
							(start 0.1778 0.2794)
							(mid 0.249642 0.249642)
							(end 0.2794 0.1778)
						)
						(arc
							(start 0.2794 -0.1778)
							(mid 0.249642 -0.249642)
							(end 0.1778 -0.2794)
						)
					)
					(width 0)
					(fill yes)
				)
			)
		)
		(pad "2" smd custom
			(at 0 0.4445 180)
			(size 0.1397 0.1397)
			(layers "F.Cu" "F.Mask" "F.Paste")
			(net "SSD_PWREN12_R")
			(options
				(clearance outline)
				(anchor circle)
			)
			(primitives
				(gr_poly
					(pts
						(arc
							(start -0.1778 -0.2794)
							(mid -0.249642 -0.249642)
							(end -0.2794 -0.1778)
						)
						(arc
							(start -0.2794 0.1778)
							(mid -0.249642 0.249642)
							(end -0.1778 0.2794)
						)
						(arc
							(start 0.1778 0.2794)
							(mid 0.249642 0.249642)
							(end 0.2794 0.1778)
						)
						(arc
							(start 0.2794 -0.1778)
							(mid 0.249642 -0.249642)
							(end 0.1778 -0.2794)
						)
					)
					(width 0)
					(fill yes)
				)
			)
		)
	)
	(footprint ""
		(layer "F.Cu")
		(at 67.3862 -164.4396 -90)
		(property "Reference" "PC74"
			(at 0 0 270)
			(layer "F.SilkS")
			(hide yes)
			(effects
				(font
					(size 1.27 1.27)
				)
			)
		)
		(property "Value" "SCD01U25V2KX-3GP"
			(at 1.1811 -2.7051 270)
			(unlocked yes)
			(layer "F.Fab")
			(hide yes)
			(effects
				(font
					(size 1.016 1.016)
					(thickness 0.1524)
				)
			)
		)
		(property "Device Type" "C402H22"
			(at 1.1811 -4.2291 270)
			(unlocked yes)
			(layer "F.Fab")
			(hide yes)
			(effects
				(font
					(size 1.016 1.016)
					(thickness 0.1524)
				)
			)
		)
		(duplicate_pad_numbers_are_jumpers no)
		(fp_rect
			(start -0.4318 0.9525)
			(end 0.4318 -0.9525)
			(stroke
				(width 0)
				(type default)
			)
			(fill no)
			(layer "F.CrtYd")
		)
		(fp_rect
			(start -0.4318 0.9525)
			(end 0.4318 -0.9525)
			(stroke
				(width 0)
				(type default)
			)
			(fill no)
			(layer "F.Fab")
		)
		(pad "1" smd custom
			(at 0 -0.4445 270)
			(size 0.1524 0.1524)
			(layers "F.Cu" "F.Mask" "F.Paste")
			(net "VR_P1V538_STBY_EN_R")
			(options
				(clearance outline)
				(anchor circle)
			)
			(primitives
				(gr_poly
					(pts
						(arc
							(start 0.3048 -0.2032)
							(mid 0.275042 -0.275042)
							(end 0.2032 -0.3048)
						)
						(arc
							(start -0.2032 -0.3048)
							(mid -0.275042 -0.275042)
							(end -0.3048 -0.2032)
						)
						(arc
							(start -0.3048 0.2032)
							(mid -0.275042 0.275042)
							(end -0.2032 0.3048)
						)
						(arc
							(start 0.2032 0.3048)
							(mid 0.275042 0.275042)
							(end 0.3048 0.2032)
						)
					)
					(width 0)
					(fill yes)
				)
			)
		)
		(pad "2" smd custom
			(at 0 0.4445 270)
			(size 0.1524 0.1524)
			(layers "F.Cu" "F.Mask" "F.Paste")
			(net "GND")
			(options
				(clearance outline)
				(anchor circle)
			)
			(primitives
				(gr_poly
					(pts
						(arc
							(start 0.3048 -0.2032)
							(mid 0.275042 -0.275042)
							(end 0.2032 -0.3048)
						)
						(arc
							(start -0.2032 -0.3048)
							(mid -0.275042 -0.275042)
							(end -0.3048 -0.2032)
						)
						(arc
							(start -0.3048 0.2032)
							(mid -0.275042 0.275042)
							(end -0.2032 0.3048)
						)
						(arc
							(start 0.2032 0.3048)
							(mid 0.275042 0.275042)
							(end 0.3048 0.2032)
						)
					)
					(width 0)
					(fill yes)
				)
			)
		)
	)
	(footprint ""
		(layer "F.Cu")
		(at 42.4688 -192.8876 180)
		(property "Reference" "R866"
			(at 0 0 180)
			(layer "F.SilkS")
			(hide yes)
			(effects
				(font
					(size 1.27 1.27)
				)
			)
		)
		(property "Value" "0R2J-2-GP"
			(at 0.064008 -3.993896 180)
			(unlocked yes)
			(layer "F.Fab")
			(hide yes)
			(effects
				(font
					(size 1.016 1.016)
					(thickness 0.1524)
				)
			)
		)
		(property "Device Type" "R402H16"
			(at 0.064008 -5.517896 180)
			(unlocked yes)
			(layer "F.Fab")
			(hide yes)
			(effects
				(font
					(size 1.016 1.016)
					(thickness 0.1524)
				)
			)
		)
		(duplicate_pad_numbers_are_jumpers no)
		(fp_line
			(start 0.508 -0.9398)
			(end -0.508 -0.9398)
			(stroke
				(width 0.1524)
				(type default)
			)
			(layer "F.SilkS")
		)
		(fp_line
			(start -0.508 -0.9398)
			(end -0.508 0.9398)
			(stroke
				(width 0.1524)
				(type default)
			)
			(layer "F.SilkS")
		)
		(fp_rect
			(start -0.508 0.9398)
			(end 0.508 -0.9398)
			(stroke
				(width 0)
				(type default)
			)
			(fill no)
			(layer "F.CrtYd")
		)
		(fp_rect
			(start -0.508 0.9398)
			(end 0.508 -0.9398)
			(stroke
				(width 0)
				(type default)
			)
			(fill no)
			(layer "F.Fab")
		)
		(pad "1" smd custom
			(at 0 -0.4445 180)
			(size 0.1397 0.1397)
			(layers "F.Cu" "F.Mask" "F.Paste")
			(net "BUF_I2C9_CLKBUF2_SDA_R")
			(options
				(clearance outline)
				(anchor circle)
			)
			(primitives
				(gr_poly
					(pts
						(arc
							(start -0.1778 -0.2794)
							(mid -0.249642 -0.249642)
							(end -0.2794 -0.1778)
						)
						(arc
							(start -0.2794 0.1778)
							(mid -0.249642 0.249642)
							(end -0.1778 0.2794)
						)
						(arc
							(start 0.1778 0.2794)
							(mid 0.249642 0.249642)
							(end 0.2794 0.1778)
						)
						(arc
							(start 0.2794 -0.1778)
							(mid 0.249642 -0.249642)
							(end 0.1778 -0.2794)
						)
					)
					(width 0)
					(fill yes)
				)
			)
		)
		(pad "2" smd custom
			(at 0 0.4445 180)
			(size 0.1397 0.1397)
			(layers "F.Cu" "F.Mask" "F.Paste")
			(net "BUF_I2C9_CLKBUF2_SDA")
			(options
				(clearance outline)
				(anchor circle)
			)
			(primitives
				(gr_poly
					(pts
						(arc
							(start -0.1778 -0.2794)
							(mid -0.249642 -0.249642)
							(end -0.2794 -0.1778)
						)
						(arc
							(start -0.2794 0.1778)
							(mid -0.249642 0.249642)
							(end -0.1778 0.2794)
						)
						(arc
							(start 0.1778 0.2794)
							(mid 0.249642 0.249642)
							(end 0.2794 0.1778)
						)
						(arc
							(start 0.2794 -0.1778)
							(mid 0.249642 -0.249642)
							(end 0.1778 -0.2794)
						)
					)
					(width 0)
					(fill yes)
				)
			)
		)
	)
	(footprint ""
		(layer "F.Cu")
		(at 50.673 -177.165)
		(property "Reference" "R899"
			(at 0 0 0)
			(layer "F.SilkS")
			(hide yes)
			(effects
				(font
					(size 1.27 1.27)
				)
			)
		)
		(property "Value" "0R2J-2-GP"
			(at 0.064008 -3.993896 0)
			(unlocked yes)
			(layer "F.Fab")
			(hide yes)
			(effects
				(font
					(size 1.016 1.016)
					(thickness 0.1524)
				)
			)
		)
		(property "Device Type" "R402H16"
			(at 0.064008 -5.517896 0)
			(unlocked yes)
			(layer "F.Fab")
			(hide yes)
			(effects
				(font
					(size 1.016 1.016)
					(thickness 0.1524)
				)
			)
		)
		(duplicate_pad_numbers_are_jumpers no)
		(fp_line
			(start -0.508 -0.9398)
			(end -0.508 0.9398)
			(stroke
				(width 0.1524)
				(type default)
			)
			(layer "F.SilkS")
		)
		(fp_line
			(start 0.508 -0.9398)
			(end -0.508 -0.9398)
			(stroke
				(width 0.1524)
				(type default)
			)
			(layer "F.SilkS")
		)
		(fp_rect
			(start -0.508 0.9398)
			(end 0.508 -0.9398)
			(stroke
				(width 0)
				(type default)
			)
			(fill no)
			(layer "F.CrtYd")
		)
		(fp_rect
			(start -0.508 0.9398)
			(end 0.508 -0.9398)
			(stroke
				(width 0)
				(type default)
			)
			(fill no)
			(layer "F.Fab")
		)
		(pad "1" smd custom
			(at 0 -0.4445)
			(size 0.1397 0.1397)
			(layers "F.Cu" "F.Mask" "F.Paste")
			(net "BMC_I2C8_CLKBUF1_SDA_R")
			(options
				(clearance outline)
				(anchor circle)
			)
			(primitives
				(gr_poly
					(pts
						(arc
							(start -0.1778 -0.2794)
							(mid -0.249642 -0.249642)
							(end -0.2794 -0.1778)
						)
						(arc
							(start -0.2794 0.1778)
							(mid -0.249642 0.249642)
							(end -0.1778 0.2794)
						)
						(arc
							(start 0.1778 0.2794)
							(mid 0.249642 0.249642)
							(end 0.2794 0.1778)
						)
						(arc
							(start 0.2794 -0.1778)
							(mid 0.249642 -0.249642)
							(end 0.1778 -0.2794)
						)
					)
					(width 0)
					(fill yes)
				)
			)
		)
		(pad "2" smd custom
			(at 0 0.4445)
			(size 0.1397 0.1397)
			(layers "F.Cu" "F.Mask" "F.Paste")
			(net "BMC_I2C8_CLKBUF1_SDA")
			(options
				(clearance outline)
				(anchor circle)
			)
			(primitives
				(gr_poly
					(pts
						(arc
							(start -0.1778 -0.2794)
							(mid -0.249642 -0.249642)
							(end -0.2794 -0.1778)
						)
						(arc
							(start -0.2794 0.1778)
							(mid -0.249642 0.249642)
							(end -0.1778 0.2794)
						)
						(arc
							(start 0.1778 0.2794)
							(mid 0.249642 0.249642)
							(end 0.2794 0.1778)
						)
						(arc
							(start 0.2794 -0.1778)
							(mid 0.249642 -0.249642)
							(end 0.1778 -0.2794)
						)
					)
					(width 0)
					(fill yes)
				)
			)
		)
	)
	(footprint ""
		(layer "F.Cu")
		(at 16.383 -107.315)
		(property "Reference" "PR91"
			(at 0 0 0)
			(layer "F.SilkS")
			(hide yes)
			(effects
				(font
					(size 1.27 1.27)
				)
			)
		)
		(property "Value" "2K74R2F-GP"
			(at 0.064008 -3.993896 0)
			(unlocked yes)
			(layer "F.Fab")
			(hide yes)
			(effects
				(font
					(size 1.016 1.016)
					(thickness 0.1524)
				)
			)
		)
		(property "Device Type" "R402H16"
			(at 0.064008 -5.517896 0)
			(unlocked yes)
			(layer "F.Fab")
			(hide yes)
			(effects
				(font
					(size 1.016 1.016)
					(thickness 0.1524)
				)
			)
		)
		(duplicate_pad_numbers_are_jumpers no)
		(fp_line
			(start -0.508 -0.9398)
			(end -0.508 0.9398)
			(stroke
				(width 0.1524)
				(type default)
			)
			(layer "F.SilkS")
		)
		(fp_line
			(start 0.508 -0.9398)
			(end -0.508 -0.9398)
			(stroke
				(width 0.1524)
				(type default)
			)
			(layer "F.SilkS")
		)
		(fp_rect
			(start -0.508 0.9398)
			(end 0.508 -0.9398)
			(stroke
				(width 0)
				(type default)
			)
			(fill no)
			(layer "F.CrtYd")
		)
		(fp_rect
			(start -0.508 0.9398)
			(end 0.508 -0.9398)
			(stroke
				(width 0)
				(type default)
			)
			(fill no)
			(layer "F.Fab")
		)
		(pad "1" smd custom
			(at 0 -0.4445)
			(size 0.1397 0.1397)
			(layers "F.Cu" "F.Mask" "F.Paste")
			(net "P1V26_PWR")
			(options
				(clearance outline)
				(anchor circle)
			)
			(primitives
				(gr_poly
					(pts
						(arc
							(start -0.1778 -0.2794)
							(mid -0.249642 -0.249642)
							(end -0.2794 -0.1778)
						)
						(arc
							(start -0.2794 0.1778)
							(mid -0.249642 0.249642)
							(end -0.1778 0.2794)
						)
						(arc
							(start 0.1778 0.2794)
							(mid 0.249642 0.249642)
							(end 0.2794 0.1778)
						)
						(arc
							(start 0.2794 -0.1778)
							(mid 0.249642 -0.249642)
							(end 0.1778 -0.2794)
						)
					)
					(width 0)
					(fill yes)
				)
			)
		)
		(pad "2" smd custom
			(at 0 0.4445)
			(size 0.1397 0.1397)
			(layers "F.Cu" "F.Mask" "F.Paste")
			(net "VR_P1V26_STBY_FB")
			(options
				(clearance outline)
				(anchor circle)
			)
			(primitives
				(gr_poly
					(pts
						(arc
							(start -0.1778 -0.2794)
							(mid -0.249642 -0.249642)
							(end -0.2794 -0.1778)
						)
						(arc
							(start -0.2794 0.1778)
							(mid -0.249642 0.249642)
							(end -0.1778 0.2794)
						)
						(arc
							(start 0.1778 0.2794)
							(mid 0.249642 0.249642)
							(end 0.2794 0.1778)
						)
						(arc
							(start 0.2794 -0.1778)
							(mid 0.249642 -0.249642)
							(end 0.1778 -0.2794)
						)
					)
					(width 0)
					(fill yes)
				)
			)
		)
	)
	(footprint ""
		(layer "F.Cu")
		(at 117.568472 -30.638496 180)
		(property "Reference" "R2960"
			(at 0 0 180)
			(layer "F.SilkS")
			(hide yes)
			(effects
				(font
					(size 1.27 1.27)
				)
			)
		)
		(property "Value" "0R2J-2-GP"
			(at 0.064008 -3.993896 180)
			(unlocked yes)
			(layer "F.Fab")
			(hide yes)
			(effects
				(font
					(size 1.016 1.016)
					(thickness 0.1524)
				)
			)
		)
		(property "Device Type" "R402H16"
			(at 0.064008 -5.517896 180)
			(unlocked yes)
			(layer "F.Fab")
			(hide yes)
			(effects
				(font
					(size 1.016 1.016)
					(thickness 0.1524)
				)
			)
		)
		(duplicate_pad_numbers_are_jumpers no)
		(fp_line
			(start 0.508 -0.9398)
			(end -0.508 -0.9398)
			(stroke
				(width 0.1524)
				(type default)
			)
			(layer "F.SilkS")
		)
		(fp_line
			(start -0.508 -0.9398)
			(end -0.508 0.9398)
			(stroke
				(width 0.1524)
				(type default)
			)
			(layer "F.SilkS")
		)
		(fp_rect
			(start -0.508 0.9398)
			(end 0.508 -0.9398)
			(stroke
				(width 0)
				(type default)
			)
			(fill no)
			(layer "F.CrtYd")
		)
		(fp_rect
			(start -0.508 0.9398)
			(end 0.508 -0.9398)
			(stroke
				(width 0)
				(type default)
			)
			(fill no)
			(layer "F.Fab")
		)
		(pad "1" smd custom
			(at 0 -0.4445 180)
			(size 0.1397 0.1397)
			(layers "F.Cu" "F.Mask" "F.Paste")
			(net "U54_SDA")
			(options
				(clearance outline)
				(anchor circle)
			)
			(primitives
				(gr_poly
					(pts
						(arc
							(start -0.1778 -0.2794)
							(mid -0.249642 -0.249642)
							(end -0.2794 -0.1778)
						)
						(arc
							(start -0.2794 0.1778)
							(mid -0.249642 0.249642)
							(end -0.1778 0.2794)
						)
						(arc
							(start 0.1778 0.2794)
							(mid 0.249642 0.249642)
							(end 0.2794 0.1778)
						)
						(arc
							(start 0.2794 -0.1778)
							(mid 0.249642 -0.249642)
							(end 0.1778 -0.2794)
						)
					)
					(width 0)
					(fill yes)
				)
			)
		)
		(pad "2" smd custom
			(at 0 0.4445 180)
			(size 0.1397 0.1397)
			(layers "F.Cu" "F.Mask" "F.Paste")
			(net "BMC_I2C1_MINI1_SDA_S")
			(options
				(clearance outline)
				(anchor circle)
			)
			(primitives
				(gr_poly
					(pts
						(arc
							(start -0.1778 -0.2794)
							(mid -0.249642 -0.249642)
							(end -0.2794 -0.1778)
						)
						(arc
							(start -0.2794 0.1778)
							(mid -0.249642 0.249642)
							(end -0.1778 0.2794)
						)
						(arc
							(start 0.1778 0.2794)
							(mid 0.249642 0.249642)
							(end 0.2794 0.1778)
						)
						(arc
							(start 0.2794 -0.1778)
							(mid 0.249642 -0.249642)
							(end 0.1778 -0.2794)
						)
					)
					(width 0)
					(fill yes)
				)
			)
		)
	)
	(footprint ""
		(layer "F.Cu")
		(at 133.453886 -83.957414 180)
		(property "Reference" "C307"
			(at 0 0 180)
			(layer "F.SilkS")
			(hide yes)
			(effects
				(font
					(size 1.27 1.27)
				)
			)
		)
		(property "Value" "SC15P50V2JN-2-GP"
			(at 1.1811 -2.7051 180)
			(unlocked yes)
			(layer "F.Fab")
			(hide yes)
			(effects
				(font
					(size 1.016 1.016)
					(thickness 0.1524)
				)
			)
		)
		(property "Device Type" "C402H22"
			(at 1.1811 -4.2291 180)
			(unlocked yes)
			(layer "F.Fab")
			(hide yes)
			(effects
				(font
					(size 1.016 1.016)
					(thickness 0.1524)
				)
			)
		)
		(duplicate_pad_numbers_are_jumpers no)
		(fp_rect
			(start -0.4318 0.9525)
			(end 0.4318 -0.9525)
			(stroke
				(width 0)
				(type default)
			)
			(fill no)
			(layer "F.CrtYd")
		)
		(fp_rect
			(start -0.4318 0.9525)
			(end 0.4318 -0.9525)
			(stroke
				(width 0)
				(type default)
			)
			(fill no)
			(layer "F.Fab")
		)
		(pad "1" smd custom
			(at 0 -0.4445 180)
			(size 0.1524 0.1524)
			(layers "F.Cu" "F.Mask" "F.Paste")
			(net "RTC_OSCO")
			(options
				(clearance outline)
				(anchor circle)
			)
			(primitives
				(gr_poly
					(pts
						(arc
							(start 0.3048 -0.2032)
							(mid 0.275042 -0.275042)
							(end 0.2032 -0.3048)
						)
						(arc
							(start -0.2032 -0.3048)
							(mid -0.275042 -0.275042)
							(end -0.3048 -0.2032)
						)
						(arc
							(start -0.3048 0.2032)
							(mid -0.275042 0.275042)
							(end -0.2032 0.3048)
						)
						(arc
							(start 0.2032 0.3048)
							(mid 0.275042 0.275042)
							(end 0.3048 0.2032)
						)
					)
					(width 0)
					(fill yes)
				)
			)
		)
		(pad "2" smd custom
			(at 0 0.4445 180)
			(size 0.1524 0.1524)
			(layers "F.Cu" "F.Mask" "F.Paste")
			(net "GND")
			(options
				(clearance outline)
				(anchor circle)
			)
			(primitives
				(gr_poly
					(pts
						(arc
							(start 0.3048 -0.2032)
							(mid 0.275042 -0.275042)
							(end 0.2032 -0.3048)
						)
						(arc
							(start -0.2032 -0.3048)
							(mid -0.275042 -0.275042)
							(end -0.3048 -0.2032)
						)
						(arc
							(start -0.3048 0.2032)
							(mid -0.275042 0.275042)
							(end -0.2032 0.3048)
						)
						(arc
							(start 0.2032 0.3048)
							(mid 0.275042 0.275042)
							(end 0.3048 0.2032)
						)
					)
					(width 0)
					(fill yes)
				)
			)
		)
	)
	(footprint ""
		(layer "F.Cu")
		(at 222.226124 -196.951092)
		(property "Reference" "U200"
			(at 0 0 0)
			(layer "F.SilkS")
			(hide yes)
			(effects
				(font
					(size 1.27 1.27)
				)
			)
		)
		(property "Value" "MAX7311AUG-GP"
			(at 0 -12.1412 0)
			(unlocked yes)
			(layer "F.Fab")
			(hide yes)
			(effects
				(font
					(size 1.016 1.016)
					(thickness 0.1524)
				)
			)
		)
		(property "Device Type" "TSOIC24H44"
			(at 0 -13.6652 0)
			(unlocked yes)
			(layer "F.Fab")
			(hide yes)
			(effects
				(font
					(size 1.016 1.016)
					(thickness 0.1524)
				)
			)
		)
		(duplicate_pad_numbers_are_jumpers no)
		(fp_line
			(start -4.1148 -1.778)
			(end -4.1148 1.778)
			(stroke
				(width 0.1524)
				(type default)
			)
			(layer "F.SilkS")
		)
		(fp_line
			(start -4.1148 -1.778)
			(end 3.683 -1.778)
			(stroke
				(width 0.1524)
				(type default)
			)
			(layer "F.SilkS")
		)
		(fp_line
			(start -4.0386 1.778)
			(end -4.0386 3.556)
			(stroke
				(width 0.3556)
				(type default)
			)
			(layer "F.SilkS")
		)
		(fp_line
			(start -3.8354 0)
			(end -4.1148 -0.2794)
			(stroke
				(width 0.1524)
				(type default)
			)
			(layer "F.SilkS")
		)
		(fp_line
			(start -3.8354 0)
			(end -4.1148 0.2794)
			(stroke
				(width 0.1524)
				(type default)
			)
			(layer "F.SilkS")
		)
		(fp_line
			(start 3.683 -1.778)
			(end 3.683 1.778)
			(stroke
				(width 0.1524)
				(type default)
			)
			(layer "F.SilkS")
		)
		(fp_line
			(start 3.683 1.778)
			(end -4.1148 1.778)
			(stroke
				(width 0.1524)
				(type default)
			)
			(layer "F.SilkS")
		)
		(fp_poly
			(pts
				(xy -3.7592 -1.778) (xy 3.683 -1.778) (xy 3.683 1.778) (xy -3.7592 1.778)
			)
			(stroke
				(width 0)
				(type default)
			)
			(fill yes)
			(layer "F.SilkS")
		)
		(fp_poly
			(pts
				(xy -4.22656 3.81) (xy 4.22656 3.81) (xy 4.22656 -3.81) (xy -4.22656 -3.81)
			)
			(stroke
				(width 0)
				(type default)
			)
			(fill no)
			(layer "F.CrtYd")
		)
		(fp_poly
			(pts
				(xy -4.22656 -3.81) (xy 4.22656 -3.81) (xy 4.22656 3.81) (xy -4.22656 3.81)
			)
			(stroke
				(width 0)
				(type default)
			)
			(fill no)
			(layer "F.Fab")
		)
		(pad "1" smd rect
			(at -3.57632 2.8194)
			(size 0.3556 1.524)
			(layers "F.Cu" "F.Mask" "F.Paste")
			(net "IOEXP_INT#_3")
		)
		(pad "2" smd rect
			(at -2.92608 2.8194)
			(size 0.3556 1.524)
			(layers "F.Cu" "F.Mask" "F.Paste")
			(net "IOEXP3_AD1")
		)
		(pad "3" smd rect
			(at -2.27584 2.8194)
			(size 0.3556 1.524)
			(layers "F.Cu" "F.Mask" "F.Paste")
			(net "IOEXP3_AD2")
		)
		(pad "4" smd rect
			(at -1.6256 2.8194)
			(size 0.3556 1.524)
			(layers "F.Cu" "F.Mask" "F.Paste")
			(net "SSD_PRSNT#3")
		)
		(pad "5" smd rect
			(at -0.97536 2.8194)
			(size 0.3556 1.524)
			(layers "F.Cu" "F.Mask" "F.Paste")
			(net "SSD_ATNLED#3")
		)
		(pad "6" smd rect
			(at -0.32512 2.8194)
			(size 0.3556 1.524)
			(layers "F.Cu" "F.Mask" "F.Paste")
			(net "SSD_PWREN3")
		)
		(pad "7" smd rect
			(at 0.32512 2.8194)
			(size 0.3556 1.524)
			(layers "F.Cu" "F.Mask" "F.Paste")
			(net "SSD_PERST#3")
		)
		(pad "8" smd rect
			(at 0.97536 2.8194)
			(size 0.3556 1.524)
			(layers "F.Cu" "F.Mask" "F.Paste")
			(net "SSD_PRSNT#8")
		)
		(pad "9" smd rect
			(at 1.6256 2.8194)
			(size 0.3556 1.524)
			(layers "F.Cu" "F.Mask" "F.Paste")
			(net "SSD_ATNLED#8")
		)
		(pad "10" smd rect
			(at 2.27584 2.8194)
			(size 0.3556 1.524)
			(layers "F.Cu" "F.Mask" "F.Paste")
			(net "SSD_PWREN8")
		)
		(pad "11" smd rect
			(at 2.92608 2.8194)
			(size 0.3556 1.524)
			(layers "F.Cu" "F.Mask" "F.Paste")
			(net "SSD_PERST#8")
		)
		(pad "12" smd rect
			(at 3.57632 2.8194)
			(size 0.3556 1.524)
			(layers "F.Cu" "F.Mask" "F.Paste")
			(net "GND")
		)
		(pad "13" smd rect
			(at 3.57632 -2.8194)
			(size 0.3556 1.524)
			(layers "F.Cu" "F.Mask" "F.Paste")
			(net "SSD_PRSNT#12")
		)
		(pad "14" smd rect
			(at 2.92608 -2.8194)
			(size 0.3556 1.524)
			(layers "F.Cu" "F.Mask" "F.Paste")
			(net "SSD_ATNLED#12")
		)
		(pad "15" smd rect
			(at 2.27584 -2.8194)
			(size 0.3556 1.524)
			(layers "F.Cu" "F.Mask" "F.Paste")
			(net "SSD_PWREN12")
		)
		(pad "16" smd rect
			(at 1.6256 -2.8194)
			(size 0.3556 1.524)
			(layers "F.Cu" "F.Mask" "F.Paste")
			(net "SSD_PERST#12")
		)
		(pad "17" smd rect
			(at 0.97536 -2.8194)
			(size 0.3556 1.524)
			(layers "F.Cu" "F.Mask" "F.Paste")
			(net "SSD_PRSNT#13")
		)
		(pad "18" smd rect
			(at 0.32512 -2.8194)
			(size 0.3556 1.524)
			(layers "F.Cu" "F.Mask" "F.Paste")
			(net "SSD_ATNLED#13")
		)
		(pad "19" smd rect
			(at -0.32512 -2.8194)
			(size 0.3556 1.524)
			(layers "F.Cu" "F.Mask" "F.Paste")
			(net "SSD_PWREN13")
		)
		(pad "20" smd rect
			(at -0.97536 -2.8194)
			(size 0.3556 1.524)
			(layers "F.Cu" "F.Mask" "F.Paste")
			(net "SSD_PERST#13")
		)
		(pad "21" smd rect
			(at -1.6256 -2.8194)
			(size 0.3556 1.524)
			(layers "F.Cu" "F.Mask" "F.Paste")
			(net "IOEXP3_AD0")
		)
		(pad "22" smd rect
			(at -2.27584 -2.8194)
			(size 0.3556 1.524)
			(layers "F.Cu" "F.Mask" "F.Paste")
			(net "I2C_GPIO_SCL_3")
		)
		(pad "23" smd rect
			(at -2.92608 -2.8194)
			(size 0.3556 1.524)
			(layers "F.Cu" "F.Mask" "F.Paste")
			(net "I2C_GPIO_SDA_3")
		)
		(pad "24" smd rect
			(at -3.57632 -2.8194)
			(size 0.3556 1.524)
			(layers "F.Cu" "F.Mask" "F.Paste")
			(net "P3V3_STBY")
		)
	)
	(footprint ""
		(layer "F.Cu")
		(at 344.678 -68.199 180)
		(property "Reference" "PC190"
			(at 0 0 180)
			(layer "F.SilkS")
			(hide yes)
			(effects
				(font
					(size 1.27 1.27)
				)
			)
		)
		(property "Value" "SC1U16V3KX-5GP"
			(at 0 -2.8194 180)
			(unlocked yes)
			(layer "F.Fab")
			(hide yes)
			(effects
				(font
					(size 1.016 1.016)
					(thickness 0.1524)
				)
			)
		)
		(property "Device Type" "C603H36"
			(at 0 -4.3434 180)
			(unlocked yes)
			(layer "F.Fab")
			(hide yes)
			(effects
				(font
					(size 1.016 1.016)
					(thickness 0.1524)
				)
			)
		)
		(duplicate_pad_numbers_are_jumpers no)
		(fp_line
			(start 0.508 0)
			(end -0.508 0)
			(stroke
				(width 0.2032)
				(type default)
			)
			(layer "F.SilkS")
		)
		(fp_rect
			(start -0.5842 1.3335)
			(end 0.5842 -1.3335)
			(stroke
				(width 0)
				(type default)
			)
			(fill no)
			(layer "F.CrtYd")
		)
		(fp_rect
			(start -0.5842 1.3335)
			(end 0.5842 -1.3335)
			(stroke
				(width 0)
				(type default)
			)
			(fill no)
			(layer "F.Fab")
		)
		(pad "1" smd custom
			(at 0 -0.762 180)
			(size 0.2159 0.2159)
			(layers "F.Cu" "F.Mask" "F.Paste")
			(net "P0V9_E_VREG")
			(options
				(clearance outline)
				(anchor circle)
			)
			(primitives
				(gr_poly
					(pts
						(arc
							(start -0.3302 -0.4318)
							(mid -0.402042 -0.402042)
							(end -0.4318 -0.3302)
						)
						(arc
							(start -0.4318 0.3302)
							(mid -0.402042 0.402042)
							(end -0.3302 0.4318)
						)
						(arc
							(start 0.3302 0.4318)
							(mid 0.402042 0.402042)
							(end 0.4318 0.3302)
						)
						(arc
							(start 0.4318 -0.3302)
							(mid 0.402042 -0.402042)
							(end 0.3302 -0.4318)
						)
					)
					(width 0)
					(fill yes)
				)
			)
		)
		(pad "2" smd custom
			(at 0 0.762 180)
			(size 0.2159 0.2159)
			(layers "F.Cu" "F.Mask" "F.Paste")
			(net "GND")
			(options
				(clearance outline)
				(anchor circle)
			)
			(primitives
				(gr_poly
					(pts
						(arc
							(start -0.3302 -0.4318)
							(mid -0.402042 -0.402042)
							(end -0.4318 -0.3302)
						)
						(arc
							(start -0.4318 0.3302)
							(mid -0.402042 0.402042)
							(end -0.3302 0.4318)
						)
						(arc
							(start 0.3302 0.4318)
							(mid 0.402042 0.402042)
							(end 0.4318 0.3302)
						)
						(arc
							(start 0.4318 -0.3302)
							(mid 0.402042 -0.402042)
							(end 0.3302 -0.4318)
						)
					)
					(width 0)
					(fill yes)
				)
			)
		)
	)
	(footprint ""
		(layer "F.Cu")
		(at 325.755 -86.487)
		(property "Reference" "R4166"
			(at 0 0 0)
			(layer "F.SilkS")
			(hide yes)
			(effects
				(font
					(size 1.27 1.27)
				)
			)
		)
		(property "Value" "4K7R2F-GP"
			(at 0.064008 -3.993896 0)
			(unlocked yes)
			(layer "F.Fab")
			(hide yes)
			(effects
				(font
					(size 1.016 1.016)
					(thickness 0.1524)
				)
			)
		)
		(property "Device Type" "R402H16"
			(at 0.064008 -5.517896 0)
			(unlocked yes)
			(layer "F.Fab")
			(hide yes)
			(effects
				(font
					(size 1.016 1.016)
					(thickness 0.1524)
				)
			)
		)
		(duplicate_pad_numbers_are_jumpers no)
		(fp_line
			(start -0.508 -0.9398)
			(end -0.508 0.9398)
			(stroke
				(width 0.1524)
				(type default)
			)
			(layer "F.SilkS")
		)
		(fp_line
			(start 0.508 -0.9398)
			(end -0.508 -0.9398)
			(stroke
				(width 0.1524)
				(type default)
			)
			(layer "F.SilkS")
		)
		(fp_rect
			(start -0.508 0.9398)
			(end 0.508 -0.9398)
			(stroke
				(width 0)
				(type default)
			)
			(fill no)
			(layer "F.CrtYd")
		)
		(fp_rect
			(start -0.508 0.9398)
			(end 0.508 -0.9398)
			(stroke
				(width 0)
				(type default)
			)
			(fill no)
			(layer "F.Fab")
		)
		(pad "1" smd custom
			(at 0 -0.4445)
			(size 0.1397 0.1397)
			(layers "F.Cu" "F.Mask" "F.Paste")
			(net "UPLINK3")
			(options
				(clearance outline)
				(anchor circle)
			)
			(primitives
				(gr_poly
					(pts
						(arc
							(start -0.1778 -0.2794)
							(mid -0.249642 -0.249642)
							(end -0.2794 -0.1778)
						)
						(arc
							(start -0.2794 0.1778)
							(mid -0.249642 0.249642)
							(end -0.1778 0.2794)
						)
						(arc
							(start 0.1778 0.2794)
							(mid 0.249642 0.249642)
							(end 0.2794 0.1778)
						)
						(arc
							(start 0.2794 -0.1778)
							(mid 0.249642 -0.249642)
							(end 0.1778 -0.2794)
						)
					)
					(width 0)
					(fill yes)
				)
			)
		)
		(pad "2" smd custom
			(at 0 0.4445)
			(size 0.1397 0.1397)
			(layers "F.Cu" "F.Mask" "F.Paste")
			(net "P3V3_STBY")
			(options
				(clearance outline)
				(anchor circle)
			)
			(primitives
				(gr_poly
					(pts
						(arc
							(start -0.1778 -0.2794)
							(mid -0.249642 -0.249642)
							(end -0.2794 -0.1778)
						)
						(arc
							(start -0.2794 0.1778)
							(mid -0.249642 0.249642)
							(end -0.1778 0.2794)
						)
						(arc
							(start 0.1778 0.2794)
							(mid 0.249642 0.249642)
							(end 0.2794 0.1778)
						)
						(arc
							(start 0.2794 -0.1778)
							(mid 0.249642 -0.249642)
							(end 0.1778 -0.2794)
						)
					)
					(width 0)
					(fill yes)
				)
			)
		)
	)
	(footprint ""
		(layer "F.Cu")
		(at 74.564748 -123.6726)
		(property "Reference" "U52"
			(at 0 0 0)
			(layer "F.SilkS")
			(hide yes)
			(effects
				(font
					(size 1.27 1.27)
				)
			)
		)
		(property "Value" "SN74LVC1G07DCKRG4-2-GP"
			(at -2.3368 -8.6868 0)
			(unlocked yes)
			(layer "F.Fab")
			(hide yes)
			(effects
				(font
					(size 1.016 1.016)
					(thickness 0.1524)
				)
			)
		)
		(property "Device Type" "SC70-5H44"
			(at -2.3114 -10.414 0)
			(unlocked yes)
			(layer "F.Fab")
			(hide yes)
			(effects
				(font
					(size 1.016 1.016)
					(thickness 0.1524)
				)
			)
		)
		(duplicate_pad_numbers_are_jumpers no)
		(fp_line
			(start -1.27 -1.7018)
			(end 1.27 -1.7018)
			(stroke
				(width 0.1524)
				(type default)
			)
			(layer "F.SilkS")
		)
		(fp_line
			(start -1.27 1.7018)
			(end -1.27 -1.7018)
			(stroke
				(width 0.1524)
				(type default)
			)
			(layer "F.SilkS")
		)
		(fp_line
			(start 0.6604 -1.8034)
			(end 1.3843 -1.8034)
			(stroke
				(width 0.3302)
				(type default)
			)
			(layer "F.SilkS")
		)
		(fp_line
			(start 1.27 -1.7018)
			(end 1.27 1.7018)
			(stroke
				(width 0.1524)
				(type default)
			)
			(layer "F.SilkS")
		)
		(fp_line
			(start 1.27 1.7018)
			(end -1.27 1.7018)
			(stroke
				(width 0.1524)
				(type default)
			)
			(layer "F.SilkS")
		)
		(fp_line
			(start 1.3843 -1.8034)
			(end 1.3843 -1.1176)
			(stroke
				(width 0.3302)
				(type default)
			)
			(layer "F.SilkS")
		)
		(fp_rect
			(start -1.524 1.9558)
			(end 1.524 -1.9558)
			(stroke
				(width 0)
				(type default)
			)
			(fill no)
			(layer "F.CrtYd")
		)
		(fp_poly
			(pts
				(xy -1.524 -1.9558) (xy 1.524 -1.9558) (xy 1.524 1.9558) (xy -1.524 1.9558)
			)
			(stroke
				(width 0)
				(type default)
			)
			(fill no)
			(layer "F.Fab")
		)
		(pad "1" smd rect
			(at 0.65024 -0.8255)
			(size 0.4064 1.2192)
			(layers "F.Cu" "F.Mask" "F.Paste")
			(net "Net_113")
		)
		(pad "2" smd rect
			(at 0 -0.8255)
			(size 0.4064 1.2192)
			(layers "F.Cu" "F.Mask" "F.Paste")
			(net "BMC_RXD5")
		)
		(pad "3" smd rect
			(at -0.65024 -0.8255)
			(size 0.4064 1.2192)
			(layers "F.Cu" "F.Mask" "F.Paste")
			(net "GND")
		)
		(pad "4" smd rect
			(at -0.65024 0.8255)
			(size 0.4064 1.2192)
			(layers "F.Cu" "F.Mask" "F.Paste")
			(net "BMC_RXD5_R")
		)
		(pad "5" smd rect
			(at 0.65024 0.8255)
			(size 0.4064 1.2192)
			(layers "F.Cu" "F.Mask" "F.Paste")
			(net "P3V3_STBY")
		)
	)
	(footprint ""
		(layer "F.Cu")
		(at 323.80809 -212.420454 180)
		(property "Reference" "C65"
			(at 0 0 180)
			(layer "F.SilkS")
			(hide yes)
			(effects
				(font
					(size 1.27 1.27)
				)
			)
		)
		(property "Value" "SCD22U10V2KX-1GP"
			(at 1.1811 -2.7051 180)
			(unlocked yes)
			(layer "F.Fab")
			(hide yes)
			(effects
				(font
					(size 1.016 1.016)
					(thickness 0.1524)
				)
			)
		)
		(property "Device Type" "C402H22"
			(at 1.1811 -4.2291 180)
			(unlocked yes)
			(layer "F.Fab")
			(hide yes)
			(effects
				(font
					(size 1.016 1.016)
					(thickness 0.1524)
				)
			)
		)
		(duplicate_pad_numbers_are_jumpers no)
		(fp_rect
			(start -0.4318 0.9525)
			(end 0.4318 -0.9525)
			(stroke
				(width 0)
				(type default)
			)
			(fill no)
			(layer "F.CrtYd")
		)
		(fp_rect
			(start -0.4318 0.9525)
			(end 0.4318 -0.9525)
			(stroke
				(width 0)
				(type default)
			)
			(fill no)
			(layer "F.Fab")
		)
		(pad "1" smd custom
			(at 0 -0.4445 180)
			(size 0.1524 0.1524)
			(layers "F.Cu" "F.Mask" "F.Paste")
			(net "PCIE_TX_CAP_N21")
			(options
				(clearance outline)
				(anchor circle)
			)
			(primitives
				(gr_poly
					(pts
						(arc
							(start 0.3048 -0.2032)
							(mid 0.275042 -0.275042)
							(end 0.2032 -0.3048)
						)
						(arc
							(start -0.2032 -0.3048)
							(mid -0.275042 -0.275042)
							(end -0.3048 -0.2032)
						)
						(arc
							(start -0.3048 0.2032)
							(mid -0.275042 0.275042)
							(end -0.2032 0.3048)
						)
						(arc
							(start 0.2032 0.3048)
							(mid 0.275042 0.275042)
							(end 0.3048 0.2032)
						)
					)
					(width 0)
					(fill yes)
				)
			)
		)
		(pad "2" smd custom
			(at 0 0.4445 180)
			(size 0.1524 0.1524)
			(layers "F.Cu" "F.Mask" "F.Paste")
			(net "PCIE_TX_N21")
			(options
				(clearance outline)
				(anchor circle)
			)
			(primitives
				(gr_poly
					(pts
						(arc
							(start 0.3048 -0.2032)
							(mid 0.275042 -0.275042)
							(end 0.2032 -0.3048)
						)
						(arc
							(start -0.2032 -0.3048)
							(mid -0.275042 -0.275042)
							(end -0.3048 -0.2032)
						)
						(arc
							(start -0.3048 0.2032)
							(mid -0.275042 0.275042)
							(end -0.2032 0.3048)
						)
						(arc
							(start 0.2032 0.3048)
							(mid 0.275042 0.275042)
							(end 0.3048 0.2032)
						)
					)
					(width 0)
					(fill yes)
				)
			)
		)
	)
	(footprint ""
		(layer "F.Cu")
		(at 264.07745 -4.340098 180)
		(property "Reference" "C266"
			(at 0 0 180)
			(layer "F.SilkS")
			(hide yes)
			(effects
				(font
					(size 1.27 1.27)
				)
			)
		)
		(property "Value" "SCD1U16V2JX-1-GP"
			(at 1.1811 -2.7051 180)
			(unlocked yes)
			(layer "F.Fab")
			(hide yes)
			(effects
				(font
					(size 1.016 1.016)
					(thickness 0.1524)
				)
			)
		)
		(property "Device Type" "C402H22"
			(at 1.1811 -4.2291 180)
			(unlocked yes)
			(layer "F.Fab")
			(hide yes)
			(effects
				(font
					(size 1.016 1.016)
					(thickness 0.1524)
				)
			)
		)
		(duplicate_pad_numbers_are_jumpers no)
		(fp_rect
			(start -0.4318 0.9525)
			(end 0.4318 -0.9525)
			(stroke
				(width 0)
				(type default)
			)
			(fill no)
			(layer "F.CrtYd")
		)
		(fp_rect
			(start -0.4318 0.9525)
			(end 0.4318 -0.9525)
			(stroke
				(width 0)
				(type default)
			)
			(fill no)
			(layer "F.Fab")
		)
		(pad "1" smd custom
			(at 0 -0.4445 180)
			(size 0.1524 0.1524)
			(layers "F.Cu" "F.Mask" "F.Paste")
			(net "RST_BTN#")
			(options
				(clearance outline)
				(anchor circle)
			)
			(primitives
				(gr_poly
					(pts
						(arc
							(start 0.3048 -0.2032)
							(mid 0.275042 -0.275042)
							(end 0.2032 -0.3048)
						)
						(arc
							(start -0.2032 -0.3048)
							(mid -0.275042 -0.275042)
							(end -0.3048 -0.2032)
						)
						(arc
							(start -0.3048 0.2032)
							(mid -0.275042 0.275042)
							(end -0.2032 0.3048)
						)
						(arc
							(start 0.2032 0.3048)
							(mid 0.275042 0.275042)
							(end 0.3048 0.2032)
						)
					)
					(width 0)
					(fill yes)
				)
			)
		)
		(pad "2" smd custom
			(at 0 0.4445 180)
			(size 0.1524 0.1524)
			(layers "F.Cu" "F.Mask" "F.Paste")
			(net "GND")
			(options
				(clearance outline)
				(anchor circle)
			)
			(primitives
				(gr_poly
					(pts
						(arc
							(start 0.3048 -0.2032)
							(mid 0.275042 -0.275042)
							(end 0.2032 -0.3048)
						)
						(arc
							(start -0.2032 -0.3048)
							(mid -0.275042 -0.275042)
							(end -0.3048 -0.2032)
						)
						(arc
							(start -0.3048 0.2032)
							(mid -0.275042 0.275042)
							(end -0.2032 0.3048)
						)
						(arc
							(start 0.2032 0.3048)
							(mid 0.275042 0.275042)
							(end 0.3048 0.2032)
						)
					)
					(width 0)
					(fill yes)
				)
			)
		)
	)
	(footprint ""
		(layer "F.Cu")
		(at 273.100038 -25.940004 90)
		(property "Reference" "CN9"
			(at 0 0 90)
			(layer "F.SilkS")
			(hide yes)
			(effects
				(font
					(size 1.27 1.27)
				)
			)
		)
		(property "Value" "FOX-CON2-S23-GP"
			(at 5.334 1.4478 90)
			(unlocked yes)
			(layer "F.Fab")
			(hide yes)
			(effects
				(font
					(size 1.016 1.016)
					(thickness 0.1524)
				)
			)
		)
		(property "Device Type" "HBA1030-H300R-EF"
			(at 5.334 -0.0762 90)
			(unlocked yes)
			(layer "F.Fab")
			(hide yes)
			(effects
				(font
					(size 1.016 1.016)
					(thickness 0.1524)
				)
			)
		)
		(duplicate_pad_numbers_are_jumpers no)
		(fp_line
			(start -4.082288 -1.63576)
			(end -2.812288 -1.63576)
			(stroke
				(width 0.4064)
				(type default)
			)
			(layer "F.SilkS")
		)
		(fp_line
			(start 3.937 -1.4859)
			(end 3.937 1.4859)
			(stroke
				(width 0.1524)
				(type default)
			)
			(layer "F.SilkS")
		)
		(fp_line
			(start -3.937 -1.4859)
			(end 3.937 -1.4859)
			(stroke
				(width 0.1524)
				(type default)
			)
			(layer "F.SilkS")
		)
		(fp_line
			(start -4.082288 -0.36576)
			(end -4.082288 -1.63576)
			(stroke
				(width 0.4064)
				(type default)
			)
			(layer "F.SilkS")
		)
		(fp_line
			(start 3.937 1.4859)
			(end -3.937 1.4859)
			(stroke
				(width 0.1524)
				(type default)
			)
			(layer "F.SilkS")
		)
		(fp_line
			(start -3.937 1.4859)
			(end -3.937 -1.4859)
			(stroke
				(width 0.1524)
				(type default)
			)
			(layer "F.SilkS")
		)
		(fp_circle
			(center 2.54 0)
			(end 2.54 1.0668)
			(stroke
				(width 0.3048)
				(type default)
			)
			(fill no)
			(layer "F.SilkS")
		)
		(fp_circle
			(center -2.54 0)
			(end -2.54 1.0668)
			(stroke
				(width 0.3048)
				(type default)
			)
			(fill no)
			(layer "F.SilkS")
		)
		(fp_rect
			(start -3.683 1.2319)
			(end 3.683 -1.2319)
			(stroke
				(width 0)
				(type default)
			)
			(fill no)
			(layer "F.CrtYd")
		)
		(fp_poly
			(pts
				(xy -4.191 1.7399) (xy -4.191 -1.7399) (xy 4.191 -1.7399) (xy 4.191 1.7399) (xy -0.2413 1.7399)
				(xy -0.2413 1.2319) (xy 3.683 1.2319) (xy 3.683 -1.2319) (xy -3.683 -1.2319) (xy -3.683 1.2319)
				(xy -0.254 1.2319) (xy -0.254 1.7399)
			)
			(stroke
				(width 0)
				(type default)
			)
			(fill no)
			(layer "F.CrtYd")
		)
		(fp_rect
			(start -4.191 1.7399)
			(end 4.191 -1.7399)
			(stroke
				(width 0)
				(type default)
			)
			(fill no)
			(layer "F.Fab")
		)
		(pad "1" thru_hole circle
			(at -2.54 0 90)
			(size 1.4224 1.4224)
			(drill 1.016)
			(layers "*.Cu" "*.Mask")
			(remove_unused_layers no)
			(net "GND")
			(clearance 0.1524)
			(thermal_gap 0.1524)
		)
		(pad "2" thru_hole circle
			(at 2.54 0 90)
			(size 1.4224 1.4224)
			(drill 1.016)
			(layers "*.Cu" "*.Mask")
			(remove_unused_layers no)
			(net "GND")
			(clearance 0.1524)
			(thermal_gap 0.1524)
		)
	)
	(footprint ""
		(layer "F.Cu")
		(at 10.287 -120.65 180)
		(property "Reference" "U8"
			(at 0 0 180)
			(layer "F.SilkS")
			(hide yes)
			(effects
				(font
					(size 1.27 1.27)
				)
			)
		)
		(property "Value" "2N7002DW-7F-GP"
			(at -2.3622 -8.2042 180)
			(unlocked yes)
			(layer "F.Fab")
			(hide yes)
			(effects
				(font
					(size 1.016 1.016)
					(thickness 0.1524)
				)
			)
		)
		(property "Device Type" "SOT-363H44"
			(at -2.3622 -10.1092 180)
			(unlocked yes)
			(layer "F.Fab")
			(hide yes)
			(effects
				(font
					(size 1.016 1.016)
					(thickness 0.1524)
				)
			)
		)
		(duplicate_pad_numbers_are_jumpers no)
		(fp_line
			(start 1.4478 1.7018)
			(end 1.4478 -1.7018)
			(stroke
				(width 0.1524)
				(type default)
			)
			(layer "F.SilkS")
		)
		(fp_line
			(start 1.4478 -1.7018)
			(end -1.4478 -1.7018)
			(stroke
				(width 0.1524)
				(type default)
			)
			(layer "F.SilkS")
		)
		(fp_line
			(start -1.27 1.524)
			(end -1.27 0.6604)
			(stroke
				(width 0.4826)
				(type default)
			)
			(layer "F.SilkS")
		)
		(fp_line
			(start -1.4478 1.7018)
			(end 1.4478 1.7018)
			(stroke
				(width 0.1524)
				(type default)
			)
			(layer "F.SilkS")
		)
		(fp_line
			(start -1.4478 -1.7018)
			(end -1.4478 1.7018)
			(stroke
				(width 0.1524)
				(type default)
			)
			(layer "F.SilkS")
		)
		(fp_poly
			(pts
				(xy -1.524 -1.778) (xy 1.524 -1.778) (xy 1.524 1.778) (xy -1.524 1.778)
			)
			(stroke
				(width 0)
				(type default)
			)
			(fill no)
			(layer "F.CrtYd")
		)
		(fp_poly
			(pts
				(xy -1.524 -1.778) (xy 1.524 -1.778) (xy 1.524 1.778) (xy -1.524 1.778)
			)
			(stroke
				(width 0)
				(type default)
			)
			(fill no)
			(layer "F.Fab")
		)
		(pad "1" smd rect
			(at -0.65024 0.9398 180)
			(size 0.4064 1.016)
			(layers "F.Cu" "F.Mask" "F.Paste")
			(net "BMC_I2C1_MINI1_SCL_S")
		)
		(pad "2" smd rect
			(at 0 0.9398 180)
			(size 0.4064 1.016)
			(layers "F.Cu" "F.Mask" "F.Paste")
			(net "I2C1_LS_G2")
		)
		(pad "3" smd rect
			(at 0.65024 0.9398 180)
			(size 0.4064 1.016)
			(layers "F.Cu" "F.Mask" "F.Paste")
			(net "BMC_I2C1_MINI1_SDA")
		)
		(pad "4" smd rect
			(at 0.65024 -0.9398 180)
			(size 0.4064 1.016)
			(layers "F.Cu" "F.Mask" "F.Paste")
			(net "BMC_I2C1_MINI1_SDA_S")
		)
		(pad "5" smd rect
			(at 0 -0.9398 180)
			(size 0.4064 1.016)
			(layers "F.Cu" "F.Mask" "F.Paste")
			(net "I2C1_LS_G1")
		)
		(pad "6" smd rect
			(at -0.65024 -0.9398 180)
			(size 0.4064 1.016)
			(layers "F.Cu" "F.Mask" "F.Paste")
			(net "BMC_I2C1_MINI1_SCL")
		)
	)
	(footprint ""
		(layer "F.Cu")
		(at 22.4663 -178.3461 -90)
		(property "Reference" "R690"
			(at 0 0 270)
			(layer "F.SilkS")
			(hide yes)
			(effects
				(font
					(size 1.27 1.27)
				)
			)
		)
		(property "Value" "10KR3F-L-GP"
			(at -0.0254 -2.5146 270)
			(unlocked yes)
			(layer "F.Fab")
			(hide yes)
			(effects
				(font
					(size 1.016 1.016)
					(thickness 0.1524)
				)
			)
		)
		(property "Device Type" "R603H22"
			(at -0.0254 -4.0386 270)
			(unlocked yes)
			(layer "F.Fab")
			(hide yes)
			(effects
				(font
					(size 1.016 1.016)
					(thickness 0.1524)
				)
			)
		)
		(duplicate_pad_numbers_are_jumpers no)
		(fp_line
			(start -0.4826 0)
			(end -0.2032 0)
			(stroke
				(width 0.2032)
				(type default)
			)
			(layer "F.SilkS")
		)
		(fp_line
			(start 0.2032 0)
			(end 0.4826 0)
			(stroke
				(width 0.2032)
				(type default)
			)
			(layer "F.SilkS")
		)
		(fp_rect
			(start -0.5842 1.3335)
			(end 0.5842 -1.3335)
			(stroke
				(width 0)
				(type default)
			)
			(fill no)
			(layer "F.CrtYd")
		)
		(fp_rect
			(start -0.5842 1.3335)
			(end 0.5842 -1.3335)
			(stroke
				(width 0)
				(type default)
			)
			(fill no)
			(layer "F.Fab")
		)
		(pad "1" smd custom
			(at 0 -0.762 270)
			(size 0.2159 0.2159)
			(layers "F.Cu" "F.Mask" "F.Paste")
			(net "P12V_PCIE")
			(options
				(clearance outline)
				(anchor circle)
			)
			(primitives
				(gr_poly
					(pts
						(arc
							(start -0.3302 -0.4318)
							(mid -0.402042 -0.402042)
							(end -0.4318 -0.3302)
						)
						(arc
							(start -0.4318 0.3302)
							(mid -0.402042 0.402042)
							(end -0.3302 0.4318)
						)
						(arc
							(start 0.3302 0.4318)
							(mid 0.402042 0.402042)
							(end 0.4318 0.3302)
						)
						(arc
							(start 0.4318 -0.3302)
							(mid 0.402042 -0.402042)
							(end 0.3302 -0.4318)
						)
					)
					(width 0)
					(fill yes)
				)
			)
		)
		(pad "2" smd custom
			(at 0 0.762 270)
			(size 0.2159 0.2159)
			(layers "F.Cu" "F.Mask" "F.Paste")
			(net "MATED_P12V_EN")
			(options
				(clearance outline)
				(anchor circle)
			)
			(primitives
				(gr_poly
					(pts
						(arc
							(start -0.3302 -0.4318)
							(mid -0.402042 -0.402042)
							(end -0.4318 -0.3302)
						)
						(arc
							(start -0.4318 0.3302)
							(mid -0.402042 0.402042)
							(end -0.3302 0.4318)
						)
						(arc
							(start 0.3302 0.4318)
							(mid 0.402042 0.402042)
							(end 0.4318 0.3302)
						)
						(arc
							(start 0.4318 -0.3302)
							(mid 0.402042 -0.402042)
							(end 0.3302 -0.4318)
						)
					)
					(width 0)
					(fill yes)
				)
			)
		)
	)
	(footprint ""
		(layer "F.Cu")
		(at 120.4976 -17.0688)
		(property "Reference" "R746"
			(at 0 0 0)
			(layer "F.SilkS")
			(hide yes)
			(effects
				(font
					(size 1.27 1.27)
				)
			)
		)
		(property "Value" "4K7R2F-GP"
			(at 0.064008 -3.993896 0)
			(unlocked yes)
			(layer "F.Fab")
			(hide yes)
			(effects
				(font
					(size 1.016 1.016)
					(thickness 0.1524)
				)
			)
		)
		(property "Device Type" "R402H16"
			(at 0.064008 -5.517896 0)
			(unlocked yes)
			(layer "F.Fab")
			(hide yes)
			(effects
				(font
					(size 1.016 1.016)
					(thickness 0.1524)
				)
			)
		)
		(duplicate_pad_numbers_are_jumpers no)
		(fp_line
			(start -0.508 -0.9398)
			(end -0.508 0.9398)
			(stroke
				(width 0.1524)
				(type default)
			)
			(layer "F.SilkS")
		)
		(fp_line
			(start 0.508 -0.9398)
			(end -0.508 -0.9398)
			(stroke
				(width 0.1524)
				(type default)
			)
			(layer "F.SilkS")
		)
		(fp_rect
			(start -0.508 0.9398)
			(end 0.508 -0.9398)
			(stroke
				(width 0)
				(type default)
			)
			(fill no)
			(layer "F.CrtYd")
		)
		(fp_rect
			(start -0.508 0.9398)
			(end 0.508 -0.9398)
			(stroke
				(width 0)
				(type default)
			)
			(fill no)
			(layer "F.Fab")
		)
		(pad "1" smd custom
			(at 0 -0.4445)
			(size 0.1397 0.1397)
			(layers "F.Cu" "F.Mask" "F.Paste")
			(net "U54_A2")
			(options
				(clearance outline)
				(anchor circle)
			)
			(primitives
				(gr_poly
					(pts
						(arc
							(start -0.1778 -0.2794)
							(mid -0.249642 -0.249642)
							(end -0.2794 -0.1778)
						)
						(arc
							(start -0.2794 0.1778)
							(mid -0.249642 0.249642)
							(end -0.1778 0.2794)
						)
						(arc
							(start 0.1778 0.2794)
							(mid 0.249642 0.249642)
							(end 0.2794 0.1778)
						)
						(arc
							(start 0.2794 -0.1778)
							(mid 0.249642 -0.249642)
							(end 0.1778 -0.2794)
						)
					)
					(width 0)
					(fill yes)
				)
			)
		)
		(pad "2" smd custom
			(at 0 0.4445)
			(size 0.1397 0.1397)
			(layers "F.Cu" "F.Mask" "F.Paste")
			(net "P3V3_STBY")
			(options
				(clearance outline)
				(anchor circle)
			)
			(primitives
				(gr_poly
					(pts
						(arc
							(start -0.1778 -0.2794)
							(mid -0.249642 -0.249642)
							(end -0.2794 -0.1778)
						)
						(arc
							(start -0.2794 0.1778)
							(mid -0.249642 0.249642)
							(end -0.1778 0.2794)
						)
						(arc
							(start 0.1778 0.2794)
							(mid 0.249642 0.249642)
							(end 0.2794 0.1778)
						)
						(arc
							(start 0.2794 -0.1778)
							(mid 0.249642 -0.249642)
							(end 0.1778 -0.2794)
						)
					)
					(width 0)
					(fill yes)
				)
			)
		)
	)
	(footprint ""
		(layer "F.Cu")
		(at 53.730652 -112.25403 -90)
		(property "Reference" "R64"
			(at 0 0 270)
			(layer "F.SilkS")
			(hide yes)
			(effects
				(font
					(size 1.27 1.27)
				)
			)
		)
		(property "Value" "0R2J-2-GP"
			(at 0.064008 -3.993896 270)
			(unlocked yes)
			(layer "F.Fab")
			(hide yes)
			(effects
				(font
					(size 1.016 1.016)
					(thickness 0.1524)
				)
			)
		)
		(property "Device Type" "R402H16"
			(at 0.064008 -5.517896 270)
			(unlocked yes)
			(layer "F.Fab")
			(hide yes)
			(effects
				(font
					(size 1.016 1.016)
					(thickness 0.1524)
				)
			)
		)
		(duplicate_pad_numbers_are_jumpers no)
		(fp_line
			(start -0.508 -0.9398)
			(end -0.508 0.9398)
			(stroke
				(width 0.1524)
				(type default)
			)
			(layer "F.SilkS")
		)
		(fp_line
			(start 0.508 -0.9398)
			(end -0.508 -0.9398)
			(stroke
				(width 0.1524)
				(type default)
			)
			(layer "F.SilkS")
		)
		(fp_rect
			(start -0.508 0.9398)
			(end 0.508 -0.9398)
			(stroke
				(width 0)
				(type default)
			)
			(fill no)
			(layer "F.CrtYd")
		)
		(fp_rect
			(start -0.508 0.9398)
			(end 0.508 -0.9398)
			(stroke
				(width 0)
				(type default)
			)
			(fill no)
			(layer "F.Fab")
		)
		(pad "1" smd custom
			(at 0 -0.4445 270)
			(size 0.1397 0.1397)
			(layers "F.Cu" "F.Mask" "F.Paste")
			(net "BMC_I2C13_MINI7_SDA")
			(options
				(clearance outline)
				(anchor circle)
			)
			(primitives
				(gr_poly
					(pts
						(arc
							(start -0.1778 -0.2794)
							(mid -0.249642 -0.249642)
							(end -0.2794 -0.1778)
						)
						(arc
							(start -0.2794 0.1778)
							(mid -0.249642 0.249642)
							(end -0.1778 0.2794)
						)
						(arc
							(start 0.1778 0.2794)
							(mid 0.249642 0.249642)
							(end 0.2794 0.1778)
						)
						(arc
							(start 0.2794 -0.1778)
							(mid 0.249642 -0.249642)
							(end 0.1778 -0.2794)
						)
					)
					(width 0)
					(fill yes)
				)
			)
		)
		(pad "2" smd custom
			(at 0 0.4445 270)
			(size 0.1397 0.1397)
			(layers "F.Cu" "F.Mask" "F.Paste")
			(net "BMC_I2C13_MINI7_SDA_S")
			(options
				(clearance outline)
				(anchor circle)
			)
			(primitives
				(gr_poly
					(pts
						(arc
							(start -0.1778 -0.2794)
							(mid -0.249642 -0.249642)
							(end -0.2794 -0.1778)
						)
						(arc
							(start -0.2794 0.1778)
							(mid -0.249642 0.249642)
							(end -0.1778 0.2794)
						)
						(arc
							(start 0.1778 0.2794)
							(mid 0.249642 0.249642)
							(end 0.2794 0.1778)
						)
						(arc
							(start 0.2794 -0.1778)
							(mid 0.249642 -0.249642)
							(end 0.1778 -0.2794)
						)
					)
					(width 0)
					(fill yes)
				)
			)
		)
	)
	(footprint ""
		(layer "F.Cu")
		(at 49.40808 -212.420454 180)
		(property "Reference" "C365"
			(at 0 0 180)
			(layer "F.SilkS")
			(hide yes)
			(effects
				(font
					(size 1.27 1.27)
				)
			)
		)
		(property "Value" "SCD22U10V2KX-1GP"
			(at 1.1811 -2.7051 180)
			(unlocked yes)
			(layer "F.Fab")
			(hide yes)
			(effects
				(font
					(size 1.016 1.016)
					(thickness 0.1524)
				)
			)
		)
		(property "Device Type" "C402H22"
			(at 1.1811 -4.2291 180)
			(unlocked yes)
			(layer "F.Fab")
			(hide yes)
			(effects
				(font
					(size 1.016 1.016)
					(thickness 0.1524)
				)
			)
		)
		(duplicate_pad_numbers_are_jumpers no)
		(fp_rect
			(start -0.4318 0.9525)
			(end 0.4318 -0.9525)
			(stroke
				(width 0)
				(type default)
			)
			(fill no)
			(layer "F.CrtYd")
		)
		(fp_rect
			(start -0.4318 0.9525)
			(end 0.4318 -0.9525)
			(stroke
				(width 0)
				(type default)
			)
			(fill no)
			(layer "F.Fab")
		)
		(pad "1" smd custom
			(at 0 -0.4445 180)
			(size 0.1524 0.1524)
			(layers "F.Cu" "F.Mask" "F.Paste")
			(net "PCIE_TX_CAP_N75")
			(options
				(clearance outline)
				(anchor circle)
			)
			(primitives
				(gr_poly
					(pts
						(arc
							(start 0.3048 -0.2032)
							(mid 0.275042 -0.275042)
							(end 0.2032 -0.3048)
						)
						(arc
							(start -0.2032 -0.3048)
							(mid -0.275042 -0.275042)
							(end -0.3048 -0.2032)
						)
						(arc
							(start -0.3048 0.2032)
							(mid -0.275042 0.275042)
							(end -0.2032 0.3048)
						)
						(arc
							(start 0.2032 0.3048)
							(mid 0.275042 0.275042)
							(end 0.3048 0.2032)
						)
					)
					(width 0)
					(fill yes)
				)
			)
		)
		(pad "2" smd custom
			(at 0 0.4445 180)
			(size 0.1524 0.1524)
			(layers "F.Cu" "F.Mask" "F.Paste")
			(net "PCIE_TX_N75")
			(options
				(clearance outline)
				(anchor circle)
			)
			(primitives
				(gr_poly
					(pts
						(arc
							(start 0.3048 -0.2032)
							(mid 0.275042 -0.275042)
							(end 0.2032 -0.3048)
						)
						(arc
							(start -0.2032 -0.3048)
							(mid -0.275042 -0.275042)
							(end -0.3048 -0.2032)
						)
						(arc
							(start -0.3048 0.2032)
							(mid -0.275042 0.275042)
							(end -0.2032 0.3048)
						)
						(arc
							(start 0.2032 0.3048)
							(mid 0.275042 0.275042)
							(end 0.3048 0.2032)
						)
					)
					(width 0)
					(fill yes)
				)
			)
		)
	)
	(footprint ""
		(layer "F.Cu")
		(at 14.986 -113.411 90)
		(property "Reference" "PG69"
			(at 0 0 90)
			(layer "F.SilkS")
			(hide yes)
			(effects
				(font
					(size 1.27 1.27)
				)
			)
		)
		(property "Value" "GAP-CLOSE-PWR-3-GP"
			(at 0.0254 -6.5786 90)
			(unlocked yes)
			(layer "F.Fab")
			(hide yes)
			(effects
				(font
					(size 1.016 1.016)
					(thickness 0.1524)
				)
			)
		)
		(property "Device Type" "GAP-CLOSE-PWR-3"
			(at 0.0254 -8.255 90)
			(unlocked yes)
			(layer "F.Fab")
			(hide yes)
			(effects
				(font
					(size 1.016 1.016)
					(thickness 0.1524)
				)
			)
		)
		(duplicate_pad_numbers_are_jumpers no)
		(fp_rect
			(start -0.7112 0.4572)
			(end 0.7112 -0.4572)
			(stroke
				(width 0)
				(type default)
			)
			(fill no)
			(layer "F.CrtYd")
		)
		(fp_poly
			(pts
				(xy -0.7112 -0.4572) (xy 0.7112 -0.4572) (xy 0.7112 0.4572) (xy -0.7112 0.4572)
			)
			(stroke
				(width 0)
				(type default)
			)
			(fill no)
			(layer "F.Fab")
		)
		(pad "1" smd rect
			(at -0.3048 0 90)
			(size 0.6604 0.762)
			(layers "F.Cu" "F.Mask" "F.Paste")
			(net "P1V26_PWR")
		)
		(pad "2" smd rect
			(at 0.3048 0 90)
			(size 0.6604 0.762)
			(layers "F.Cu" "F.Mask" "F.Paste")
			(net "P1V26_STBY")
		)
	)
	(footprint ""
		(layer "F.Cu")
		(at 57.99201 -212.420454 180)
		(property "Reference" "C359"
			(at 0 0 180)
			(layer "F.SilkS")
			(hide yes)
			(effects
				(font
					(size 1.27 1.27)
				)
			)
		)
		(property "Value" "SCD22U10V2KX-1GP"
			(at 1.1811 -2.7051 180)
			(unlocked yes)
			(layer "F.Fab")
			(hide yes)
			(effects
				(font
					(size 1.016 1.016)
					(thickness 0.1524)
				)
			)
		)
		(property "Device Type" "C402H22"
			(at 1.1811 -4.2291 180)
			(unlocked yes)
			(layer "F.Fab")
			(hide yes)
			(effects
				(font
					(size 1.016 1.016)
					(thickness 0.1524)
				)
			)
		)
		(duplicate_pad_numbers_are_jumpers no)
		(fp_rect
			(start -0.4318 0.9525)
			(end 0.4318 -0.9525)
			(stroke
				(width 0)
				(type default)
			)
			(fill no)
			(layer "F.CrtYd")
		)
		(fp_rect
			(start -0.4318 0.9525)
			(end 0.4318 -0.9525)
			(stroke
				(width 0)
				(type default)
			)
			(fill no)
			(layer "F.Fab")
		)
		(pad "1" smd custom
			(at 0 -0.4445 180)
			(size 0.1524 0.1524)
			(layers "F.Cu" "F.Mask" "F.Paste")
			(net "PCIE_TX_CAP_P72")
			(options
				(clearance outline)
				(anchor circle)
			)
			(primitives
				(gr_poly
					(pts
						(arc
							(start 0.3048 -0.2032)
							(mid 0.275042 -0.275042)
							(end 0.2032 -0.3048)
						)
						(arc
							(start -0.2032 -0.3048)
							(mid -0.275042 -0.275042)
							(end -0.3048 -0.2032)
						)
						(arc
							(start -0.3048 0.2032)
							(mid -0.275042 0.275042)
							(end -0.2032 0.3048)
						)
						(arc
							(start 0.2032 0.3048)
							(mid 0.275042 0.275042)
							(end 0.3048 0.2032)
						)
					)
					(width 0)
					(fill yes)
				)
			)
		)
		(pad "2" smd custom
			(at 0 0.4445 180)
			(size 0.1524 0.1524)
			(layers "F.Cu" "F.Mask" "F.Paste")
			(net "PCIE_TX_P72")
			(options
				(clearance outline)
				(anchor circle)
			)
			(primitives
				(gr_poly
					(pts
						(arc
							(start 0.3048 -0.2032)
							(mid 0.275042 -0.275042)
							(end 0.2032 -0.3048)
						)
						(arc
							(start -0.2032 -0.3048)
							(mid -0.275042 -0.275042)
							(end -0.3048 -0.2032)
						)
						(arc
							(start -0.3048 0.2032)
							(mid -0.275042 0.275042)
							(end -0.2032 0.3048)
						)
						(arc
							(start 0.2032 0.3048)
							(mid 0.275042 0.275042)
							(end 0.3048 0.2032)
						)
					)
					(width 0)
					(fill yes)
				)
			)
		)
	)
	(footprint ""
		(layer "F.Cu")
		(at 21.0312 -193.6496 90)
		(property "Reference" "C7275"
			(at 0 0 90)
			(layer "F.SilkS")
			(hide yes)
			(effects
				(font
					(size 1.27 1.27)
				)
			)
		)
		(property "Value" "SC1U16V3KX-5GP"
			(at 0 -2.8194 90)
			(unlocked yes)
			(layer "F.Fab")
			(hide yes)
			(effects
				(font
					(size 1.016 1.016)
					(thickness 0.1524)
				)
			)
		)
		(property "Device Type" "C603H36"
			(at 0 -4.3434 90)
			(unlocked yes)
			(layer "F.Fab")
			(hide yes)
			(effects
				(font
					(size 1.016 1.016)
					(thickness 0.1524)
				)
			)
		)
		(duplicate_pad_numbers_are_jumpers no)
		(fp_line
			(start 0.508 0)
			(end -0.508 0)
			(stroke
				(width 0.2032)
				(type default)
			)
			(layer "F.SilkS")
		)
		(fp_rect
			(start -0.5842 1.3335)
			(end 0.5842 -1.3335)
			(stroke
				(width 0)
				(type default)
			)
			(fill no)
			(layer "F.CrtYd")
		)
		(fp_rect
			(start -0.5842 1.3335)
			(end 0.5842 -1.3335)
			(stroke
				(width 0)
				(type default)
			)
			(fill no)
			(layer "F.Fab")
		)
		(pad "1" smd custom
			(at 0 -0.762 90)
			(size 0.2159 0.2159)
			(layers "F.Cu" "F.Mask" "F.Paste")
			(net "MB0_CM_OV_R")
			(options
				(clearance outline)
				(anchor circle)
			)
			(primitives
				(gr_poly
					(pts
						(arc
							(start -0.3302 -0.4318)
							(mid -0.402042 -0.402042)
							(end -0.4318 -0.3302)
						)
						(arc
							(start -0.4318 0.3302)
							(mid -0.402042 0.402042)
							(end -0.3302 0.4318)
						)
						(arc
							(start 0.3302 0.4318)
							(mid 0.402042 0.402042)
							(end 0.4318 0.3302)
						)
						(arc
							(start 0.4318 -0.3302)
							(mid 0.402042 -0.402042)
							(end 0.3302 -0.4318)
						)
					)
					(width 0)
					(fill yes)
				)
			)
		)
		(pad "2" smd custom
			(at 0 0.762 90)
			(size 0.2159 0.2159)
			(layers "F.Cu" "F.Mask" "F.Paste")
			(net "AGND_CURRENT_MON")
			(options
				(clearance outline)
				(anchor circle)
			)
			(primitives
				(gr_poly
					(pts
						(arc
							(start -0.3302 -0.4318)
							(mid -0.402042 -0.402042)
							(end -0.4318 -0.3302)
						)
						(arc
							(start -0.4318 0.3302)
							(mid -0.402042 0.402042)
							(end -0.3302 0.4318)
						)
						(arc
							(start 0.3302 0.4318)
							(mid 0.402042 0.402042)
							(end 0.4318 0.3302)
						)
						(arc
							(start 0.4318 -0.3302)
							(mid 0.402042 -0.402042)
							(end 0.3302 -0.4318)
						)
					)
					(width 0)
					(fill yes)
				)
			)
		)
	)
	(footprint ""
		(layer "F.Cu")
		(at 320.421 -99.568)
		(property "Reference" "R7914"
			(at 0 0 0)
			(layer "F.SilkS")
			(hide yes)
			(effects
				(font
					(size 1.27 1.27)
				)
			)
		)
		(property "Value" "330R2J-3-GP"
			(at 0.064008 -3.993896 0)
			(unlocked yes)
			(layer "F.Fab")
			(hide yes)
			(effects
				(font
					(size 1.016 1.016)
					(thickness 0.1524)
				)
			)
		)
		(property "Device Type" "R402H16"
			(at 0.064008 -5.517896 0)
			(unlocked yes)
			(layer "F.Fab")
			(hide yes)
			(effects
				(font
					(size 1.016 1.016)
					(thickness 0.1524)
				)
			)
		)
		(duplicate_pad_numbers_are_jumpers no)
		(fp_line
			(start -0.508 -0.9398)
			(end -0.508 0.9398)
			(stroke
				(width 0.1524)
				(type default)
			)
			(layer "F.SilkS")
		)
		(fp_line
			(start 0.508 -0.9398)
			(end -0.508 -0.9398)
			(stroke
				(width 0.1524)
				(type default)
			)
			(layer "F.SilkS")
		)
		(fp_rect
			(start -0.508 0.9398)
			(end 0.508 -0.9398)
			(stroke
				(width 0)
				(type default)
			)
			(fill no)
			(layer "F.CrtYd")
		)
		(fp_rect
			(start -0.508 0.9398)
			(end 0.508 -0.9398)
			(stroke
				(width 0)
				(type default)
			)
			(fill no)
			(layer "F.Fab")
		)
		(pad "1" smd custom
			(at 0 -0.4445)
			(size 0.1397 0.1397)
			(layers "F.Cu" "F.Mask" "F.Paste")
			(net "TWI_SDA3")
			(options
				(clearance outline)
				(anchor circle)
			)
			(primitives
				(gr_poly
					(pts
						(arc
							(start -0.1778 -0.2794)
							(mid -0.249642 -0.249642)
							(end -0.2794 -0.1778)
						)
						(arc
							(start -0.2794 0.1778)
							(mid -0.249642 0.249642)
							(end -0.1778 0.2794)
						)
						(arc
							(start 0.1778 0.2794)
							(mid 0.249642 0.249642)
							(end 0.2794 0.1778)
						)
						(arc
							(start 0.2794 -0.1778)
							(mid 0.249642 -0.249642)
							(end 0.1778 -0.2794)
						)
					)
					(width 0)
					(fill yes)
				)
			)
		)
		(pad "2" smd custom
			(at 0 0.4445)
			(size 0.1397 0.1397)
			(layers "F.Cu" "F.Mask" "F.Paste")
			(net "IOEXP_TWI_SDA3")
			(options
				(clearance outline)
				(anchor circle)
			)
			(primitives
				(gr_poly
					(pts
						(arc
							(start -0.1778 -0.2794)
							(mid -0.249642 -0.249642)
							(end -0.2794 -0.1778)
						)
						(arc
							(start -0.2794 0.1778)
							(mid -0.249642 0.249642)
							(end -0.1778 0.2794)
						)
						(arc
							(start 0.1778 0.2794)
							(mid 0.249642 0.249642)
							(end 0.2794 0.1778)
						)
						(arc
							(start 0.2794 -0.1778)
							(mid 0.249642 -0.249642)
							(end 0.1778 -0.2794)
						)
					)
					(width 0)
					(fill yes)
				)
			)
		)
	)
	(footprint ""
		(layer "F.Cu")
		(at 288.544 -57.15 180)
		(property "Reference" "Q38"
			(at 0 0 180)
			(layer "F.SilkS")
			(hide yes)
			(effects
				(font
					(size 1.27 1.27)
				)
			)
		)
		(property "Value" "2N7002K-1-GP"
			(at 0.127 -8.9662 180)
			(unlocked yes)
			(layer "F.Fab")
			(hide yes)
			(effects
				(font
					(size 1.016 1.016)
					(thickness 0.1524)
				)
			)
		)
		(property "Device Type" "SOT23DGS2D4H44"
			(at 0.127 -10.4902 180)
			(unlocked yes)
			(layer "F.Fab")
			(hide yes)
			(effects
				(font
					(size 1.016 1.016)
					(thickness 0.1524)
				)
			)
		)
		(duplicate_pad_numbers_are_jumpers no)
		(fp_line
			(start 1.651 1.778)
			(end 1.651 -1.778)
			(stroke
				(width 0.1524)
				(type default)
			)
			(layer "F.SilkS")
		)
		(fp_line
			(start 1.651 -1.778)
			(end -1.651 -1.778)
			(stroke
				(width 0.1524)
				(type default)
			)
			(layer "F.SilkS")
		)
		(fp_line
			(start -1.651 1.778)
			(end 1.651 1.778)
			(stroke
				(width 0.1524)
				(type default)
			)
			(layer "F.SilkS")
		)
		(fp_line
			(start -1.651 -1.778)
			(end -1.651 1.778)
			(stroke
				(width 0.1524)
				(type default)
			)
			(layer "F.SilkS")
		)
		(fp_poly
			(pts
				(xy -1.778 1.8796) (xy -1.778 -1.8796) (xy 1.778 -1.8796) (xy 1.778 1.8796)
			)
			(stroke
				(width 0)
				(type default)
			)
			(fill no)
			(layer "F.CrtYd")
		)
		(fp_poly
			(pts
				(xy -1.778 1.8796) (xy -1.778 -1.8796) (xy 1.778 -1.8796) (xy 1.778 1.8796)
			)
			(stroke
				(width 0)
				(type default)
			)
			(fill no)
			(layer "F.Fab")
		)
		(pad "D" smd custom
			(at 0 -0.9525 180)
			(size 0.1905 0.1905)
			(layers "F.Cu" "F.Mask" "F.Paste")
			(net "LED_Q_13")
			(options
				(clearance outline)
				(anchor circle)
			)
			(primitives
				(gr_poly
					(pts
						(arc
							(start -0.1778 0.5715)
							(mid -0.321484 0.511984)
							(end -0.381 0.3683)
						)
						(arc
							(start -0.381 -0.3683)
							(mid -0.321484 -0.511984)
							(end -0.1778 -0.5715)
						)
						(arc
							(start 0.1778 -0.5715)
							(mid 0.321484 -0.511984)
							(end 0.381 -0.3683)
						)
						(arc
							(start 0.381 0.3683)
							(mid 0.321484 0.511984)
							(end 0.1778 0.5715)
						)
					)
					(width 0)
					(fill yes)
				)
			)
		)
		(pad "G" smd custom
			(at -0.98425 0.9525 180)
			(size 0.1905 0.1905)
			(layers "F.Cu" "F.Mask" "F.Paste")
			(net "VS5_LED_R")
			(options
				(clearance outline)
				(anchor circle)
			)
			(primitives
				(gr_poly
					(pts
						(arc
							(start -0.1778 0.5715)
							(mid -0.321484 0.511984)
							(end -0.381 0.3683)
						)
						(arc
							(start -0.381 -0.3683)
							(mid -0.321484 -0.511984)
							(end -0.1778 -0.5715)
						)
						(arc
							(start 0.1778 -0.5715)
							(mid 0.321484 -0.511984)
							(end 0.381 -0.3683)
						)
						(arc
							(start 0.381 0.3683)
							(mid 0.321484 0.511984)
							(end 0.1778 0.5715)
						)
					)
					(width 0)
					(fill yes)
				)
			)
		)
		(pad "S" smd custom
			(at 0.98425 0.9525 180)
			(size 0.1905 0.1905)
			(layers "F.Cu" "F.Mask" "F.Paste")
			(net "GND")
			(options
				(clearance outline)
				(anchor circle)
			)
			(primitives
				(gr_poly
					(pts
						(arc
							(start -0.1778 0.5715)
							(mid -0.321484 0.511984)
							(end -0.381 0.3683)
						)
						(arc
							(start -0.381 -0.3683)
							(mid -0.321484 -0.511984)
							(end -0.1778 -0.5715)
						)
						(arc
							(start 0.1778 -0.5715)
							(mid 0.321484 -0.511984)
							(end 0.381 -0.3683)
						)
						(arc
							(start 0.381 0.3683)
							(mid 0.321484 0.511984)
							(end 0.1778 0.5715)
						)
					)
					(width 0)
					(fill yes)
				)
			)
		)
	)
	(footprint ""
		(layer "F.Cu")
		(at 248.7676 -9.0424)
		(property "Reference" "C470"
			(at 0 0 0)
			(layer "F.SilkS")
			(hide yes)
			(effects
				(font
					(size 1.27 1.27)
				)
			)
		)
		(property "Value" "SC4D7U16V5KX-1-GP"
			(at -0.0762 -6.1214 0)
			(unlocked yes)
			(layer "F.Fab")
			(hide yes)
			(effects
				(font
					(size 1.016 1.016)
					(thickness 0.1524)
				)
			)
		)
		(property "Device Type" "C805H56"
			(at -0.0762 -8.1534 0)
			(unlocked yes)
			(layer "F.Fab")
			(hide yes)
			(effects
				(font
					(size 1.016 1.016)
					(thickness 0.1524)
				)
			)
		)
		(duplicate_pad_numbers_are_jumpers no)
		(fp_line
			(start 0.635 0)
			(end -0.635 0)
			(stroke
				(width 0.508)
				(type default)
			)
			(layer "F.SilkS")
		)
		(fp_rect
			(start -0.9652 1.778)
			(end 0.9652 -1.778)
			(stroke
				(width 0)
				(type default)
			)
			(fill no)
			(layer "F.CrtYd")
		)
		(fp_poly
			(pts
				(xy -0.9652 -1.778) (xy 0.9652 -1.778) (xy 0.9652 1.778) (xy -0.9652 1.778)
			)
			(stroke
				(width 0)
				(type default)
			)
			(fill no)
			(layer "F.Fab")
		)
		(pad "1" smd rect
			(at 0 -0.9652)
			(size 1.397 1.143)
			(layers "F.Cu" "F.Mask" "F.Paste")
			(net "DUT_VDDO")
		)
		(pad "2" smd rect
			(at 0 0.9652)
			(size 1.397 1.143)
			(layers "F.Cu" "F.Mask" "F.Paste")
			(net "GND")
		)
	)
	(footprint ""
		(layer "F.Cu")
		(at 7.874 -108.966 90)
		(property "Reference" "PR73"
			(at 0 0 90)
			(layer "F.SilkS")
			(hide yes)
			(effects
				(font
					(size 1.27 1.27)
				)
			)
		)
		(property "Value" "10KR2F-2-GP"
			(at 0.064008 -3.993896 90)
			(unlocked yes)
			(layer "F.Fab")
			(hide yes)
			(effects
				(font
					(size 1.016 1.016)
					(thickness 0.1524)
				)
			)
		)
		(property "Device Type" "R402H16"
			(at 0.064008 -5.517896 90)
			(unlocked yes)
			(layer "F.Fab")
			(hide yes)
			(effects
				(font
					(size 1.016 1.016)
					(thickness 0.1524)
				)
			)
		)
		(duplicate_pad_numbers_are_jumpers no)
		(fp_line
			(start 0.508 -0.9398)
			(end -0.508 -0.9398)
			(stroke
				(width 0.1524)
				(type default)
			)
			(layer "F.SilkS")
		)
		(fp_line
			(start -0.508 -0.9398)
			(end -0.508 0.9398)
			(stroke
				(width 0.1524)
				(type default)
			)
			(layer "F.SilkS")
		)
		(fp_rect
			(start -0.508 0.9398)
			(end 0.508 -0.9398)
			(stroke
				(width 0)
				(type default)
			)
			(fill no)
			(layer "F.CrtYd")
		)
		(fp_rect
			(start -0.508 0.9398)
			(end 0.508 -0.9398)
			(stroke
				(width 0)
				(type default)
			)
			(fill no)
			(layer "F.Fab")
		)
		(pad "1" smd custom
			(at 0 -0.4445 90)
			(size 0.1397 0.1397)
			(layers "F.Cu" "F.Mask" "F.Paste")
			(net "P3V3_STBY")
			(options
				(clearance outline)
				(anchor circle)
			)
			(primitives
				(gr_poly
					(pts
						(arc
							(start -0.1778 -0.2794)
							(mid -0.249642 -0.249642)
							(end -0.2794 -0.1778)
						)
						(arc
							(start -0.2794 0.1778)
							(mid -0.249642 0.249642)
							(end -0.1778 0.2794)
						)
						(arc
							(start 0.1778 0.2794)
							(mid 0.249642 0.249642)
							(end 0.2794 0.1778)
						)
						(arc
							(start 0.2794 -0.1778)
							(mid 0.249642 -0.249642)
							(end 0.1778 -0.2794)
						)
					)
					(width 0)
					(fill yes)
				)
			)
		)
		(pad "2" smd custom
			(at 0 0.4445 90)
			(size 0.1397 0.1397)
			(layers "F.Cu" "F.Mask" "F.Paste")
			(net "PWRGD_P1V26_STBY")
			(options
				(clearance outline)
				(anchor circle)
			)
			(primitives
				(gr_poly
					(pts
						(arc
							(start -0.1778 -0.2794)
							(mid -0.249642 -0.249642)
							(end -0.2794 -0.1778)
						)
						(arc
							(start -0.2794 0.1778)
							(mid -0.249642 0.249642)
							(end -0.1778 0.2794)
						)
						(arc
							(start 0.1778 0.2794)
							(mid 0.249642 0.249642)
							(end 0.2794 0.1778)
						)
						(arc
							(start 0.2794 -0.1778)
							(mid 0.249642 -0.249642)
							(end 0.1778 -0.2794)
						)
					)
					(width 0)
					(fill yes)
				)
			)
		)
	)
	(footprint ""
		(layer "F.Cu")
		(at 150.231602 -53.672232 90)
		(property "Reference" "R13"
			(at 0 0 90)
			(layer "F.SilkS")
			(hide yes)
			(effects
				(font
					(size 1.27 1.27)
				)
			)
		)
		(property "Value" "0R2J-2-GP"
			(at 0.064008 -3.993896 90)
			(unlocked yes)
			(layer "F.Fab")
			(hide yes)
			(effects
				(font
					(size 1.016 1.016)
					(thickness 0.1524)
				)
			)
		)
		(property "Device Type" "R402H16"
			(at 0.064008 -5.517896 90)
			(unlocked yes)
			(layer "F.Fab")
			(hide yes)
			(effects
				(font
					(size 1.016 1.016)
					(thickness 0.1524)
				)
			)
		)
		(duplicate_pad_numbers_are_jumpers no)
		(fp_line
			(start 0.508 -0.9398)
			(end -0.508 -0.9398)
			(stroke
				(width 0.1524)
				(type default)
			)
			(layer "F.SilkS")
		)
		(fp_line
			(start -0.508 -0.9398)
			(end -0.508 0.9398)
			(stroke
				(width 0.1524)
				(type default)
			)
			(layer "F.SilkS")
		)
		(fp_rect
			(start -0.508 0.9398)
			(end 0.508 -0.9398)
			(stroke
				(width 0)
				(type default)
			)
			(fill no)
			(layer "F.CrtYd")
		)
		(fp_rect
			(start -0.508 0.9398)
			(end 0.508 -0.9398)
			(stroke
				(width 0)
				(type default)
			)
			(fill no)
			(layer "F.Fab")
		)
		(pad "1" smd custom
			(at 0 -0.4445 90)
			(size 0.1397 0.1397)
			(layers "F.Cu" "F.Mask" "F.Paste")
			(net "AVS_ENB1_R")
			(options
				(clearance outline)
				(anchor circle)
			)
			(primitives
				(gr_poly
					(pts
						(arc
							(start -0.1778 -0.2794)
							(mid -0.249642 -0.249642)
							(end -0.2794 -0.1778)
						)
						(arc
							(start -0.2794 0.1778)
							(mid -0.249642 0.249642)
							(end -0.1778 0.2794)
						)
						(arc
							(start 0.1778 0.2794)
							(mid 0.249642 0.249642)
							(end 0.2794 0.1778)
						)
						(arc
							(start 0.2794 -0.1778)
							(mid 0.249642 -0.249642)
							(end 0.1778 -0.2794)
						)
					)
					(width 0)
					(fill yes)
				)
			)
		)
		(pad "2" smd custom
			(at 0 0.4445 90)
			(size 0.1397 0.1397)
			(layers "F.Cu" "F.Mask" "F.Paste")
			(net "AVS_ENB")
			(options
				(clearance outline)
				(anchor circle)
			)
			(primitives
				(gr_poly
					(pts
						(arc
							(start -0.1778 -0.2794)
							(mid -0.249642 -0.249642)
							(end -0.2794 -0.1778)
						)
						(arc
							(start -0.2794 0.1778)
							(mid -0.249642 0.249642)
							(end -0.1778 0.2794)
						)
						(arc
							(start 0.1778 0.2794)
							(mid 0.249642 0.249642)
							(end 0.2794 0.1778)
						)
						(arc
							(start 0.2794 -0.1778)
							(mid 0.249642 -0.249642)
							(end 0.1778 -0.2794)
						)
					)
					(width 0)
					(fill yes)
				)
			)
		)
	)
	(footprint ""
		(layer "F.Cu")
		(at 142.247874 -86.10092 -90)
		(property "Reference" "PC87"
			(at 0 0 270)
			(layer "F.SilkS")
			(hide yes)
			(effects
				(font
					(size 1.27 1.27)
				)
			)
		)
		(property "Value" "SCD01U25V2KX-3GP"
			(at 1.1811 -2.7051 270)
			(unlocked yes)
			(layer "F.Fab")
			(hide yes)
			(effects
				(font
					(size 1.016 1.016)
					(thickness 0.1524)
				)
			)
		)
		(property "Device Type" "C402H22"
			(at 1.1811 -4.2291 270)
			(unlocked yes)
			(layer "F.Fab")
			(hide yes)
			(effects
				(font
					(size 1.016 1.016)
					(thickness 0.1524)
				)
			)
		)
		(duplicate_pad_numbers_are_jumpers no)
		(fp_rect
			(start -0.4318 0.9525)
			(end 0.4318 -0.9525)
			(stroke
				(width 0)
				(type default)
			)
			(fill no)
			(layer "F.CrtYd")
		)
		(fp_rect
			(start -0.4318 0.9525)
			(end 0.4318 -0.9525)
			(stroke
				(width 0)
				(type default)
			)
			(fill no)
			(layer "F.Fab")
		)
		(pad "1" smd custom
			(at 0 -0.4445 270)
			(size 0.1524 0.1524)
			(layers "F.Cu" "F.Mask" "F.Paste")
			(net "P1V8_PWR")
			(options
				(clearance outline)
				(anchor circle)
			)
			(primitives
				(gr_poly
					(pts
						(arc
							(start 0.3048 -0.2032)
							(mid 0.275042 -0.275042)
							(end 0.2032 -0.3048)
						)
						(arc
							(start -0.2032 -0.3048)
							(mid -0.275042 -0.275042)
							(end -0.3048 -0.2032)
						)
						(arc
							(start -0.3048 0.2032)
							(mid -0.275042 0.275042)
							(end -0.2032 0.3048)
						)
						(arc
							(start 0.2032 0.3048)
							(mid 0.275042 0.275042)
							(end 0.3048 0.2032)
						)
					)
					(width 0)
					(fill yes)
				)
			)
		)
		(pad "2" smd custom
			(at 0 0.4445 270)
			(size 0.1524 0.1524)
			(layers "F.Cu" "F.Mask" "F.Paste")
			(net "VR_P1V8_STBY_FB")
			(options
				(clearance outline)
				(anchor circle)
			)
			(primitives
				(gr_poly
					(pts
						(arc
							(start 0.3048 -0.2032)
							(mid 0.275042 -0.275042)
							(end 0.2032 -0.3048)
						)
						(arc
							(start -0.2032 -0.3048)
							(mid -0.275042 -0.275042)
							(end -0.3048 -0.2032)
						)
						(arc
							(start -0.3048 0.2032)
							(mid -0.275042 0.275042)
							(end -0.2032 0.3048)
						)
						(arc
							(start 0.2032 0.3048)
							(mid 0.275042 0.275042)
							(end 0.3048 0.2032)
						)
					)
					(width 0)
					(fill yes)
				)
			)
		)
	)
	(footprint ""
		(layer "F.Cu")
		(at 166.116 -95.6564 90)
		(property "Reference" "R62"
			(at 0 0 90)
			(layer "F.SilkS")
			(hide yes)
			(effects
				(font
					(size 1.27 1.27)
				)
			)
		)
		(property "Value" "10KR2F-2-GP"
			(at 0.064008 -3.993896 90)
			(unlocked yes)
			(layer "F.Fab")
			(hide yes)
			(effects
				(font
					(size 1.016 1.016)
					(thickness 0.1524)
				)
			)
		)
		(property "Device Type" "R402H16"
			(at 0.064008 -5.517896 90)
			(unlocked yes)
			(layer "F.Fab")
			(hide yes)
			(effects
				(font
					(size 1.016 1.016)
					(thickness 0.1524)
				)
			)
		)
		(duplicate_pad_numbers_are_jumpers no)
		(fp_line
			(start 0.508 -0.9398)
			(end -0.508 -0.9398)
			(stroke
				(width 0.1524)
				(type default)
			)
			(layer "F.SilkS")
		)
		(fp_line
			(start -0.508 -0.9398)
			(end -0.508 0.9398)
			(stroke
				(width 0.1524)
				(type default)
			)
			(layer "F.SilkS")
		)
		(fp_rect
			(start -0.508 0.9398)
			(end 0.508 -0.9398)
			(stroke
				(width 0)
				(type default)
			)
			(fill no)
			(layer "F.CrtYd")
		)
		(fp_rect
			(start -0.508 0.9398)
			(end 0.508 -0.9398)
			(stroke
				(width 0)
				(type default)
			)
			(fill no)
			(layer "F.Fab")
		)
		(pad "1" smd custom
			(at 0 -0.4445 90)
			(size 0.1397 0.1397)
			(layers "F.Cu" "F.Mask" "F.Paste")
			(net "GND")
			(options
				(clearance outline)
				(anchor circle)
			)
			(primitives
				(gr_poly
					(pts
						(arc
							(start -0.1778 -0.2794)
							(mid -0.249642 -0.249642)
							(end -0.2794 -0.1778)
						)
						(arc
							(start -0.2794 0.1778)
							(mid -0.249642 0.249642)
							(end -0.1778 0.2794)
						)
						(arc
							(start 0.1778 0.2794)
							(mid 0.249642 0.249642)
							(end 0.2794 0.1778)
						)
						(arc
							(start 0.2794 -0.1778)
							(mid 0.249642 -0.249642)
							(end 0.1778 -0.2794)
						)
					)
					(width 0)
					(fill yes)
				)
			)
		)
		(pad "2" smd custom
			(at 0 0.4445 90)
			(size 0.1397 0.1397)
			(layers "F.Cu" "F.Mask" "F.Paste")
			(net "CLKGEN_OE2")
			(options
				(clearance outline)
				(anchor circle)
			)
			(primitives
				(gr_poly
					(pts
						(arc
							(start -0.1778 -0.2794)
							(mid -0.249642 -0.249642)
							(end -0.2794 -0.1778)
						)
						(arc
							(start -0.2794 0.1778)
							(mid -0.249642 0.249642)
							(end -0.1778 0.2794)
						)
						(arc
							(start 0.1778 0.2794)
							(mid 0.249642 0.249642)
							(end 0.2794 0.1778)
						)
						(arc
							(start 0.2794 -0.1778)
							(mid 0.249642 -0.249642)
							(end 0.1778 -0.2794)
						)
					)
					(width 0)
					(fill yes)
				)
			)
		)
	)
	(footprint ""
		(layer "F.Cu")
		(at 40.554148 -68.890642 90)
		(property "Reference" "PG1"
			(at 0 0 90)
			(layer "F.SilkS")
			(hide yes)
			(effects
				(font
					(size 1.27 1.27)
				)
			)
		)
		(property "Value" "GAP-CLOSE-PWR-3-GP"
			(at 0.0254 -6.5786 90)
			(unlocked yes)
			(layer "F.Fab")
			(hide yes)
			(effects
				(font
					(size 1.016 1.016)
					(thickness 0.1524)
				)
			)
		)
		(property "Device Type" "GAP-CLOSE-PWR-3"
			(at 0.0254 -8.255 90)
			(unlocked yes)
			(layer "F.Fab")
			(hide yes)
			(effects
				(font
					(size 1.016 1.016)
					(thickness 0.1524)
				)
			)
		)
		(duplicate_pad_numbers_are_jumpers no)
		(fp_rect
			(start -0.7112 0.4572)
			(end 0.7112 -0.4572)
			(stroke
				(width 0)
				(type default)
			)
			(fill no)
			(layer "F.CrtYd")
		)
		(fp_poly
			(pts
				(xy -0.7112 -0.4572) (xy 0.7112 -0.4572) (xy 0.7112 0.4572) (xy -0.7112 0.4572)
			)
			(stroke
				(width 0)
				(type default)
			)
			(fill no)
			(layer "F.Fab")
		)
		(pad "1" smd rect
			(at -0.3048 0 90)
			(size 0.6604 0.762)
			(layers "F.Cu" "F.Mask" "F.Paste")
			(net "P5V_STBY")
		)
		(pad "2" smd rect
			(at 0.3048 0 90)
			(size 0.6604 0.762)
			(layers "F.Cu" "F.Mask" "F.Paste")
			(net "P5V_STBY_LR")
		)
	)
	(footprint ""
		(layer "F.Cu")
		(at 16.891 -105.918 90)
		(property "Reference" "PC84"
			(at 0 0 90)
			(layer "F.SilkS")
			(hide yes)
			(effects
				(font
					(size 1.27 1.27)
				)
			)
		)
		(property "Value" "SC820P50V2KX-1GP"
			(at 1.1811 -2.7051 90)
			(unlocked yes)
			(layer "F.Fab")
			(hide yes)
			(effects
				(font
					(size 1.016 1.016)
					(thickness 0.1524)
				)
			)
		)
		(property "Device Type" "C402H22"
			(at 1.1811 -4.2291 90)
			(unlocked yes)
			(layer "F.Fab")
			(hide yes)
			(effects
				(font
					(size 1.016 1.016)
					(thickness 0.1524)
				)
			)
		)
		(duplicate_pad_numbers_are_jumpers no)
		(fp_rect
			(start -0.4318 0.9525)
			(end 0.4318 -0.9525)
			(stroke
				(width 0)
				(type default)
			)
			(fill no)
			(layer "F.CrtYd")
		)
		(fp_rect
			(start -0.4318 0.9525)
			(end 0.4318 -0.9525)
			(stroke
				(width 0)
				(type default)
			)
			(fill no)
			(layer "F.Fab")
		)
		(pad "1" smd custom
			(at 0 -0.4445 90)
			(size 0.1524 0.1524)
			(layers "F.Cu" "F.Mask" "F.Paste")
			(net "VR_P1V26_STBY_SS_C")
			(options
				(clearance outline)
				(anchor circle)
			)
			(primitives
				(gr_poly
					(pts
						(arc
							(start 0.3048 -0.2032)
							(mid 0.275042 -0.275042)
							(end 0.2032 -0.3048)
						)
						(arc
							(start -0.2032 -0.3048)
							(mid -0.275042 -0.275042)
							(end -0.3048 -0.2032)
						)
						(arc
							(start -0.3048 0.2032)
							(mid -0.275042 0.275042)
							(end -0.2032 0.3048)
						)
						(arc
							(start 0.2032 0.3048)
							(mid 0.275042 0.275042)
							(end 0.3048 0.2032)
						)
					)
					(width 0)
					(fill yes)
				)
			)
		)
		(pad "2" smd custom
			(at 0 0.4445 90)
			(size 0.1524 0.1524)
			(layers "F.Cu" "F.Mask" "F.Paste")
			(net "GND")
			(options
				(clearance outline)
				(anchor circle)
			)
			(primitives
				(gr_poly
					(pts
						(arc
							(start 0.3048 -0.2032)
							(mid 0.275042 -0.275042)
							(end 0.2032 -0.3048)
						)
						(arc
							(start -0.2032 -0.3048)
							(mid -0.275042 -0.275042)
							(end -0.3048 -0.2032)
						)
						(arc
							(start -0.3048 0.2032)
							(mid -0.275042 0.275042)
							(end -0.2032 0.3048)
						)
						(arc
							(start 0.2032 0.3048)
							(mid 0.275042 0.275042)
							(end 0.3048 0.2032)
						)
					)
					(width 0)
					(fill yes)
				)
			)
		)
	)
	(footprint ""
		(layer "F.Cu")
		(at 50.673 -191.262)
		(property "Reference" "R889"
			(at 0 0 0)
			(layer "F.SilkS")
			(hide yes)
			(effects
				(font
					(size 1.27 1.27)
				)
			)
		)
		(property "Value" "0R2J-2-GP"
			(at 0.064008 -3.993896 0)
			(unlocked yes)
			(layer "F.Fab")
			(hide yes)
			(effects
				(font
					(size 1.016 1.016)
					(thickness 0.1524)
				)
			)
		)
		(property "Device Type" "R402H16"
			(at 0.064008 -5.517896 0)
			(unlocked yes)
			(layer "F.Fab")
			(hide yes)
			(effects
				(font
					(size 1.016 1.016)
					(thickness 0.1524)
				)
			)
		)
		(duplicate_pad_numbers_are_jumpers no)
		(fp_line
			(start -0.508 -0.9398)
			(end -0.508 0.9398)
			(stroke
				(width 0.1524)
				(type default)
			)
			(layer "F.SilkS")
		)
		(fp_line
			(start 0.508 -0.9398)
			(end -0.508 -0.9398)
			(stroke
				(width 0.1524)
				(type default)
			)
			(layer "F.SilkS")
		)
		(fp_rect
			(start -0.508 0.9398)
			(end 0.508 -0.9398)
			(stroke
				(width 0)
				(type default)
			)
			(fill no)
			(layer "F.CrtYd")
		)
		(fp_rect
			(start -0.508 0.9398)
			(end 0.508 -0.9398)
			(stroke
				(width 0)
				(type default)
			)
			(fill no)
			(layer "F.Fab")
		)
		(pad "1" smd custom
			(at 0 -0.4445)
			(size 0.1397 0.1397)
			(layers "F.Cu" "F.Mask" "F.Paste")
			(net "BMC_I2C7_B_DPB_SDA_R")
			(options
				(clearance outline)
				(anchor circle)
			)
			(primitives
				(gr_poly
					(pts
						(arc
							(start -0.1778 -0.2794)
							(mid -0.249642 -0.249642)
							(end -0.2794 -0.1778)
						)
						(arc
							(start -0.2794 0.1778)
							(mid -0.249642 0.249642)
							(end -0.1778 0.2794)
						)
						(arc
							(start 0.1778 0.2794)
							(mid 0.249642 0.249642)
							(end 0.2794 0.1778)
						)
						(arc
							(start 0.2794 -0.1778)
							(mid 0.249642 -0.249642)
							(end 0.1778 -0.2794)
						)
					)
					(width 0)
					(fill yes)
				)
			)
		)
		(pad "2" smd custom
			(at 0 0.4445)
			(size 0.1397 0.1397)
			(layers "F.Cu" "F.Mask" "F.Paste")
			(net "BMC_I2C7_B_DPB_SDA")
			(options
				(clearance outline)
				(anchor circle)
			)
			(primitives
				(gr_poly
					(pts
						(arc
							(start -0.1778 -0.2794)
							(mid -0.249642 -0.249642)
							(end -0.2794 -0.1778)
						)
						(arc
							(start -0.2794 0.1778)
							(mid -0.249642 0.249642)
							(end -0.1778 0.2794)
						)
						(arc
							(start 0.1778 0.2794)
							(mid 0.249642 0.249642)
							(end 0.2794 0.1778)
						)
						(arc
							(start 0.2794 -0.1778)
							(mid 0.249642 -0.249642)
							(end 0.1778 -0.2794)
						)
					)
					(width 0)
					(fill yes)
				)
			)
		)
	)
	(footprint ""
		(layer "F.Cu")
		(at 59.00801 -212.420454 180)
		(property "Reference" "C360"
			(at 0 0 180)
			(layer "F.SilkS")
			(hide yes)
			(effects
				(font
					(size 1.27 1.27)
				)
			)
		)
		(property "Value" "SCD22U10V2KX-1GP"
			(at 1.1811 -2.7051 180)
			(unlocked yes)
			(layer "F.Fab")
			(hide yes)
			(effects
				(font
					(size 1.016 1.016)
					(thickness 0.1524)
				)
			)
		)
		(property "Device Type" "C402H22"
			(at 1.1811 -4.2291 180)
			(unlocked yes)
			(layer "F.Fab")
			(hide yes)
			(effects
				(font
					(size 1.016 1.016)
					(thickness 0.1524)
				)
			)
		)
		(duplicate_pad_numbers_are_jumpers no)
		(fp_rect
			(start -0.4318 0.9525)
			(end 0.4318 -0.9525)
			(stroke
				(width 0)
				(type default)
			)
			(fill no)
			(layer "F.CrtYd")
		)
		(fp_rect
			(start -0.4318 0.9525)
			(end 0.4318 -0.9525)
			(stroke
				(width 0)
				(type default)
			)
			(fill no)
			(layer "F.Fab")
		)
		(pad "1" smd custom
			(at 0 -0.4445 180)
			(size 0.1524 0.1524)
			(layers "F.Cu" "F.Mask" "F.Paste")
			(net "PCIE_TX_CAP_N72")
			(options
				(clearance outline)
				(anchor circle)
			)
			(primitives
				(gr_poly
					(pts
						(arc
							(start 0.3048 -0.2032)
							(mid 0.275042 -0.275042)
							(end 0.2032 -0.3048)
						)
						(arc
							(start -0.2032 -0.3048)
							(mid -0.275042 -0.275042)
							(end -0.3048 -0.2032)
						)
						(arc
							(start -0.3048 0.2032)
							(mid -0.275042 0.275042)
							(end -0.2032 0.3048)
						)
						(arc
							(start 0.2032 0.3048)
							(mid 0.275042 0.275042)
							(end 0.3048 0.2032)
						)
					)
					(width 0)
					(fill yes)
				)
			)
		)
		(pad "2" smd custom
			(at 0 0.4445 180)
			(size 0.1524 0.1524)
			(layers "F.Cu" "F.Mask" "F.Paste")
			(net "PCIE_TX_N72")
			(options
				(clearance outline)
				(anchor circle)
			)
			(primitives
				(gr_poly
					(pts
						(arc
							(start 0.3048 -0.2032)
							(mid 0.275042 -0.275042)
							(end 0.2032 -0.3048)
						)
						(arc
							(start -0.2032 -0.3048)
							(mid -0.275042 -0.275042)
							(end -0.3048 -0.2032)
						)
						(arc
							(start -0.3048 0.2032)
							(mid -0.275042 0.275042)
							(end -0.2032 0.3048)
						)
						(arc
							(start 0.2032 0.3048)
							(mid 0.275042 0.275042)
							(end 0.3048 0.2032)
						)
					)
					(width 0)
					(fill yes)
				)
			)
		)
	)
	(footprint ""
		(layer "F.Cu")
		(at 219.456 -12.319 -90)
		(property "Reference" "R654"
			(at 0 0 270)
			(layer "F.SilkS")
			(hide yes)
			(effects
				(font
					(size 1.27 1.27)
				)
			)
		)
		(property "Value" "100KR2F-L1-GP"
			(at 0.064008 -3.993896 270)
			(unlocked yes)
			(layer "F.Fab")
			(hide yes)
			(effects
				(font
					(size 1.016 1.016)
					(thickness 0.1524)
				)
			)
		)
		(property "Device Type" "R402H16"
			(at 0.064008 -5.517896 270)
			(unlocked yes)
			(layer "F.Fab")
			(hide yes)
			(effects
				(font
					(size 1.016 1.016)
					(thickness 0.1524)
				)
			)
		)
		(duplicate_pad_numbers_are_jumpers no)
		(fp_line
			(start -0.508 -0.9398)
			(end -0.508 0.9398)
			(stroke
				(width 0.1524)
				(type default)
			)
			(layer "F.SilkS")
		)
		(fp_line
			(start 0.508 -0.9398)
			(end -0.508 -0.9398)
			(stroke
				(width 0.1524)
				(type default)
			)
			(layer "F.SilkS")
		)
		(fp_rect
			(start -0.508 0.9398)
			(end 0.508 -0.9398)
			(stroke
				(width 0)
				(type default)
			)
			(fill no)
			(layer "F.CrtYd")
		)
		(fp_rect
			(start -0.508 0.9398)
			(end 0.508 -0.9398)
			(stroke
				(width 0)
				(type default)
			)
			(fill no)
			(layer "F.Fab")
		)
		(pad "1" smd custom
			(at 0 -0.4445 270)
			(size 0.1397 0.1397)
			(layers "F.Cu" "F.Mask" "F.Paste")
			(net "EEPROM_A0")
			(options
				(clearance outline)
				(anchor circle)
			)
			(primitives
				(gr_poly
					(pts
						(arc
							(start -0.1778 -0.2794)
							(mid -0.249642 -0.249642)
							(end -0.2794 -0.1778)
						)
						(arc
							(start -0.2794 0.1778)
							(mid -0.249642 0.249642)
							(end -0.1778 0.2794)
						)
						(arc
							(start 0.1778 0.2794)
							(mid 0.249642 0.249642)
							(end 0.2794 0.1778)
						)
						(arc
							(start 0.2794 -0.1778)
							(mid 0.249642 -0.249642)
							(end 0.1778 -0.2794)
						)
					)
					(width 0)
					(fill yes)
				)
			)
		)
		(pad "2" smd custom
			(at 0 0.4445 270)
			(size 0.1397 0.1397)
			(layers "F.Cu" "F.Mask" "F.Paste")
			(net "GND")
			(options
				(clearance outline)
				(anchor circle)
			)
			(primitives
				(gr_poly
					(pts
						(arc
							(start -0.1778 -0.2794)
							(mid -0.249642 -0.249642)
							(end -0.2794 -0.1778)
						)
						(arc
							(start -0.2794 0.1778)
							(mid -0.249642 0.249642)
							(end -0.1778 0.2794)
						)
						(arc
							(start 0.1778 0.2794)
							(mid 0.249642 0.249642)
							(end 0.2794 0.1778)
						)
						(arc
							(start 0.2794 -0.1778)
							(mid 0.249642 -0.249642)
							(end 0.1778 -0.2794)
						)
					)
					(width 0)
					(fill yes)
				)
			)
		)
	)
	(footprint ""
		(layer "F.Cu")
		(at 199.99198 -212.420454 180)
		(property "Reference" "C117"
			(at 0 0 180)
			(layer "F.SilkS")
			(hide yes)
			(effects
				(font
					(size 1.27 1.27)
				)
			)
		)
		(property "Value" "SCD22U10V2KX-1GP"
			(at 1.1811 -2.7051 180)
			(unlocked yes)
			(layer "F.Fab")
			(hide yes)
			(effects
				(font
					(size 1.016 1.016)
					(thickness 0.1524)
				)
			)
		)
		(property "Device Type" "C402H22"
			(at 1.1811 -4.2291 180)
			(unlocked yes)
			(layer "F.Fab")
			(hide yes)
			(effects
				(font
					(size 1.016 1.016)
					(thickness 0.1524)
				)
			)
		)
		(duplicate_pad_numbers_are_jumpers no)
		(fp_rect
			(start -0.4318 0.9525)
			(end 0.4318 -0.9525)
			(stroke
				(width 0)
				(type default)
			)
			(fill no)
			(layer "F.CrtYd")
		)
		(fp_rect
			(start -0.4318 0.9525)
			(end 0.4318 -0.9525)
			(stroke
				(width 0)
				(type default)
			)
			(fill no)
			(layer "F.Fab")
		)
		(pad "1" smd custom
			(at 0 -0.4445 180)
			(size 0.1524 0.1524)
			(layers "F.Cu" "F.Mask" "F.Paste")
			(net "PCIE_TX_CAP_P42")
			(options
				(clearance outline)
				(anchor circle)
			)
			(primitives
				(gr_poly
					(pts
						(arc
							(start 0.3048 -0.2032)
							(mid 0.275042 -0.275042)
							(end 0.2032 -0.3048)
						)
						(arc
							(start -0.2032 -0.3048)
							(mid -0.275042 -0.275042)
							(end -0.3048 -0.2032)
						)
						(arc
							(start -0.3048 0.2032)
							(mid -0.275042 0.275042)
							(end -0.2032 0.3048)
						)
						(arc
							(start 0.2032 0.3048)
							(mid 0.275042 0.275042)
							(end 0.3048 0.2032)
						)
					)
					(width 0)
					(fill yes)
				)
			)
		)
		(pad "2" smd custom
			(at 0 0.4445 180)
			(size 0.1524 0.1524)
			(layers "F.Cu" "F.Mask" "F.Paste")
			(net "PCIE_TX_P42")
			(options
				(clearance outline)
				(anchor circle)
			)
			(primitives
				(gr_poly
					(pts
						(arc
							(start 0.3048 -0.2032)
							(mid 0.275042 -0.275042)
							(end 0.2032 -0.3048)
						)
						(arc
							(start -0.2032 -0.3048)
							(mid -0.275042 -0.275042)
							(end -0.3048 -0.2032)
						)
						(arc
							(start -0.3048 0.2032)
							(mid -0.275042 0.275042)
							(end -0.2032 0.3048)
						)
						(arc
							(start 0.2032 0.3048)
							(mid 0.275042 0.275042)
							(end 0.3048 0.2032)
						)
					)
					(width 0)
					(fill yes)
				)
			)
		)
	)
	(footprint ""
		(layer "F.Cu")
		(at 229.108 -87.7824 -90)
		(property "Reference" "R178"
			(at 0 0 270)
			(layer "F.SilkS")
			(hide yes)
			(effects
				(font
					(size 1.27 1.27)
				)
			)
		)
		(property "Value" "4K7R2F-GP"
			(at 0.064008 -3.993896 270)
			(unlocked yes)
			(layer "F.Fab")
			(hide yes)
			(effects
				(font
					(size 1.016 1.016)
					(thickness 0.1524)
				)
			)
		)
		(property "Device Type" "R402H16"
			(at 0.064008 -5.517896 270)
			(unlocked yes)
			(layer "F.Fab")
			(hide yes)
			(effects
				(font
					(size 1.016 1.016)
					(thickness 0.1524)
				)
			)
		)
		(duplicate_pad_numbers_are_jumpers no)
		(fp_line
			(start -0.508 -0.9398)
			(end -0.508 0.9398)
			(stroke
				(width 0.1524)
				(type default)
			)
			(layer "F.SilkS")
		)
		(fp_line
			(start 0.508 -0.9398)
			(end -0.508 -0.9398)
			(stroke
				(width 0.1524)
				(type default)
			)
			(layer "F.SilkS")
		)
		(fp_rect
			(start -0.508 0.9398)
			(end 0.508 -0.9398)
			(stroke
				(width 0)
				(type default)
			)
			(fill no)
			(layer "F.CrtYd")
		)
		(fp_rect
			(start -0.508 0.9398)
			(end 0.508 -0.9398)
			(stroke
				(width 0)
				(type default)
			)
			(fill no)
			(layer "F.Fab")
		)
		(pad "1" smd custom
			(at 0 -0.4445 270)
			(size 0.1397 0.1397)
			(layers "F.Cu" "F.Mask" "F.Paste")
			(net "P3V3_STBY")
			(options
				(clearance outline)
				(anchor circle)
			)
			(primitives
				(gr_poly
					(pts
						(arc
							(start -0.1778 -0.2794)
							(mid -0.249642 -0.249642)
							(end -0.2794 -0.1778)
						)
						(arc
							(start -0.2794 0.1778)
							(mid -0.249642 0.249642)
							(end -0.1778 0.2794)
						)
						(arc
							(start 0.1778 0.2794)
							(mid 0.249642 0.249642)
							(end 0.2794 0.1778)
						)
						(arc
							(start 0.2794 -0.1778)
							(mid 0.249642 -0.249642)
							(end 0.1778 -0.2794)
						)
					)
					(width 0)
					(fill yes)
				)
			)
		)
		(pad "2" smd custom
			(at 0 0.4445 270)
			(size 0.1397 0.1397)
			(layers "F.Cu" "F.Mask" "F.Paste")
			(net "TEMP_3_A2")
			(options
				(clearance outline)
				(anchor circle)
			)
			(primitives
				(gr_poly
					(pts
						(arc
							(start -0.1778 -0.2794)
							(mid -0.249642 -0.249642)
							(end -0.2794 -0.1778)
						)
						(arc
							(start -0.2794 0.1778)
							(mid -0.249642 0.249642)
							(end -0.1778 0.2794)
						)
						(arc
							(start 0.1778 0.2794)
							(mid 0.249642 0.249642)
							(end 0.2794 0.1778)
						)
						(arc
							(start 0.2794 -0.1778)
							(mid 0.249642 -0.249642)
							(end 0.1778 -0.2794)
						)
					)
					(width 0)
					(fill yes)
				)
			)
		)
	)
	(footprint ""
		(layer "F.Cu")
		(at 26.035 -75.9206 -90)
		(property "Reference" "R393"
			(at 0 0 270)
			(layer "F.SilkS")
			(hide yes)
			(effects
				(font
					(size 1.27 1.27)
				)
			)
		)
		(property "Value" "10KR2F-2-GP"
			(at 0.064008 -3.993896 270)
			(unlocked yes)
			(layer "F.Fab")
			(hide yes)
			(effects
				(font
					(size 1.016 1.016)
					(thickness 0.1524)
				)
			)
		)
		(property "Device Type" "R402H16"
			(at 0.064008 -5.517896 270)
			(unlocked yes)
			(layer "F.Fab")
			(hide yes)
			(effects
				(font
					(size 1.016 1.016)
					(thickness 0.1524)
				)
			)
		)
		(duplicate_pad_numbers_are_jumpers no)
		(fp_line
			(start -0.508 -0.9398)
			(end -0.508 0.9398)
			(stroke
				(width 0.1524)
				(type default)
			)
			(layer "F.SilkS")
		)
		(fp_line
			(start 0.508 -0.9398)
			(end -0.508 -0.9398)
			(stroke
				(width 0.1524)
				(type default)
			)
			(layer "F.SilkS")
		)
		(fp_rect
			(start -0.508 0.9398)
			(end 0.508 -0.9398)
			(stroke
				(width 0)
				(type default)
			)
			(fill no)
			(layer "F.CrtYd")
		)
		(fp_rect
			(start -0.508 0.9398)
			(end 0.508 -0.9398)
			(stroke
				(width 0)
				(type default)
			)
			(fill no)
			(layer "F.Fab")
		)
		(pad "1" smd custom
			(at 0 -0.4445 270)
			(size 0.1397 0.1397)
			(layers "F.Cu" "F.Mask" "F.Paste")
			(net "P3V3_STBY")
			(options
				(clearance outline)
				(anchor circle)
			)
			(primitives
				(gr_poly
					(pts
						(arc
							(start -0.1778 -0.2794)
							(mid -0.249642 -0.249642)
							(end -0.2794 -0.1778)
						)
						(arc
							(start -0.2794 0.1778)
							(mid -0.249642 0.249642)
							(end -0.1778 0.2794)
						)
						(arc
							(start 0.1778 0.2794)
							(mid 0.249642 0.249642)
							(end 0.2794 0.1778)
						)
						(arc
							(start 0.2794 -0.1778)
							(mid 0.249642 -0.249642)
							(end 0.1778 -0.2794)
						)
					)
					(width 0)
					(fill yes)
				)
			)
		)
		(pad "2" smd custom
			(at 0 0.4445 270)
			(size 0.1397 0.1397)
			(layers "F.Cu" "F.Mask" "F.Paste")
			(net "RMII_BMC_PHY_TXD1")
			(options
				(clearance outline)
				(anchor circle)
			)
			(primitives
				(gr_poly
					(pts
						(arc
							(start -0.1778 -0.2794)
							(mid -0.249642 -0.249642)
							(end -0.2794 -0.1778)
						)
						(arc
							(start -0.2794 0.1778)
							(mid -0.249642 0.249642)
							(end -0.1778 0.2794)
						)
						(arc
							(start 0.1778 0.2794)
							(mid 0.249642 0.249642)
							(end 0.2794 0.1778)
						)
						(arc
							(start 0.2794 -0.1778)
							(mid 0.249642 -0.249642)
							(end 0.1778 -0.2794)
						)
					)
					(width 0)
					(fill yes)
				)
			)
		)
	)
	(footprint ""
		(layer "F.Cu")
		(at 267.592048 -212.420454 180)
		(property "Reference" "C105"
			(at 0 0 180)
			(layer "F.SilkS")
			(hide yes)
			(effects
				(font
					(size 1.27 1.27)
				)
			)
		)
		(property "Value" "SCD22U10V2KX-1GP"
			(at 1.1811 -2.7051 180)
			(unlocked yes)
			(layer "F.Fab")
			(hide yes)
			(effects
				(font
					(size 1.016 1.016)
					(thickness 0.1524)
				)
			)
		)
		(property "Device Type" "C402H22"
			(at 1.1811 -4.2291 180)
			(unlocked yes)
			(layer "F.Fab")
			(hide yes)
			(effects
				(font
					(size 1.016 1.016)
					(thickness 0.1524)
				)
			)
		)
		(duplicate_pad_numbers_are_jumpers no)
		(fp_rect
			(start -0.4318 0.9525)
			(end 0.4318 -0.9525)
			(stroke
				(width 0)
				(type default)
			)
			(fill no)
			(layer "F.CrtYd")
		)
		(fp_rect
			(start -0.4318 0.9525)
			(end 0.4318 -0.9525)
			(stroke
				(width 0)
				(type default)
			)
			(fill no)
			(layer "F.Fab")
		)
		(pad "1" smd custom
			(at 0 -0.4445 180)
			(size 0.1524 0.1524)
			(layers "F.Cu" "F.Mask" "F.Paste")
			(net "PCIE_TX_CAP_P36")
			(options
				(clearance outline)
				(anchor circle)
			)
			(primitives
				(gr_poly
					(pts
						(arc
							(start 0.3048 -0.2032)
							(mid 0.275042 -0.275042)
							(end 0.2032 -0.3048)
						)
						(arc
							(start -0.2032 -0.3048)
							(mid -0.275042 -0.275042)
							(end -0.3048 -0.2032)
						)
						(arc
							(start -0.3048 0.2032)
							(mid -0.275042 0.275042)
							(end -0.2032 0.3048)
						)
						(arc
							(start 0.2032 0.3048)
							(mid 0.275042 0.275042)
							(end 0.3048 0.2032)
						)
					)
					(width 0)
					(fill yes)
				)
			)
		)
		(pad "2" smd custom
			(at 0 0.4445 180)
			(size 0.1524 0.1524)
			(layers "F.Cu" "F.Mask" "F.Paste")
			(net "PCIE_TX_P36")
			(options
				(clearance outline)
				(anchor circle)
			)
			(primitives
				(gr_poly
					(pts
						(arc
							(start 0.3048 -0.2032)
							(mid 0.275042 -0.275042)
							(end 0.2032 -0.3048)
						)
						(arc
							(start -0.2032 -0.3048)
							(mid -0.275042 -0.275042)
							(end -0.3048 -0.2032)
						)
						(arc
							(start -0.3048 0.2032)
							(mid -0.275042 0.275042)
							(end -0.2032 0.3048)
						)
						(arc
							(start 0.2032 0.3048)
							(mid 0.275042 0.275042)
							(end 0.3048 0.2032)
						)
					)
					(width 0)
					(fill yes)
				)
			)
		)
	)
	(footprint ""
		(layer "F.Cu")
		(at 48.518572 -50.306224)
		(property "Reference" "R499"
			(at 0 0 0)
			(layer "F.SilkS")
			(hide yes)
			(effects
				(font
					(size 1.27 1.27)
				)
			)
		)
		(property "Value" "3K3R2F-2-GP"
			(at 0.064008 -3.993896 0)
			(unlocked yes)
			(layer "F.Fab")
			(hide yes)
			(effects
				(font
					(size 1.016 1.016)
					(thickness 0.1524)
				)
			)
		)
		(property "Device Type" "R402H16"
			(at 0.064008 -5.517896 0)
			(unlocked yes)
			(layer "F.Fab")
			(hide yes)
			(effects
				(font
					(size 1.016 1.016)
					(thickness 0.1524)
				)
			)
		)
		(duplicate_pad_numbers_are_jumpers no)
		(fp_line
			(start -0.508 -0.9398)
			(end -0.508 0.9398)
			(stroke
				(width 0.1524)
				(type default)
			)
			(layer "F.SilkS")
		)
		(fp_line
			(start 0.508 -0.9398)
			(end -0.508 -0.9398)
			(stroke
				(width 0.1524)
				(type default)
			)
			(layer "F.SilkS")
		)
		(fp_rect
			(start -0.508 0.9398)
			(end 0.508 -0.9398)
			(stroke
				(width 0)
				(type default)
			)
			(fill no)
			(layer "F.CrtYd")
		)
		(fp_rect
			(start -0.508 0.9398)
			(end 0.508 -0.9398)
			(stroke
				(width 0)
				(type default)
			)
			(fill no)
			(layer "F.Fab")
		)
		(pad "1" smd custom
			(at 0 -0.4445)
			(size 0.1397 0.1397)
			(layers "F.Cu" "F.Mask" "F.Paste")
			(net "NVM_SI_R")
			(options
				(clearance outline)
				(anchor circle)
			)
			(primitives
				(gr_poly
					(pts
						(arc
							(start -0.1778 -0.2794)
							(mid -0.249642 -0.249642)
							(end -0.2794 -0.1778)
						)
						(arc
							(start -0.2794 0.1778)
							(mid -0.249642 0.249642)
							(end -0.1778 0.2794)
						)
						(arc
							(start 0.1778 0.2794)
							(mid 0.249642 0.249642)
							(end 0.2794 0.1778)
						)
						(arc
							(start 0.2794 -0.1778)
							(mid 0.249642 -0.249642)
							(end 0.1778 -0.2794)
						)
					)
					(width 0)
					(fill yes)
				)
			)
		)
		(pad "2" smd custom
			(at 0 0.4445)
			(size 0.1397 0.1397)
			(layers "F.Cu" "F.Mask" "F.Paste")
			(net "GND")
			(options
				(clearance outline)
				(anchor circle)
			)
			(primitives
				(gr_poly
					(pts
						(arc
							(start -0.1778 -0.2794)
							(mid -0.249642 -0.249642)
							(end -0.2794 -0.1778)
						)
						(arc
							(start -0.2794 0.1778)
							(mid -0.249642 0.249642)
							(end -0.1778 0.2794)
						)
						(arc
							(start 0.1778 0.2794)
							(mid 0.249642 0.249642)
							(end 0.2794 0.1778)
						)
						(arc
							(start 0.2794 -0.1778)
							(mid 0.249642 -0.249642)
							(end 0.1778 -0.2794)
						)
					)
					(width 0)
					(fill yes)
				)
			)
		)
	)
	(footprint ""
		(layer "F.Cu")
		(at 330.099924 -7.999984 -90)
		(property "Reference" "LED15"
			(at 0 0 270)
			(layer "F.SilkS")
			(hide yes)
			(effects
				(font
					(size 1.27 1.27)
				)
			)
		)
		(property "Value" "LED-YG-51-GP"
			(at -2.6924 -1.4224 270)
			(unlocked yes)
			(layer "F.Fab")
			(hide yes)
			(effects
				(font
					(size 1.016 1.016)
					(thickness 0.1524)
				)
			)
		)
		(property "Device Type" "LED1608AKH40"
			(at -2.6924 -2.9464 270)
			(unlocked yes)
			(layer "F.Fab")
			(hide yes)
			(effects
				(font
					(size 1.016 1.016)
					(thickness 0.1524)
				)
			)
		)
		(duplicate_pad_numbers_are_jumpers no)
		(fp_line
			(start -0.7493 1.651)
			(end -0.7493 1.1811)
			(stroke
				(width 0.3302)
				(type default)
			)
			(layer "F.SilkS")
		)
		(fp_line
			(start 0.7493 1.651)
			(end 0.7493 1.1811)
			(stroke
				(width 0.3302)
				(type default)
			)
			(layer "F.SilkS")
		)
		(fp_line
			(start -0.5969 1.5494)
			(end 0.5842 1.5494)
			(stroke
				(width 0.508)
				(type default)
			)
			(layer "F.SilkS")
		)
		(fp_line
			(start -0.6604 1.3716)
			(end -0.6604 -1.3716)
			(stroke
				(width 0.1524)
				(type default)
			)
			(layer "F.SilkS")
		)
		(fp_line
			(start 0.6604 1.3716)
			(end -0.6604 1.3716)
			(stroke
				(width 0.1524)
				(type default)
			)
			(layer "F.SilkS")
		)
		(fp_line
			(start -0.6604 -1.3716)
			(end 0.6604 -1.3716)
			(stroke
				(width 0.1524)
				(type default)
			)
			(layer "F.SilkS")
		)
		(fp_line
			(start 0.6604 -1.3716)
			(end 0.6604 1.3716)
			(stroke
				(width 0.1524)
				(type default)
			)
			(layer "F.SilkS")
		)
		(fp_rect
			(start -0.6223 1.3335)
			(end 0.6223 -1.3335)
			(stroke
				(width 0)
				(type default)
			)
			(fill no)
			(layer "F.CrtYd")
		)
		(fp_rect
			(start -0.6223 1.3335)
			(end 0.6223 -1.3335)
			(stroke
				(width 0)
				(type default)
			)
			(fill no)
			(layer "F.Fab")
		)
		(pad "A" smd custom
			(at 0 -0.762 270)
			(size 0.2159 0.2159)
			(layers "F.Cu" "F.Mask" "F.Paste")
			(net "LED_R_7")
			(options
				(clearance outline)
				(anchor circle)
			)
			(primitives
				(gr_poly
					(pts
						(arc
							(start -0.3302 -0.4318)
							(mid -0.402042 -0.402042)
							(end -0.4318 -0.3302)
						)
						(arc
							(start -0.4318 0.3302)
							(mid -0.402042 0.402042)
							(end -0.3302 0.4318)
						)
						(arc
							(start 0.3302 0.4318)
							(mid 0.402042 0.402042)
							(end 0.4318 0.3302)
						)
						(arc
							(start 0.4318 -0.3302)
							(mid 0.402042 -0.402042)
							(end 0.3302 -0.4318)
						)
					)
					(width 0)
					(fill yes)
				)
			)
		)
		(pad "K" smd custom
			(at 0 0.762 270)
			(size 0.2159 0.2159)
			(layers "F.Cu" "F.Mask" "F.Paste")
			(net "LED_Q_7")
			(options
				(clearance outline)
				(anchor circle)
			)
			(primitives
				(gr_poly
					(pts
						(arc
							(start -0.3302 -0.4318)
							(mid -0.402042 -0.402042)
							(end -0.4318 -0.3302)
						)
						(arc
							(start -0.4318 0.3302)
							(mid -0.402042 0.402042)
							(end -0.3302 0.4318)
						)
						(arc
							(start 0.3302 0.4318)
							(mid 0.402042 0.402042)
							(end 0.4318 0.3302)
						)
						(arc
							(start 0.4318 -0.3302)
							(mid 0.402042 -0.402042)
							(end 0.3302 -0.4318)
						)
					)
					(width 0)
					(fill yes)
				)
			)
		)
	)
	(footprint ""
		(layer "F.Cu")
		(at 70.993 -32.004 90)
		(property "Reference" "PR33"
			(at 0 0 90)
			(layer "F.SilkS")
			(hide yes)
			(effects
				(font
					(size 1.27 1.27)
				)
			)
		)
		(property "Value" "44K2R2F-1-GP"
			(at 0.064008 -3.993896 90)
			(unlocked yes)
			(layer "F.Fab")
			(hide yes)
			(effects
				(font
					(size 1.016 1.016)
					(thickness 0.1524)
				)
			)
		)
		(property "Device Type" "R402H16"
			(at 0.064008 -5.517896 90)
			(unlocked yes)
			(layer "F.Fab")
			(hide yes)
			(effects
				(font
					(size 1.016 1.016)
					(thickness 0.1524)
				)
			)
		)
		(duplicate_pad_numbers_are_jumpers no)
		(fp_line
			(start 0.508 -0.9398)
			(end -0.508 -0.9398)
			(stroke
				(width 0.1524)
				(type default)
			)
			(layer "F.SilkS")
		)
		(fp_line
			(start -0.508 -0.9398)
			(end -0.508 0.9398)
			(stroke
				(width 0.1524)
				(type default)
			)
			(layer "F.SilkS")
		)
		(fp_rect
			(start -0.508 0.9398)
			(end 0.508 -0.9398)
			(stroke
				(width 0)
				(type default)
			)
			(fill no)
			(layer "F.CrtYd")
		)
		(fp_rect
			(start -0.508 0.9398)
			(end 0.508 -0.9398)
			(stroke
				(width 0)
				(type default)
			)
			(fill no)
			(layer "F.Fab")
		)
		(pad "1" smd custom
			(at 0 -0.4445 90)
			(size 0.1397 0.1397)
			(layers "F.Cu" "F.Mask" "F.Paste")
			(net "P3V3_STBY_VFB")
			(options
				(clearance outline)
				(anchor circle)
			)
			(primitives
				(gr_poly
					(pts
						(arc
							(start -0.1778 -0.2794)
							(mid -0.249642 -0.249642)
							(end -0.2794 -0.1778)
						)
						(arc
							(start -0.2794 0.1778)
							(mid -0.249642 0.249642)
							(end -0.1778 0.2794)
						)
						(arc
							(start 0.1778 0.2794)
							(mid 0.249642 0.249642)
							(end 0.2794 0.1778)
						)
						(arc
							(start 0.2794 -0.1778)
							(mid 0.249642 -0.249642)
							(end 0.1778 -0.2794)
						)
					)
					(width 0)
					(fill yes)
				)
			)
		)
		(pad "2" smd custom
			(at 0 0.4445 90)
			(size 0.1397 0.1397)
			(layers "F.Cu" "F.Mask" "F.Paste")
			(net "P3V3_STBY_VFB_R")
			(options
				(clearance outline)
				(anchor circle)
			)
			(primitives
				(gr_poly
					(pts
						(arc
							(start -0.1778 -0.2794)
							(mid -0.249642 -0.249642)
							(end -0.2794 -0.1778)
						)
						(arc
							(start -0.2794 0.1778)
							(mid -0.249642 0.249642)
							(end -0.1778 0.2794)
						)
						(arc
							(start 0.1778 0.2794)
							(mid 0.249642 0.249642)
							(end 0.2794 0.1778)
						)
						(arc
							(start 0.2794 -0.1778)
							(mid 0.249642 -0.249642)
							(end 0.1778 -0.2794)
						)
					)
					(width 0)
					(fill yes)
				)
			)
		)
	)
	(footprint ""
		(layer "F.Cu")
		(at 90.2081 -212.420454 180)
		(property "Reference" "C345"
			(at 0 0 180)
			(layer "F.SilkS")
			(hide yes)
			(effects
				(font
					(size 1.27 1.27)
				)
			)
		)
		(property "Value" "SCD22U10V2KX-1GP"
			(at 1.1811 -2.7051 180)
			(unlocked yes)
			(layer "F.Fab")
			(hide yes)
			(effects
				(font
					(size 1.016 1.016)
					(thickness 0.1524)
				)
			)
		)
		(property "Device Type" "C402H22"
			(at 1.1811 -4.2291 180)
			(unlocked yes)
			(layer "F.Fab")
			(hide yes)
			(effects
				(font
					(size 1.016 1.016)
					(thickness 0.1524)
				)
			)
		)
		(duplicate_pad_numbers_are_jumpers no)
		(fp_rect
			(start -0.4318 0.9525)
			(end 0.4318 -0.9525)
			(stroke
				(width 0)
				(type default)
			)
			(fill no)
			(layer "F.CrtYd")
		)
		(fp_rect
			(start -0.4318 0.9525)
			(end 0.4318 -0.9525)
			(stroke
				(width 0)
				(type default)
			)
			(fill no)
			(layer "F.Fab")
		)
		(pad "1" smd custom
			(at 0 -0.4445 180)
			(size 0.1524 0.1524)
			(layers "F.Cu" "F.Mask" "F.Paste")
			(net "PCIE_TX_CAP_N65")
			(options
				(clearance outline)
				(anchor circle)
			)
			(primitives
				(gr_poly
					(pts
						(arc
							(start 0.3048 -0.2032)
							(mid 0.275042 -0.275042)
							(end 0.2032 -0.3048)
						)
						(arc
							(start -0.2032 -0.3048)
							(mid -0.275042 -0.275042)
							(end -0.3048 -0.2032)
						)
						(arc
							(start -0.3048 0.2032)
							(mid -0.275042 0.275042)
							(end -0.2032 0.3048)
						)
						(arc
							(start 0.2032 0.3048)
							(mid 0.275042 0.275042)
							(end 0.3048 0.2032)
						)
					)
					(width 0)
					(fill yes)
				)
			)
		)
		(pad "2" smd custom
			(at 0 0.4445 180)
			(size 0.1524 0.1524)
			(layers "F.Cu" "F.Mask" "F.Paste")
			(net "PCIE_TX_N65")
			(options
				(clearance outline)
				(anchor circle)
			)
			(primitives
				(gr_poly
					(pts
						(arc
							(start 0.3048 -0.2032)
							(mid 0.275042 -0.275042)
							(end 0.2032 -0.3048)
						)
						(arc
							(start -0.2032 -0.3048)
							(mid -0.275042 -0.275042)
							(end -0.3048 -0.2032)
						)
						(arc
							(start -0.3048 0.2032)
							(mid -0.275042 0.275042)
							(end -0.2032 0.3048)
						)
						(arc
							(start 0.2032 0.3048)
							(mid 0.275042 0.275042)
							(end 0.3048 0.2032)
						)
					)
					(width 0)
					(fill yes)
				)
			)
		)
	)
	(footprint ""
		(layer "F.Cu")
		(at 178.1048 -66.167 180)
		(property "Reference" "PG14"
			(at 0 0 180)
			(layer "F.SilkS")
			(hide yes)
			(effects
				(font
					(size 1.27 1.27)
				)
			)
		)
		(property "Value" "GAP-CLOSE-PWR-3-GP"
			(at 0.0254 -6.5786 180)
			(unlocked yes)
			(layer "F.Fab")
			(hide yes)
			(effects
				(font
					(size 1.016 1.016)
					(thickness 0.1524)
				)
			)
		)
		(property "Device Type" "GAP-CLOSE-PWR-3"
			(at 0.0254 -8.255 180)
			(unlocked yes)
			(layer "F.Fab")
			(hide yes)
			(effects
				(font
					(size 1.016 1.016)
					(thickness 0.1524)
				)
			)
		)
		(duplicate_pad_numbers_are_jumpers no)
		(fp_rect
			(start -0.7112 0.4572)
			(end 0.7112 -0.4572)
			(stroke
				(width 0)
				(type default)
			)
			(fill no)
			(layer "F.CrtYd")
		)
		(fp_poly
			(pts
				(xy -0.7112 -0.4572) (xy 0.7112 -0.4572) (xy 0.7112 0.4572) (xy -0.7112 0.4572)
			)
			(stroke
				(width 0)
				(type default)
			)
			(fill no)
			(layer "F.Fab")
		)
		(pad "1" smd rect
			(at -0.3048 0 180)
			(size 0.6604 0.762)
			(layers "F.Cu" "F.Mask" "F.Paste")
			(net "DUT_AVD_PCIE")
		)
		(pad "2" smd rect
			(at 0.3048 0 180)
			(size 0.6604 0.762)
			(layers "F.Cu" "F.Mask" "F.Paste")
			(net "P0V9")
		)
	)
	(footprint ""
		(layer "F.Cu")
		(at 206.60995 -31.402274 90)
		(property "Reference" "R2980"
			(at 0 0 90)
			(layer "F.SilkS")
			(hide yes)
			(effects
				(font
					(size 1.27 1.27)
				)
			)
		)
		(property "Value" "0R2J-2-GP"
			(at 0.064008 -3.993896 90)
			(unlocked yes)
			(layer "F.Fab")
			(hide yes)
			(effects
				(font
					(size 1.016 1.016)
					(thickness 0.1524)
				)
			)
		)
		(property "Device Type" "R402H16"
			(at 0.064008 -5.517896 90)
			(unlocked yes)
			(layer "F.Fab")
			(hide yes)
			(effects
				(font
					(size 1.016 1.016)
					(thickness 0.1524)
				)
			)
		)
		(duplicate_pad_numbers_are_jumpers no)
		(fp_line
			(start 0.508 -0.9398)
			(end -0.508 -0.9398)
			(stroke
				(width 0.1524)
				(type default)
			)
			(layer "F.SilkS")
		)
		(fp_line
			(start -0.508 -0.9398)
			(end -0.508 0.9398)
			(stroke
				(width 0.1524)
				(type default)
			)
			(layer "F.SilkS")
		)
		(fp_rect
			(start -0.508 0.9398)
			(end 0.508 -0.9398)
			(stroke
				(width 0)
				(type default)
			)
			(fill no)
			(layer "F.CrtYd")
		)
		(fp_rect
			(start -0.508 0.9398)
			(end 0.508 -0.9398)
			(stroke
				(width 0)
				(type default)
			)
			(fill no)
			(layer "F.Fab")
		)
		(pad "1" smd custom
			(at 0 -0.4445 90)
			(size 0.1397 0.1397)
			(layers "F.Cu" "F.Mask" "F.Paste")
			(net "U55_SCL")
			(options
				(clearance outline)
				(anchor circle)
			)
			(primitives
				(gr_poly
					(pts
						(arc
							(start -0.1778 -0.2794)
							(mid -0.249642 -0.249642)
							(end -0.2794 -0.1778)
						)
						(arc
							(start -0.2794 0.1778)
							(mid -0.249642 0.249642)
							(end -0.1778 0.2794)
						)
						(arc
							(start 0.1778 0.2794)
							(mid 0.249642 0.249642)
							(end 0.2794 0.1778)
						)
						(arc
							(start 0.2794 -0.1778)
							(mid 0.249642 -0.249642)
							(end 0.1778 -0.2794)
						)
					)
					(width 0)
					(fill yes)
				)
			)
		)
		(pad "2" smd custom
			(at 0 0.4445 90)
			(size 0.1397 0.1397)
			(layers "F.Cu" "F.Mask" "F.Paste")
			(net "BMC_I2C11_MINI5_SCL_S")
			(options
				(clearance outline)
				(anchor circle)
			)
			(primitives
				(gr_poly
					(pts
						(arc
							(start -0.1778 -0.2794)
							(mid -0.249642 -0.249642)
							(end -0.2794 -0.1778)
						)
						(arc
							(start -0.2794 0.1778)
							(mid -0.249642 0.249642)
							(end -0.1778 0.2794)
						)
						(arc
							(start 0.1778 0.2794)
							(mid 0.249642 0.249642)
							(end 0.2794 0.1778)
						)
						(arc
							(start 0.2794 -0.1778)
							(mid 0.249642 -0.249642)
							(end 0.1778 -0.2794)
						)
					)
					(width 0)
					(fill yes)
				)
			)
		)
	)
	(footprint ""
		(layer "F.Cu")
		(at 280.392124 -212.420454 180)
		(property "Reference" "C97"
			(at 0 0 180)
			(layer "F.SilkS")
			(hide yes)
			(effects
				(font
					(size 1.27 1.27)
				)
			)
		)
		(property "Value" "SCD22U10V2KX-1GP"
			(at 1.1811 -2.7051 180)
			(unlocked yes)
			(layer "F.Fab")
			(hide yes)
			(effects
				(font
					(size 1.016 1.016)
					(thickness 0.1524)
				)
			)
		)
		(property "Device Type" "C402H22"
			(at 1.1811 -4.2291 180)
			(unlocked yes)
			(layer "F.Fab")
			(hide yes)
			(effects
				(font
					(size 1.016 1.016)
					(thickness 0.1524)
				)
			)
		)
		(duplicate_pad_numbers_are_jumpers no)
		(fp_rect
			(start -0.4318 0.9525)
			(end 0.4318 -0.9525)
			(stroke
				(width 0)
				(type default)
			)
			(fill no)
			(layer "F.CrtYd")
		)
		(fp_rect
			(start -0.4318 0.9525)
			(end 0.4318 -0.9525)
			(stroke
				(width 0)
				(type default)
			)
			(fill no)
			(layer "F.Fab")
		)
		(pad "1" smd custom
			(at 0 -0.4445 180)
			(size 0.1524 0.1524)
			(layers "F.Cu" "F.Mask" "F.Paste")
			(net "PCIE_TX_CAP_P32")
			(options
				(clearance outline)
				(anchor circle)
			)
			(primitives
				(gr_poly
					(pts
						(arc
							(start 0.3048 -0.2032)
							(mid 0.275042 -0.275042)
							(end 0.2032 -0.3048)
						)
						(arc
							(start -0.2032 -0.3048)
							(mid -0.275042 -0.275042)
							(end -0.3048 -0.2032)
						)
						(arc
							(start -0.3048 0.2032)
							(mid -0.275042 0.275042)
							(end -0.2032 0.3048)
						)
						(arc
							(start 0.2032 0.3048)
							(mid 0.275042 0.275042)
							(end 0.3048 0.2032)
						)
					)
					(width 0)
					(fill yes)
				)
			)
		)
		(pad "2" smd custom
			(at 0 0.4445 180)
			(size 0.1524 0.1524)
			(layers "F.Cu" "F.Mask" "F.Paste")
			(net "PCIE_TX_P32")
			(options
				(clearance outline)
				(anchor circle)
			)
			(primitives
				(gr_poly
					(pts
						(arc
							(start 0.3048 -0.2032)
							(mid 0.275042 -0.275042)
							(end 0.2032 -0.3048)
						)
						(arc
							(start -0.2032 -0.3048)
							(mid -0.275042 -0.275042)
							(end -0.3048 -0.2032)
						)
						(arc
							(start -0.3048 0.2032)
							(mid -0.275042 0.275042)
							(end -0.2032 0.3048)
						)
						(arc
							(start 0.2032 0.3048)
							(mid 0.275042 0.275042)
							(end 0.3048 0.2032)
						)
					)
					(width 0)
					(fill yes)
				)
			)
		)
	)
	(footprint ""
		(layer "F.Cu")
		(at 290.068 -33.528)
		(property "Reference" "C11"
			(at 0 0 0)
			(layer "F.SilkS")
			(hide yes)
			(effects
				(font
					(size 1.27 1.27)
				)
			)
		)
		(property "Value" "SCD22U10V2KX-1GP"
			(at 1.1811 -2.7051 0)
			(unlocked yes)
			(layer "F.Fab")
			(hide yes)
			(effects
				(font
					(size 1.016 1.016)
					(thickness 0.1524)
				)
			)
		)
		(property "Device Type" "C402H22"
			(at 1.1811 -4.2291 0)
			(unlocked yes)
			(layer "F.Fab")
			(hide yes)
			(effects
				(font
					(size 1.016 1.016)
					(thickness 0.1524)
				)
			)
		)
		(duplicate_pad_numbers_are_jumpers no)
		(fp_rect
			(start -0.4318 0.9525)
			(end 0.4318 -0.9525)
			(stroke
				(width 0)
				(type default)
			)
			(fill no)
			(layer "F.CrtYd")
		)
		(fp_rect
			(start -0.4318 0.9525)
			(end 0.4318 -0.9525)
			(stroke
				(width 0)
				(type default)
			)
			(fill no)
			(layer "F.Fab")
		)
		(pad "1" smd custom
			(at 0 -0.4445)
			(size 0.1524 0.1524)
			(layers "F.Cu" "F.Mask" "F.Paste")
			(net "PCIE_TX_CAP_N3")
			(options
				(clearance outline)
				(anchor circle)
			)
			(primitives
				(gr_poly
					(pts
						(arc
							(start 0.3048 -0.2032)
							(mid 0.275042 -0.275042)
							(end 0.2032 -0.3048)
						)
						(arc
							(start -0.2032 -0.3048)
							(mid -0.275042 -0.275042)
							(end -0.3048 -0.2032)
						)
						(arc
							(start -0.3048 0.2032)
							(mid -0.275042 0.275042)
							(end -0.2032 0.3048)
						)
						(arc
							(start 0.2032 0.3048)
							(mid 0.275042 0.275042)
							(end 0.3048 0.2032)
						)
					)
					(width 0)
					(fill yes)
				)
			)
		)
		(pad "2" smd custom
			(at 0 0.4445)
			(size 0.1524 0.1524)
			(layers "F.Cu" "F.Mask" "F.Paste")
			(net "PCIE_TX_N3")
			(options
				(clearance outline)
				(anchor circle)
			)
			(primitives
				(gr_poly
					(pts
						(arc
							(start 0.3048 -0.2032)
							(mid 0.275042 -0.275042)
							(end 0.2032 -0.3048)
						)
						(arc
							(start -0.2032 -0.3048)
							(mid -0.275042 -0.275042)
							(end -0.3048 -0.2032)
						)
						(arc
							(start -0.3048 0.2032)
							(mid -0.275042 0.275042)
							(end -0.2032 0.3048)
						)
						(arc
							(start 0.2032 0.3048)
							(mid 0.275042 0.275042)
							(end 0.3048 0.2032)
						)
					)
					(width 0)
					(fill yes)
				)
			)
		)
	)
	(footprint ""
		(layer "F.Cu")
		(at 134.0993 -33.54324)
		(property "Reference" "C384"
			(at 0 0 0)
			(layer "F.SilkS")
			(hide yes)
			(effects
				(font
					(size 1.27 1.27)
				)
			)
		)
		(property "Value" "SCD22U10V2KX-1GP"
			(at 1.1811 -2.7051 0)
			(unlocked yes)
			(layer "F.Fab")
			(hide yes)
			(effects
				(font
					(size 1.016 1.016)
					(thickness 0.1524)
				)
			)
		)
		(property "Device Type" "C402H22"
			(at 1.1811 -4.2291 0)
			(unlocked yes)
			(layer "F.Fab")
			(hide yes)
			(effects
				(font
					(size 1.016 1.016)
					(thickness 0.1524)
				)
			)
		)
		(duplicate_pad_numbers_are_jumpers no)
		(fp_rect
			(start -0.4318 0.9525)
			(end 0.4318 -0.9525)
			(stroke
				(width 0)
				(type default)
			)
			(fill no)
			(layer "F.CrtYd")
		)
		(fp_rect
			(start -0.4318 0.9525)
			(end 0.4318 -0.9525)
			(stroke
				(width 0)
				(type default)
			)
			(fill no)
			(layer "F.Fab")
		)
		(pad "1" smd custom
			(at 0 -0.4445)
			(size 0.1524 0.1524)
			(layers "F.Cu" "F.Mask" "F.Paste")
			(net "PCIE_TX_CAP_N82")
			(options
				(clearance outline)
				(anchor circle)
			)
			(primitives
				(gr_poly
					(pts
						(arc
							(start 0.3048 -0.2032)
							(mid 0.275042 -0.275042)
							(end 0.2032 -0.3048)
						)
						(arc
							(start -0.2032 -0.3048)
							(mid -0.275042 -0.275042)
							(end -0.3048 -0.2032)
						)
						(arc
							(start -0.3048 0.2032)
							(mid -0.275042 0.275042)
							(end -0.2032 0.3048)
						)
						(arc
							(start 0.2032 0.3048)
							(mid 0.275042 0.275042)
							(end 0.3048 0.2032)
						)
					)
					(width 0)
					(fill yes)
				)
			)
		)
		(pad "2" smd custom
			(at 0 0.4445)
			(size 0.1524 0.1524)
			(layers "F.Cu" "F.Mask" "F.Paste")
			(net "PCIE_TX_N82")
			(options
				(clearance outline)
				(anchor circle)
			)
			(primitives
				(gr_poly
					(pts
						(arc
							(start 0.3048 -0.2032)
							(mid 0.275042 -0.275042)
							(end 0.2032 -0.3048)
						)
						(arc
							(start -0.2032 -0.3048)
							(mid -0.275042 -0.275042)
							(end -0.3048 -0.2032)
						)
						(arc
							(start -0.3048 0.2032)
							(mid -0.275042 0.275042)
							(end -0.2032 0.3048)
						)
						(arc
							(start 0.2032 0.3048)
							(mid 0.275042 0.275042)
							(end 0.3048 0.2032)
						)
					)
					(width 0)
					(fill yes)
				)
			)
		)
	)
	(footprint ""
		(layer "F.Cu")
		(at 42.545 -204.216 90)
		(property "Reference" "C699"
			(at 0 0 90)
			(layer "F.SilkS")
			(hide yes)
			(effects
				(font
					(size 1.27 1.27)
				)
			)
		)
		(property "Value" "SC220P50V3JN-GP"
			(at 0 -2.8194 90)
			(unlocked yes)
			(layer "F.Fab")
			(hide yes)
			(effects
				(font
					(size 1.016 1.016)
					(thickness 0.1524)
				)
			)
		)
		(property "Device Type" "C603H36"
			(at 0 -4.3434 90)
			(unlocked yes)
			(layer "F.Fab")
			(hide yes)
			(effects
				(font
					(size 1.016 1.016)
					(thickness 0.1524)
				)
			)
		)
		(duplicate_pad_numbers_are_jumpers no)
		(fp_line
			(start 0.508 0)
			(end -0.508 0)
			(stroke
				(width 0.2032)
				(type default)
			)
			(layer "F.SilkS")
		)
		(fp_rect
			(start -0.5842 1.3335)
			(end 0.5842 -1.3335)
			(stroke
				(width 0)
				(type default)
			)
			(fill no)
			(layer "F.CrtYd")
		)
		(fp_rect
			(start -0.5842 1.3335)
			(end 0.5842 -1.3335)
			(stroke
				(width 0)
				(type default)
			)
			(fill no)
			(layer "F.Fab")
		)
		(pad "1" smd custom
			(at 0 -0.762 90)
			(size 0.2159 0.2159)
			(layers "F.Cu" "F.Mask" "F.Paste")
			(net "BUF_I2C6_C_FCB_SCL_R")
			(options
				(clearance outline)
				(anchor circle)
			)
			(primitives
				(gr_poly
					(pts
						(arc
							(start -0.3302 -0.4318)
							(mid -0.402042 -0.402042)
							(end -0.4318 -0.3302)
						)
						(arc
							(start -0.4318 0.3302)
							(mid -0.402042 0.402042)
							(end -0.3302 0.4318)
						)
						(arc
							(start 0.3302 0.4318)
							(mid 0.402042 0.402042)
							(end 0.4318 0.3302)
						)
						(arc
							(start 0.4318 -0.3302)
							(mid 0.402042 -0.402042)
							(end 0.3302 -0.4318)
						)
					)
					(width 0)
					(fill yes)
				)
			)
		)
		(pad "2" smd custom
			(at 0 0.762 90)
			(size 0.2159 0.2159)
			(layers "F.Cu" "F.Mask" "F.Paste")
			(net "GND")
			(options
				(clearance outline)
				(anchor circle)
			)
			(primitives
				(gr_poly
					(pts
						(arc
							(start -0.3302 -0.4318)
							(mid -0.402042 -0.402042)
							(end -0.4318 -0.3302)
						)
						(arc
							(start -0.4318 0.3302)
							(mid -0.402042 0.402042)
							(end -0.3302 0.4318)
						)
						(arc
							(start 0.3302 0.4318)
							(mid 0.402042 0.402042)
							(end 0.4318 0.3302)
						)
						(arc
							(start 0.4318 -0.3302)
							(mid 0.402042 -0.402042)
							(end 0.3302 -0.4318)
						)
					)
					(width 0)
					(fill yes)
				)
			)
		)
	)
	(footprint ""
		(layer "F.Cu")
		(at 16.764 -150.495 180)
		(property "Reference" "R491"
			(at 0 0 180)
			(layer "F.SilkS")
			(hide yes)
			(effects
				(font
					(size 1.27 1.27)
				)
			)
		)
		(property "Value" "0R2J-2-GP"
			(at 0.064008 -3.993896 180)
			(unlocked yes)
			(layer "F.Fab")
			(hide yes)
			(effects
				(font
					(size 1.016 1.016)
					(thickness 0.1524)
				)
			)
		)
		(property "Device Type" "R402H16"
			(at 0.064008 -5.517896 180)
			(unlocked yes)
			(layer "F.Fab")
			(hide yes)
			(effects
				(font
					(size 1.016 1.016)
					(thickness 0.1524)
				)
			)
		)
		(duplicate_pad_numbers_are_jumpers no)
		(fp_line
			(start 0.508 -0.9398)
			(end -0.508 -0.9398)
			(stroke
				(width 0.1524)
				(type default)
			)
			(layer "F.SilkS")
		)
		(fp_line
			(start -0.508 -0.9398)
			(end -0.508 0.9398)
			(stroke
				(width 0.1524)
				(type default)
			)
			(layer "F.SilkS")
		)
		(fp_rect
			(start -0.508 0.9398)
			(end 0.508 -0.9398)
			(stroke
				(width 0)
				(type default)
			)
			(fill no)
			(layer "F.CrtYd")
		)
		(fp_rect
			(start -0.508 0.9398)
			(end 0.508 -0.9398)
			(stroke
				(width 0)
				(type default)
			)
			(fill no)
			(layer "F.Fab")
		)
		(pad "1" smd custom
			(at 0 -0.4445 180)
			(size 0.1397 0.1397)
			(layers "F.Cu" "F.Mask" "F.Paste")
			(net "RST_BMC_DDR3_R_N")
			(options
				(clearance outline)
				(anchor circle)
			)
			(primitives
				(gr_poly
					(pts
						(arc
							(start -0.1778 -0.2794)
							(mid -0.249642 -0.249642)
							(end -0.2794 -0.1778)
						)
						(arc
							(start -0.2794 0.1778)
							(mid -0.249642 0.249642)
							(end -0.1778 0.2794)
						)
						(arc
							(start 0.1778 0.2794)
							(mid 0.249642 0.249642)
							(end 0.2794 0.1778)
						)
						(arc
							(start 0.2794 -0.1778)
							(mid 0.249642 -0.249642)
							(end 0.1778 -0.2794)
						)
					)
					(width 0)
					(fill yes)
				)
			)
		)
		(pad "2" smd custom
			(at 0 0.4445 180)
			(size 0.1397 0.1397)
			(layers "F.Cu" "F.Mask" "F.Paste")
			(net "BMC_DDR3_RST_N")
			(options
				(clearance outline)
				(anchor circle)
			)
			(primitives
				(gr_poly
					(pts
						(arc
							(start -0.1778 -0.2794)
							(mid -0.249642 -0.249642)
							(end -0.2794 -0.1778)
						)
						(arc
							(start -0.2794 0.1778)
							(mid -0.249642 0.249642)
							(end -0.1778 0.2794)
						)
						(arc
							(start 0.1778 0.2794)
							(mid 0.249642 0.249642)
							(end 0.2794 0.1778)
						)
						(arc
							(start 0.2794 -0.1778)
							(mid 0.249642 -0.249642)
							(end 0.1778 -0.2794)
						)
					)
					(width 0)
					(fill yes)
				)
			)
		)
	)
	(footprint ""
		(layer "F.Cu")
		(at 133.072124 -196.443092)
		(property "Reference" "R7974"
			(at 0 0 0)
			(layer "F.SilkS")
			(hide yes)
			(effects
				(font
					(size 1.27 1.27)
				)
			)
		)
		(property "Value" "0R2J-2-GP"
			(at 0.064008 -3.993896 0)
			(unlocked yes)
			(layer "F.Fab")
			(hide yes)
			(effects
				(font
					(size 1.016 1.016)
					(thickness 0.1524)
				)
			)
		)
		(property "Device Type" "R402H16"
			(at 0.064008 -5.517896 0)
			(unlocked yes)
			(layer "F.Fab")
			(hide yes)
			(effects
				(font
					(size 1.016 1.016)
					(thickness 0.1524)
				)
			)
		)
		(duplicate_pad_numbers_are_jumpers no)
		(fp_line
			(start -0.508 -0.9398)
			(end -0.508 0.9398)
			(stroke
				(width 0.1524)
				(type default)
			)
			(layer "F.SilkS")
		)
		(fp_line
			(start 0.508 -0.9398)
			(end -0.508 -0.9398)
			(stroke
				(width 0.1524)
				(type default)
			)
			(layer "F.SilkS")
		)
		(fp_rect
			(start -0.508 0.9398)
			(end 0.508 -0.9398)
			(stroke
				(width 0)
				(type default)
			)
			(fill no)
			(layer "F.CrtYd")
		)
		(fp_rect
			(start -0.508 0.9398)
			(end 0.508 -0.9398)
			(stroke
				(width 0)
				(type default)
			)
			(fill no)
			(layer "F.Fab")
		)
		(pad "1" smd custom
			(at 0 -0.4445)
			(size 0.1397 0.1397)
			(layers "F.Cu" "F.Mask" "F.Paste")
			(net "SSD_PERST#2")
			(options
				(clearance outline)
				(anchor circle)
			)
			(primitives
				(gr_poly
					(pts
						(arc
							(start -0.1778 -0.2794)
							(mid -0.249642 -0.249642)
							(end -0.2794 -0.1778)
						)
						(arc
							(start -0.2794 0.1778)
							(mid -0.249642 0.249642)
							(end -0.1778 0.2794)
						)
						(arc
							(start 0.1778 0.2794)
							(mid 0.249642 0.249642)
							(end 0.2794 0.1778)
						)
						(arc
							(start 0.2794 -0.1778)
							(mid 0.249642 -0.249642)
							(end 0.1778 -0.2794)
						)
					)
					(width 0)
					(fill yes)
				)
			)
		)
		(pad "2" smd custom
			(at 0 0.4445)
			(size 0.1397 0.1397)
			(layers "F.Cu" "F.Mask" "F.Paste")
			(net "SSD_PERST#2_R")
			(options
				(clearance outline)
				(anchor circle)
			)
			(primitives
				(gr_poly
					(pts
						(arc
							(start -0.1778 -0.2794)
							(mid -0.249642 -0.249642)
							(end -0.2794 -0.1778)
						)
						(arc
							(start -0.2794 0.1778)
							(mid -0.249642 0.249642)
							(end -0.1778 0.2794)
						)
						(arc
							(start 0.1778 0.2794)
							(mid 0.249642 0.249642)
							(end 0.2794 0.1778)
						)
						(arc
							(start 0.2794 -0.1778)
							(mid 0.249642 -0.249642)
							(end 0.1778 -0.2794)
						)
					)
					(width 0)
					(fill yes)
				)
			)
		)
	)
	(footprint ""
		(layer "F.Cu")
		(at 53.781452 -108.11383 -90)
		(property "Reference" "R65"
			(at 0 0 270)
			(layer "F.SilkS")
			(hide yes)
			(effects
				(font
					(size 1.27 1.27)
				)
			)
		)
		(property "Value" "0R2J-2-GP"
			(at 0.064008 -3.993896 270)
			(unlocked yes)
			(layer "F.Fab")
			(hide yes)
			(effects
				(font
					(size 1.016 1.016)
					(thickness 0.1524)
				)
			)
		)
		(property "Device Type" "R402H16"
			(at 0.064008 -5.517896 270)
			(unlocked yes)
			(layer "F.Fab")
			(hide yes)
			(effects
				(font
					(size 1.016 1.016)
					(thickness 0.1524)
				)
			)
		)
		(duplicate_pad_numbers_are_jumpers no)
		(fp_line
			(start -0.508 -0.9398)
			(end -0.508 0.9398)
			(stroke
				(width 0.1524)
				(type default)
			)
			(layer "F.SilkS")
		)
		(fp_line
			(start 0.508 -0.9398)
			(end -0.508 -0.9398)
			(stroke
				(width 0.1524)
				(type default)
			)
			(layer "F.SilkS")
		)
		(fp_rect
			(start -0.508 0.9398)
			(end 0.508 -0.9398)
			(stroke
				(width 0)
				(type default)
			)
			(fill no)
			(layer "F.CrtYd")
		)
		(fp_rect
			(start -0.508 0.9398)
			(end 0.508 -0.9398)
			(stroke
				(width 0)
				(type default)
			)
			(fill no)
			(layer "F.Fab")
		)
		(pad "1" smd custom
			(at 0 -0.4445 270)
			(size 0.1397 0.1397)
			(layers "F.Cu" "F.Mask" "F.Paste")
			(net "BMC_I2C13_MINI7_SCL_S")
			(options
				(clearance outline)
				(anchor circle)
			)
			(primitives
				(gr_poly
					(pts
						(arc
							(start -0.1778 -0.2794)
							(mid -0.249642 -0.249642)
							(end -0.2794 -0.1778)
						)
						(arc
							(start -0.2794 0.1778)
							(mid -0.249642 0.249642)
							(end -0.1778 0.2794)
						)
						(arc
							(start 0.1778 0.2794)
							(mid 0.249642 0.249642)
							(end 0.2794 0.1778)
						)
						(arc
							(start 0.2794 -0.1778)
							(mid 0.249642 -0.249642)
							(end 0.1778 -0.2794)
						)
					)
					(width 0)
					(fill yes)
				)
			)
		)
		(pad "2" smd custom
			(at 0 0.4445 270)
			(size 0.1397 0.1397)
			(layers "F.Cu" "F.Mask" "F.Paste")
			(net "BMC_I2C13_MINI7_SCL")
			(options
				(clearance outline)
				(anchor circle)
			)
			(primitives
				(gr_poly
					(pts
						(arc
							(start -0.1778 -0.2794)
							(mid -0.249642 -0.249642)
							(end -0.2794 -0.1778)
						)
						(arc
							(start -0.2794 0.1778)
							(mid -0.249642 0.249642)
							(end -0.1778 0.2794)
						)
						(arc
							(start 0.1778 0.2794)
							(mid 0.249642 0.249642)
							(end 0.2794 0.1778)
						)
						(arc
							(start 0.2794 -0.1778)
							(mid 0.249642 -0.249642)
							(end 0.1778 -0.2794)
						)
					)
					(width 0)
					(fill yes)
				)
			)
		)
	)
	(footprint ""
		(layer "F.Cu")
		(at 181.30012 -226.70008 180)
		(property "Reference" "GF9"
			(at 0 0 180)
			(layer "F.SilkS")
			(hide yes)
			(effects
				(font
					(size 1.27 1.27)
				)
			)
		)
		(property "Value" "GF-200P-8-GP-U1"
			(at -43.1673 -7.6327 180)
			(unlocked yes)
			(layer "F.Fab")
			(hide yes)
			(effects
				(font
					(size 1.016 1.016)
					(thickness 0.1524)
				)
			)
		)
		(property "Device Type" "GF-200P-8-U1"
			(at -43.1673 -9.1567 180)
			(unlocked yes)
			(layer "F.Fab")
			(hide yes)
			(effects
				(font
					(size 1.016 1.016)
					(thickness 0.1524)
				)
			)
		)
		(duplicate_pad_numbers_are_jumpers no)
		(fp_rect
			(start -38.7096 2.032)
			(end 48.3108 -4.3434)
			(stroke
				(width 0)
				(type default)
			)
			(fill no)
			(layer "B.CrtYd")
		)
		(fp_rect
			(start -38.7096 2.032)
			(end 48.3108 -4.3434)
			(stroke
				(width 0)
				(type default)
			)
			(fill no)
			(layer "F.CrtYd")
		)
		(fp_rect
			(start -38.7096 2.032)
			(end 48.3108 -4.3434)
			(stroke
				(width 0)
				(type default)
			)
			(fill no)
			(layer "B.Fab")
		)
		(fp_rect
			(start -38.7096 2.032)
			(end 48.3108 -4.3434)
			(stroke
				(width 0)
				(type default)
			)
			(fill no)
			(layer "F.Fab")
		)
		(fp_text user "02 Do not mirror"
			(at -7.62 4.1148 180)
			(unlocked yes)
			(layer "F.Fab")
			(effects
				(font
					(size 1.016 1.016)
					(thickness 0.1524)
				)
				(justify left)
			)
		)
		(pad "A1" smd rect
			(at -36.399978 -1.1557 180)
			(size 0.5588 2.3114)
			(layers "F.Cu" "F.Mask" "F.Paste")
			(net "GND")
		)
		(pad "A2" smd rect
			(at -35.599878 -1.1557 180)
			(size 0.5588 2.3114)
			(layers "F.Cu" "F.Mask" "F.Paste")
			(net "PCIE_TX_N38")
		)
		(pad "A3" smd rect
			(at -34.800032 -1.1557 180)
			(size 0.5588 2.3114)
			(layers "F.Cu" "F.Mask" "F.Paste")
			(net "PCIE_TX_P38")
		)
		(pad "A4" smd rect
			(at -33.999932 -1.1557 180)
			(size 0.5588 2.3114)
			(layers "F.Cu" "F.Mask" "F.Paste")
			(net "GND")
		)
		(pad "A5" smd rect
			(at -33.200086 -1.1557 180)
			(size 0.5588 2.3114)
			(layers "F.Cu" "F.Mask" "F.Paste")
			(net "GND")
		)
		(pad "A6" smd rect
			(at -32.399986 -1.1557 180)
			(size 0.5588 2.3114)
			(layers "F.Cu" "F.Mask" "F.Paste")
			(net "PCIE_TX_N39")
		)
		(pad "A7" smd rect
			(at -31.599886 -1.1557 180)
			(size 0.5588 2.3114)
			(layers "F.Cu" "F.Mask" "F.Paste")
			(net "PCIE_TX_P39")
		)
		(pad "A8" smd rect
			(at -30.80004 -1.1557 180)
			(size 0.5588 2.3114)
			(layers "F.Cu" "F.Mask" "F.Paste")
			(net "GND")
		)
		(pad "A9" smd rect
			(at -29.99994 -1.1557 180)
			(size 0.5588 2.3114)
			(layers "F.Cu" "F.Mask" "F.Paste")
			(net "SSD_PERST#3_R")
		)
		(pad "A10" smd rect
			(at -29.200094 -1.1557 180)
			(size 0.5588 2.3114)
			(layers "F.Cu" "F.Mask" "F.Paste")
			(net "SSD_PWREN3_R")
		)
		(pad "A11" smd rect
			(at -28.399994 -1.1557 180)
			(size 0.5588 2.3114)
			(layers "F.Cu" "F.Mask" "F.Paste")
			(net "SSD_ATNLED#3_R")
		)
		(pad "A12" smd rect
			(at -27.599894 -1.1557 180)
			(size 0.5588 2.3114)
			(layers "F.Cu" "F.Mask" "F.Paste")
			(net "SSD_PRSNT#3_R")
		)
		(pad "A13" smd rect
			(at -26.800048 -1.1557 180)
			(size 0.5588 2.3114)
			(layers "F.Cu" "F.Mask" "F.Paste")
			(net "GND")
		)
		(pad "A14" smd rect
			(at -25.999948 -1.1557 180)
			(size 0.5588 2.3114)
			(layers "F.Cu" "F.Mask" "F.Paste")
			(net "PCIE_TX_N40")
		)
		(pad "A15" smd rect
			(at -25.200102 -1.1557 180)
			(size 0.5588 2.3114)
			(layers "F.Cu" "F.Mask" "F.Paste")
			(net "PCIE_TX_P40")
		)
		(pad "A16" smd rect
			(at -24.400002 -1.1557 180)
			(size 0.5588 2.3114)
			(layers "F.Cu" "F.Mask" "F.Paste")
			(net "GND")
		)
		(pad "A17" smd rect
			(at -23.599902 -1.1557 180)
			(size 0.5588 2.3114)
			(layers "F.Cu" "F.Mask" "F.Paste")
			(net "GND")
		)
		(pad "A18" smd rect
			(at -22.800056 -1.1557 180)
			(size 0.5588 2.3114)
			(layers "F.Cu" "F.Mask" "F.Paste")
			(net "PCIE_TX_N41")
		)
		(pad "A19" smd rect
			(at -21.999956 -1.1557 180)
			(size 0.5588 2.3114)
			(layers "F.Cu" "F.Mask" "F.Paste")
			(net "PCIE_TX_P41")
		)
		(pad "A20" smd rect
			(at -21.20011 -1.1557 180)
			(size 0.5588 2.3114)
			(layers "F.Cu" "F.Mask" "F.Paste")
			(net "GND")
		)
		(pad "A21" smd rect
			(at -20.40001 -1.1557 180)
			(size 0.5588 2.3114)
			(layers "F.Cu" "F.Mask" "F.Paste")
			(net "GND")
		)
		(pad "A22" smd rect
			(at -19.59991 -1.1557 180)
			(size 0.5588 2.3114)
			(layers "F.Cu" "F.Mask" "F.Paste")
			(net "PCIE_TX_N42")
		)
		(pad "A23" smd rect
			(at -18.800064 -1.1557 180)
			(size 0.5588 2.3114)
			(layers "F.Cu" "F.Mask" "F.Paste")
			(net "PCIE_TX_P42")
		)
		(pad "A24" smd rect
			(at -17.999964 -1.1557 180)
			(size 0.5588 2.3114)
			(layers "F.Cu" "F.Mask" "F.Paste")
			(net "GND")
		)
		(pad "A25" smd rect
			(at -17.200118 -1.1557 180)
			(size 0.5588 2.3114)
			(layers "F.Cu" "F.Mask" "F.Paste")
			(net "GND")
		)
		(pad "A26" smd rect
			(at -16.400018 -1.1557 180)
			(size 0.5588 2.3114)
			(layers "F.Cu" "F.Mask" "F.Paste")
			(net "PCIE_TX_N43")
		)
		(pad "A27" smd rect
			(at -15.599918 -1.1557 180)
			(size 0.5588 2.3114)
			(layers "F.Cu" "F.Mask" "F.Paste")
			(net "PCIE_TX_P43")
		)
		(pad "A28" smd rect
			(at -14.800072 -1.1557 180)
			(size 0.5588 2.3114)
			(layers "F.Cu" "F.Mask" "F.Paste")
			(net "GND")
		)
		(pad "A29" smd rect
			(at -13.999972 -1.1557 180)
			(size 0.5588 2.3114)
			(layers "F.Cu" "F.Mask" "F.Paste")
			(net "GND")
		)
		(pad "A30" smd rect
			(at -13.200126 -1.1557 180)
			(size 0.5588 2.3114)
			(layers "F.Cu" "F.Mask" "F.Paste")
			(net "PCIE_TX_N44")
		)
		(pad "A31" smd rect
			(at -12.400026 -1.1557 180)
			(size 0.5588 2.3114)
			(layers "F.Cu" "F.Mask" "F.Paste")
			(net "PCIE_TX_P44")
		)
		(pad "A32" smd rect
			(at -11.599926 -1.1557 180)
			(size 0.5588 2.3114)
			(layers "F.Cu" "F.Mask" "F.Paste")
			(net "GND")
		)
		(pad "A33" smd rect
			(at -10.80008 -1.1557 180)
			(size 0.5588 2.3114)
			(layers "F.Cu" "F.Mask" "F.Paste")
			(net "GND")
		)
		(pad "A34" smd rect
			(at -9.99998 -1.1557 180)
			(size 0.5588 2.3114)
			(layers "F.Cu" "F.Mask" "F.Paste")
			(net "PCIE_TX_N45")
		)
		(pad "A35" smd rect
			(at -9.19988 -1.1557 180)
			(size 0.5588 2.3114)
			(layers "F.Cu" "F.Mask" "F.Paste")
			(net "PCIE_TX_P45")
		)
		(pad "A36" smd rect
			(at -8.400034 -1.1557 180)
			(size 0.5588 2.3114)
			(layers "F.Cu" "F.Mask" "F.Paste")
			(net "GND")
		)
		(pad "A37" smd rect
			(at -7.599934 -1.1557 180)
			(size 0.5588 2.3114)
			(layers "F.Cu" "F.Mask" "F.Paste")
			(net "GND")
		)
		(pad "A38" smd rect
			(at -6.800088 -1.1557 180)
			(size 0.5588 2.3114)
			(layers "F.Cu" "F.Mask" "F.Paste")
			(net "PCIE_TX_N46")
		)
		(pad "A39" smd rect
			(at -5.999988 -1.1557 180)
			(size 0.5588 2.3114)
			(layers "F.Cu" "F.Mask" "F.Paste")
			(net "PCIE_TX_P46")
		)
		(pad "A40" smd rect
			(at -5.199888 -1.1557 180)
			(size 0.5588 2.3114)
			(layers "F.Cu" "F.Mask" "F.Paste")
			(net "GND")
		)
		(pad "A41" smd rect
			(at -4.400042 -1.1557 180)
			(size 0.5588 2.3114)
			(layers "F.Cu" "F.Mask" "F.Paste")
			(net "GND")
		)
		(pad "A42" smd rect
			(at -3.599942 -1.1557 180)
			(size 0.5588 2.3114)
			(layers "F.Cu" "F.Mask" "F.Paste")
			(net "PCIE_TX_N47")
		)
		(pad "A43" smd rect
			(at -2.800096 -1.1557 180)
			(size 0.5588 2.3114)
			(layers "F.Cu" "F.Mask" "F.Paste")
			(net "PCIE_TX_P47")
		)
		(pad "A44" smd rect
			(at -1.999996 -1.1557 180)
			(size 0.5588 2.3114)
			(layers "F.Cu" "F.Mask" "F.Paste")
			(net "GND")
		)
		(pad "A45" smd rect
			(at 1.999996 -1.1557 180)
			(size 0.5588 2.3114)
			(layers "F.Cu" "F.Mask" "F.Paste")
			(net "SSD_ATNLED#7_R")
		)
		(pad "A46" smd rect
			(at 2.800096 -1.1557 180)
			(size 0.5588 1.8796)
			(drill
				(offset 0 -0.2159)
			)
			(layers "F.Cu" "F.Mask" "F.Paste")
			(net "SSD_PRSNT#7_R")
		)
		(pad "A47" smd rect
			(at 3.599942 -1.1557 180)
			(size 0.5588 2.3114)
			(layers "F.Cu" "F.Mask" "F.Paste")
			(net "GND")
		)
		(pad "A48" smd rect
			(at 4.400042 -1.1557 180)
			(size 0.5588 2.3114)
			(layers "F.Cu" "F.Mask" "F.Paste")
			(net "PCIE_TX_N48")
		)
		(pad "A49" smd rect
			(at 5.199888 -1.1557 180)
			(size 0.5588 2.3114)
			(layers "F.Cu" "F.Mask" "F.Paste")
			(net "PCIE_TX_P48")
		)
		(pad "A50" smd rect
			(at 5.999988 -1.1557 180)
			(size 0.5588 2.3114)
			(layers "F.Cu" "F.Mask" "F.Paste")
			(net "GND")
		)
		(pad "A51" smd rect
			(at 6.800088 -1.1557 180)
			(size 0.5588 2.3114)
			(layers "F.Cu" "F.Mask" "F.Paste")
			(net "GND")
		)
		(pad "A52" smd rect
			(at 7.599934 -1.1557 180)
			(size 0.5588 2.3114)
			(layers "F.Cu" "F.Mask" "F.Paste")
			(net "PCIE_TX_N49")
		)
		(pad "A53" smd rect
			(at 8.400034 -1.1557 180)
			(size 0.5588 2.3114)
			(layers "F.Cu" "F.Mask" "F.Paste")
			(net "PCIE_TX_P49")
		)
		(pad "A54" smd rect
			(at 9.19988 -1.1557 180)
			(size 0.5588 2.3114)
			(layers "F.Cu" "F.Mask" "F.Paste")
			(net "GND")
		)
		(pad "A55" smd rect
			(at 9.99998 -1.1557 180)
			(size 0.5588 2.3114)
			(layers "F.Cu" "F.Mask" "F.Paste")
			(net "GND")
		)
		(pad "A56" smd rect
			(at 10.80008 -1.1557 180)
			(size 0.5588 2.3114)
			(layers "F.Cu" "F.Mask" "F.Paste")
			(net "PCIE_TX_N50")
		)
		(pad "A57" smd rect
			(at 11.599926 -1.1557 180)
			(size 0.5588 2.3114)
			(layers "F.Cu" "F.Mask" "F.Paste")
			(net "PCIE_TX_P50")
		)
		(pad "A58" smd rect
			(at 12.400026 -1.1557 180)
			(size 0.5588 2.3114)
			(layers "F.Cu" "F.Mask" "F.Paste")
			(net "GND")
		)
		(pad "A59" smd rect
			(at 13.200126 -1.1557 180)
			(size 0.5588 2.3114)
			(layers "F.Cu" "F.Mask" "F.Paste")
			(net "GND")
		)
		(pad "A60" smd rect
			(at 13.999972 -1.1557 180)
			(size 0.5588 2.3114)
			(layers "F.Cu" "F.Mask" "F.Paste")
			(net "PCIE_TX_N51")
		)
		(pad "A61" smd rect
			(at 14.800072 -1.1557 180)
			(size 0.5588 2.3114)
			(layers "F.Cu" "F.Mask" "F.Paste")
			(net "PCIE_TX_P51")
		)
		(pad "A62" smd rect
			(at 15.599918 -1.1557 180)
			(size 0.5588 2.3114)
			(layers "F.Cu" "F.Mask" "F.Paste")
			(net "GND")
		)
		(pad "A63" smd rect
			(at 16.400018 -1.1557 180)
			(size 0.5588 2.3114)
			(layers "F.Cu" "F.Mask" "F.Paste")
			(net "SSD_PWREN2_R")
		)
		(pad "A64" smd rect
			(at 17.200118 -1.1557 180)
			(size 0.5588 2.3114)
			(layers "F.Cu" "F.Mask" "F.Paste")
			(net "SSD_ATNLED#2_R")
		)
		(pad "A65" smd rect
			(at 17.999964 -1.1557 180)
			(size 0.5588 2.3114)
			(layers "F.Cu" "F.Mask" "F.Paste")
			(net "SSD_PRSNT#2_R")
		)
		(pad "A66" smd rect
			(at 18.800064 -1.1557 180)
			(size 0.5588 2.3114)
			(layers "F.Cu" "F.Mask" "F.Paste")
			(net "GND")
		)
		(pad "A67" smd rect
			(at 19.59991 -1.1557 180)
			(size 0.5588 2.3114)
			(layers "F.Cu" "F.Mask" "F.Paste")
			(net "PCIE_TX_N52")
		)
		(pad "A68" smd rect
			(at 20.40001 -1.1557 180)
			(size 0.5588 2.3114)
			(layers "F.Cu" "F.Mask" "F.Paste")
			(net "PCIE_TX_P52")
		)
		(pad "A69" smd rect
			(at 21.20011 -1.1557 180)
			(size 0.5588 2.3114)
			(layers "F.Cu" "F.Mask" "F.Paste")
			(net "GND")
		)
		(pad "A70" smd rect
			(at 21.999956 -1.1557 180)
			(size 0.5588 2.3114)
			(layers "F.Cu" "F.Mask" "F.Paste")
			(net "GND")
		)
		(pad "A71" smd rect
			(at 22.800056 -1.1557 180)
			(size 0.5588 2.3114)
			(layers "F.Cu" "F.Mask" "F.Paste")
			(net "PCIE_TX_N53")
		)
		(pad "A72" smd rect
			(at 23.599902 -1.1557 180)
			(size 0.5588 2.3114)
			(layers "F.Cu" "F.Mask" "F.Paste")
			(net "PCIE_TX_P53")
		)
		(pad "A73" smd rect
			(at 24.400002 -1.1557 180)
			(size 0.5588 2.3114)
			(layers "F.Cu" "F.Mask" "F.Paste")
			(net "GND")
		)
		(pad "A74" smd rect
			(at 25.200102 -1.1557 180)
			(size 0.5588 2.3114)
			(layers "F.Cu" "F.Mask" "F.Paste")
			(net "GND")
		)
		(pad "A75" smd rect
			(at 25.999948 -1.1557 180)
			(size 0.5588 2.3114)
			(layers "F.Cu" "F.Mask" "F.Paste")
			(net "PCIE_TX_N54")
		)
		(pad "A76" smd rect
			(at 26.800048 -1.1557 180)
			(size 0.5588 2.3114)
			(layers "F.Cu" "F.Mask" "F.Paste")
			(net "PCIE_TX_P54")
		)
		(pad "A77" smd rect
			(at 27.599894 -1.1557 180)
			(size 0.5588 2.3114)
			(layers "F.Cu" "F.Mask" "F.Paste")
			(net "GND")
		)
		(pad "A78" smd rect
			(at 28.399994 -1.1557 180)
			(size 0.5588 2.3114)
			(layers "F.Cu" "F.Mask" "F.Paste")
			(net "GND")
		)
		(pad "A79" smd rect
			(at 29.200094 -1.1557 180)
			(size 0.5588 2.3114)
			(layers "F.Cu" "F.Mask" "F.Paste")
			(net "PCIE_TX_N55")
		)
		(pad "A80" smd rect
			(at 29.99994 -1.1557 180)
			(size 0.5588 2.3114)
			(layers "F.Cu" "F.Mask" "F.Paste")
			(net "PCIE_TX_P55")
		)
		(pad "A81" smd rect
			(at 30.80004 -1.1557 180)
			(size 0.5588 2.3114)
			(layers "F.Cu" "F.Mask" "F.Paste")
			(net "GND")
		)
		(pad "A82" smd rect
			(at 31.599886 -1.1557 180)
			(size 0.5588 2.3114)
			(layers "F.Cu" "F.Mask" "F.Paste")
			(net "GND")
		)
		(pad "A83" smd rect
			(at 32.399986 -1.1557 180)
			(size 0.5588 2.3114)
			(layers "F.Cu" "F.Mask" "F.Paste")
			(net "PCIE_TX_N56")
		)
		(pad "A84" smd rect
			(at 33.200086 -1.1557 180)
			(size 0.5588 2.3114)
			(layers "F.Cu" "F.Mask" "F.Paste")
			(net "PCIE_TX_P56")
		)
		(pad "A85" smd rect
			(at 33.999932 -1.1557 180)
			(size 0.5588 2.3114)
			(layers "F.Cu" "F.Mask" "F.Paste")
			(net "GND")
		)
		(pad "A86" smd rect
			(at 34.800032 -1.1557 180)
			(size 0.5588 2.3114)
			(layers "F.Cu" "F.Mask" "F.Paste")
			(net "GND")
		)
		(pad "A87" smd rect
			(at 35.599878 -1.1557 180)
			(size 0.5588 2.3114)
			(layers "F.Cu" "F.Mask" "F.Paste")
			(net "PCIE_TX_N57")
		)
		(pad "A88" smd rect
			(at 36.399978 -1.1557 180)
			(size 0.5588 2.3114)
			(layers "F.Cu" "F.Mask" "F.Paste")
			(net "PCIE_TX_P57")
		)
		(pad "A89" smd rect
			(at 37.200078 -1.1557 180)
			(size 0.5588 2.3114)
			(layers "F.Cu" "F.Mask" "F.Paste")
			(net "GND")
		)
		(pad "A90" smd rect
			(at 37.999924 -1.1557 180)
			(size 0.5588 2.3114)
			(layers "F.Cu" "F.Mask" "F.Paste")
			(net "GND")
		)
		(pad "A91" smd rect
			(at 38.800024 -1.1557 180)
			(size 0.5588 2.3114)
			(layers "F.Cu" "F.Mask" "F.Paste")
			(net "PCIE_TX_N58")
		)
		(pad "A92" smd rect
			(at 39.600124 -1.1557 180)
			(size 0.5588 2.3114)
			(layers "F.Cu" "F.Mask" "F.Paste")
			(net "PCIE_TX_P58")
		)
		(pad "A93" smd rect
			(at 40.39997 -1.1557 180)
			(size 0.5588 2.3114)
			(layers "F.Cu" "F.Mask" "F.Paste")
			(net "GND")
		)
		(pad "A94" smd rect
			(at 41.20007 -1.1557 180)
			(size 0.5588 2.3114)
			(layers "F.Cu" "F.Mask" "F.Paste")
			(net "GND")
		)
		(pad "A95" smd rect
			(at 41.999916 -1.1557 180)
			(size 0.5588 2.3114)
			(layers "F.Cu" "F.Mask" "F.Paste")
			(net "PCIE_TX_N59")
		)
		(pad "A96" smd rect
			(at 42.800016 -1.1557 180)
			(size 0.5588 2.3114)
			(layers "F.Cu" "F.Mask" "F.Paste")
			(net "PCIE_TX_P59")
		)
		(pad "A97" smd rect
			(at 43.600116 -1.1557 180)
			(size 0.5588 2.3114)
			(layers "F.Cu" "F.Mask" "F.Paste")
			(net "GND")
		)
		(pad "A98" smd rect
			(at 44.399962 -1.1557 180)
			(size 0.5588 2.3114)
			(layers "F.Cu" "F.Mask" "F.Paste")
			(net "SSD_PRSNT#6_R")
		)
		(pad "A99" smd rect
			(at 45.200062 -1.1557 180)
			(size 0.5588 2.3114)
			(layers "F.Cu" "F.Mask" "F.Paste")
			(net "SSD_ATNLED#6_R")
		)
		(pad "A100" smd rect
			(at 45.999908 -1.1557 180)
			(size 0.5588 1.8796)
			(drill
				(offset 0 -0.2159)
			)
			(layers "F.Cu" "F.Mask" "F.Paste")
			(net "SSD_PWREN6_R")
		)
		(pad "B1" smd rect
			(at -36.399978 -0.7747 180)
			(size 0.5588 2.3114)
			(drill
				(offset 0 -0.381)
			)
			(layers "F.Cu" "F.Mask" "F.Paste")
			(net "SSD_PERST#11_R")
		)
		(pad "B2" smd rect
			(at -35.599878 -0.7747 180)
			(size 0.5588 2.3114)
			(drill
				(offset 0 -0.381)
			)
			(layers "F.Cu" "F.Mask" "F.Paste")
			(net "SSD_PERST#2_R")
		)
		(pad "B3" smd rect
			(at -34.800032 -0.7747 180)
			(size 0.5588 2.3114)
			(drill
				(offset 0 -0.381)
			)
			(layers "F.Cu" "F.Mask" "F.Paste")
			(net "GND")
		)
		(pad "B4" smd rect
			(at -33.999932 -0.7747 180)
			(size 0.5588 2.3114)
			(drill
				(offset 0 -0.381)
			)
			(layers "F.Cu" "F.Mask" "F.Paste")
			(net "PCIE_RX_N38")
		)
		(pad "B5" smd rect
			(at -33.200086 -0.7747 180)
			(size 0.5588 2.3114)
			(drill
				(offset 0 -0.381)
			)
			(layers "F.Cu" "F.Mask" "F.Paste")
			(net "PCIE_RX_P38")
		)
		(pad "B6" smd rect
			(at -32.399986 -0.7747 180)
			(size 0.5588 2.3114)
			(drill
				(offset 0 -0.381)
			)
			(layers "F.Cu" "F.Mask" "F.Paste")
			(net "GND")
		)
		(pad "B7" smd rect
			(at -31.599886 -0.7747 180)
			(size 0.5588 2.3114)
			(drill
				(offset 0 -0.381)
			)
			(layers "F.Cu" "F.Mask" "F.Paste")
			(net "GND")
		)
		(pad "B8" smd rect
			(at -30.80004 -0.7747 180)
			(size 0.5588 2.3114)
			(drill
				(offset 0 -0.381)
			)
			(layers "F.Cu" "F.Mask" "F.Paste")
			(net "PCIE_RX_N39")
		)
		(pad "B9" smd rect
			(at -29.99994 -0.7747 180)
			(size 0.5588 2.3114)
			(drill
				(offset 0 -0.381)
			)
			(layers "F.Cu" "F.Mask" "F.Paste")
			(net "PCIE_RX_P39")
		)
		(pad "B10" smd rect
			(at -29.200094 -0.7747 180)
			(size 0.5588 2.3114)
			(drill
				(offset 0 -0.381)
			)
			(layers "F.Cu" "F.Mask" "F.Paste")
			(net "GND")
		)
		(pad "B11" smd rect
			(at -28.399994 -0.7747 180)
			(size 0.5588 2.3114)
			(drill
				(offset 0 -0.381)
			)
			(layers "F.Cu" "F.Mask" "F.Paste")
			(net "SSD_PERST#12_R")
		)
		(pad "B12" smd rect
			(at -27.599894 -0.7747 180)
			(size 0.5588 2.3114)
			(drill
				(offset 0 -0.381)
			)
			(layers "F.Cu" "F.Mask" "F.Paste")
			(net "SSD_PWREN12_R")
		)
		(pad "B13" smd rect
			(at -26.800048 -0.7747 180)
			(size 0.5588 2.3114)
			(drill
				(offset 0 -0.381)
			)
			(layers "F.Cu" "F.Mask" "F.Paste")
			(net "SSD_ATNLED#12_R")
		)
		(pad "B14" smd rect
			(at -25.999948 -0.7747 180)
			(size 0.5588 2.3114)
			(drill
				(offset 0 -0.381)
			)
			(layers "F.Cu" "F.Mask" "F.Paste")
			(net "SSD_PRSNT#12_R")
		)
		(pad "B15" smd rect
			(at -25.200102 -0.7747 180)
			(size 0.5588 2.3114)
			(drill
				(offset 0 -0.381)
			)
			(layers "F.Cu" "F.Mask" "F.Paste")
			(net "GND")
		)
		(pad "B16" smd rect
			(at -24.400002 -0.7747 180)
			(size 0.5588 2.3114)
			(drill
				(offset 0 -0.381)
			)
			(layers "F.Cu" "F.Mask" "F.Paste")
			(net "PCIE_RX_N40")
		)
		(pad "B17" smd rect
			(at -23.599902 -0.7747 180)
			(size 0.5588 2.3114)
			(drill
				(offset 0 -0.381)
			)
			(layers "F.Cu" "F.Mask" "F.Paste")
			(net "PCIE_RX_P40")
		)
		(pad "B18" smd rect
			(at -22.800056 -0.7747 180)
			(size 0.5588 2.3114)
			(drill
				(offset 0 -0.381)
			)
			(layers "F.Cu" "F.Mask" "F.Paste")
			(net "GND")
		)
		(pad "B19" smd rect
			(at -21.999956 -0.7747 180)
			(size 0.5588 2.3114)
			(drill
				(offset 0 -0.381)
			)
			(layers "F.Cu" "F.Mask" "F.Paste")
			(net "GND")
		)
		(pad "B20" smd rect
			(at -21.20011 -0.7747 180)
			(size 0.5588 2.3114)
			(drill
				(offset 0 -0.381)
			)
			(layers "F.Cu" "F.Mask" "F.Paste")
			(net "PCIE_RX_N41")
		)
		(pad "B21" smd rect
			(at -20.40001 -0.7747 180)
			(size 0.5588 2.3114)
			(drill
				(offset 0 -0.381)
			)
			(layers "F.Cu" "F.Mask" "F.Paste")
			(net "PCIE_RX_P41")
		)
		(pad "B22" smd rect
			(at -19.59991 -0.7747 180)
			(size 0.5588 2.3114)
			(drill
				(offset 0 -0.381)
			)
			(layers "F.Cu" "F.Mask" "F.Paste")
			(net "GND")
		)
		(pad "B23" smd rect
			(at -18.800064 -0.7747 180)
			(size 0.5588 2.3114)
			(drill
				(offset 0 -0.381)
			)
			(layers "F.Cu" "F.Mask" "F.Paste")
			(net "GND")
		)
		(pad "B24" smd rect
			(at -17.999964 -0.7747 180)
			(size 0.5588 2.3114)
			(drill
				(offset 0 -0.381)
			)
			(layers "F.Cu" "F.Mask" "F.Paste")
			(net "PCIE_RX_N42")
		)
		(pad "B25" smd rect
			(at -17.200118 -0.7747 180)
			(size 0.5588 2.3114)
			(drill
				(offset 0 -0.381)
			)
			(layers "F.Cu" "F.Mask" "F.Paste")
			(net "PCIE_RX_P42")
		)
		(pad "B26" smd rect
			(at -16.400018 -0.7747 180)
			(size 0.5588 2.3114)
			(drill
				(offset 0 -0.381)
			)
			(layers "F.Cu" "F.Mask" "F.Paste")
			(net "GND")
		)
		(pad "B27" smd rect
			(at -15.599918 -0.7747 180)
			(size 0.5588 2.3114)
			(drill
				(offset 0 -0.381)
			)
			(layers "F.Cu" "F.Mask" "F.Paste")
			(net "GND")
		)
		(pad "B28" smd rect
			(at -14.800072 -0.7747 180)
			(size 0.5588 2.3114)
			(drill
				(offset 0 -0.381)
			)
			(layers "F.Cu" "F.Mask" "F.Paste")
			(net "PCIE_RX_N43")
		)
		(pad "B29" smd rect
			(at -13.999972 -0.7747 180)
			(size 0.5588 2.3114)
			(drill
				(offset 0 -0.381)
			)
			(layers "F.Cu" "F.Mask" "F.Paste")
			(net "PCIE_RX_P43")
		)
		(pad "B30" smd rect
			(at -13.200126 -0.7747 180)
			(size 0.5588 2.3114)
			(drill
				(offset 0 -0.381)
			)
			(layers "F.Cu" "F.Mask" "F.Paste")
			(net "GND")
		)
		(pad "B31" smd rect
			(at -12.400026 -0.7747 180)
			(size 0.5588 2.3114)
			(drill
				(offset 0 -0.381)
			)
			(layers "F.Cu" "F.Mask" "F.Paste")
			(net "GND")
		)
		(pad "B32" smd rect
			(at -11.599926 -0.7747 180)
			(size 0.5588 2.3114)
			(drill
				(offset 0 -0.381)
			)
			(layers "F.Cu" "F.Mask" "F.Paste")
			(net "PCIE_RX_N44")
		)
		(pad "B33" smd rect
			(at -10.80008 -0.7747 180)
			(size 0.5588 2.3114)
			(drill
				(offset 0 -0.381)
			)
			(layers "F.Cu" "F.Mask" "F.Paste")
			(net "PCIE_RX_P44")
		)
		(pad "B34" smd rect
			(at -9.99998 -0.7747 180)
			(size 0.5588 2.3114)
			(drill
				(offset 0 -0.381)
			)
			(layers "F.Cu" "F.Mask" "F.Paste")
			(net "GND")
		)
		(pad "B35" smd rect
			(at -9.19988 -0.7747 180)
			(size 0.5588 2.3114)
			(drill
				(offset 0 -0.381)
			)
			(layers "F.Cu" "F.Mask" "F.Paste")
			(net "GND")
		)
		(pad "B36" smd rect
			(at -8.400034 -0.7747 180)
			(size 0.5588 2.3114)
			(drill
				(offset 0 -0.381)
			)
			(layers "F.Cu" "F.Mask" "F.Paste")
			(net "PCIE_RX_N45")
		)
		(pad "B37" smd rect
			(at -7.599934 -0.7747 180)
			(size 0.5588 2.3114)
			(drill
				(offset 0 -0.381)
			)
			(layers "F.Cu" "F.Mask" "F.Paste")
			(net "PCIE_RX_P45")
		)
		(pad "B38" smd rect
			(at -6.800088 -0.7747 180)
			(size 0.5588 2.3114)
			(drill
				(offset 0 -0.381)
			)
			(layers "F.Cu" "F.Mask" "F.Paste")
			(net "GND")
		)
		(pad "B39" smd rect
			(at -5.999988 -0.7747 180)
			(size 0.5588 2.3114)
			(drill
				(offset 0 -0.381)
			)
			(layers "F.Cu" "F.Mask" "F.Paste")
			(net "GND")
		)
		(pad "B40" smd rect
			(at -5.199888 -0.7747 180)
			(size 0.5588 2.3114)
			(drill
				(offset 0 -0.381)
			)
			(layers "F.Cu" "F.Mask" "F.Paste")
			(net "PCIE_RX_N46")
		)
		(pad "B41" smd rect
			(at -4.400042 -0.7747 180)
			(size 0.5588 2.3114)
			(drill
				(offset 0 -0.381)
			)
			(layers "F.Cu" "F.Mask" "F.Paste")
			(net "PCIE_RX_P46")
		)
		(pad "B42" smd rect
			(at -3.599942 -0.7747 180)
			(size 0.5588 2.3114)
			(drill
				(offset 0 -0.381)
			)
			(layers "F.Cu" "F.Mask" "F.Paste")
			(net "GND")
		)
		(pad "B43" smd rect
			(at -2.800096 -0.7747 180)
			(size 0.5588 2.3114)
			(drill
				(offset 0 -0.381)
			)
			(layers "F.Cu" "F.Mask" "F.Paste")
			(net "SSD_PERST#7_R")
		)
		(pad "B44" smd rect
			(at -1.999996 -0.7747 180)
			(size 0.5588 2.3114)
			(drill
				(offset 0 -0.381)
			)
			(layers "F.Cu" "F.Mask" "F.Paste")
			(net "SSD_PWREN7_R")
		)
		(pad "B45" smd rect
			(at 1.999996 -0.7747 180)
			(size 0.5588 2.3114)
			(drill
				(offset 0 -0.381)
			)
			(layers "F.Cu" "F.Mask" "F.Paste")
			(net "GND")
		)
		(pad "B46" smd rect
			(at 2.800096 -0.7747 180)
			(size 0.5588 2.3114)
			(drill
				(offset 0 -0.381)
			)
			(layers "F.Cu" "F.Mask" "F.Paste")
			(net "PCIE_RX_N47")
		)
		(pad "B47" smd rect
			(at 3.599942 -0.7747 180)
			(size 0.5588 2.3114)
			(drill
				(offset 0 -0.381)
			)
			(layers "F.Cu" "F.Mask" "F.Paste")
			(net "PCIE_RX_P47")
		)
		(pad "B48" smd rect
			(at 4.400042 -0.7747 180)
			(size 0.5588 2.3114)
			(drill
				(offset 0 -0.381)
			)
			(layers "F.Cu" "F.Mask" "F.Paste")
			(net "GND")
		)
		(pad "B49" smd rect
			(at 5.199888 -0.7747 180)
			(size 0.5588 2.3114)
			(drill
				(offset 0 -0.381)
			)
			(layers "F.Cu" "F.Mask" "F.Paste")
			(net "GND")
		)
		(pad "B50" smd rect
			(at 5.999988 -0.7747 180)
			(size 0.5588 2.3114)
			(drill
				(offset 0 -0.381)
			)
			(layers "F.Cu" "F.Mask" "F.Paste")
			(net "PCIE_RX_N48")
		)
		(pad "B51" smd rect
			(at 6.800088 -0.7747 180)
			(size 0.5588 2.3114)
			(drill
				(offset 0 -0.381)
			)
			(layers "F.Cu" "F.Mask" "F.Paste")
			(net "PCIE_RX_P48")
		)
		(pad "B52" smd rect
			(at 7.599934 -0.7747 180)
			(size 0.5588 2.3114)
			(drill
				(offset 0 -0.381)
			)
			(layers "F.Cu" "F.Mask" "F.Paste")
			(net "GND")
		)
		(pad "B53" smd rect
			(at 8.400034 -0.7747 180)
			(size 0.5588 2.3114)
			(drill
				(offset 0 -0.381)
			)
			(layers "F.Cu" "F.Mask" "F.Paste")
			(net "GND")
		)
		(pad "B54" smd rect
			(at 9.19988 -0.7747 180)
			(size 0.5588 2.3114)
			(drill
				(offset 0 -0.381)
			)
			(layers "F.Cu" "F.Mask" "F.Paste")
			(net "PCIE_RX_N49")
		)
		(pad "B55" smd rect
			(at 9.99998 -0.7747 180)
			(size 0.5588 2.3114)
			(drill
				(offset 0 -0.381)
			)
			(layers "F.Cu" "F.Mask" "F.Paste")
			(net "PCIE_RX_P49")
		)
		(pad "B56" smd rect
			(at 10.80008 -0.7747 180)
			(size 0.5588 2.3114)
			(drill
				(offset 0 -0.381)
			)
			(layers "F.Cu" "F.Mask" "F.Paste")
			(net "GND")
		)
		(pad "B57" smd rect
			(at 11.599926 -0.7747 180)
			(size 0.5588 2.3114)
			(drill
				(offset 0 -0.381)
			)
			(layers "F.Cu" "F.Mask" "F.Paste")
			(net "GND")
		)
		(pad "B58" smd rect
			(at 12.400026 -0.7747 180)
			(size 0.5588 2.3114)
			(drill
				(offset 0 -0.381)
			)
			(layers "F.Cu" "F.Mask" "F.Paste")
			(net "PCIE_RX_N50")
		)
		(pad "B59" smd rect
			(at 13.200126 -0.7747 180)
			(size 0.5588 2.3114)
			(drill
				(offset 0 -0.381)
			)
			(layers "F.Cu" "F.Mask" "F.Paste")
			(net "PCIE_RX_P50")
		)
		(pad "B60" smd rect
			(at 13.999972 -0.7747 180)
			(size 0.5588 2.3114)
			(drill
				(offset 0 -0.381)
			)
			(layers "F.Cu" "F.Mask" "F.Paste")
			(net "GND")
		)
		(pad "B61" smd rect
			(at 14.800072 -0.7747 180)
			(size 0.5588 2.3114)
			(drill
				(offset 0 -0.381)
			)
			(layers "F.Cu" "F.Mask" "F.Paste")
			(net "GND")
		)
		(pad "B62" smd rect
			(at 15.599918 -0.7747 180)
			(size 0.5588 2.3114)
			(drill
				(offset 0 -0.381)
			)
			(layers "F.Cu" "F.Mask" "F.Paste")
			(net "PCIE_RX_N51")
		)
		(pad "B63" smd rect
			(at 16.400018 -0.7747 180)
			(size 0.5588 2.3114)
			(drill
				(offset 0 -0.381)
			)
			(layers "F.Cu" "F.Mask" "F.Paste")
			(net "PCIE_RX_P51")
		)
		(pad "B64" smd rect
			(at 17.200118 -0.7747 180)
			(size 0.5588 2.3114)
			(drill
				(offset 0 -0.381)
			)
			(layers "F.Cu" "F.Mask" "F.Paste")
			(net "GND")
		)
		(pad "B65" smd rect
			(at 17.999964 -0.7747 180)
			(size 0.5588 2.3114)
			(drill
				(offset 0 -0.381)
			)
			(layers "F.Cu" "F.Mask" "F.Paste")
			(net "SSD_PWREN11_R")
		)
		(pad "B66" smd rect
			(at 18.800064 -0.7747 180)
			(size 0.5588 2.3114)
			(drill
				(offset 0 -0.381)
			)
			(layers "F.Cu" "F.Mask" "F.Paste")
			(net "SSD_ATNLED#11_R")
		)
		(pad "B67" smd rect
			(at 19.59991 -0.7747 180)
			(size 0.5588 2.3114)
			(drill
				(offset 0 -0.381)
			)
			(layers "F.Cu" "F.Mask" "F.Paste")
			(net "SSD_PRSNT#11_R")
		)
		(pad "B68" smd rect
			(at 20.40001 -0.7747 180)
			(size 0.5588 2.3114)
			(drill
				(offset 0 -0.381)
			)
			(layers "F.Cu" "F.Mask" "F.Paste")
			(net "GND")
		)
		(pad "B69" smd rect
			(at 21.20011 -0.7747 180)
			(size 0.5588 2.3114)
			(drill
				(offset 0 -0.381)
			)
			(layers "F.Cu" "F.Mask" "F.Paste")
			(net "PCIE_RX_N52")
		)
		(pad "B70" smd rect
			(at 21.999956 -0.7747 180)
			(size 0.5588 2.3114)
			(drill
				(offset 0 -0.381)
			)
			(layers "F.Cu" "F.Mask" "F.Paste")
			(net "PCIE_RX_P52")
		)
		(pad "B71" smd rect
			(at 22.800056 -0.7747 180)
			(size 0.5588 2.3114)
			(drill
				(offset 0 -0.381)
			)
			(layers "F.Cu" "F.Mask" "F.Paste")
			(net "GND")
		)
		(pad "B72" smd rect
			(at 23.599902 -0.7747 180)
			(size 0.5588 2.3114)
			(drill
				(offset 0 -0.381)
			)
			(layers "F.Cu" "F.Mask" "F.Paste")
			(net "GND")
		)
		(pad "B73" smd rect
			(at 24.400002 -0.7747 180)
			(size 0.5588 2.3114)
			(drill
				(offset 0 -0.381)
			)
			(layers "F.Cu" "F.Mask" "F.Paste")
			(net "PCIE_RX_N53")
		)
		(pad "B74" smd rect
			(at 25.200102 -0.7747 180)
			(size 0.5588 2.3114)
			(drill
				(offset 0 -0.381)
			)
			(layers "F.Cu" "F.Mask" "F.Paste")
			(net "PCIE_RX_P53")
		)
		(pad "B75" smd rect
			(at 25.999948 -0.7747 180)
			(size 0.5588 2.3114)
			(drill
				(offset 0 -0.381)
			)
			(layers "F.Cu" "F.Mask" "F.Paste")
			(net "GND")
		)
		(pad "B76" smd rect
			(at 26.800048 -0.7747 180)
			(size 0.5588 2.3114)
			(drill
				(offset 0 -0.381)
			)
			(layers "F.Cu" "F.Mask" "F.Paste")
			(net "GND")
		)
		(pad "B77" smd rect
			(at 27.599894 -0.7747 180)
			(size 0.5588 2.3114)
			(drill
				(offset 0 -0.381)
			)
			(layers "F.Cu" "F.Mask" "F.Paste")
			(net "PCIE_RX_N54")
		)
		(pad "B78" smd rect
			(at 28.399994 -0.7747 180)
			(size 0.5588 2.3114)
			(drill
				(offset 0 -0.381)
			)
			(layers "F.Cu" "F.Mask" "F.Paste")
			(net "PCIE_RX_P54")
		)
		(pad "B79" smd rect
			(at 29.200094 -0.7747 180)
			(size 0.5588 2.3114)
			(drill
				(offset 0 -0.381)
			)
			(layers "F.Cu" "F.Mask" "F.Paste")
			(net "GND")
		)
		(pad "B80" smd rect
			(at 29.99994 -0.7747 180)
			(size 0.5588 2.3114)
			(drill
				(offset 0 -0.381)
			)
			(layers "F.Cu" "F.Mask" "F.Paste")
			(net "GND")
		)
		(pad "B81" smd rect
			(at 30.80004 -0.7747 180)
			(size 0.5588 2.3114)
			(drill
				(offset 0 -0.381)
			)
			(layers "F.Cu" "F.Mask" "F.Paste")
			(net "PCIE_RX_N55")
		)
		(pad "B82" smd rect
			(at 31.599886 -0.7747 180)
			(size 0.5588 2.3114)
			(drill
				(offset 0 -0.381)
			)
			(layers "F.Cu" "F.Mask" "F.Paste")
			(net "PCIE_RX_P55")
		)
		(pad "B83" smd rect
			(at 32.399986 -0.7747 180)
			(size 0.5588 2.3114)
			(drill
				(offset 0 -0.381)
			)
			(layers "F.Cu" "F.Mask" "F.Paste")
			(net "GND")
		)
		(pad "B84" smd rect
			(at 33.200086 -0.7747 180)
			(size 0.5588 2.3114)
			(drill
				(offset 0 -0.381)
			)
			(layers "F.Cu" "F.Mask" "F.Paste")
			(net "GND")
		)
		(pad "B85" smd rect
			(at 33.999932 -0.7747 180)
			(size 0.5588 2.3114)
			(drill
				(offset 0 -0.381)
			)
			(layers "F.Cu" "F.Mask" "F.Paste")
			(net "PCIE_RX_N56")
		)
		(pad "B86" smd rect
			(at 34.800032 -0.7747 180)
			(size 0.5588 2.3114)
			(drill
				(offset 0 -0.381)
			)
			(layers "F.Cu" "F.Mask" "F.Paste")
			(net "PCIE_RX_P56")
		)
		(pad "B87" smd rect
			(at 35.599878 -0.7747 180)
			(size 0.5588 2.3114)
			(drill
				(offset 0 -0.381)
			)
			(layers "F.Cu" "F.Mask" "F.Paste")
			(net "GND")
		)
		(pad "B88" smd rect
			(at 36.399978 -0.7747 180)
			(size 0.5588 2.3114)
			(drill
				(offset 0 -0.381)
			)
			(layers "F.Cu" "F.Mask" "F.Paste")
			(net "GND")
		)
		(pad "B89" smd rect
			(at 37.200078 -0.7747 180)
			(size 0.5588 2.3114)
			(drill
				(offset 0 -0.381)
			)
			(layers "F.Cu" "F.Mask" "F.Paste")
			(net "PCIE_RX_N57")
		)
		(pad "B90" smd rect
			(at 37.999924 -0.7747 180)
			(size 0.5588 2.3114)
			(drill
				(offset 0 -0.381)
			)
			(layers "F.Cu" "F.Mask" "F.Paste")
			(net "PCIE_RX_P57")
		)
		(pad "B91" smd rect
			(at 38.800024 -0.7747 180)
			(size 0.5588 2.3114)
			(drill
				(offset 0 -0.381)
			)
			(layers "F.Cu" "F.Mask" "F.Paste")
			(net "GND")
		)
		(pad "B92" smd rect
			(at 39.600124 -0.7747 180)
			(size 0.5588 2.3114)
			(drill
				(offset 0 -0.381)
			)
			(layers "F.Cu" "F.Mask" "F.Paste")
			(net "GND")
		)
		(pad "B93" smd rect
			(at 40.39997 -0.7747 180)
			(size 0.5588 2.3114)
			(drill
				(offset 0 -0.381)
			)
			(layers "F.Cu" "F.Mask" "F.Paste")
			(net "PCIE_RX_N58")
		)
		(pad "B94" smd rect
			(at 41.20007 -0.7747 180)
			(size 0.5588 2.3114)
			(drill
				(offset 0 -0.381)
			)
			(layers "F.Cu" "F.Mask" "F.Paste")
			(net "PCIE_RX_P58")
		)
		(pad "B95" smd rect
			(at 41.999916 -0.7747 180)
			(size 0.5588 2.3114)
			(drill
				(offset 0 -0.381)
			)
			(layers "F.Cu" "F.Mask" "F.Paste")
			(net "GND")
		)
		(pad "B96" smd rect
			(at 42.800016 -0.7747 180)
			(size 0.5588 2.3114)
			(drill
				(offset 0 -0.381)
			)
			(layers "F.Cu" "F.Mask" "F.Paste")
			(net "GND")
		)
		(pad "B97" smd rect
			(at 43.600116 -0.7747 180)
			(size 0.5588 2.3114)
			(drill
				(offset 0 -0.381)
			)
			(layers "F.Cu" "F.Mask" "F.Paste")
			(net "PCIE_RX_N59")
		)
		(pad "B98" smd rect
			(at 44.399962 -0.7747 180)
			(size 0.5588 2.3114)
			(drill
				(offset 0 -0.381)
			)
			(layers "F.Cu" "F.Mask" "F.Paste")
			(net "PCIE_RX_P59")
		)
		(pad "B99" smd rect
			(at 45.200062 -0.7747 180)
			(size 0.5588 2.3114)
			(drill
				(offset 0 -0.381)
			)
			(layers "F.Cu" "F.Mask" "F.Paste")
			(net "GND")
		)
		(pad "B100" smd rect
			(at 45.999908 -0.7747 180)
			(size 0.5588 2.3114)
			(drill
				(offset 0 -0.381)
			)
			(layers "F.Cu" "F.Mask" "F.Paste")
			(net "SSD_PERST#6_R")
		)
		(zone
			(layer "F.Cu")
			(hatch none 0.5)
			(connect_pads
				(clearance 0)
			)
			(min_thickness 0.25)
			(keepout
				(tracks not_allowed)
				(vias allowed)
				(pads allowed)
				(copperpour not_allowed)
				(footprints allowed)
			)
			(placement
				(enabled no)
				(sheetname "")
			)
			(fill
				(thermal_gap 0.5)
				(thermal_bridge_width 0.5)
				(island_removal_mode 0)
			)
			(polygon
				(pts
					(xy 218.99372 -227.71608) (xy 134.00532 -227.71608) (xy 134.00532 -226.70008) (xy 218.99372 -226.70008)
				)
			)
		)
		(zone
			(layer "F.Cu")
			(hatch none 0.5)
			(connect_pads
				(clearance 0)
			)
			(min_thickness 0.25)
			(keepout
				(tracks allowed)
				(vias not_allowed)
				(pads allowed)
				(copperpour not_allowed)
				(footprints allowed)
			)
			(placement
				(enabled no)
				(sheetname "")
			)
			(fill
				(thermal_gap 0.5)
				(thermal_bridge_width 0.5)
				(island_removal_mode 0)
			)
			(polygon
				(pts
					(xy 218.99372 -227.71608) (xy 134.00532 -227.71608) (xy 134.00532 -223.37268) (xy 218.99372 -223.37268)
				)
			)
		)
		(zone
			(layer "B.Cu")
			(hatch none 0.5)
			(connect_pads
				(clearance 0)
			)
			(min_thickness 0.25)
			(keepout
				(tracks not_allowed)
				(vias allowed)
				(pads allowed)
				(copperpour not_allowed)
				(footprints allowed)
			)
			(placement
				(enabled no)
				(sheetname "")
			)
			(fill
				(thermal_gap 0.5)
				(thermal_bridge_width 0.5)
				(island_removal_mode 0)
			)
			(polygon
				(pts
					(xy 218.99372 -227.71608) (xy 134.00532 -227.71608) (xy 134.00532 -226.70008) (xy 218.99372 -226.70008)
				)
			)
		)
		(zone
			(layer "B.Cu")
			(hatch none 0.5)
			(connect_pads
				(clearance 0)
			)
			(min_thickness 0.25)
			(keepout
				(tracks allowed)
				(vias not_allowed)
				(pads allowed)
				(copperpour not_allowed)
				(footprints allowed)
			)
			(placement
				(enabled no)
				(sheetname "")
			)
			(fill
				(thermal_gap 0.5)
				(thermal_bridge_width 0.5)
				(island_removal_mode 0)
			)
			(polygon
				(pts
					(xy 218.99372 -227.71608) (xy 134.00532 -227.71608) (xy 134.00532 -223.37268) (xy 218.99372 -223.37268)
				)
			)
		)
	)
	(footprint ""
		(layer "F.Cu")
		(at 34.798 -116.713)
		(property "Reference" "R23"
			(at 0 0 0)
			(layer "F.SilkS")
			(hide yes)
			(effects
				(font
					(size 1.27 1.27)
				)
			)
		)
		(property "Value" "10KR2F-2-GP"
			(at 0.064008 -3.993896 0)
			(unlocked yes)
			(layer "F.Fab")
			(hide yes)
			(effects
				(font
					(size 1.016 1.016)
					(thickness 0.1524)
				)
			)
		)
		(property "Device Type" "R402H16"
			(at 0.064008 -5.517896 0)
			(unlocked yes)
			(layer "F.Fab")
			(hide yes)
			(effects
				(font
					(size 1.016 1.016)
					(thickness 0.1524)
				)
			)
		)
		(duplicate_pad_numbers_are_jumpers no)
		(fp_line
			(start -0.508 -0.9398)
			(end -0.508 0.9398)
			(stroke
				(width 0.1524)
				(type default)
			)
			(layer "F.SilkS")
		)
		(fp_line
			(start 0.508 -0.9398)
			(end -0.508 -0.9398)
			(stroke
				(width 0.1524)
				(type default)
			)
			(layer "F.SilkS")
		)
		(fp_rect
			(start -0.508 0.9398)
			(end 0.508 -0.9398)
			(stroke
				(width 0)
				(type default)
			)
			(fill no)
			(layer "F.CrtYd")
		)
		(fp_rect
			(start -0.508 0.9398)
			(end 0.508 -0.9398)
			(stroke
				(width 0)
				(type default)
			)
			(fill no)
			(layer "F.Fab")
		)
		(pad "1" smd custom
			(at 0 -0.4445)
			(size 0.1397 0.1397)
			(layers "F.Cu" "F.Mask" "F.Paste")
			(net "PMC_PLX_BOARD")
			(options
				(clearance outline)
				(anchor circle)
			)
			(primitives
				(gr_poly
					(pts
						(arc
							(start -0.1778 -0.2794)
							(mid -0.249642 -0.249642)
							(end -0.2794 -0.1778)
						)
						(arc
							(start -0.2794 0.1778)
							(mid -0.249642 0.249642)
							(end -0.1778 0.2794)
						)
						(arc
							(start 0.1778 0.2794)
							(mid 0.249642 0.249642)
							(end 0.2794 0.1778)
						)
						(arc
							(start 0.2794 -0.1778)
							(mid 0.249642 -0.249642)
							(end 0.1778 -0.2794)
						)
					)
					(width 0)
					(fill yes)
				)
			)
		)
		(pad "2" smd custom
			(at 0 0.4445)
			(size 0.1397 0.1397)
			(layers "F.Cu" "F.Mask" "F.Paste")
			(net "P3V3_STBY")
			(options
				(clearance outline)
				(anchor circle)
			)
			(primitives
				(gr_poly
					(pts
						(arc
							(start -0.1778 -0.2794)
							(mid -0.249642 -0.249642)
							(end -0.2794 -0.1778)
						)
						(arc
							(start -0.2794 0.1778)
							(mid -0.249642 0.249642)
							(end -0.1778 0.2794)
						)
						(arc
							(start 0.1778 0.2794)
							(mid 0.249642 0.249642)
							(end 0.2794 0.1778)
						)
						(arc
							(start 0.2794 -0.1778)
							(mid 0.249642 -0.249642)
							(end 0.1778 -0.2794)
						)
					)
					(width 0)
					(fill yes)
				)
			)
		)
	)
	(footprint ""
		(layer "F.Cu")
		(at 155.65882 -86.0171 180)
		(property "Reference" "L10"
			(at 0 0 180)
			(layer "F.SilkS")
			(hide yes)
			(effects
				(font
					(size 1.27 1.27)
				)
			)
		)
		(property "Value" "BLM18SG121TN1D-GP"
			(at 0.0254 -2.7686 180)
			(unlocked yes)
			(layer "F.Fab")
			(hide yes)
			(effects
				(font
					(size 1.016 1.016)
					(thickness 0.1524)
				)
			)
		)
		(property "Device Type" "L603H26"
			(at 0.0254 -4.2926 180)
			(unlocked yes)
			(layer "F.Fab")
			(hide yes)
			(effects
				(font
					(size 1.016 1.016)
					(thickness 0.1524)
				)
			)
		)
		(duplicate_pad_numbers_are_jumpers no)
		(fp_line
			(start 0.254 0)
			(end -0.254 0)
			(stroke
				(width 0.2032)
				(type default)
			)
			(layer "F.SilkS")
		)
		(fp_rect
			(start -0.5842 1.3335)
			(end 0.5842 -1.3335)
			(stroke
				(width 0)
				(type default)
			)
			(fill no)
			(layer "F.CrtYd")
		)
		(fp_rect
			(start -0.5842 1.3335)
			(end 0.5842 -1.3335)
			(stroke
				(width 0)
				(type default)
			)
			(fill no)
			(layer "F.Fab")
		)
		(pad "1" smd custom
			(at 0 -0.762 180)
			(size 0.2159 0.2159)
			(layers "F.Cu" "F.Mask" "F.Paste")
			(net "P1V8_STBY")
			(options
				(clearance outline)
				(anchor circle)
			)
			(primitives
				(gr_poly
					(pts
						(arc
							(start -0.3302 -0.4318)
							(mid -0.402042 -0.402042)
							(end -0.4318 -0.3302)
						)
						(arc
							(start -0.4318 0.3302)
							(mid -0.402042 0.402042)
							(end -0.3302 0.4318)
						)
						(arc
							(start 0.3302 0.4318)
							(mid 0.402042 0.402042)
							(end 0.4318 0.3302)
						)
						(arc
							(start 0.4318 -0.3302)
							(mid 0.402042 -0.402042)
							(end 0.3302 -0.4318)
						)
					)
					(width 0)
					(fill yes)
				)
			)
		)
		(pad "2" smd custom
			(at 0 0.762 180)
			(size 0.2159 0.2159)
			(layers "F.Cu" "F.Mask" "F.Paste")
			(net "P1V8_CLKGEN")
			(options
				(clearance outline)
				(anchor circle)
			)
			(primitives
				(gr_poly
					(pts
						(arc
							(start -0.3302 -0.4318)
							(mid -0.402042 -0.402042)
							(end -0.4318 -0.3302)
						)
						(arc
							(start -0.4318 0.3302)
							(mid -0.402042 0.402042)
							(end -0.3302 0.4318)
						)
						(arc
							(start 0.3302 0.4318)
							(mid 0.402042 0.402042)
							(end 0.4318 0.3302)
						)
						(arc
							(start 0.4318 -0.3302)
							(mid 0.402042 -0.402042)
							(end 0.3302 -0.4318)
						)
					)
					(width 0)
					(fill yes)
				)
			)
		)
	)
	(footprint ""
		(layer "F.Cu")
		(at 74.742548 -120.0912 -90)
		(property "Reference" "U53"
			(at 0 0 270)
			(layer "F.SilkS")
			(hide yes)
			(effects
				(font
					(size 1.27 1.27)
				)
			)
		)
		(property "Value" "SN74LVC1G07DCKRG4-2-GP"
			(at -2.3368 -8.6868 270)
			(unlocked yes)
			(layer "F.Fab")
			(hide yes)
			(effects
				(font
					(size 1.016 1.016)
					(thickness 0.1524)
				)
			)
		)
		(property "Device Type" "SC70-5H44"
			(at -2.3114 -10.414 270)
			(unlocked yes)
			(layer "F.Fab")
			(hide yes)
			(effects
				(font
					(size 1.016 1.016)
					(thickness 0.1524)
				)
			)
		)
		(duplicate_pad_numbers_are_jumpers no)
		(fp_line
			(start -1.27 1.7018)
			(end -1.27 -1.7018)
			(stroke
				(width 0.1524)
				(type default)
			)
			(layer "F.SilkS")
		)
		(fp_line
			(start 1.27 1.7018)
			(end -1.27 1.7018)
			(stroke
				(width 0.1524)
				(type default)
			)
			(layer "F.SilkS")
		)
		(fp_line
			(start -1.27 -1.7018)
			(end 1.27 -1.7018)
			(stroke
				(width 0.1524)
				(type default)
			)
			(layer "F.SilkS")
		)
		(fp_line
			(start 1.27 -1.7018)
			(end 1.27 1.7018)
			(stroke
				(width 0.1524)
				(type default)
			)
			(layer "F.SilkS")
		)
		(fp_line
			(start 0.6604 -1.8034)
			(end 1.3843 -1.8034)
			(stroke
				(width 0.3302)
				(type default)
			)
			(layer "F.SilkS")
		)
		(fp_line
			(start 1.3843 -1.8034)
			(end 1.3843 -1.1176)
			(stroke
				(width 0.3302)
				(type default)
			)
			(layer "F.SilkS")
		)
		(fp_rect
			(start -1.524 1.9558)
			(end 1.524 -1.9558)
			(stroke
				(width 0)
				(type default)
			)
			(fill no)
			(layer "F.CrtYd")
		)
		(fp_poly
			(pts
				(xy -1.524 -1.9558) (xy 1.524 -1.9558) (xy 1.524 1.9558) (xy -1.524 1.9558)
			)
			(stroke
				(width 0)
				(type default)
			)
			(fill no)
			(layer "F.Fab")
		)
		(pad "1" smd rect
			(at 0.65024 -0.8255 270)
			(size 0.4064 1.2192)
			(layers "F.Cu" "F.Mask" "F.Paste")
			(net "Net_112")
		)
		(pad "2" smd rect
			(at 0 -0.8255 270)
			(size 0.4064 1.2192)
			(layers "F.Cu" "F.Mask" "F.Paste")
			(net "MBP_UART_RX")
		)
		(pad "3" smd rect
			(at -0.65024 -0.8255 270)
			(size 0.4064 1.2192)
			(layers "F.Cu" "F.Mask" "F.Paste")
			(net "GND")
		)
		(pad "4" smd rect
			(at -0.65024 0.8255 270)
			(size 0.4064 1.2192)
			(layers "F.Cu" "F.Mask" "F.Paste")
			(net "BMC_RXD5_R")
		)
		(pad "5" smd rect
			(at 0.65024 0.8255 270)
			(size 0.4064 1.2192)
			(layers "F.Cu" "F.Mask" "F.Paste")
			(net "P3V3_STBY")
		)
	)
	(footprint ""
		(layer "F.Cu")
		(at 130.024124 -196.443092)
		(property "Reference" "R7922"
			(at 0 0 0)
			(layer "F.SilkS")
			(hide yes)
			(effects
				(font
					(size 1.27 1.27)
				)
			)
		)
		(property "Value" "0R2J-2-GP"
			(at 0.064008 -3.993896 0)
			(unlocked yes)
			(layer "F.Fab")
			(hide yes)
			(effects
				(font
					(size 1.016 1.016)
					(thickness 0.1524)
				)
			)
		)
		(property "Device Type" "R402H16"
			(at 0.064008 -5.517896 0)
			(unlocked yes)
			(layer "F.Fab")
			(hide yes)
			(effects
				(font
					(size 1.016 1.016)
					(thickness 0.1524)
				)
			)
		)
		(duplicate_pad_numbers_are_jumpers no)
		(fp_line
			(start -0.508 -0.9398)
			(end -0.508 0.9398)
			(stroke
				(width 0.1524)
				(type default)
			)
			(layer "F.SilkS")
		)
		(fp_line
			(start 0.508 -0.9398)
			(end -0.508 -0.9398)
			(stroke
				(width 0.1524)
				(type default)
			)
			(layer "F.SilkS")
		)
		(fp_rect
			(start -0.508 0.9398)
			(end 0.508 -0.9398)
			(stroke
				(width 0)
				(type default)
			)
			(fill no)
			(layer "F.CrtYd")
		)
		(fp_rect
			(start -0.508 0.9398)
			(end 0.508 -0.9398)
			(stroke
				(width 0)
				(type default)
			)
			(fill no)
			(layer "F.Fab")
		)
		(pad "1" smd custom
			(at 0 -0.4445)
			(size 0.1397 0.1397)
			(layers "F.Cu" "F.Mask" "F.Paste")
			(net "SSD_PRSNT#2")
			(options
				(clearance outline)
				(anchor circle)
			)
			(primitives
				(gr_poly
					(pts
						(arc
							(start -0.1778 -0.2794)
							(mid -0.249642 -0.249642)
							(end -0.2794 -0.1778)
						)
						(arc
							(start -0.2794 0.1778)
							(mid -0.249642 0.249642)
							(end -0.1778 0.2794)
						)
						(arc
							(start 0.1778 0.2794)
							(mid 0.249642 0.249642)
							(end 0.2794 0.1778)
						)
						(arc
							(start 0.2794 -0.1778)
							(mid 0.249642 -0.249642)
							(end 0.1778 -0.2794)
						)
					)
					(width 0)
					(fill yes)
				)
			)
		)
		(pad "2" smd custom
			(at 0 0.4445)
			(size 0.1397 0.1397)
			(layers "F.Cu" "F.Mask" "F.Paste")
			(net "SSD_PRSNT#2_R")
			(options
				(clearance outline)
				(anchor circle)
			)
			(primitives
				(gr_poly
					(pts
						(arc
							(start -0.1778 -0.2794)
							(mid -0.249642 -0.249642)
							(end -0.2794 -0.1778)
						)
						(arc
							(start -0.2794 0.1778)
							(mid -0.249642 0.249642)
							(end -0.1778 0.2794)
						)
						(arc
							(start 0.1778 0.2794)
							(mid 0.249642 0.249642)
							(end 0.2794 0.1778)
						)
						(arc
							(start 0.2794 -0.1778)
							(mid 0.249642 -0.249642)
							(end 0.1778 -0.2794)
						)
					)
					(width 0)
					(fill yes)
				)
			)
		)
	)
	(footprint ""
		(layer "F.Cu")
		(at 118.59387 -30.639512 180)
		(property "Reference" "R2961"
			(at 0 0 180)
			(layer "F.SilkS")
			(hide yes)
			(effects
				(font
					(size 1.27 1.27)
				)
			)
		)
		(property "Value" "0R2J-2-GP"
			(at 0.064008 -3.993896 180)
			(unlocked yes)
			(layer "F.Fab")
			(hide yes)
			(effects
				(font
					(size 1.016 1.016)
					(thickness 0.1524)
				)
			)
		)
		(property "Device Type" "R402H16"
			(at 0.064008 -5.517896 180)
			(unlocked yes)
			(layer "F.Fab")
			(hide yes)
			(effects
				(font
					(size 1.016 1.016)
					(thickness 0.1524)
				)
			)
		)
		(duplicate_pad_numbers_are_jumpers no)
		(fp_line
			(start 0.508 -0.9398)
			(end -0.508 -0.9398)
			(stroke
				(width 0.1524)
				(type default)
			)
			(layer "F.SilkS")
		)
		(fp_line
			(start -0.508 -0.9398)
			(end -0.508 0.9398)
			(stroke
				(width 0.1524)
				(type default)
			)
			(layer "F.SilkS")
		)
		(fp_rect
			(start -0.508 0.9398)
			(end 0.508 -0.9398)
			(stroke
				(width 0)
				(type default)
			)
			(fill no)
			(layer "F.CrtYd")
		)
		(fp_rect
			(start -0.508 0.9398)
			(end 0.508 -0.9398)
			(stroke
				(width 0)
				(type default)
			)
			(fill no)
			(layer "F.Fab")
		)
		(pad "1" smd custom
			(at 0 -0.4445 180)
			(size 0.1397 0.1397)
			(layers "F.Cu" "F.Mask" "F.Paste")
			(net "U54_SCL")
			(options
				(clearance outline)
				(anchor circle)
			)
			(primitives
				(gr_poly
					(pts
						(arc
							(start -0.1778 -0.2794)
							(mid -0.249642 -0.249642)
							(end -0.2794 -0.1778)
						)
						(arc
							(start -0.2794 0.1778)
							(mid -0.249642 0.249642)
							(end -0.1778 0.2794)
						)
						(arc
							(start 0.1778 0.2794)
							(mid 0.249642 0.249642)
							(end 0.2794 0.1778)
						)
						(arc
							(start 0.2794 -0.1778)
							(mid 0.249642 -0.249642)
							(end 0.1778 -0.2794)
						)
					)
					(width 0)
					(fill yes)
				)
			)
		)
		(pad "2" smd custom
			(at 0 0.4445 180)
			(size 0.1397 0.1397)
			(layers "F.Cu" "F.Mask" "F.Paste")
			(net "BMC_I2C1_MINI1_SCL_S")
			(options
				(clearance outline)
				(anchor circle)
			)
			(primitives
				(gr_poly
					(pts
						(arc
							(start -0.1778 -0.2794)
							(mid -0.249642 -0.249642)
							(end -0.2794 -0.1778)
						)
						(arc
							(start -0.2794 0.1778)
							(mid -0.249642 0.249642)
							(end -0.1778 0.2794)
						)
						(arc
							(start 0.1778 0.2794)
							(mid 0.249642 0.249642)
							(end 0.2794 0.1778)
						)
						(arc
							(start 0.2794 -0.1778)
							(mid 0.249642 -0.249642)
							(end 0.1778 -0.2794)
						)
					)
					(width 0)
					(fill yes)
				)
			)
		)
	)
	(footprint ""
		(layer "F.Cu")
		(at 317.418466 -33.42513)
		(property "Reference" "R377"
			(at 0 0 0)
			(layer "F.SilkS")
			(hide yes)
			(effects
				(font
					(size 1.27 1.27)
				)
			)
		)
		(property "Value" "0R2J-2-GP"
			(at 0.064008 -3.993896 0)
			(unlocked yes)
			(layer "F.Fab")
			(hide yes)
			(effects
				(font
					(size 1.016 1.016)
					(thickness 0.1524)
				)
			)
		)
		(property "Device Type" "R402H16"
			(at 0.064008 -5.517896 0)
			(unlocked yes)
			(layer "F.Fab")
			(hide yes)
			(effects
				(font
					(size 1.016 1.016)
					(thickness 0.1524)
				)
			)
		)
		(duplicate_pad_numbers_are_jumpers no)
		(fp_line
			(start -0.508 -0.9398)
			(end -0.508 0.9398)
			(stroke
				(width 0.1524)
				(type default)
			)
			(layer "F.SilkS")
		)
		(fp_line
			(start 0.508 -0.9398)
			(end -0.508 -0.9398)
			(stroke
				(width 0.1524)
				(type default)
			)
			(layer "F.SilkS")
		)
		(fp_rect
			(start -0.508 0.9398)
			(end 0.508 -0.9398)
			(stroke
				(width 0)
				(type default)
			)
			(fill no)
			(layer "F.CrtYd")
		)
		(fp_rect
			(start -0.508 0.9398)
			(end 0.508 -0.9398)
			(stroke
				(width 0)
				(type default)
			)
			(fill no)
			(layer "F.Fab")
		)
		(pad "1" smd custom
			(at 0 -0.4445)
			(size 0.1397 0.1397)
			(layers "F.Cu" "F.Mask" "F.Paste")
			(net "CLK_P_8_R")
			(options
				(clearance outline)
				(anchor circle)
			)
			(primitives
				(gr_poly
					(pts
						(arc
							(start -0.1778 -0.2794)
							(mid -0.249642 -0.249642)
							(end -0.2794 -0.1778)
						)
						(arc
							(start -0.2794 0.1778)
							(mid -0.249642 0.249642)
							(end -0.1778 0.2794)
						)
						(arc
							(start 0.1778 0.2794)
							(mid 0.249642 0.249642)
							(end 0.2794 0.1778)
						)
						(arc
							(start 0.2794 -0.1778)
							(mid 0.249642 -0.249642)
							(end 0.1778 -0.2794)
						)
					)
					(width 0)
					(fill yes)
				)
			)
		)
		(pad "2" smd custom
			(at 0 0.4445)
			(size 0.1397 0.1397)
			(layers "F.Cu" "F.Mask" "F.Paste")
			(net "CLK_P_8")
			(options
				(clearance outline)
				(anchor circle)
			)
			(primitives
				(gr_poly
					(pts
						(arc
							(start -0.1778 -0.2794)
							(mid -0.249642 -0.249642)
							(end -0.2794 -0.1778)
						)
						(arc
							(start -0.2794 0.1778)
							(mid -0.249642 0.249642)
							(end -0.1778 0.2794)
						)
						(arc
							(start 0.1778 0.2794)
							(mid 0.249642 0.249642)
							(end 0.2794 0.1778)
						)
						(arc
							(start 0.2794 -0.1778)
							(mid 0.249642 -0.249642)
							(end 0.1778 -0.2794)
						)
					)
					(width 0)
					(fill yes)
				)
			)
		)
	)
	(footprint ""
		(layer "F.Cu")
		(at 321.437 -99.568)
		(property "Reference" "R7998"
			(at 0 0 0)
			(layer "F.SilkS")
			(hide yes)
			(effects
				(font
					(size 1.27 1.27)
				)
			)
		)
		(property "Value" "330R2J-3-GP"
			(at 0.064008 -3.993896 0)
			(unlocked yes)
			(layer "F.Fab")
			(hide yes)
			(effects
				(font
					(size 1.016 1.016)
					(thickness 0.1524)
				)
			)
		)
		(property "Device Type" "R402H16"
			(at 0.064008 -5.517896 0)
			(unlocked yes)
			(layer "F.Fab")
			(hide yes)
			(effects
				(font
					(size 1.016 1.016)
					(thickness 0.1524)
				)
			)
		)
		(duplicate_pad_numbers_are_jumpers no)
		(fp_line
			(start -0.508 -0.9398)
			(end -0.508 0.9398)
			(stroke
				(width 0.1524)
				(type default)
			)
			(layer "F.SilkS")
		)
		(fp_line
			(start 0.508 -0.9398)
			(end -0.508 -0.9398)
			(stroke
				(width 0.1524)
				(type default)
			)
			(layer "F.SilkS")
		)
		(fp_rect
			(start -0.508 0.9398)
			(end 0.508 -0.9398)
			(stroke
				(width 0)
				(type default)
			)
			(fill no)
			(layer "F.CrtYd")
		)
		(fp_rect
			(start -0.508 0.9398)
			(end 0.508 -0.9398)
			(stroke
				(width 0)
				(type default)
			)
			(fill no)
			(layer "F.Fab")
		)
		(pad "1" smd custom
			(at 0 -0.4445)
			(size 0.1397 0.1397)
			(layers "F.Cu" "F.Mask" "F.Paste")
			(net "TWI_SCL3")
			(options
				(clearance outline)
				(anchor circle)
			)
			(primitives
				(gr_poly
					(pts
						(arc
							(start -0.1778 -0.2794)
							(mid -0.249642 -0.249642)
							(end -0.2794 -0.1778)
						)
						(arc
							(start -0.2794 0.1778)
							(mid -0.249642 0.249642)
							(end -0.1778 0.2794)
						)
						(arc
							(start 0.1778 0.2794)
							(mid 0.249642 0.249642)
							(end 0.2794 0.1778)
						)
						(arc
							(start 0.2794 -0.1778)
							(mid 0.249642 -0.249642)
							(end 0.1778 -0.2794)
						)
					)
					(width 0)
					(fill yes)
				)
			)
		)
		(pad "2" smd custom
			(at 0 0.4445)
			(size 0.1397 0.1397)
			(layers "F.Cu" "F.Mask" "F.Paste")
			(net "IOEXP_TWI_SCL3")
			(options
				(clearance outline)
				(anchor circle)
			)
			(primitives
				(gr_poly
					(pts
						(arc
							(start -0.1778 -0.2794)
							(mid -0.249642 -0.249642)
							(end -0.2794 -0.1778)
						)
						(arc
							(start -0.2794 0.1778)
							(mid -0.249642 0.249642)
							(end -0.1778 0.2794)
						)
						(arc
							(start 0.1778 0.2794)
							(mid 0.249642 0.249642)
							(end 0.2794 0.1778)
						)
						(arc
							(start 0.2794 -0.1778)
							(mid 0.249642 -0.249642)
							(end 0.1778 -0.2794)
						)
					)
					(width 0)
					(fill yes)
				)
			)
		)
	)
	(footprint ""
		(layer "F.Cu")
		(at 178.1048 -65.405 180)
		(property "Reference" "PG15"
			(at 0 0 180)
			(layer "F.SilkS")
			(hide yes)
			(effects
				(font
					(size 1.27 1.27)
				)
			)
		)
		(property "Value" "GAP-CLOSE-PWR-3-GP"
			(at 0.0254 -6.5786 180)
			(unlocked yes)
			(layer "F.Fab")
			(hide yes)
			(effects
				(font
					(size 1.016 1.016)
					(thickness 0.1524)
				)
			)
		)
		(property "Device Type" "GAP-CLOSE-PWR-3"
			(at 0.0254 -8.255 180)
			(unlocked yes)
			(layer "F.Fab")
			(hide yes)
			(effects
				(font
					(size 1.016 1.016)
					(thickness 0.1524)
				)
			)
		)
		(duplicate_pad_numbers_are_jumpers no)
		(fp_rect
			(start -0.7112 0.4572)
			(end 0.7112 -0.4572)
			(stroke
				(width 0)
				(type default)
			)
			(fill no)
			(layer "F.CrtYd")
		)
		(fp_poly
			(pts
				(xy -0.7112 -0.4572) (xy 0.7112 -0.4572) (xy 0.7112 0.4572) (xy -0.7112 0.4572)
			)
			(stroke
				(width 0)
				(type default)
			)
			(fill no)
			(layer "F.Fab")
		)
		(pad "1" smd rect
			(at -0.3048 0 180)
			(size 0.6604 0.762)
			(layers "F.Cu" "F.Mask" "F.Paste")
			(net "DUT_AVD_PCIE")
		)
		(pad "2" smd rect
			(at 0.3048 0 180)
			(size 0.6604 0.762)
			(layers "F.Cu" "F.Mask" "F.Paste")
			(net "P0V9")
		)
	)
	(footprint ""
		(layer "F.Cu")
		(at 51.816 -191.262 180)
		(property "Reference" "R893"
			(at 0 0 180)
			(layer "F.SilkS")
			(hide yes)
			(effects
				(font
					(size 1.27 1.27)
				)
			)
		)
		(property "Value" "0R2J-2-GP"
			(at 0.064008 -3.993896 180)
			(unlocked yes)
			(layer "F.Fab")
			(hide yes)
			(effects
				(font
					(size 1.016 1.016)
					(thickness 0.1524)
				)
			)
		)
		(property "Device Type" "R402H16"
			(at 0.064008 -5.517896 180)
			(unlocked yes)
			(layer "F.Fab")
			(hide yes)
			(effects
				(font
					(size 1.016 1.016)
					(thickness 0.1524)
				)
			)
		)
		(duplicate_pad_numbers_are_jumpers no)
		(fp_line
			(start 0.508 -0.9398)
			(end -0.508 -0.9398)
			(stroke
				(width 0.1524)
				(type default)
			)
			(layer "F.SilkS")
		)
		(fp_line
			(start -0.508 -0.9398)
			(end -0.508 0.9398)
			(stroke
				(width 0.1524)
				(type default)
			)
			(layer "F.SilkS")
		)
		(fp_rect
			(start -0.508 0.9398)
			(end 0.508 -0.9398)
			(stroke
				(width 0)
				(type default)
			)
			(fill no)
			(layer "F.CrtYd")
		)
		(fp_rect
			(start -0.508 0.9398)
			(end 0.508 -0.9398)
			(stroke
				(width 0)
				(type default)
			)
			(fill no)
			(layer "F.Fab")
		)
		(pad "1" smd custom
			(at 0 -0.4445 180)
			(size 0.1397 0.1397)
			(layers "F.Cu" "F.Mask" "F.Paste")
			(net "BMC_I2C7_B_DBP_SCL")
			(options
				(clearance outline)
				(anchor circle)
			)
			(primitives
				(gr_poly
					(pts
						(arc
							(start -0.1778 -0.2794)
							(mid -0.249642 -0.249642)
							(end -0.2794 -0.1778)
						)
						(arc
							(start -0.2794 0.1778)
							(mid -0.249642 0.249642)
							(end -0.1778 0.2794)
						)
						(arc
							(start 0.1778 0.2794)
							(mid 0.249642 0.249642)
							(end 0.2794 0.1778)
						)
						(arc
							(start 0.2794 -0.1778)
							(mid 0.249642 -0.249642)
							(end 0.1778 -0.2794)
						)
					)
					(width 0)
					(fill yes)
				)
			)
		)
		(pad "2" smd custom
			(at 0 0.4445 180)
			(size 0.1397 0.1397)
			(layers "F.Cu" "F.Mask" "F.Paste")
			(net "BMC_I2C7_B_DBP_SCL_R")
			(options
				(clearance outline)
				(anchor circle)
			)
			(primitives
				(gr_poly
					(pts
						(arc
							(start -0.1778 -0.2794)
							(mid -0.249642 -0.249642)
							(end -0.2794 -0.1778)
						)
						(arc
							(start -0.2794 0.1778)
							(mid -0.249642 0.249642)
							(end -0.1778 0.2794)
						)
						(arc
							(start 0.1778 0.2794)
							(mid 0.249642 0.249642)
							(end 0.2794 0.1778)
						)
						(arc
							(start 0.2794 -0.1778)
							(mid 0.249642 -0.249642)
							(end 0.1778 -0.2794)
						)
					)
					(width 0)
					(fill yes)
				)
			)
		)
	)
	(footprint ""
		(layer "F.Cu")
		(at 178.9938 -71.628 180)
		(property "Reference" "C558"
			(at 0 0 180)
			(layer "F.SilkS")
			(hide yes)
			(effects
				(font
					(size 1.27 1.27)
				)
			)
		)
		(property "Value" "SC4D7U16V5KX-1-GP"
			(at -0.0762 -6.1214 180)
			(unlocked yes)
			(layer "F.Fab")
			(hide yes)
			(effects
				(font
					(size 1.016 1.016)
					(thickness 0.1524)
				)
			)
		)
		(property "Device Type" "C805H56"
			(at -0.0762 -8.1534 180)
			(unlocked yes)
			(layer "F.Fab")
			(hide yes)
			(effects
				(font
					(size 1.016 1.016)
					(thickness 0.1524)
				)
			)
		)
		(duplicate_pad_numbers_are_jumpers no)
		(fp_line
			(start 0.635 0)
			(end -0.635 0)
			(stroke
				(width 0.508)
				(type default)
			)
			(layer "F.SilkS")
		)
		(fp_rect
			(start -0.9652 1.778)
			(end 0.9652 -1.778)
			(stroke
				(width 0)
				(type default)
			)
			(fill no)
			(layer "F.CrtYd")
		)
		(fp_poly
			(pts
				(xy -0.9652 -1.778) (xy 0.9652 -1.778) (xy 0.9652 1.778) (xy -0.9652 1.778)
			)
			(stroke
				(width 0)
				(type default)
			)
			(fill no)
			(layer "F.Fab")
		)
		(pad "1" smd rect
			(at 0 -0.9652 180)
			(size 1.397 1.143)
			(layers "F.Cu" "F.Mask" "F.Paste")
			(net "DUT_AVD_PCIE")
		)
		(pad "2" smd rect
			(at 0 0.9652 180)
			(size 1.397 1.143)
			(layers "F.Cu" "F.Mask" "F.Paste")
			(net "GND")
		)
	)
	(footprint ""
		(layer "F.Cu")
		(at 65.532 -131.953)
		(property "Reference" "R5764"
			(at 0 0 0)
			(layer "F.SilkS")
			(hide yes)
			(effects
				(font
					(size 1.27 1.27)
				)
			)
		)
		(property "Value" "5K6R2F-2-GP"
			(at 0.064008 -3.993896 0)
			(unlocked yes)
			(layer "F.Fab")
			(hide yes)
			(effects
				(font
					(size 1.016 1.016)
					(thickness 0.1524)
				)
			)
		)
		(property "Device Type" "R402H16"
			(at 0.064008 -5.517896 0)
			(unlocked yes)
			(layer "F.Fab")
			(hide yes)
			(effects
				(font
					(size 1.016 1.016)
					(thickness 0.1524)
				)
			)
		)
		(duplicate_pad_numbers_are_jumpers no)
		(fp_line
			(start -0.508 -0.9398)
			(end -0.508 0.9398)
			(stroke
				(width 0.1524)
				(type default)
			)
			(layer "F.SilkS")
		)
		(fp_line
			(start 0.508 -0.9398)
			(end -0.508 -0.9398)
			(stroke
				(width 0.1524)
				(type default)
			)
			(layer "F.SilkS")
		)
		(fp_rect
			(start -0.508 0.9398)
			(end 0.508 -0.9398)
			(stroke
				(width 0)
				(type default)
			)
			(fill no)
			(layer "F.CrtYd")
		)
		(fp_rect
			(start -0.508 0.9398)
			(end 0.508 -0.9398)
			(stroke
				(width 0)
				(type default)
			)
			(fill no)
			(layer "F.Fab")
		)
		(pad "1" smd custom
			(at 0 -0.4445)
			(size 0.1397 0.1397)
			(layers "F.Cu" "F.Mask" "F.Paste")
			(net "P12V")
			(options
				(clearance outline)
				(anchor circle)
			)
			(primitives
				(gr_poly
					(pts
						(arc
							(start -0.1778 -0.2794)
							(mid -0.249642 -0.249642)
							(end -0.2794 -0.1778)
						)
						(arc
							(start -0.2794 0.1778)
							(mid -0.249642 0.249642)
							(end -0.1778 0.2794)
						)
						(arc
							(start 0.1778 0.2794)
							(mid 0.249642 0.249642)
							(end 0.2794 0.1778)
						)
						(arc
							(start 0.2794 -0.1778)
							(mid 0.249642 -0.249642)
							(end 0.1778 -0.2794)
						)
					)
					(width 0)
					(fill yes)
				)
			)
		)
		(pad "2" smd custom
			(at 0 0.4445)
			(size 0.1397 0.1397)
			(layers "F.Cu" "F.Mask" "F.Paste")
			(net "ADC_12V")
			(options
				(clearance outline)
				(anchor circle)
			)
			(primitives
				(gr_poly
					(pts
						(arc
							(start -0.1778 -0.2794)
							(mid -0.249642 -0.249642)
							(end -0.2794 -0.1778)
						)
						(arc
							(start -0.2794 0.1778)
							(mid -0.249642 0.249642)
							(end -0.1778 0.2794)
						)
						(arc
							(start 0.1778 0.2794)
							(mid 0.249642 0.249642)
							(end 0.2794 0.1778)
						)
						(arc
							(start 0.2794 -0.1778)
							(mid 0.249642 -0.249642)
							(end 0.1778 -0.2794)
						)
					)
					(width 0)
					(fill yes)
				)
			)
		)
	)
	(footprint ""
		(layer "F.Cu")
		(at 129.466086 -51.351688 -90)
		(property "Reference" "R946"
			(at 0 0 270)
			(layer "F.SilkS")
			(hide yes)
			(effects
				(font
					(size 1.27 1.27)
				)
			)
		)
		(property "Value" "0R2J-2-GP"
			(at 0.064008 -3.993896 270)
			(unlocked yes)
			(layer "F.Fab")
			(hide yes)
			(effects
				(font
					(size 1.016 1.016)
					(thickness 0.1524)
				)
			)
		)
		(property "Device Type" "R402H16"
			(at 0.064008 -5.517896 270)
			(unlocked yes)
			(layer "F.Fab")
			(hide yes)
			(effects
				(font
					(size 1.016 1.016)
					(thickness 0.1524)
				)
			)
		)
		(duplicate_pad_numbers_are_jumpers no)
		(fp_line
			(start -0.508 -0.9398)
			(end -0.508 0.9398)
			(stroke
				(width 0.1524)
				(type default)
			)
			(layer "F.SilkS")
		)
		(fp_line
			(start 0.508 -0.9398)
			(end -0.508 -0.9398)
			(stroke
				(width 0.1524)
				(type default)
			)
			(layer "F.SilkS")
		)
		(fp_rect
			(start -0.508 0.9398)
			(end 0.508 -0.9398)
			(stroke
				(width 0)
				(type default)
			)
			(fill no)
			(layer "F.CrtYd")
		)
		(fp_rect
			(start -0.508 0.9398)
			(end 0.508 -0.9398)
			(stroke
				(width 0)
				(type default)
			)
			(fill no)
			(layer "F.Fab")
		)
		(pad "1" smd custom
			(at 0 -0.4445 270)
			(size 0.1397 0.1397)
			(layers "F.Cu" "F.Mask" "F.Paste")
			(net "PMC_R_RXD5")
			(options
				(clearance outline)
				(anchor circle)
			)
			(primitives
				(gr_poly
					(pts
						(arc
							(start -0.1778 -0.2794)
							(mid -0.249642 -0.249642)
							(end -0.2794 -0.1778)
						)
						(arc
							(start -0.2794 0.1778)
							(mid -0.249642 0.249642)
							(end -0.1778 0.2794)
						)
						(arc
							(start 0.1778 0.2794)
							(mid 0.249642 0.249642)
							(end 0.2794 0.1778)
						)
						(arc
							(start 0.2794 -0.1778)
							(mid 0.249642 -0.249642)
							(end 0.1778 -0.2794)
						)
					)
					(width 0)
					(fill yes)
				)
			)
		)
		(pad "2" smd custom
			(at 0 0.4445 270)
			(size 0.1397 0.1397)
			(layers "F.Cu" "F.Mask" "F.Paste")
			(net "EXP_SMART_RX")
			(options
				(clearance outline)
				(anchor circle)
			)
			(primitives
				(gr_poly
					(pts
						(arc
							(start -0.1778 -0.2794)
							(mid -0.249642 -0.249642)
							(end -0.2794 -0.1778)
						)
						(arc
							(start -0.2794 0.1778)
							(mid -0.249642 0.249642)
							(end -0.1778 0.2794)
						)
						(arc
							(start 0.1778 0.2794)
							(mid 0.249642 0.249642)
							(end 0.2794 0.1778)
						)
						(arc
							(start 0.2794 -0.1778)
							(mid 0.249642 -0.249642)
							(end 0.1778 -0.2794)
						)
					)
					(width 0)
					(fill yes)
				)
			)
		)
	)
	(footprint ""
		(layer "F.Cu")
		(at 238.252 -6.35)
		(property "Reference" "R173"
			(at 0 0 0)
			(layer "F.SilkS")
			(hide yes)
			(effects
				(font
					(size 1.27 1.27)
				)
			)
		)
		(property "Value" "4K7R2F-GP"
			(at 0.064008 -3.993896 0)
			(unlocked yes)
			(layer "F.Fab")
			(hide yes)
			(effects
				(font
					(size 1.016 1.016)
					(thickness 0.1524)
				)
			)
		)
		(property "Device Type" "R402H16"
			(at 0.064008 -5.517896 0)
			(unlocked yes)
			(layer "F.Fab")
			(hide yes)
			(effects
				(font
					(size 1.016 1.016)
					(thickness 0.1524)
				)
			)
		)
		(duplicate_pad_numbers_are_jumpers no)
		(fp_line
			(start -0.508 -0.9398)
			(end -0.508 0.9398)
			(stroke
				(width 0.1524)
				(type default)
			)
			(layer "F.SilkS")
		)
		(fp_line
			(start 0.508 -0.9398)
			(end -0.508 -0.9398)
			(stroke
				(width 0.1524)
				(type default)
			)
			(layer "F.SilkS")
		)
		(fp_rect
			(start -0.508 0.9398)
			(end 0.508 -0.9398)
			(stroke
				(width 0)
				(type default)
			)
			(fill no)
			(layer "F.CrtYd")
		)
		(fp_rect
			(start -0.508 0.9398)
			(end 0.508 -0.9398)
			(stroke
				(width 0)
				(type default)
			)
			(fill no)
			(layer "F.Fab")
		)
		(pad "1" smd custom
			(at 0 -0.4445)
			(size 0.1397 0.1397)
			(layers "F.Cu" "F.Mask" "F.Paste")
			(net "P3V3_STBY")
			(options
				(clearance outline)
				(anchor circle)
			)
			(primitives
				(gr_poly
					(pts
						(arc
							(start -0.1778 -0.2794)
							(mid -0.249642 -0.249642)
							(end -0.2794 -0.1778)
						)
						(arc
							(start -0.2794 0.1778)
							(mid -0.249642 0.249642)
							(end -0.1778 0.2794)
						)
						(arc
							(start 0.1778 0.2794)
							(mid 0.249642 0.249642)
							(end 0.2794 0.1778)
						)
						(arc
							(start 0.2794 -0.1778)
							(mid 0.249642 -0.249642)
							(end 0.1778 -0.2794)
						)
					)
					(width 0)
					(fill yes)
				)
			)
		)
		(pad "2" smd custom
			(at 0 0.4445)
			(size 0.1397 0.1397)
			(layers "F.Cu" "F.Mask" "F.Paste")
			(net "UART_COUNT")
			(options
				(clearance outline)
				(anchor circle)
			)
			(primitives
				(gr_poly
					(pts
						(arc
							(start -0.1778 -0.2794)
							(mid -0.249642 -0.249642)
							(end -0.2794 -0.1778)
						)
						(arc
							(start -0.2794 0.1778)
							(mid -0.249642 0.249642)
							(end -0.1778 0.2794)
						)
						(arc
							(start 0.1778 0.2794)
							(mid 0.249642 0.249642)
							(end 0.2794 0.1778)
						)
						(arc
							(start 0.2794 -0.1778)
							(mid 0.249642 -0.249642)
							(end 0.1778 -0.2794)
						)
					)
					(width 0)
					(fill yes)
				)
			)
		)
	)
	(footprint ""
		(layer "F.Cu")
		(at 81.448148 -75.00366)
		(property "Reference" "R968"
			(at 0 0 0)
			(layer "F.SilkS")
			(hide yes)
			(effects
				(font
					(size 1.27 1.27)
				)
			)
		)
		(property "Value" "4K7R2F-GP"
			(at 0.064008 -3.993896 0)
			(unlocked yes)
			(layer "F.Fab")
			(hide yes)
			(effects
				(font
					(size 1.016 1.016)
					(thickness 0.1524)
				)
			)
		)
		(property "Device Type" "R402H16"
			(at 0.064008 -5.517896 0)
			(unlocked yes)
			(layer "F.Fab")
			(hide yes)
			(effects
				(font
					(size 1.016 1.016)
					(thickness 0.1524)
				)
			)
		)
		(duplicate_pad_numbers_are_jumpers no)
		(fp_line
			(start -0.508 -0.9398)
			(end -0.508 0.9398)
			(stroke
				(width 0.1524)
				(type default)
			)
			(layer "F.SilkS")
		)
		(fp_line
			(start 0.508 -0.9398)
			(end -0.508 -0.9398)
			(stroke
				(width 0.1524)
				(type default)
			)
			(layer "F.SilkS")
		)
		(fp_rect
			(start -0.508 0.9398)
			(end 0.508 -0.9398)
			(stroke
				(width 0)
				(type default)
			)
			(fill no)
			(layer "F.CrtYd")
		)
		(fp_rect
			(start -0.508 0.9398)
			(end 0.508 -0.9398)
			(stroke
				(width 0)
				(type default)
			)
			(fill no)
			(layer "F.Fab")
		)
		(pad "1" smd custom
			(at 0 -0.4445)
			(size 0.1397 0.1397)
			(layers "F.Cu" "F.Mask" "F.Paste")
			(net "P3V3_STBY")
			(options
				(clearance outline)
				(anchor circle)
			)
			(primitives
				(gr_poly
					(pts
						(arc
							(start -0.1778 -0.2794)
							(mid -0.249642 -0.249642)
							(end -0.2794 -0.1778)
						)
						(arc
							(start -0.2794 0.1778)
							(mid -0.249642 0.249642)
							(end -0.1778 0.2794)
						)
						(arc
							(start 0.1778 0.2794)
							(mid 0.249642 0.249642)
							(end 0.2794 0.1778)
						)
						(arc
							(start 0.2794 -0.1778)
							(mid 0.249642 -0.249642)
							(end 0.1778 -0.2794)
						)
					)
					(width 0)
					(fill yes)
				)
			)
		)
		(pad "2" smd custom
			(at 0 0.4445)
			(size 0.1397 0.1397)
			(layers "F.Cu" "F.Mask" "F.Paste")
			(net "SEC_RST_N_R")
			(options
				(clearance outline)
				(anchor circle)
			)
			(primitives
				(gr_poly
					(pts
						(arc
							(start -0.1778 -0.2794)
							(mid -0.249642 -0.249642)
							(end -0.2794 -0.1778)
						)
						(arc
							(start -0.2794 0.1778)
							(mid -0.249642 0.249642)
							(end -0.1778 0.2794)
						)
						(arc
							(start 0.1778 0.2794)
							(mid 0.249642 0.249642)
							(end 0.2794 0.1778)
						)
						(arc
							(start 0.2794 -0.1778)
							(mid 0.249642 -0.249642)
							(end 0.1778 -0.2794)
						)
					)
					(width 0)
					(fill yes)
				)
			)
		)
	)
	(footprint ""
		(layer "F.Cu")
		(at 14.605 -122.682 -90)
		(property "Reference" "R295"
			(at 0 0 270)
			(layer "F.SilkS")
			(hide yes)
			(effects
				(font
					(size 1.27 1.27)
				)
			)
		)
		(property "Value" "4K7R2F-GP"
			(at 0.064008 -3.993896 270)
			(unlocked yes)
			(layer "F.Fab")
			(hide yes)
			(effects
				(font
					(size 1.016 1.016)
					(thickness 0.1524)
				)
			)
		)
		(property "Device Type" "R402H16"
			(at 0.064008 -5.517896 270)
			(unlocked yes)
			(layer "F.Fab")
			(hide yes)
			(effects
				(font
					(size 1.016 1.016)
					(thickness 0.1524)
				)
			)
		)
		(duplicate_pad_numbers_are_jumpers no)
		(fp_line
			(start -0.508 -0.9398)
			(end -0.508 0.9398)
			(stroke
				(width 0.1524)
				(type default)
			)
			(layer "F.SilkS")
		)
		(fp_line
			(start 0.508 -0.9398)
			(end -0.508 -0.9398)
			(stroke
				(width 0.1524)
				(type default)
			)
			(layer "F.SilkS")
		)
		(fp_rect
			(start -0.508 0.9398)
			(end 0.508 -0.9398)
			(stroke
				(width 0)
				(type default)
			)
			(fill no)
			(layer "F.CrtYd")
		)
		(fp_rect
			(start -0.508 0.9398)
			(end 0.508 -0.9398)
			(stroke
				(width 0)
				(type default)
			)
			(fill no)
			(layer "F.Fab")
		)
		(pad "1" smd custom
			(at 0 -0.4445 270)
			(size 0.1397 0.1397)
			(layers "F.Cu" "F.Mask" "F.Paste")
			(net "P3V3_STBY")
			(options
				(clearance outline)
				(anchor circle)
			)
			(primitives
				(gr_poly
					(pts
						(arc
							(start -0.1778 -0.2794)
							(mid -0.249642 -0.249642)
							(end -0.2794 -0.1778)
						)
						(arc
							(start -0.2794 0.1778)
							(mid -0.249642 0.249642)
							(end -0.1778 0.2794)
						)
						(arc
							(start 0.1778 0.2794)
							(mid 0.249642 0.249642)
							(end 0.2794 0.1778)
						)
						(arc
							(start 0.2794 -0.1778)
							(mid 0.249642 -0.249642)
							(end 0.1778 -0.2794)
						)
					)
					(width 0)
					(fill yes)
				)
			)
		)
		(pad "2" smd custom
			(at 0 0.4445 270)
			(size 0.1397 0.1397)
			(layers "F.Cu" "F.Mask" "F.Paste")
			(net "I2C2_LS_G2")
			(options
				(clearance outline)
				(anchor circle)
			)
			(primitives
				(gr_poly
					(pts
						(arc
							(start -0.1778 -0.2794)
							(mid -0.249642 -0.249642)
							(end -0.2794 -0.1778)
						)
						(arc
							(start -0.2794 0.1778)
							(mid -0.249642 0.249642)
							(end -0.1778 0.2794)
						)
						(arc
							(start 0.1778 0.2794)
							(mid 0.249642 0.249642)
							(end 0.2794 0.1778)
						)
						(arc
							(start 0.2794 -0.1778)
							(mid 0.249642 -0.249642)
							(end 0.1778 -0.2794)
						)
					)
					(width 0)
					(fill yes)
				)
			)
		)
	)
	(footprint ""
		(layer "F.Cu")
		(at 128.509268 -33.158938 90)
		(property "Reference" "R633"
			(at 0 0 90)
			(layer "F.SilkS")
			(hide yes)
			(effects
				(font
					(size 1.27 1.27)
				)
			)
		)
		(property "Value" "0R2J-2-GP"
			(at 0.064008 -3.993896 90)
			(unlocked yes)
			(layer "F.Fab")
			(hide yes)
			(effects
				(font
					(size 1.016 1.016)
					(thickness 0.1524)
				)
			)
		)
		(property "Device Type" "R402H16"
			(at 0.064008 -5.517896 90)
			(unlocked yes)
			(layer "F.Fab")
			(hide yes)
			(effects
				(font
					(size 1.016 1.016)
					(thickness 0.1524)
				)
			)
		)
		(duplicate_pad_numbers_are_jumpers no)
		(fp_line
			(start 0.508 -0.9398)
			(end -0.508 -0.9398)
			(stroke
				(width 0.1524)
				(type default)
			)
			(layer "F.SilkS")
		)
		(fp_line
			(start -0.508 -0.9398)
			(end -0.508 0.9398)
			(stroke
				(width 0.1524)
				(type default)
			)
			(layer "F.SilkS")
		)
		(fp_rect
			(start -0.508 0.9398)
			(end 0.508 -0.9398)
			(stroke
				(width 0)
				(type default)
			)
			(fill no)
			(layer "F.CrtYd")
		)
		(fp_rect
			(start -0.508 0.9398)
			(end 0.508 -0.9398)
			(stroke
				(width 0)
				(type default)
			)
			(fill no)
			(layer "F.Fab")
		)
		(pad "1" smd custom
			(at 0 -0.4445 90)
			(size 0.1397 0.1397)
			(layers "F.Cu" "F.Mask" "F.Paste")
			(net "8644_USB_DP1")
			(options
				(clearance outline)
				(anchor circle)
			)
			(primitives
				(gr_poly
					(pts
						(arc
							(start -0.1778 -0.2794)
							(mid -0.249642 -0.249642)
							(end -0.2794 -0.1778)
						)
						(arc
							(start -0.2794 0.1778)
							(mid -0.249642 0.249642)
							(end -0.1778 0.2794)
						)
						(arc
							(start 0.1778 0.2794)
							(mid 0.249642 0.249642)
							(end 0.2794 0.1778)
						)
						(arc
							(start 0.2794 -0.1778)
							(mid 0.249642 -0.249642)
							(end 0.1778 -0.2794)
						)
					)
					(width 0)
					(fill yes)
				)
			)
		)
		(pad "2" smd custom
			(at 0 0.4445 90)
			(size 0.1397 0.1397)
			(layers "F.Cu" "F.Mask" "F.Paste")
			(net "P3V3_STBY")
			(options
				(clearance outline)
				(anchor circle)
			)
			(primitives
				(gr_poly
					(pts
						(arc
							(start -0.1778 -0.2794)
							(mid -0.249642 -0.249642)
							(end -0.2794 -0.1778)
						)
						(arc
							(start -0.2794 0.1778)
							(mid -0.249642 0.249642)
							(end -0.1778 0.2794)
						)
						(arc
							(start 0.1778 0.2794)
							(mid 0.249642 0.249642)
							(end 0.2794 0.1778)
						)
						(arc
							(start 0.2794 -0.1778)
							(mid 0.249642 -0.249642)
							(end 0.1778 -0.2794)
						)
					)
					(width 0)
					(fill yes)
				)
			)
		)
	)
	(footprint ""
		(layer "F.Cu")
		(at 148.098002 -58.066432 90)
		(property "Reference" "PR170"
			(at 0 0 90)
			(layer "F.SilkS")
			(hide yes)
			(effects
				(font
					(size 1.27 1.27)
				)
			)
		)
		(property "Value" "475KR2F-GP"
			(at 0.064008 -3.993896 90)
			(unlocked yes)
			(layer "F.Fab")
			(hide yes)
			(effects
				(font
					(size 1.016 1.016)
					(thickness 0.1524)
				)
			)
		)
		(property "Device Type" "R402H16"
			(at 0.064008 -5.517896 90)
			(unlocked yes)
			(layer "F.Fab")
			(hide yes)
			(effects
				(font
					(size 1.016 1.016)
					(thickness 0.1524)
				)
			)
		)
		(duplicate_pad_numbers_are_jumpers no)
		(fp_line
			(start 0.508 -0.9398)
			(end -0.508 -0.9398)
			(stroke
				(width 0.1524)
				(type default)
			)
			(layer "F.SilkS")
		)
		(fp_line
			(start -0.508 -0.9398)
			(end -0.508 0.9398)
			(stroke
				(width 0.1524)
				(type default)
			)
			(layer "F.SilkS")
		)
		(fp_rect
			(start -0.508 0.9398)
			(end 0.508 -0.9398)
			(stroke
				(width 0)
				(type default)
			)
			(fill no)
			(layer "F.CrtYd")
		)
		(fp_rect
			(start -0.508 0.9398)
			(end 0.508 -0.9398)
			(stroke
				(width 0)
				(type default)
			)
			(fill no)
			(layer "F.Fab")
		)
		(pad "1" smd custom
			(at 0 -0.4445 90)
			(size 0.1397 0.1397)
			(layers "F.Cu" "F.Mask" "F.Paste")
			(net "P0V9_PG")
			(options
				(clearance outline)
				(anchor circle)
			)
			(primitives
				(gr_poly
					(pts
						(arc
							(start -0.1778 -0.2794)
							(mid -0.249642 -0.249642)
							(end -0.2794 -0.1778)
						)
						(arc
							(start -0.2794 0.1778)
							(mid -0.249642 0.249642)
							(end -0.1778 0.2794)
						)
						(arc
							(start 0.1778 0.2794)
							(mid 0.249642 0.249642)
							(end 0.2794 0.1778)
						)
						(arc
							(start 0.2794 -0.1778)
							(mid 0.249642 -0.249642)
							(end 0.1778 -0.2794)
						)
					)
					(width 0)
					(fill yes)
				)
			)
		)
		(pad "2" smd custom
			(at 0 0.4445 90)
			(size 0.1397 0.1397)
			(layers "F.Cu" "F.Mask" "F.Paste")
			(net "P0V9_MODE")
			(options
				(clearance outline)
				(anchor circle)
			)
			(primitives
				(gr_poly
					(pts
						(arc
							(start -0.1778 -0.2794)
							(mid -0.249642 -0.249642)
							(end -0.2794 -0.1778)
						)
						(arc
							(start -0.2794 0.1778)
							(mid -0.249642 0.249642)
							(end -0.1778 0.2794)
						)
						(arc
							(start 0.1778 0.2794)
							(mid 0.249642 0.249642)
							(end 0.2794 0.1778)
						)
						(arc
							(start 0.2794 -0.1778)
							(mid 0.249642 -0.249642)
							(end 0.1778 -0.2794)
						)
					)
					(width 0)
					(fill yes)
				)
			)
		)
	)
	(footprint ""
		(layer "F.Cu")
		(at 31.369 -46.99 -90)
		(property "Reference" "C338"
			(at 0 0 270)
			(layer "F.SilkS")
			(hide yes)
			(effects
				(font
					(size 1.27 1.27)
				)
			)
		)
		(property "Value" "SC1U10V2KX-4-GP"
			(at 1.1811 -2.7051 270)
			(unlocked yes)
			(layer "F.Fab")
			(hide yes)
			(effects
				(font
					(size 1.016 1.016)
					(thickness 0.1524)
				)
			)
		)
		(property "Device Type" "C402H22"
			(at 1.1811 -4.2291 270)
			(unlocked yes)
			(layer "F.Fab")
			(hide yes)
			(effects
				(font
					(size 1.016 1.016)
					(thickness 0.1524)
				)
			)
		)
		(duplicate_pad_numbers_are_jumpers no)
		(fp_rect
			(start -0.4318 0.9525)
			(end 0.4318 -0.9525)
			(stroke
				(width 0)
				(type default)
			)
			(fill no)
			(layer "F.CrtYd")
		)
		(fp_rect
			(start -0.4318 0.9525)
			(end 0.4318 -0.9525)
			(stroke
				(width 0)
				(type default)
			)
			(fill no)
			(layer "F.Fab")
		)
		(pad "1" smd custom
			(at 0 -0.4445 270)
			(size 0.1524 0.1524)
			(layers "F.Cu" "F.Mask" "F.Paste")
			(net "P5V_USB")
			(options
				(clearance outline)
				(anchor circle)
			)
			(primitives
				(gr_poly
					(pts
						(arc
							(start 0.3048 -0.2032)
							(mid 0.275042 -0.275042)
							(end 0.2032 -0.3048)
						)
						(arc
							(start -0.2032 -0.3048)
							(mid -0.275042 -0.275042)
							(end -0.3048 -0.2032)
						)
						(arc
							(start -0.3048 0.2032)
							(mid -0.275042 0.275042)
							(end -0.2032 0.3048)
						)
						(arc
							(start 0.2032 0.3048)
							(mid 0.275042 0.275042)
							(end 0.3048 0.2032)
						)
					)
					(width 0)
					(fill yes)
				)
			)
		)
		(pad "2" smd custom
			(at 0 0.4445 270)
			(size 0.1524 0.1524)
			(layers "F.Cu" "F.Mask" "F.Paste")
			(net "GND")
			(options
				(clearance outline)
				(anchor circle)
			)
			(primitives
				(gr_poly
					(pts
						(arc
							(start 0.3048 -0.2032)
							(mid 0.275042 -0.275042)
							(end 0.2032 -0.3048)
						)
						(arc
							(start -0.2032 -0.3048)
							(mid -0.275042 -0.275042)
							(end -0.3048 -0.2032)
						)
						(arc
							(start -0.3048 0.2032)
							(mid -0.275042 0.275042)
							(end -0.2032 0.3048)
						)
						(arc
							(start 0.2032 0.3048)
							(mid 0.275042 0.275042)
							(end 0.3048 0.2032)
						)
					)
					(width 0)
					(fill yes)
				)
			)
		)
	)
	(footprint ""
		(layer "F.Cu")
		(at 41.7068 -190.2206 -90)
		(property "Reference" "C691"
			(at 0 0 270)
			(layer "F.SilkS")
			(hide yes)
			(effects
				(font
					(size 1.27 1.27)
				)
			)
		)
		(property "Value" "SC220P50V3JN-GP"
			(at 0 -2.8194 270)
			(unlocked yes)
			(layer "F.Fab")
			(hide yes)
			(effects
				(font
					(size 1.016 1.016)
					(thickness 0.1524)
				)
			)
		)
		(property "Device Type" "C603H36"
			(at 0 -4.3434 270)
			(unlocked yes)
			(layer "F.Fab")
			(hide yes)
			(effects
				(font
					(size 1.016 1.016)
					(thickness 0.1524)
				)
			)
		)
		(duplicate_pad_numbers_are_jumpers no)
		(fp_line
			(start 0.508 0)
			(end -0.508 0)
			(stroke
				(width 0.2032)
				(type default)
			)
			(layer "F.SilkS")
		)
		(fp_rect
			(start -0.5842 1.3335)
			(end 0.5842 -1.3335)
			(stroke
				(width 0)
				(type default)
			)
			(fill no)
			(layer "F.CrtYd")
		)
		(fp_rect
			(start -0.5842 1.3335)
			(end 0.5842 -1.3335)
			(stroke
				(width 0)
				(type default)
			)
			(fill no)
			(layer "F.Fab")
		)
		(pad "1" smd custom
			(at 0 -0.762 270)
			(size 0.2159 0.2159)
			(layers "F.Cu" "F.Mask" "F.Paste")
			(net "BUF_I2C9_CLKBUF2_SDA_R")
			(options
				(clearance outline)
				(anchor circle)
			)
			(primitives
				(gr_poly
					(pts
						(arc
							(start -0.3302 -0.4318)
							(mid -0.402042 -0.402042)
							(end -0.4318 -0.3302)
						)
						(arc
							(start -0.4318 0.3302)
							(mid -0.402042 0.402042)
							(end -0.3302 0.4318)
						)
						(arc
							(start 0.3302 0.4318)
							(mid 0.402042 0.402042)
							(end 0.4318 0.3302)
						)
						(arc
							(start 0.4318 -0.3302)
							(mid 0.402042 -0.402042)
							(end 0.3302 -0.4318)
						)
					)
					(width 0)
					(fill yes)
				)
			)
		)
		(pad "2" smd custom
			(at 0 0.762 270)
			(size 0.2159 0.2159)
			(layers "F.Cu" "F.Mask" "F.Paste")
			(net "GND")
			(options
				(clearance outline)
				(anchor circle)
			)
			(primitives
				(gr_poly
					(pts
						(arc
							(start -0.3302 -0.4318)
							(mid -0.402042 -0.402042)
							(end -0.4318 -0.3302)
						)
						(arc
							(start -0.4318 0.3302)
							(mid -0.402042 0.402042)
							(end -0.3302 0.4318)
						)
						(arc
							(start 0.3302 0.4318)
							(mid 0.402042 0.402042)
							(end 0.4318 0.3302)
						)
						(arc
							(start 0.4318 -0.3302)
							(mid 0.402042 -0.402042)
							(end 0.3302 -0.4318)
						)
					)
					(width 0)
					(fill yes)
				)
			)
		)
	)
	(footprint ""
		(layer "F.Cu")
		(at 289.992054 -212.420454 180)
		(property "Reference" "C80"
			(at 0 0 180)
			(layer "F.SilkS")
			(hide yes)
			(effects
				(font
					(size 1.27 1.27)
				)
			)
		)
		(property "Value" "SCD22U10V2KX-1GP"
			(at 1.1811 -2.7051 180)
			(unlocked yes)
			(layer "F.Fab")
			(hide yes)
			(effects
				(font
					(size 1.016 1.016)
					(thickness 0.1524)
				)
			)
		)
		(property "Device Type" "C402H22"
			(at 1.1811 -4.2291 180)
			(unlocked yes)
			(layer "F.Fab")
			(hide yes)
			(effects
				(font
					(size 1.016 1.016)
					(thickness 0.1524)
				)
			)
		)
		(duplicate_pad_numbers_are_jumpers no)
		(fp_rect
			(start -0.4318 0.9525)
			(end 0.4318 -0.9525)
			(stroke
				(width 0)
				(type default)
			)
			(fill no)
			(layer "F.CrtYd")
		)
		(fp_rect
			(start -0.4318 0.9525)
			(end 0.4318 -0.9525)
			(stroke
				(width 0)
				(type default)
			)
			(fill no)
			(layer "F.Fab")
		)
		(pad "1" smd custom
			(at 0 -0.4445 180)
			(size 0.1524 0.1524)
			(layers "F.Cu" "F.Mask" "F.Paste")
			(net "PCIE_TX_CAP_P29")
			(options
				(clearance outline)
				(anchor circle)
			)
			(primitives
				(gr_poly
					(pts
						(arc
							(start 0.3048 -0.2032)
							(mid 0.275042 -0.275042)
							(end 0.2032 -0.3048)
						)
						(arc
							(start -0.2032 -0.3048)
							(mid -0.275042 -0.275042)
							(end -0.3048 -0.2032)
						)
						(arc
							(start -0.3048 0.2032)
							(mid -0.275042 0.275042)
							(end -0.2032 0.3048)
						)
						(arc
							(start 0.2032 0.3048)
							(mid 0.275042 0.275042)
							(end 0.3048 0.2032)
						)
					)
					(width 0)
					(fill yes)
				)
			)
		)
		(pad "2" smd custom
			(at 0 0.4445 180)
			(size 0.1524 0.1524)
			(layers "F.Cu" "F.Mask" "F.Paste")
			(net "PCIE_TX_P29")
			(options
				(clearance outline)
				(anchor circle)
			)
			(primitives
				(gr_poly
					(pts
						(arc
							(start 0.3048 -0.2032)
							(mid 0.275042 -0.275042)
							(end 0.2032 -0.3048)
						)
						(arc
							(start -0.2032 -0.3048)
							(mid -0.275042 -0.275042)
							(end -0.3048 -0.2032)
						)
						(arc
							(start -0.3048 0.2032)
							(mid -0.275042 0.275042)
							(end -0.2032 0.3048)
						)
						(arc
							(start 0.2032 0.3048)
							(mid 0.275042 0.275042)
							(end 0.3048 0.2032)
						)
					)
					(width 0)
					(fill yes)
				)
			)
		)
	)
	(footprint ""
		(layer "F.Cu")
		(at 64.607948 -212.420454 180)
		(property "Reference" "C358"
			(at 0 0 180)
			(layer "F.SilkS")
			(hide yes)
			(effects
				(font
					(size 1.27 1.27)
				)
			)
		)
		(property "Value" "SCD22U10V2KX-1GP"
			(at 1.1811 -2.7051 180)
			(unlocked yes)
			(layer "F.Fab")
			(hide yes)
			(effects
				(font
					(size 1.016 1.016)
					(thickness 0.1524)
				)
			)
		)
		(property "Device Type" "C402H22"
			(at 1.1811 -4.2291 180)
			(unlocked yes)
			(layer "F.Fab")
			(hide yes)
			(effects
				(font
					(size 1.016 1.016)
					(thickness 0.1524)
				)
			)
		)
		(duplicate_pad_numbers_are_jumpers no)
		(fp_rect
			(start -0.4318 0.9525)
			(end 0.4318 -0.9525)
			(stroke
				(width 0)
				(type default)
			)
			(fill no)
			(layer "F.CrtYd")
		)
		(fp_rect
			(start -0.4318 0.9525)
			(end 0.4318 -0.9525)
			(stroke
				(width 0)
				(type default)
			)
			(fill no)
			(layer "F.Fab")
		)
		(pad "1" smd custom
			(at 0 -0.4445 180)
			(size 0.1524 0.1524)
			(layers "F.Cu" "F.Mask" "F.Paste")
			(net "PCIE_TX_CAP_N71")
			(options
				(clearance outline)
				(anchor circle)
			)
			(primitives
				(gr_poly
					(pts
						(arc
							(start 0.3048 -0.2032)
							(mid 0.275042 -0.275042)
							(end 0.2032 -0.3048)
						)
						(arc
							(start -0.2032 -0.3048)
							(mid -0.275042 -0.275042)
							(end -0.3048 -0.2032)
						)
						(arc
							(start -0.3048 0.2032)
							(mid -0.275042 0.275042)
							(end -0.2032 0.3048)
						)
						(arc
							(start 0.2032 0.3048)
							(mid 0.275042 0.275042)
							(end 0.3048 0.2032)
						)
					)
					(width 0)
					(fill yes)
				)
			)
		)
		(pad "2" smd custom
			(at 0 0.4445 180)
			(size 0.1524 0.1524)
			(layers "F.Cu" "F.Mask" "F.Paste")
			(net "PCIE_TX_N71")
			(options
				(clearance outline)
				(anchor circle)
			)
			(primitives
				(gr_poly
					(pts
						(arc
							(start 0.3048 -0.2032)
							(mid 0.275042 -0.275042)
							(end 0.2032 -0.3048)
						)
						(arc
							(start -0.2032 -0.3048)
							(mid -0.275042 -0.275042)
							(end -0.3048 -0.2032)
						)
						(arc
							(start -0.3048 0.2032)
							(mid -0.275042 0.275042)
							(end -0.2032 0.3048)
						)
						(arc
							(start 0.2032 0.3048)
							(mid 0.275042 0.275042)
							(end 0.3048 0.2032)
						)
					)
					(width 0)
					(fill yes)
				)
			)
		)
	)
	(footprint ""
		(layer "F.Cu")
		(at 184.0484 -61.595)
		(property "Reference" "C564"
			(at 0 0 0)
			(layer "F.SilkS")
			(hide yes)
			(effects
				(font
					(size 1.27 1.27)
				)
			)
		)
		(property "Value" "SC4D7U16V5KX-1-GP"
			(at -0.0762 -6.1214 0)
			(unlocked yes)
			(layer "F.Fab")
			(hide yes)
			(effects
				(font
					(size 1.016 1.016)
					(thickness 0.1524)
				)
			)
		)
		(property "Device Type" "C805H56"
			(at -0.0762 -8.1534 0)
			(unlocked yes)
			(layer "F.Fab")
			(hide yes)
			(effects
				(font
					(size 1.016 1.016)
					(thickness 0.1524)
				)
			)
		)
		(duplicate_pad_numbers_are_jumpers no)
		(fp_line
			(start 0.635 0)
			(end -0.635 0)
			(stroke
				(width 0.508)
				(type default)
			)
			(layer "F.SilkS")
		)
		(fp_rect
			(start -0.9652 1.778)
			(end 0.9652 -1.778)
			(stroke
				(width 0)
				(type default)
			)
			(fill no)
			(layer "F.CrtYd")
		)
		(fp_poly
			(pts
				(xy -0.9652 -1.778) (xy 0.9652 -1.778) (xy 0.9652 1.778) (xy -0.9652 1.778)
			)
			(stroke
				(width 0)
				(type default)
			)
			(fill no)
			(layer "F.Fab")
		)
		(pad "1" smd rect
			(at 0 -0.9652)
			(size 1.397 1.143)
			(layers "F.Cu" "F.Mask" "F.Paste")
			(net "DUT_AVD_PCIE")
		)
		(pad "2" smd rect
			(at 0 0.9652)
			(size 1.397 1.143)
			(layers "F.Cu" "F.Mask" "F.Paste")
			(net "GND")
		)
	)
	(footprint ""
		(layer "F.Cu")
		(at 65.405 -133.985 180)
		(property "Reference" "R3029"
			(at 0 0 180)
			(layer "F.SilkS")
			(hide yes)
			(effects
				(font
					(size 1.27 1.27)
				)
			)
		)
		(property "Value" "1KR2F-3-GP"
			(at 0.064008 -3.993896 180)
			(unlocked yes)
			(layer "F.Fab")
			(hide yes)
			(effects
				(font
					(size 1.016 1.016)
					(thickness 0.1524)
				)
			)
		)
		(property "Device Type" "R402H16"
			(at 0.064008 -5.517896 180)
			(unlocked yes)
			(layer "F.Fab")
			(hide yes)
			(effects
				(font
					(size 1.016 1.016)
					(thickness 0.1524)
				)
			)
		)
		(duplicate_pad_numbers_are_jumpers no)
		(fp_line
			(start 0.508 -0.9398)
			(end -0.508 -0.9398)
			(stroke
				(width 0.1524)
				(type default)
			)
			(layer "F.SilkS")
		)
		(fp_line
			(start -0.508 -0.9398)
			(end -0.508 0.9398)
			(stroke
				(width 0.1524)
				(type default)
			)
			(layer "F.SilkS")
		)
		(fp_rect
			(start -0.508 0.9398)
			(end 0.508 -0.9398)
			(stroke
				(width 0)
				(type default)
			)
			(fill no)
			(layer "F.CrtYd")
		)
		(fp_rect
			(start -0.508 0.9398)
			(end 0.508 -0.9398)
			(stroke
				(width 0)
				(type default)
			)
			(fill no)
			(layer "F.Fab")
		)
		(pad "1" smd custom
			(at 0 -0.4445 180)
			(size 0.1397 0.1397)
			(layers "F.Cu" "F.Mask" "F.Paste")
			(net "P0V9")
			(options
				(clearance outline)
				(anchor circle)
			)
			(primitives
				(gr_poly
					(pts
						(arc
							(start -0.1778 -0.2794)
							(mid -0.249642 -0.249642)
							(end -0.2794 -0.1778)
						)
						(arc
							(start -0.2794 0.1778)
							(mid -0.249642 0.249642)
							(end -0.1778 0.2794)
						)
						(arc
							(start 0.1778 0.2794)
							(mid 0.249642 0.249642)
							(end 0.2794 0.1778)
						)
						(arc
							(start 0.2794 -0.1778)
							(mid 0.249642 -0.249642)
							(end 0.1778 -0.2794)
						)
					)
					(width 0)
					(fill yes)
				)
			)
		)
		(pad "2" smd custom
			(at 0 0.4445 180)
			(size 0.1397 0.1397)
			(layers "F.Cu" "F.Mask" "F.Paste")
			(net "ADC_P0V9")
			(options
				(clearance outline)
				(anchor circle)
			)
			(primitives
				(gr_poly
					(pts
						(arc
							(start -0.1778 -0.2794)
							(mid -0.249642 -0.249642)
							(end -0.2794 -0.1778)
						)
						(arc
							(start -0.2794 0.1778)
							(mid -0.249642 0.249642)
							(end -0.1778 0.2794)
						)
						(arc
							(start 0.1778 0.2794)
							(mid 0.249642 0.249642)
							(end 0.2794 0.1778)
						)
						(arc
							(start 0.2794 -0.1778)
							(mid 0.249642 -0.249642)
							(end 0.1778 -0.2794)
						)
					)
					(width 0)
					(fill yes)
				)
			)
		)
	)
	(footprint ""
		(layer "F.Cu")
		(at 54.102 -120.269 90)
		(property "Reference" "C188"
			(at 0 0 90)
			(layer "F.SilkS")
			(hide yes)
			(effects
				(font
					(size 1.27 1.27)
				)
			)
		)
		(property "Value" "SC1U10V3KX-4GP-U"
			(at 0 -2.8194 90)
			(unlocked yes)
			(layer "F.Fab")
			(hide yes)
			(effects
				(font
					(size 1.016 1.016)
					(thickness 0.1524)
				)
			)
		)
		(property "Device Type" "C603H36"
			(at 0 -4.3434 90)
			(unlocked yes)
			(layer "F.Fab")
			(hide yes)
			(effects
				(font
					(size 1.016 1.016)
					(thickness 0.1524)
				)
			)
		)
		(duplicate_pad_numbers_are_jumpers no)
		(fp_line
			(start 0.508 0)
			(end -0.508 0)
			(stroke
				(width 0.2032)
				(type default)
			)
			(layer "F.SilkS")
		)
		(fp_rect
			(start -0.5842 1.3335)
			(end 0.5842 -1.3335)
			(stroke
				(width 0)
				(type default)
			)
			(fill no)
			(layer "F.CrtYd")
		)
		(fp_rect
			(start -0.5842 1.3335)
			(end 0.5842 -1.3335)
			(stroke
				(width 0)
				(type default)
			)
			(fill no)
			(layer "F.Fab")
		)
		(pad "1" smd custom
			(at 0 -0.762 90)
			(size 0.2159 0.2159)
			(layers "F.Cu" "F.Mask" "F.Paste")
			(net "JTAG_BMC_TRST_N")
			(options
				(clearance outline)
				(anchor circle)
			)
			(primitives
				(gr_poly
					(pts
						(arc
							(start -0.3302 -0.4318)
							(mid -0.402042 -0.402042)
							(end -0.4318 -0.3302)
						)
						(arc
							(start -0.4318 0.3302)
							(mid -0.402042 0.402042)
							(end -0.3302 0.4318)
						)
						(arc
							(start 0.3302 0.4318)
							(mid 0.402042 0.402042)
							(end 0.4318 0.3302)
						)
						(arc
							(start 0.4318 -0.3302)
							(mid 0.402042 -0.402042)
							(end 0.3302 -0.4318)
						)
					)
					(width 0)
					(fill yes)
				)
			)
		)
		(pad "2" smd custom
			(at 0 0.762 90)
			(size 0.2159 0.2159)
			(layers "F.Cu" "F.Mask" "F.Paste")
			(net "GND")
			(options
				(clearance outline)
				(anchor circle)
			)
			(primitives
				(gr_poly
					(pts
						(arc
							(start -0.3302 -0.4318)
							(mid -0.402042 -0.402042)
							(end -0.4318 -0.3302)
						)
						(arc
							(start -0.4318 0.3302)
							(mid -0.402042 0.402042)
							(end -0.3302 0.4318)
						)
						(arc
							(start 0.3302 0.4318)
							(mid 0.402042 0.402042)
							(end 0.4318 0.3302)
						)
						(arc
							(start 0.4318 -0.3302)
							(mid 0.402042 -0.402042)
							(end 0.3302 -0.4318)
						)
					)
					(width 0)
					(fill yes)
				)
			)
		)
	)
	(footprint ""
		(layer "F.Cu")
		(at 328.324718 -33.433258)
		(property "Reference" "C52"
			(at 0 0 0)
			(layer "F.SilkS")
			(hide yes)
			(effects
				(font
					(size 1.27 1.27)
				)
			)
		)
		(property "Value" "SCD22U10V2KX-1GP"
			(at 1.1811 -2.7051 0)
			(unlocked yes)
			(layer "F.Fab")
			(hide yes)
			(effects
				(font
					(size 1.016 1.016)
					(thickness 0.1524)
				)
			)
		)
		(property "Device Type" "C402H22"
			(at 1.1811 -4.2291 0)
			(unlocked yes)
			(layer "F.Fab")
			(hide yes)
			(effects
				(font
					(size 1.016 1.016)
					(thickness 0.1524)
				)
			)
		)
		(duplicate_pad_numbers_are_jumpers no)
		(fp_rect
			(start -0.4318 0.9525)
			(end 0.4318 -0.9525)
			(stroke
				(width 0)
				(type default)
			)
			(fill no)
			(layer "F.CrtYd")
		)
		(fp_rect
			(start -0.4318 0.9525)
			(end 0.4318 -0.9525)
			(stroke
				(width 0)
				(type default)
			)
			(fill no)
			(layer "F.Fab")
		)
		(pad "1" smd custom
			(at 0 -0.4445)
			(size 0.1524 0.1524)
			(layers "F.Cu" "F.Mask" "F.Paste")
			(net "PCIE_TX_CAP_P15")
			(options
				(clearance outline)
				(anchor circle)
			)
			(primitives
				(gr_poly
					(pts
						(arc
							(start 0.3048 -0.2032)
							(mid 0.275042 -0.275042)
							(end 0.2032 -0.3048)
						)
						(arc
							(start -0.2032 -0.3048)
							(mid -0.275042 -0.275042)
							(end -0.3048 -0.2032)
						)
						(arc
							(start -0.3048 0.2032)
							(mid -0.275042 0.275042)
							(end -0.2032 0.3048)
						)
						(arc
							(start 0.2032 0.3048)
							(mid 0.275042 0.275042)
							(end 0.3048 0.2032)
						)
					)
					(width 0)
					(fill yes)
				)
			)
		)
		(pad "2" smd custom
			(at 0 0.4445)
			(size 0.1524 0.1524)
			(layers "F.Cu" "F.Mask" "F.Paste")
			(net "PCIE_TX_P15")
			(options
				(clearance outline)
				(anchor circle)
			)
			(primitives
				(gr_poly
					(pts
						(arc
							(start 0.3048 -0.2032)
							(mid 0.275042 -0.275042)
							(end 0.2032 -0.3048)
						)
						(arc
							(start -0.2032 -0.3048)
							(mid -0.275042 -0.275042)
							(end -0.3048 -0.2032)
						)
						(arc
							(start -0.3048 0.2032)
							(mid -0.275042 0.275042)
							(end -0.2032 0.3048)
						)
						(arc
							(start 0.2032 0.3048)
							(mid 0.275042 0.275042)
							(end 0.3048 0.2032)
						)
					)
					(width 0)
					(fill yes)
				)
			)
		)
	)
	(footprint ""
		(layer "F.Cu")
		(at 117.309646 -53.591206 -90)
		(property "Reference" "R934"
			(at 0 0 270)
			(layer "F.SilkS")
			(hide yes)
			(effects
				(font
					(size 1.27 1.27)
				)
			)
		)
		(property "Value" "4K7R2F-GP"
			(at 0.064008 -3.993896 270)
			(unlocked yes)
			(layer "F.Fab")
			(hide yes)
			(effects
				(font
					(size 1.016 1.016)
					(thickness 0.1524)
				)
			)
		)
		(property "Device Type" "R402H16"
			(at 0.064008 -5.517896 270)
			(unlocked yes)
			(layer "F.Fab")
			(hide yes)
			(effects
				(font
					(size 1.016 1.016)
					(thickness 0.1524)
				)
			)
		)
		(duplicate_pad_numbers_are_jumpers no)
		(fp_line
			(start -0.508 -0.9398)
			(end -0.508 0.9398)
			(stroke
				(width 0.1524)
				(type default)
			)
			(layer "F.SilkS")
		)
		(fp_line
			(start 0.508 -0.9398)
			(end -0.508 -0.9398)
			(stroke
				(width 0.1524)
				(type default)
			)
			(layer "F.SilkS")
		)
		(fp_rect
			(start -0.508 0.9398)
			(end 0.508 -0.9398)
			(stroke
				(width 0)
				(type default)
			)
			(fill no)
			(layer "F.CrtYd")
		)
		(fp_rect
			(start -0.508 0.9398)
			(end 0.508 -0.9398)
			(stroke
				(width 0)
				(type default)
			)
			(fill no)
			(layer "F.Fab")
		)
		(pad "1" smd custom
			(at 0 -0.4445 270)
			(size 0.1397 0.1397)
			(layers "F.Cu" "F.Mask" "F.Paste")
			(net "BMC_ADD2_GND")
			(options
				(clearance outline)
				(anchor circle)
			)
			(primitives
				(gr_poly
					(pts
						(arc
							(start -0.1778 -0.2794)
							(mid -0.249642 -0.249642)
							(end -0.2794 -0.1778)
						)
						(arc
							(start -0.2794 0.1778)
							(mid -0.249642 0.249642)
							(end -0.1778 0.2794)
						)
						(arc
							(start 0.1778 0.2794)
							(mid 0.249642 0.249642)
							(end 0.2794 0.1778)
						)
						(arc
							(start 0.2794 -0.1778)
							(mid 0.249642 -0.249642)
							(end 0.1778 -0.2794)
						)
					)
					(width 0)
					(fill yes)
				)
			)
		)
		(pad "2" smd custom
			(at 0 0.4445 270)
			(size 0.1397 0.1397)
			(layers "F.Cu" "F.Mask" "F.Paste")
			(net "GND")
			(options
				(clearance outline)
				(anchor circle)
			)
			(primitives
				(gr_poly
					(pts
						(arc
							(start -0.1778 -0.2794)
							(mid -0.249642 -0.249642)
							(end -0.2794 -0.1778)
						)
						(arc
							(start -0.2794 0.1778)
							(mid -0.249642 0.249642)
							(end -0.1778 0.2794)
						)
						(arc
							(start 0.1778 0.2794)
							(mid 0.249642 0.249642)
							(end 0.2794 0.1778)
						)
						(arc
							(start 0.2794 -0.1778)
							(mid 0.249642 -0.249642)
							(end 0.1778 -0.2794)
						)
					)
					(width 0)
					(fill yes)
				)
			)
		)
	)
	(footprint ""
		(layer "F.Cu")
		(at 260.17982 -7.780528 180)
		(property "Reference" "PQ21"
			(at 0 0 180)
			(layer "F.SilkS")
			(hide yes)
			(effects
				(font
					(size 1.27 1.27)
				)
			)
		)
		(property "Value" "AO3400-GP-U"
			(at 0.0254 -12.3444 180)
			(unlocked yes)
			(layer "F.Fab")
			(hide yes)
			(effects
				(font
					(size 1.016 1.016)
					(thickness 0.1524)
				)
			)
		)
		(property "Device Type" "SOT23DGS2D8H50"
			(at 0.0254 -14.2494 180)
			(unlocked yes)
			(layer "F.Fab")
			(hide yes)
			(effects
				(font
					(size 1.016 1.016)
					(thickness 0.1524)
				)
			)
		)
		(duplicate_pad_numbers_are_jumpers no)
		(fp_line
			(start 1.7018 0.254)
			(end -1.7018 0.254)
			(stroke
				(width 0.1524)
				(type default)
			)
			(layer "F.SilkS")
		)
		(fp_line
			(start 1.7018 -0.254)
			(end 1.7018 0.254)
			(stroke
				(width 0.1524)
				(type default)
			)
			(layer "F.SilkS")
		)
		(fp_line
			(start -1.7018 0.254)
			(end -1.7018 -0.254)
			(stroke
				(width 0.1524)
				(type default)
			)
			(layer "F.SilkS")
		)
		(fp_line
			(start -1.7018 -0.254)
			(end 1.7018 -0.254)
			(stroke
				(width 0.1524)
				(type default)
			)
			(layer "F.SilkS")
		)
		(fp_rect
			(start -1.778 1.9812)
			(end 1.778 -1.9812)
			(stroke
				(width 0)
				(type default)
			)
			(fill no)
			(layer "F.CrtYd")
		)
		(fp_poly
			(pts
				(xy -1.778 -1.9812) (xy 1.778 -1.9812) (xy 1.778 1.9812) (xy -1.778 1.9812)
			)
			(stroke
				(width 0)
				(type default)
			)
			(fill no)
			(layer "F.Fab")
		)
		(pad "D" smd custom
			(at 0 -1.1176 180)
			(size 0.254 0.254)
			(layers "F.Cu" "F.Mask" "F.Paste")
			(net "PQ22_G")
			(options
				(clearance outline)
				(anchor circle)
			)
			(primitives
				(gr_poly
					(pts
						(arc
							(start -0.508 -0.4064)
							(mid -0.448484 -0.550084)
							(end -0.3048 -0.6096)
						)
						(arc
							(start 0.3048 -0.6096)
							(mid 0.448484 -0.550084)
							(end 0.508 -0.4064)
						)
						(arc
							(start 0.508 0.4064)
							(mid 0.448484 0.550084)
							(end 0.3048 0.6096)
						)
						(arc
							(start -0.3048 0.6096)
							(mid -0.448484 0.550084)
							(end -0.508 0.4064)
						)
					)
					(width 0)
					(fill yes)
				)
			)
		)
		(pad "G" smd custom
			(at -1.016 1.1176 180)
			(size 0.254 0.254)
			(layers "F.Cu" "F.Mask" "F.Paste")
			(net "PQ21_G")
			(options
				(clearance outline)
				(anchor circle)
			)
			(primitives
				(gr_poly
					(pts
						(arc
							(start -0.508 -0.4064)
							(mid -0.448484 -0.550084)
							(end -0.3048 -0.6096)
						)
						(arc
							(start 0.3048 -0.6096)
							(mid 0.448484 -0.550084)
							(end 0.508 -0.4064)
						)
						(arc
							(start 0.508 0.4064)
							(mid 0.448484 0.550084)
							(end 0.3048 0.6096)
						)
						(arc
							(start -0.3048 0.6096)
							(mid -0.448484 0.550084)
							(end -0.508 0.4064)
						)
					)
					(width 0)
					(fill yes)
				)
			)
		)
		(pad "S" smd custom
			(at 1.016 1.1176 180)
			(size 0.254 0.254)
			(layers "F.Cu" "F.Mask" "F.Paste")
			(net "GND")
			(options
				(clearance outline)
				(anchor circle)
			)
			(primitives
				(gr_poly
					(pts
						(arc
							(start -0.508 -0.4064)
							(mid -0.448484 -0.550084)
							(end -0.3048 -0.6096)
						)
						(arc
							(start 0.3048 -0.6096)
							(mid 0.448484 -0.550084)
							(end 0.508 -0.4064)
						)
						(arc
							(start 0.508 0.4064)
							(mid 0.448484 0.550084)
							(end 0.3048 0.6096)
						)
						(arc
							(start -0.3048 0.6096)
							(mid -0.448484 0.550084)
							(end -0.508 0.4064)
						)
					)
					(width 0)
					(fill yes)
				)
			)
		)
	)
	(footprint ""
		(layer "F.Cu")
		(at 60.2742 -161.8996 180)
		(property "Reference" "PR62"
			(at 0 0 180)
			(layer "F.SilkS")
			(hide yes)
			(effects
				(font
					(size 1.27 1.27)
				)
			)
		)
		(property "Value" "4K42R2F-GP"
			(at 0.064008 -3.993896 180)
			(unlocked yes)
			(layer "F.Fab")
			(hide yes)
			(effects
				(font
					(size 1.016 1.016)
					(thickness 0.1524)
				)
			)
		)
		(property "Device Type" "R402H16"
			(at 0.064008 -5.517896 180)
			(unlocked yes)
			(layer "F.Fab")
			(hide yes)
			(effects
				(font
					(size 1.016 1.016)
					(thickness 0.1524)
				)
			)
		)
		(duplicate_pad_numbers_are_jumpers no)
		(fp_line
			(start 0.508 -0.9398)
			(end -0.508 -0.9398)
			(stroke
				(width 0.1524)
				(type default)
			)
			(layer "F.SilkS")
		)
		(fp_line
			(start -0.508 -0.9398)
			(end -0.508 0.9398)
			(stroke
				(width 0.1524)
				(type default)
			)
			(layer "F.SilkS")
		)
		(fp_rect
			(start -0.508 0.9398)
			(end 0.508 -0.9398)
			(stroke
				(width 0)
				(type default)
			)
			(fill no)
			(layer "F.CrtYd")
		)
		(fp_rect
			(start -0.508 0.9398)
			(end 0.508 -0.9398)
			(stroke
				(width 0)
				(type default)
			)
			(fill no)
			(layer "F.Fab")
		)
		(pad "1" smd custom
			(at 0 -0.4445 180)
			(size 0.1397 0.1397)
			(layers "F.Cu" "F.Mask" "F.Paste")
			(net "P1V53_PWR")
			(options
				(clearance outline)
				(anchor circle)
			)
			(primitives
				(gr_poly
					(pts
						(arc
							(start -0.1778 -0.2794)
							(mid -0.249642 -0.249642)
							(end -0.2794 -0.1778)
						)
						(arc
							(start -0.2794 0.1778)
							(mid -0.249642 0.249642)
							(end -0.1778 0.2794)
						)
						(arc
							(start 0.1778 0.2794)
							(mid 0.249642 0.249642)
							(end 0.2794 0.1778)
						)
						(arc
							(start 0.2794 -0.1778)
							(mid 0.249642 -0.249642)
							(end 0.1778 -0.2794)
						)
					)
					(width 0)
					(fill yes)
				)
			)
		)
		(pad "2" smd custom
			(at 0 0.4445 180)
			(size 0.1397 0.1397)
			(layers "F.Cu" "F.Mask" "F.Paste")
			(net "VR_P1V538_STBY_FB")
			(options
				(clearance outline)
				(anchor circle)
			)
			(primitives
				(gr_poly
					(pts
						(arc
							(start -0.1778 -0.2794)
							(mid -0.249642 -0.249642)
							(end -0.2794 -0.1778)
						)
						(arc
							(start -0.2794 0.1778)
							(mid -0.249642 0.249642)
							(end -0.1778 0.2794)
						)
						(arc
							(start 0.1778 0.2794)
							(mid 0.249642 0.249642)
							(end 0.2794 0.1778)
						)
						(arc
							(start 0.2794 -0.1778)
							(mid 0.249642 -0.249642)
							(end 0.1778 -0.2794)
						)
					)
					(width 0)
					(fill yes)
				)
			)
		)
	)
	(footprint ""
		(layer "F.Cu")
		(at 336.836512 -172.432218)
		(property "Reference" "R7925"
			(at 0 0 0)
			(layer "F.SilkS")
			(hide yes)
			(effects
				(font
					(size 1.27 1.27)
				)
			)
		)
		(property "Value" "0R2J-2-GP"
			(at 0.064008 -3.993896 0)
			(unlocked yes)
			(layer "F.Fab")
			(hide yes)
			(effects
				(font
					(size 1.016 1.016)
					(thickness 0.1524)
				)
			)
		)
		(property "Device Type" "R402H16"
			(at 0.064008 -5.517896 0)
			(unlocked yes)
			(layer "F.Fab")
			(hide yes)
			(effects
				(font
					(size 1.016 1.016)
					(thickness 0.1524)
				)
			)
		)
		(duplicate_pad_numbers_are_jumpers no)
		(fp_line
			(start -0.508 -0.9398)
			(end -0.508 0.9398)
			(stroke
				(width 0.1524)
				(type default)
			)
			(layer "F.SilkS")
		)
		(fp_line
			(start 0.508 -0.9398)
			(end -0.508 -0.9398)
			(stroke
				(width 0.1524)
				(type default)
			)
			(layer "F.SilkS")
		)
		(fp_rect
			(start -0.508 0.9398)
			(end 0.508 -0.9398)
			(stroke
				(width 0)
				(type default)
			)
			(fill no)
			(layer "F.CrtYd")
		)
		(fp_rect
			(start -0.508 0.9398)
			(end 0.508 -0.9398)
			(stroke
				(width 0)
				(type default)
			)
			(fill no)
			(layer "F.Fab")
		)
		(pad "1" smd custom
			(at 0 -0.4445)
			(size 0.1397 0.1397)
			(layers "F.Cu" "F.Mask" "F.Paste")
			(net "SSD_PRSNT#9")
			(options
				(clearance outline)
				(anchor circle)
			)
			(primitives
				(gr_poly
					(pts
						(arc
							(start -0.1778 -0.2794)
							(mid -0.249642 -0.249642)
							(end -0.2794 -0.1778)
						)
						(arc
							(start -0.2794 0.1778)
							(mid -0.249642 0.249642)
							(end -0.1778 0.2794)
						)
						(arc
							(start 0.1778 0.2794)
							(mid 0.249642 0.249642)
							(end 0.2794 0.1778)
						)
						(arc
							(start 0.2794 -0.1778)
							(mid 0.249642 -0.249642)
							(end 0.1778 -0.2794)
						)
					)
					(width 0)
					(fill yes)
				)
			)
		)
		(pad "2" smd custom
			(at 0 0.4445)
			(size 0.1397 0.1397)
			(layers "F.Cu" "F.Mask" "F.Paste")
			(net "SSD_PRSNT#9_R")
			(options
				(clearance outline)
				(anchor circle)
			)
			(primitives
				(gr_poly
					(pts
						(arc
							(start -0.1778 -0.2794)
							(mid -0.249642 -0.249642)
							(end -0.2794 -0.1778)
						)
						(arc
							(start -0.2794 0.1778)
							(mid -0.249642 0.249642)
							(end -0.1778 0.2794)
						)
						(arc
							(start 0.1778 0.2794)
							(mid 0.249642 0.249642)
							(end 0.2794 0.1778)
						)
						(arc
							(start 0.2794 -0.1778)
							(mid 0.249642 -0.249642)
							(end 0.1778 -0.2794)
						)
					)
					(width 0)
					(fill yes)
				)
			)
		)
	)
	(footprint ""
		(layer "F.Cu")
		(at 346.456 -55.118 90)
		(property "Reference" "PC219"
			(at 0 0 90)
			(layer "F.SilkS")
			(hide yes)
			(effects
				(font
					(size 1.27 1.27)
				)
			)
		)
		(property "Value" "SC22U25V6KX-GP-U"
			(at -2.860802 -5.279644 90)
			(unlocked yes)
			(layer "F.Fab")
			(hide yes)
			(effects
				(font
					(size 1.016 1.016)
					(thickness 0.1524)
				)
			)
		)
		(property "Device Type" "C1206-TO0D3H75"
			(at -2.860802 -6.803644 90)
			(unlocked yes)
			(layer "F.Fab")
			(hide yes)
			(effects
				(font
					(size 1.016 1.016)
					(thickness 0.1524)
				)
			)
		)
		(duplicate_pad_numbers_are_jumpers no)
		(fp_line
			(start 1.3081 -2.3749)
			(end 1.3081 2.3749)
			(stroke
				(width 0.1524)
				(type default)
			)
			(layer "F.SilkS")
		)
		(fp_line
			(start -1.3081 -2.3749)
			(end 1.3081 -2.3749)
			(stroke
				(width 0.1524)
				(type default)
			)
			(layer "F.SilkS")
		)
		(fp_line
			(start 1.3081 2.3749)
			(end -1.3081 2.3749)
			(stroke
				(width 0.1524)
				(type default)
			)
			(layer "F.SilkS")
		)
		(fp_line
			(start -1.3081 2.3749)
			(end -1.3081 -2.3749)
			(stroke
				(width 0.1524)
				(type default)
			)
			(layer "F.SilkS")
		)
		(fp_rect
			(start -0.8001 1.6002)
			(end 0.8001 -1.6002)
			(stroke
				(width 0)
				(type default)
			)
			(fill no)
			(layer "F.CrtYd")
		)
		(fp_poly
			(pts
				(xy -1.5621 2.4511) (xy -1.5621 1.6002) (xy 0.8001 1.6002) (xy 0.8001 -1.6002) (xy -0.8001 -1.6002)
				(xy -0.8001 1.5875) (xy -1.5621 1.5875) (xy -1.5621 -2.4511) (xy 1.5621 -2.4511) (xy 1.5621 2.4511)
			)
			(stroke
				(width 0)
				(type default)
			)
			(fill no)
			(layer "F.CrtYd")
		)
		(fp_rect
			(start -1.5621 2.4511)
			(end 1.5621 -2.4511)
			(stroke
				(width 0)
				(type default)
			)
			(fill no)
			(layer "F.Fab")
		)
		(pad "1" smd rect
			(at 0 -1.392936 90)
			(size 2.1082 1.4478)
			(layers "F.Cu" "F.Mask" "F.Paste")
			(net "P0V9_E_VIN")
		)
		(pad "2" smd rect
			(at 0 1.392936 90)
			(size 2.1082 1.4478)
			(layers "F.Cu" "F.Mask" "F.Paste")
			(net "GND")
		)
	)
	(footprint ""
		(layer "F.Cu")
		(at 219.329 -9.144 90)
		(property "Reference" "R662"
			(at 0 0 90)
			(layer "F.SilkS")
			(hide yes)
			(effects
				(font
					(size 1.27 1.27)
				)
			)
		)
		(property "Value" "100KR2F-L1-GP"
			(at 0.064008 -3.993896 90)
			(unlocked yes)
			(layer "F.Fab")
			(hide yes)
			(effects
				(font
					(size 1.016 1.016)
					(thickness 0.1524)
				)
			)
		)
		(property "Device Type" "R402H16"
			(at 0.064008 -5.517896 90)
			(unlocked yes)
			(layer "F.Fab")
			(hide yes)
			(effects
				(font
					(size 1.016 1.016)
					(thickness 0.1524)
				)
			)
		)
		(duplicate_pad_numbers_are_jumpers no)
		(fp_line
			(start 0.508 -0.9398)
			(end -0.508 -0.9398)
			(stroke
				(width 0.1524)
				(type default)
			)
			(layer "F.SilkS")
		)
		(fp_line
			(start -0.508 -0.9398)
			(end -0.508 0.9398)
			(stroke
				(width 0.1524)
				(type default)
			)
			(layer "F.SilkS")
		)
		(fp_rect
			(start -0.508 0.9398)
			(end 0.508 -0.9398)
			(stroke
				(width 0)
				(type default)
			)
			(fill no)
			(layer "F.CrtYd")
		)
		(fp_rect
			(start -0.508 0.9398)
			(end 0.508 -0.9398)
			(stroke
				(width 0)
				(type default)
			)
			(fill no)
			(layer "F.Fab")
		)
		(pad "1" smd custom
			(at 0 -0.4445 90)
			(size 0.1397 0.1397)
			(layers "F.Cu" "F.Mask" "F.Paste")
			(net "P3V3_STBY")
			(options
				(clearance outline)
				(anchor circle)
			)
			(primitives
				(gr_poly
					(pts
						(arc
							(start -0.1778 -0.2794)
							(mid -0.249642 -0.249642)
							(end -0.2794 -0.1778)
						)
						(arc
							(start -0.2794 0.1778)
							(mid -0.249642 0.249642)
							(end -0.1778 0.2794)
						)
						(arc
							(start 0.1778 0.2794)
							(mid 0.249642 0.249642)
							(end 0.2794 0.1778)
						)
						(arc
							(start 0.2794 -0.1778)
							(mid 0.249642 -0.249642)
							(end 0.1778 -0.2794)
						)
					)
					(width 0)
					(fill yes)
				)
			)
		)
		(pad "2" smd custom
			(at 0 0.4445 90)
			(size 0.1397 0.1397)
			(layers "F.Cu" "F.Mask" "F.Paste")
			(net "EEPROM_A1")
			(options
				(clearance outline)
				(anchor circle)
			)
			(primitives
				(gr_poly
					(pts
						(arc
							(start -0.1778 -0.2794)
							(mid -0.249642 -0.249642)
							(end -0.2794 -0.1778)
						)
						(arc
							(start -0.2794 0.1778)
							(mid -0.249642 0.249642)
							(end -0.1778 0.2794)
						)
						(arc
							(start 0.1778 0.2794)
							(mid 0.249642 0.249642)
							(end 0.2794 0.1778)
						)
						(arc
							(start 0.2794 -0.1778)
							(mid 0.249642 -0.249642)
							(end 0.1778 -0.2794)
						)
					)
					(width 0)
					(fill yes)
				)
			)
		)
	)
	(footprint ""
		(layer "F.Cu")
		(at 337.058 -73.787 90)
		(property "Reference" "PR165"
			(at 0 0 90)
			(layer "F.SilkS")
			(hide yes)
			(effects
				(font
					(size 1.27 1.27)
				)
			)
		)
		(property "Value" "10KR2F-2-GP"
			(at 0.064008 -3.993896 90)
			(unlocked yes)
			(layer "F.Fab")
			(hide yes)
			(effects
				(font
					(size 1.016 1.016)
					(thickness 0.1524)
				)
			)
		)
		(property "Device Type" "R402H16"
			(at 0.064008 -5.517896 90)
			(unlocked yes)
			(layer "F.Fab")
			(hide yes)
			(effects
				(font
					(size 1.016 1.016)
					(thickness 0.1524)
				)
			)
		)
		(duplicate_pad_numbers_are_jumpers no)
		(fp_line
			(start 0.508 -0.9398)
			(end -0.508 -0.9398)
			(stroke
				(width 0.1524)
				(type default)
			)
			(layer "F.SilkS")
		)
		(fp_line
			(start -0.508 -0.9398)
			(end -0.508 0.9398)
			(stroke
				(width 0.1524)
				(type default)
			)
			(layer "F.SilkS")
		)
		(fp_rect
			(start -0.508 0.9398)
			(end 0.508 -0.9398)
			(stroke
				(width 0)
				(type default)
			)
			(fill no)
			(layer "F.CrtYd")
		)
		(fp_rect
			(start -0.508 0.9398)
			(end 0.508 -0.9398)
			(stroke
				(width 0)
				(type default)
			)
			(fill no)
			(layer "F.Fab")
		)
		(pad "1" smd custom
			(at 0 -0.4445 90)
			(size 0.1397 0.1397)
			(layers "F.Cu" "F.Mask" "F.Paste")
			(net "P0V9_E_VFB")
			(options
				(clearance outline)
				(anchor circle)
			)
			(primitives
				(gr_poly
					(pts
						(arc
							(start -0.1778 -0.2794)
							(mid -0.249642 -0.249642)
							(end -0.2794 -0.1778)
						)
						(arc
							(start -0.2794 0.1778)
							(mid -0.249642 0.249642)
							(end -0.1778 0.2794)
						)
						(arc
							(start 0.1778 0.2794)
							(mid 0.249642 0.249642)
							(end 0.2794 0.1778)
						)
						(arc
							(start 0.2794 -0.1778)
							(mid 0.249642 -0.249642)
							(end 0.1778 -0.2794)
						)
					)
					(width 0)
					(fill yes)
				)
			)
		)
		(pad "2" smd custom
			(at 0 0.4445 90)
			(size 0.1397 0.1397)
			(layers "F.Cu" "F.Mask" "F.Paste")
			(net "AGND_P0V9_E")
			(options
				(clearance outline)
				(anchor circle)
			)
			(primitives
				(gr_poly
					(pts
						(arc
							(start -0.1778 -0.2794)
							(mid -0.249642 -0.249642)
							(end -0.2794 -0.1778)
						)
						(arc
							(start -0.2794 0.1778)
							(mid -0.249642 0.249642)
							(end -0.1778 0.2794)
						)
						(arc
							(start 0.1778 0.2794)
							(mid 0.249642 0.249642)
							(end 0.2794 0.1778)
						)
						(arc
							(start 0.2794 -0.1778)
							(mid 0.249642 -0.249642)
							(end 0.1778 -0.2794)
						)
					)
					(width 0)
					(fill yes)
				)
			)
		)
	)
	(footprint ""
		(layer "F.Cu")
		(at 9.5631 -53.594 180)
		(property "Reference" "R597"
			(at 0 0 180)
			(layer "F.SilkS")
			(hide yes)
			(effects
				(font
					(size 1.27 1.27)
				)
			)
		)
		(property "Value" "0R2J-2-GP"
			(at 0.064008 -3.993896 180)
			(unlocked yes)
			(layer "F.Fab")
			(hide yes)
			(effects
				(font
					(size 1.016 1.016)
					(thickness 0.1524)
				)
			)
		)
		(property "Device Type" "R402H16"
			(at 0.064008 -5.517896 180)
			(unlocked yes)
			(layer "F.Fab")
			(hide yes)
			(effects
				(font
					(size 1.016 1.016)
					(thickness 0.1524)
				)
			)
		)
		(duplicate_pad_numbers_are_jumpers no)
		(fp_line
			(start 0.508 -0.9398)
			(end -0.508 -0.9398)
			(stroke
				(width 0.1524)
				(type default)
			)
			(layer "F.SilkS")
		)
		(fp_line
			(start -0.508 -0.9398)
			(end -0.508 0.9398)
			(stroke
				(width 0.1524)
				(type default)
			)
			(layer "F.SilkS")
		)
		(fp_rect
			(start -0.508 0.9398)
			(end 0.508 -0.9398)
			(stroke
				(width 0)
				(type default)
			)
			(fill no)
			(layer "F.CrtYd")
		)
		(fp_rect
			(start -0.508 0.9398)
			(end 0.508 -0.9398)
			(stroke
				(width 0)
				(type default)
			)
			(fill no)
			(layer "F.Fab")
		)
		(pad "1" smd custom
			(at 0 -0.4445 180)
			(size 0.1397 0.1397)
			(layers "F.Cu" "F.Mask" "F.Paste")
			(net "NIC0_MDI0_P0_R")
			(options
				(clearance outline)
				(anchor circle)
			)
			(primitives
				(gr_poly
					(pts
						(arc
							(start -0.1778 -0.2794)
							(mid -0.249642 -0.249642)
							(end -0.2794 -0.1778)
						)
						(arc
							(start -0.2794 0.1778)
							(mid -0.249642 0.249642)
							(end -0.1778 0.2794)
						)
						(arc
							(start 0.1778 0.2794)
							(mid 0.249642 0.249642)
							(end 0.2794 0.1778)
						)
						(arc
							(start 0.2794 -0.1778)
							(mid 0.249642 -0.249642)
							(end 0.1778 -0.2794)
						)
					)
					(width 0)
					(fill yes)
				)
			)
		)
		(pad "2" smd custom
			(at 0 0.4445 180)
			(size 0.1397 0.1397)
			(layers "F.Cu" "F.Mask" "F.Paste")
			(net "NIC0_MDI0_P0")
			(options
				(clearance outline)
				(anchor circle)
			)
			(primitives
				(gr_poly
					(pts
						(arc
							(start -0.1778 -0.2794)
							(mid -0.249642 -0.249642)
							(end -0.2794 -0.1778)
						)
						(arc
							(start -0.2794 0.1778)
							(mid -0.249642 0.249642)
							(end -0.1778 0.2794)
						)
						(arc
							(start 0.1778 0.2794)
							(mid 0.249642 0.249642)
							(end 0.2794 0.1778)
						)
						(arc
							(start 0.2794 -0.1778)
							(mid 0.249642 -0.249642)
							(end 0.1778 -0.2794)
						)
					)
					(width 0)
					(fill yes)
				)
			)
		)
	)
	(footprint ""
		(layer "F.Cu")
		(at 335.820512 -172.432218)
		(property "Reference" "R7967"
			(at 0 0 0)
			(layer "F.SilkS")
			(hide yes)
			(effects
				(font
					(size 1.27 1.27)
				)
			)
		)
		(property "Value" "0R2J-2-GP"
			(at 0.064008 -3.993896 0)
			(unlocked yes)
			(layer "F.Fab")
			(hide yes)
			(effects
				(font
					(size 1.016 1.016)
					(thickness 0.1524)
				)
			)
		)
		(property "Device Type" "R402H16"
			(at 0.064008 -5.517896 0)
			(unlocked yes)
			(layer "F.Fab")
			(hide yes)
			(effects
				(font
					(size 1.016 1.016)
					(thickness 0.1524)
				)
			)
		)
		(duplicate_pad_numbers_are_jumpers no)
		(fp_line
			(start -0.508 -0.9398)
			(end -0.508 0.9398)
			(stroke
				(width 0.1524)
				(type default)
			)
			(layer "F.SilkS")
		)
		(fp_line
			(start 0.508 -0.9398)
			(end -0.508 -0.9398)
			(stroke
				(width 0.1524)
				(type default)
			)
			(layer "F.SilkS")
		)
		(fp_rect
			(start -0.508 0.9398)
			(end 0.508 -0.9398)
			(stroke
				(width 0)
				(type default)
			)
			(fill no)
			(layer "F.CrtYd")
		)
		(fp_rect
			(start -0.508 0.9398)
			(end 0.508 -0.9398)
			(stroke
				(width 0)
				(type default)
			)
			(fill no)
			(layer "F.Fab")
		)
		(pad "1" smd custom
			(at 0 -0.4445)
			(size 0.1397 0.1397)
			(layers "F.Cu" "F.Mask" "F.Paste")
			(net "SSD_PERST#4")
			(options
				(clearance outline)
				(anchor circle)
			)
			(primitives
				(gr_poly
					(pts
						(arc
							(start -0.1778 -0.2794)
							(mid -0.249642 -0.249642)
							(end -0.2794 -0.1778)
						)
						(arc
							(start -0.2794 0.1778)
							(mid -0.249642 0.249642)
							(end -0.1778 0.2794)
						)
						(arc
							(start 0.1778 0.2794)
							(mid 0.249642 0.249642)
							(end 0.2794 0.1778)
						)
						(arc
							(start 0.2794 -0.1778)
							(mid 0.249642 -0.249642)
							(end 0.1778 -0.2794)
						)
					)
					(width 0)
					(fill yes)
				)
			)
		)
		(pad "2" smd custom
			(at 0 0.4445)
			(size 0.1397 0.1397)
			(layers "F.Cu" "F.Mask" "F.Paste")
			(net "SSD_PERST#4_R")
			(options
				(clearance outline)
				(anchor circle)
			)
			(primitives
				(gr_poly
					(pts
						(arc
							(start -0.1778 -0.2794)
							(mid -0.249642 -0.249642)
							(end -0.2794 -0.1778)
						)
						(arc
							(start -0.2794 0.1778)
							(mid -0.249642 0.249642)
							(end -0.1778 0.2794)
						)
						(arc
							(start 0.1778 0.2794)
							(mid 0.249642 0.249642)
							(end 0.2794 0.1778)
						)
						(arc
							(start 0.2794 -0.1778)
							(mid 0.249642 -0.249642)
							(end 0.1778 -0.2794)
						)
					)
					(width 0)
					(fill yes)
				)
			)
		)
	)
	(footprint ""
		(layer "F.Cu")
		(at 25.95626 -81.22412 90)
		(property "Reference" "R387"
			(at 0 0 90)
			(layer "F.SilkS")
			(hide yes)
			(effects
				(font
					(size 1.27 1.27)
				)
			)
		)
		(property "Value" "0R2J-2-GP"
			(at 0.064008 -3.993896 90)
			(unlocked yes)
			(layer "F.Fab")
			(hide yes)
			(effects
				(font
					(size 1.016 1.016)
					(thickness 0.1524)
				)
			)
		)
		(property "Device Type" "R402H16"
			(at 0.064008 -5.517896 90)
			(unlocked yes)
			(layer "F.Fab")
			(hide yes)
			(effects
				(font
					(size 1.016 1.016)
					(thickness 0.1524)
				)
			)
		)
		(duplicate_pad_numbers_are_jumpers no)
		(fp_line
			(start 0.508 -0.9398)
			(end -0.508 -0.9398)
			(stroke
				(width 0.1524)
				(type default)
			)
			(layer "F.SilkS")
		)
		(fp_line
			(start -0.508 -0.9398)
			(end -0.508 0.9398)
			(stroke
				(width 0.1524)
				(type default)
			)
			(layer "F.SilkS")
		)
		(fp_rect
			(start -0.508 0.9398)
			(end 0.508 -0.9398)
			(stroke
				(width 0)
				(type default)
			)
			(fill no)
			(layer "F.CrtYd")
		)
		(fp_rect
			(start -0.508 0.9398)
			(end 0.508 -0.9398)
			(stroke
				(width 0)
				(type default)
			)
			(fill no)
			(layer "F.Fab")
		)
		(pad "1" smd custom
			(at 0 -0.4445 90)
			(size 0.1397 0.1397)
			(layers "F.Cu" "F.Mask" "F.Paste")
			(net "NVM_SK")
			(options
				(clearance outline)
				(anchor circle)
			)
			(primitives
				(gr_poly
					(pts
						(arc
							(start -0.1778 -0.2794)
							(mid -0.249642 -0.249642)
							(end -0.2794 -0.1778)
						)
						(arc
							(start -0.2794 0.1778)
							(mid -0.249642 0.249642)
							(end -0.1778 0.2794)
						)
						(arc
							(start 0.1778 0.2794)
							(mid 0.249642 0.249642)
							(end 0.2794 0.1778)
						)
						(arc
							(start 0.2794 -0.1778)
							(mid 0.249642 -0.249642)
							(end 0.1778 -0.2794)
						)
					)
					(width 0)
					(fill yes)
				)
			)
		)
		(pad "2" smd custom
			(at 0 0.4445 90)
			(size 0.1397 0.1397)
			(layers "F.Cu" "F.Mask" "F.Paste")
			(net "I210_SK_R")
			(options
				(clearance outline)
				(anchor circle)
			)
			(primitives
				(gr_poly
					(pts
						(arc
							(start -0.1778 -0.2794)
							(mid -0.249642 -0.249642)
							(end -0.2794 -0.1778)
						)
						(arc
							(start -0.2794 0.1778)
							(mid -0.249642 0.249642)
							(end -0.1778 0.2794)
						)
						(arc
							(start 0.1778 0.2794)
							(mid 0.249642 0.249642)
							(end 0.2794 0.1778)
						)
						(arc
							(start 0.2794 -0.1778)
							(mid 0.249642 -0.249642)
							(end 0.1778 -0.2794)
						)
					)
					(width 0)
					(fill yes)
				)
			)
		)
	)
	(footprint ""
		(layer "F.Cu")
		(at 326.517 -99.568 180)
		(property "Reference" "R4171"
			(at 0 0 180)
			(layer "F.SilkS")
			(hide yes)
			(effects
				(font
					(size 1.27 1.27)
				)
			)
		)
		(property "Value" "4K7R2F-GP"
			(at 0.064008 -3.993896 180)
			(unlocked yes)
			(layer "F.Fab")
			(hide yes)
			(effects
				(font
					(size 1.016 1.016)
					(thickness 0.1524)
				)
			)
		)
		(property "Device Type" "R402H16"
			(at 0.064008 -5.517896 180)
			(unlocked yes)
			(layer "F.Fab")
			(hide yes)
			(effects
				(font
					(size 1.016 1.016)
					(thickness 0.1524)
				)
			)
		)
		(duplicate_pad_numbers_are_jumpers no)
		(fp_line
			(start 0.508 -0.9398)
			(end -0.508 -0.9398)
			(stroke
				(width 0.1524)
				(type default)
			)
			(layer "F.SilkS")
		)
		(fp_line
			(start -0.508 -0.9398)
			(end -0.508 0.9398)
			(stroke
				(width 0.1524)
				(type default)
			)
			(layer "F.SilkS")
		)
		(fp_rect
			(start -0.508 0.9398)
			(end 0.508 -0.9398)
			(stroke
				(width 0)
				(type default)
			)
			(fill no)
			(layer "F.CrtYd")
		)
		(fp_rect
			(start -0.508 0.9398)
			(end 0.508 -0.9398)
			(stroke
				(width 0)
				(type default)
			)
			(fill no)
			(layer "F.Fab")
		)
		(pad "1" smd custom
			(at 0 -0.4445 180)
			(size 0.1397 0.1397)
			(layers "F.Cu" "F.Mask" "F.Paste")
			(net "VS6_LED")
			(options
				(clearance outline)
				(anchor circle)
			)
			(primitives
				(gr_poly
					(pts
						(arc
							(start -0.1778 -0.2794)
							(mid -0.249642 -0.249642)
							(end -0.2794 -0.1778)
						)
						(arc
							(start -0.2794 0.1778)
							(mid -0.249642 0.249642)
							(end -0.1778 0.2794)
						)
						(arc
							(start 0.1778 0.2794)
							(mid 0.249642 0.249642)
							(end 0.2794 0.1778)
						)
						(arc
							(start 0.2794 -0.1778)
							(mid 0.249642 -0.249642)
							(end 0.1778 -0.2794)
						)
					)
					(width 0)
					(fill yes)
				)
			)
		)
		(pad "2" smd custom
			(at 0 0.4445 180)
			(size 0.1397 0.1397)
			(layers "F.Cu" "F.Mask" "F.Paste")
			(net "P3V3_STBY")
			(options
				(clearance outline)
				(anchor circle)
			)
			(primitives
				(gr_poly
					(pts
						(arc
							(start -0.1778 -0.2794)
							(mid -0.249642 -0.249642)
							(end -0.2794 -0.1778)
						)
						(arc
							(start -0.2794 0.1778)
							(mid -0.249642 0.249642)
							(end -0.1778 0.2794)
						)
						(arc
							(start 0.1778 0.2794)
							(mid 0.249642 0.249642)
							(end 0.2794 0.1778)
						)
						(arc
							(start 0.2794 -0.1778)
							(mid 0.249642 -0.249642)
							(end 0.1778 -0.2794)
						)
					)
					(width 0)
					(fill yes)
				)
			)
		)
	)
	(footprint ""
		(layer "F.Cu")
		(at 150.375874 -86.25332)
		(property "Reference" "PG10"
			(at 0 0 0)
			(layer "F.SilkS")
			(hide yes)
			(effects
				(font
					(size 1.27 1.27)
				)
			)
		)
		(property "Value" "GAP-CLOSE-PWR-3-GP"
			(at 0.0254 -6.5786 0)
			(unlocked yes)
			(layer "F.Fab")
			(hide yes)
			(effects
				(font
					(size 1.016 1.016)
					(thickness 0.1524)
				)
			)
		)
		(property "Device Type" "GAP-CLOSE-PWR-3"
			(at 0.0254 -8.255 0)
			(unlocked yes)
			(layer "F.Fab")
			(hide yes)
			(effects
				(font
					(size 1.016 1.016)
					(thickness 0.1524)
				)
			)
		)
		(duplicate_pad_numbers_are_jumpers no)
		(fp_rect
			(start -0.7112 0.4572)
			(end 0.7112 -0.4572)
			(stroke
				(width 0)
				(type default)
			)
			(fill no)
			(layer "F.CrtYd")
		)
		(fp_poly
			(pts
				(xy -0.7112 -0.4572) (xy 0.7112 -0.4572) (xy 0.7112 0.4572) (xy -0.7112 0.4572)
			)
			(stroke
				(width 0)
				(type default)
			)
			(fill no)
			(layer "F.Fab")
		)
		(pad "1" smd rect
			(at -0.3048 0)
			(size 0.6604 0.762)
			(layers "F.Cu" "F.Mask" "F.Paste")
			(net "P1V8_PWR")
		)
		(pad "2" smd rect
			(at 0.3048 0)
			(size 0.6604 0.762)
			(layers "F.Cu" "F.Mask" "F.Paste")
			(net "P1V8_STBY")
		)
	)
	(footprint ""
		(layer "F.Cu")
		(at 217.996008 -4.064)
		(property "Reference" "SC1114"
			(at 0 0 0)
			(layer "F.SilkS")
			(hide yes)
			(effects
				(font
					(size 1.27 1.27)
				)
			)
		)
		(property "Value" "SCD1U16V2KX-3GP"
			(at 1.1811 -2.7051 0)
			(unlocked yes)
			(layer "F.Fab")
			(hide yes)
			(effects
				(font
					(size 1.016 1.016)
					(thickness 0.1524)
				)
			)
		)
		(property "Device Type" "C402H22"
			(at 1.1811 -4.2291 0)
			(unlocked yes)
			(layer "F.Fab")
			(hide yes)
			(effects
				(font
					(size 1.016 1.016)
					(thickness 0.1524)
				)
			)
		)
		(duplicate_pad_numbers_are_jumpers no)
		(fp_rect
			(start -0.4318 0.9525)
			(end 0.4318 -0.9525)
			(stroke
				(width 0)
				(type default)
			)
			(fill no)
			(layer "F.CrtYd")
		)
		(fp_rect
			(start -0.4318 0.9525)
			(end 0.4318 -0.9525)
			(stroke
				(width 0)
				(type default)
			)
			(fill no)
			(layer "F.Fab")
		)
		(pad "1" smd custom
			(at 0 -0.4445)
			(size 0.1524 0.1524)
			(layers "F.Cu" "F.Mask" "F.Paste")
			(net "P3V3_STBY")
			(options
				(clearance outline)
				(anchor circle)
			)
			(primitives
				(gr_poly
					(pts
						(arc
							(start 0.3048 -0.2032)
							(mid 0.275042 -0.275042)
							(end 0.2032 -0.3048)
						)
						(arc
							(start -0.2032 -0.3048)
							(mid -0.275042 -0.275042)
							(end -0.3048 -0.2032)
						)
						(arc
							(start -0.3048 0.2032)
							(mid -0.275042 0.275042)
							(end -0.2032 0.3048)
						)
						(arc
							(start 0.2032 0.3048)
							(mid 0.275042 0.275042)
							(end 0.3048 0.2032)
						)
					)
					(width 0)
					(fill yes)
				)
			)
		)
		(pad "2" smd custom
			(at 0 0.4445)
			(size 0.1524 0.1524)
			(layers "F.Cu" "F.Mask" "F.Paste")
			(net "GND")
			(options
				(clearance outline)
				(anchor circle)
			)
			(primitives
				(gr_poly
					(pts
						(arc
							(start 0.3048 -0.2032)
							(mid 0.275042 -0.275042)
							(end 0.2032 -0.3048)
						)
						(arc
							(start -0.2032 -0.3048)
							(mid -0.275042 -0.275042)
							(end -0.3048 -0.2032)
						)
						(arc
							(start -0.3048 0.2032)
							(mid -0.275042 0.275042)
							(end -0.2032 0.3048)
						)
						(arc
							(start 0.2032 0.3048)
							(mid 0.275042 0.275042)
							(end 0.3048 0.2032)
						)
					)
					(width 0)
					(fill yes)
				)
			)
		)
	)
	(footprint ""
		(layer "F.Cu")
		(at 82.792062 -212.420454 180)
		(property "Reference" "C349"
			(at 0 0 180)
			(layer "F.SilkS")
			(hide yes)
			(effects
				(font
					(size 1.27 1.27)
				)
			)
		)
		(property "Value" "SCD22U10V2KX-1GP"
			(at 1.1811 -2.7051 180)
			(unlocked yes)
			(layer "F.Fab")
			(hide yes)
			(effects
				(font
					(size 1.016 1.016)
					(thickness 0.1524)
				)
			)
		)
		(property "Device Type" "C402H22"
			(at 1.1811 -4.2291 180)
			(unlocked yes)
			(layer "F.Fab")
			(hide yes)
			(effects
				(font
					(size 1.016 1.016)
					(thickness 0.1524)
				)
			)
		)
		(duplicate_pad_numbers_are_jumpers no)
		(fp_rect
			(start -0.4318 0.9525)
			(end 0.4318 -0.9525)
			(stroke
				(width 0)
				(type default)
			)
			(fill no)
			(layer "F.CrtYd")
		)
		(fp_rect
			(start -0.4318 0.9525)
			(end 0.4318 -0.9525)
			(stroke
				(width 0)
				(type default)
			)
			(fill no)
			(layer "F.Fab")
		)
		(pad "1" smd custom
			(at 0 -0.4445 180)
			(size 0.1524 0.1524)
			(layers "F.Cu" "F.Mask" "F.Paste")
			(net "PCIE_TX_CAP_P67")
			(options
				(clearance outline)
				(anchor circle)
			)
			(primitives
				(gr_poly
					(pts
						(arc
							(start 0.3048 -0.2032)
							(mid 0.275042 -0.275042)
							(end 0.2032 -0.3048)
						)
						(arc
							(start -0.2032 -0.3048)
							(mid -0.275042 -0.275042)
							(end -0.3048 -0.2032)
						)
						(arc
							(start -0.3048 0.2032)
							(mid -0.275042 0.275042)
							(end -0.2032 0.3048)
						)
						(arc
							(start 0.2032 0.3048)
							(mid 0.275042 0.275042)
							(end 0.3048 0.2032)
						)
					)
					(width 0)
					(fill yes)
				)
			)
		)
		(pad "2" smd custom
			(at 0 0.4445 180)
			(size 0.1524 0.1524)
			(layers "F.Cu" "F.Mask" "F.Paste")
			(net "PCIE_TX_P67")
			(options
				(clearance outline)
				(anchor circle)
			)
			(primitives
				(gr_poly
					(pts
						(arc
							(start 0.3048 -0.2032)
							(mid 0.275042 -0.275042)
							(end 0.2032 -0.3048)
						)
						(arc
							(start -0.2032 -0.3048)
							(mid -0.275042 -0.275042)
							(end -0.3048 -0.2032)
						)
						(arc
							(start -0.3048 0.2032)
							(mid -0.275042 0.275042)
							(end -0.2032 0.3048)
						)
						(arc
							(start 0.2032 0.3048)
							(mid 0.275042 0.275042)
							(end 0.3048 0.2032)
						)
					)
					(width 0)
					(fill yes)
				)
			)
		)
	)
	(footprint ""
		(layer "F.Cu")
		(at 308.037992 -33.48101 180)
		(property "Reference" "R729"
			(at 0 0 180)
			(layer "F.SilkS")
			(hide yes)
			(effects
				(font
					(size 1.27 1.27)
				)
			)
		)
		(property "Value" "0R2J-2-GP"
			(at 0.064008 -3.993896 180)
			(unlocked yes)
			(layer "F.Fab")
			(hide yes)
			(effects
				(font
					(size 1.016 1.016)
					(thickness 0.1524)
				)
			)
		)
		(property "Device Type" "R402H16"
			(at 0.064008 -5.517896 180)
			(unlocked yes)
			(layer "F.Fab")
			(hide yes)
			(effects
				(font
					(size 1.016 1.016)
					(thickness 0.1524)
				)
			)
		)
		(duplicate_pad_numbers_are_jumpers no)
		(fp_line
			(start 0.508 -0.9398)
			(end -0.508 -0.9398)
			(stroke
				(width 0.1524)
				(type default)
			)
			(layer "F.SilkS")
		)
		(fp_line
			(start -0.508 -0.9398)
			(end -0.508 0.9398)
			(stroke
				(width 0.1524)
				(type default)
			)
			(layer "F.SilkS")
		)
		(fp_rect
			(start -0.508 0.9398)
			(end 0.508 -0.9398)
			(stroke
				(width 0)
				(type default)
			)
			(fill no)
			(layer "F.CrtYd")
		)
		(fp_rect
			(start -0.508 0.9398)
			(end 0.508 -0.9398)
			(stroke
				(width 0)
				(type default)
			)
			(fill no)
			(layer "F.Fab")
		)
		(pad "1" smd custom
			(at 0 -0.4445 180)
			(size 0.1397 0.1397)
			(layers "F.Cu" "F.Mask" "F.Paste")
			(net "8644_USB_DN7")
			(options
				(clearance outline)
				(anchor circle)
			)
			(primitives
				(gr_poly
					(pts
						(arc
							(start -0.1778 -0.2794)
							(mid -0.249642 -0.249642)
							(end -0.2794 -0.1778)
						)
						(arc
							(start -0.2794 0.1778)
							(mid -0.249642 0.249642)
							(end -0.1778 0.2794)
						)
						(arc
							(start 0.1778 0.2794)
							(mid 0.249642 0.249642)
							(end 0.2794 0.1778)
						)
						(arc
							(start 0.2794 -0.1778)
							(mid 0.249642 -0.249642)
							(end 0.1778 -0.2794)
						)
					)
					(width 0)
					(fill yes)
				)
			)
		)
		(pad "2" smd custom
			(at 0 0.4445 180)
			(size 0.1397 0.1397)
			(layers "F.Cu" "F.Mask" "F.Paste")
			(net "P3V3_STBY")
			(options
				(clearance outline)
				(anchor circle)
			)
			(primitives
				(gr_poly
					(pts
						(arc
							(start -0.1778 -0.2794)
							(mid -0.249642 -0.249642)
							(end -0.2794 -0.1778)
						)
						(arc
							(start -0.2794 0.1778)
							(mid -0.249642 0.249642)
							(end -0.1778 0.2794)
						)
						(arc
							(start 0.1778 0.2794)
							(mid 0.249642 0.249642)
							(end 0.2794 0.1778)
						)
						(arc
							(start 0.2794 -0.1778)
							(mid 0.249642 -0.249642)
							(end 0.1778 -0.2794)
						)
					)
					(width 0)
					(fill yes)
				)
			)
		)
	)
	(footprint ""
		(layer "F.Cu")
		(at 349.749872 -5.40004)
		(property "Reference" "PAD3"
			(at 0 0 0)
			(layer "F.SilkS")
			(hide yes)
			(effects
				(font
					(size 1.27 1.27)
				)
			)
		)
		(property "Value" "PAD-3P-GP"
			(at -18.082768 -12.6492 0)
			(unlocked yes)
			(layer "F.Fab")
			(hide yes)
			(effects
				(font
					(size 1.016 1.016)
					(thickness 0.1524)
				)
			)
		)
		(property "Device Type" "HT219X276B8R32-3P-S"
			(at -18.082768 -14.1732 0)
			(unlocked yes)
			(layer "F.Fab")
			(hide yes)
			(effects
				(font
					(size 1.016 1.016)
					(thickness 0.1524)
				)
			)
		)
		(duplicate_pad_numbers_are_jumpers no)
		(fp_poly
			(pts
				(arc
					(start -6.694678 -8.800084)
					(mid -15.305278 -8.800084)
					(end -6.694678 -8.800084)
				)
			)
			(stroke
				(width 0)
				(type default)
			)
			(fill no)
			(layer "B.CrtYd")
		)
		(fp_poly
			(pts
				(arc
					(start 4.3053 -17.599914)
					(mid -4.3053 -17.599914)
					(end 4.3053 -17.599914)
				)
			)
			(stroke
				(width 0)
				(type default)
			)
			(fill no)
			(layer "B.CrtYd")
		)
		(fp_poly
			(pts
				(arc
					(start 4.3053 0)
					(mid -4.3053 0)
					(end 4.3053 0)
				)
			)
			(stroke
				(width 0)
				(type default)
			)
			(fill no)
			(layer "B.CrtYd")
		)
		(fp_poly
			(pts
				(xy -16.304768 5.30479) (xy -16.304768 -22.904704) (xy 6.154674 -22.904704)
				(arc
					(start 6.154674 -13.79982)
					(mid 5.918991 -13.230831)
					(end 5.350002 -12.995148)
				)
				(arc
					(start 4.99999 -12.995148)
					(mid 4.862053 -12.938013)
					(end 4.804918 -12.800076)
				)
				(arc
					(start 4.804918 -4.800092)
					(mid 4.862038 -4.662065)
					(end 4.99999 -4.604766)
				)
				(arc
					(start 5.350002 -4.604766)
					(mid 5.918991 -4.369083)
					(end 6.154674 -3.800094)
				)
				(xy 6.154674 5.30479)
			)
			(stroke
				(width 0)
				(type default)
			)
			(fill no)
			(layer "F.CrtYd")
		)
		(fp_poly
			(pts
				(arc
					(start -6.694678 -8.800084)
					(mid -15.305278 -8.800084)
					(end -6.694678 -8.800084)
				)
			)
			(stroke
				(width 0)
				(type default)
			)
			(fill no)
			(layer "B.Fab")
		)
		(fp_poly
			(pts
				(arc
					(start 4.3053 -17.599914)
					(mid -4.3053 -17.599914)
					(end 4.3053 -17.599914)
				)
			)
			(stroke
				(width 0)
				(type default)
			)
			(fill no)
			(layer "B.Fab")
		)
		(fp_poly
			(pts
				(arc
					(start 4.3053 0)
					(mid -4.3053 0)
					(end 4.3053 0)
				)
			)
			(stroke
				(width 0)
				(type default)
			)
			(fill no)
			(layer "B.Fab")
		)
		(fp_poly
			(pts
				(xy -16.304768 5.30479) (xy -16.304768 -22.904704) (xy 6.154674 -22.904704)
				(arc
					(start 6.154674 -13.79982)
					(mid 5.918991 -13.230831)
					(end 5.350002 -12.995148)
				)
				(arc
					(start 4.99999 -12.995148)
					(mid 4.862053 -12.938013)
					(end 4.804918 -12.800076)
				)
				(arc
					(start 4.804918 -4.800092)
					(mid 4.862038 -4.662065)
					(end 4.99999 -4.604766)
				)
				(arc
					(start 5.350002 -4.604766)
					(mid 5.918991 -4.369083)
					(end 6.154674 -3.800094)
				)
				(xy 6.154674 5.30479)
			)
			(stroke
				(width 0)
				(type default)
			)
			(fill no)
			(layer "F.Fab")
		)
		(pad "1" thru_hole custom
			(at 0 0)
			(size 5.46246 5.46246)
			(drill 3.2004)
			(layers "*.Cu" "*.Mask")
			(remove_unused_layers no)
			(net "GND")
			(clearance -8.816848)
			(thermal_gap 0.3048)
			(options
				(clearance outline)
				(anchor circle)
			)
			(primitives
				(gr_poly
					(pts
						(xy 10.924794 -13.800074) (xy -10.925048 -13.800074) (xy -10.925048 13.79982) (xy 10.924794 13.79982)
						(arc
							(start 10.924794 4.999736)
							(mid 10.778385 4.646273)
							(end 10.424922 4.499864)
						)
						(arc
							(start 10.07491 4.499864)
							(mid 9.721432 4.353291)
							(end 9.575038 3.999738)
						)
						(arc
							(start 9.575038 -4.000246)
							(mid 9.721447 -4.353709)
							(end 10.07491 -4.500118)
						)
						(arc
							(start 10.424922 -4.500118)
							(mid 10.778475 -4.646617)
							(end 10.924794 -5.000244)
						)
					)
					(width 0)
					(fill yes)
				)
			)
			(padstack
				(mode front_inner_back)
				(layer "Inner"
					(shape circle)
					(size 3.6068 3.6068)
					(clearance 0.3048)
				)
				(layer "B.Cu"
					(shape circle)
					(size 8.001 8.001)
					(clearance -1.8923)
				)
			)
		)
		(pad "2" thru_hole circle
			(at -10.999978 -8.800084)
			(size 8.001 8.001)
			(drill 3.2004)
			(layers "*.Cu" "*.Mask")
			(remove_unused_layers no)
			(net "GND")
			(clearance -1.8923)
			(thermal_gap 0.3048)
			(padstack
				(mode front_inner_back)
				(layer "Inner"
					(shape circle)
					(size 3.6068 3.6068)
					(clearance 0.3048)
				)
				(layer "B.Cu"
					(shape circle)
					(size 8.001 8.001)
					(clearance -1.8923)
				)
			)
		)
		(pad "3" thru_hole circle
			(at 0 -17.599914)
			(size 8.001 8.001)
			(drill 3.2004)
			(layers "*.Cu" "*.Mask")
			(remove_unused_layers no)
			(net "GND")
			(clearance -1.8923)
			(thermal_gap 0.3048)
			(padstack
				(mode front_inner_back)
				(layer "Inner"
					(shape circle)
					(size 3.6068 3.6068)
					(clearance 0.3048)
				)
				(layer "B.Cu"
					(shape circle)
					(size 8.001 8.001)
					(clearance -1.8923)
				)
			)
		)
	)
	(footprint ""
		(layer "F.Cu")
		(at 20.447 -145.415 180)
		(property "Reference" "C196"
			(at 0 0 180)
			(layer "F.SilkS")
			(hide yes)
			(effects
				(font
					(size 1.27 1.27)
				)
			)
		)
		(property "Value" "SC100P50V2JN-3GP"
			(at 1.1811 -2.7051 180)
			(unlocked yes)
			(layer "F.Fab")
			(hide yes)
			(effects
				(font
					(size 1.016 1.016)
					(thickness 0.1524)
				)
			)
		)
		(property "Device Type" "C402H22"
			(at 1.1811 -4.2291 180)
			(unlocked yes)
			(layer "F.Fab")
			(hide yes)
			(effects
				(font
					(size 1.016 1.016)
					(thickness 0.1524)
				)
			)
		)
		(duplicate_pad_numbers_are_jumpers no)
		(fp_rect
			(start -0.4318 0.9525)
			(end 0.4318 -0.9525)
			(stroke
				(width 0)
				(type default)
			)
			(fill no)
			(layer "F.CrtYd")
		)
		(fp_rect
			(start -0.4318 0.9525)
			(end 0.4318 -0.9525)
			(stroke
				(width 0)
				(type default)
			)
			(fill no)
			(layer "F.Fab")
		)
		(pad "1" smd custom
			(at 0 -0.4445 180)
			(size 0.1524 0.1524)
			(layers "F.Cu" "F.Mask" "F.Paste")
			(net "MPLLAV33")
			(options
				(clearance outline)
				(anchor circle)
			)
			(primitives
				(gr_poly
					(pts
						(arc
							(start 0.3048 -0.2032)
							(mid 0.275042 -0.275042)
							(end 0.2032 -0.3048)
						)
						(arc
							(start -0.2032 -0.3048)
							(mid -0.275042 -0.275042)
							(end -0.3048 -0.2032)
						)
						(arc
							(start -0.3048 0.2032)
							(mid -0.275042 0.275042)
							(end -0.2032 0.3048)
						)
						(arc
							(start 0.2032 0.3048)
							(mid 0.275042 0.275042)
							(end 0.3048 0.2032)
						)
					)
					(width 0)
					(fill yes)
				)
			)
		)
		(pad "2" smd custom
			(at 0 0.4445 180)
			(size 0.1524 0.1524)
			(layers "F.Cu" "F.Mask" "F.Paste")
			(net "GND")
			(options
				(clearance outline)
				(anchor circle)
			)
			(primitives
				(gr_poly
					(pts
						(arc
							(start 0.3048 -0.2032)
							(mid 0.275042 -0.275042)
							(end 0.2032 -0.3048)
						)
						(arc
							(start -0.2032 -0.3048)
							(mid -0.275042 -0.275042)
							(end -0.3048 -0.2032)
						)
						(arc
							(start -0.3048 0.2032)
							(mid -0.275042 0.275042)
							(end -0.2032 0.3048)
						)
						(arc
							(start 0.2032 0.3048)
							(mid 0.275042 0.275042)
							(end 0.3048 0.2032)
						)
					)
					(width 0)
					(fill yes)
				)
			)
		)
	)
	(footprint ""
		(layer "F.Cu")
		(at 157.877002 -53.240432 90)
		(property "Reference" "PR180"
			(at 0 0 90)
			(layer "F.SilkS")
			(hide yes)
			(effects
				(font
					(size 1.27 1.27)
				)
			)
		)
		(property "Value" "80K6R2F-GP"
			(at 0.064008 -3.993896 90)
			(unlocked yes)
			(layer "F.Fab")
			(hide yes)
			(effects
				(font
					(size 1.016 1.016)
					(thickness 0.1524)
				)
			)
		)
		(property "Device Type" "R402H16"
			(at 0.064008 -5.517896 90)
			(unlocked yes)
			(layer "F.Fab")
			(hide yes)
			(effects
				(font
					(size 1.016 1.016)
					(thickness 0.1524)
				)
			)
		)
		(duplicate_pad_numbers_are_jumpers no)
		(fp_line
			(start 0.508 -0.9398)
			(end -0.508 -0.9398)
			(stroke
				(width 0.1524)
				(type default)
			)
			(layer "F.SilkS")
		)
		(fp_line
			(start -0.508 -0.9398)
			(end -0.508 0.9398)
			(stroke
				(width 0.1524)
				(type default)
			)
			(layer "F.SilkS")
		)
		(fp_rect
			(start -0.508 0.9398)
			(end 0.508 -0.9398)
			(stroke
				(width 0)
				(type default)
			)
			(fill no)
			(layer "F.CrtYd")
		)
		(fp_rect
			(start -0.508 0.9398)
			(end 0.508 -0.9398)
			(stroke
				(width 0)
				(type default)
			)
			(fill no)
			(layer "F.Fab")
		)
		(pad "1" smd custom
			(at 0 -0.4445 90)
			(size 0.1397 0.1397)
			(layers "F.Cu" "F.Mask" "F.Paste")
			(net "P0V9_VFB")
			(options
				(clearance outline)
				(anchor circle)
			)
			(primitives
				(gr_poly
					(pts
						(arc
							(start -0.1778 -0.2794)
							(mid -0.249642 -0.249642)
							(end -0.2794 -0.1778)
						)
						(arc
							(start -0.2794 0.1778)
							(mid -0.249642 0.249642)
							(end -0.1778 0.2794)
						)
						(arc
							(start 0.1778 0.2794)
							(mid 0.249642 0.249642)
							(end 0.2794 0.1778)
						)
						(arc
							(start 0.2794 -0.1778)
							(mid 0.249642 -0.249642)
							(end 0.1778 -0.2794)
						)
					)
					(width 0)
					(fill yes)
				)
			)
		)
		(pad "2" smd custom
			(at 0 0.4445 90)
			(size 0.1397 0.1397)
			(layers "F.Cu" "F.Mask" "F.Paste")
			(net "P0V9_VFB_AVS")
			(options
				(clearance outline)
				(anchor circle)
			)
			(primitives
				(gr_poly
					(pts
						(arc
							(start -0.1778 -0.2794)
							(mid -0.249642 -0.249642)
							(end -0.2794 -0.1778)
						)
						(arc
							(start -0.2794 0.1778)
							(mid -0.249642 0.249642)
							(end -0.1778 0.2794)
						)
						(arc
							(start 0.1778 0.2794)
							(mid 0.249642 0.249642)
							(end 0.2794 0.1778)
						)
						(arc
							(start 0.2794 -0.1778)
							(mid 0.249642 -0.249642)
							(end 0.1778 -0.2794)
						)
					)
					(width 0)
					(fill yes)
				)
			)
		)
	)
	(footprint ""
		(layer "F.Cu")
		(at 256.8702 -15.9766 90)
		(property "Reference" "Q3203"
			(at 0 0 90)
			(layer "F.SilkS")
			(hide yes)
			(effects
				(font
					(size 1.27 1.27)
				)
			)
		)
		(property "Value" "P2003EVG-GP"
			(at 0 -11.1252 90)
			(unlocked yes)
			(layer "F.Fab")
			(hide yes)
			(effects
				(font
					(size 1.016 1.016)
					(thickness 0.1524)
				)
			)
		)
		(property "Device Type" "SOIC8H79"
			(at 0 -12.6492 90)
			(unlocked yes)
			(layer "F.Fab")
			(hide yes)
			(effects
				(font
					(size 1.016 1.016)
					(thickness 0.1524)
				)
			)
		)
		(duplicate_pad_numbers_are_jumpers no)
		(fp_line
			(start 2.1336 -1.4224)
			(end -2.7432 -1.4224)
			(stroke
				(width 0.1524)
				(type default)
			)
			(layer "F.SilkS")
		)
		(fp_line
			(start -2.7432 -1.4224)
			(end -2.7432 1.4224)
			(stroke
				(width 0.1524)
				(type default)
			)
			(layer "F.SilkS")
		)
		(fp_line
			(start -2.7432 -0.508)
			(end -2.2352 0)
			(stroke
				(width 0.1524)
				(type default)
			)
			(layer "F.SilkS")
		)
		(fp_line
			(start -2.2352 0)
			(end -2.7432 0.508)
			(stroke
				(width 0.1524)
				(type default)
			)
			(layer "F.SilkS")
		)
		(fp_line
			(start 2.1336 1.4224)
			(end 2.1336 -1.4224)
			(stroke
				(width 0.1524)
				(type default)
			)
			(layer "F.SilkS")
		)
		(fp_line
			(start -2.7432 1.4224)
			(end 2.1336 1.4224)
			(stroke
				(width 0.1524)
				(type default)
			)
			(layer "F.SilkS")
		)
		(fp_line
			(start -2.6162 3.429)
			(end -2.6162 1.4732)
			(stroke
				(width 0.4064)
				(type default)
			)
			(layer "F.SilkS")
		)
		(fp_poly
			(pts
				(xy 2.2098 -1.4224) (xy 2.2098 1.4224) (xy -2.2225 1.4224) (xy -2.2225 -1.4224)
			)
			(stroke
				(width 0)
				(type default)
			)
			(fill yes)
			(layer "F.SilkS")
		)
		(fp_rect
			(start -2.4511 2.9972)
			(end 2.4511 -2.9972)
			(stroke
				(width 0)
				(type default)
			)
			(fill no)
			(layer "F.CrtYd")
		)
		(fp_poly
			(pts
				(xy -2.8194 3.6322) (xy -2.8194 -3.6322) (xy 2.8194 -3.6322) (xy 2.8194 -2.2987) (xy 2.4511 -2.2987)
				(xy 2.4511 -2.9972) (xy -2.4511 -2.9972) (xy -2.4511 2.9972) (xy 2.4511 2.9972) (xy 2.4511 -2.286)
				(xy 2.8194 -2.286) (xy 2.8194 3.6322)
			)
			(stroke
				(width 0)
				(type default)
			)
			(fill no)
			(layer "F.CrtYd")
		)
		(fp_rect
			(start -2.8194 3.6322)
			(end 2.8194 -3.6322)
			(stroke
				(width 0)
				(type default)
			)
			(fill no)
			(layer "F.Fab")
		)
		(pad "1" smd rect
			(at -1.905 2.54 90)
			(size 0.635 1.651)
			(layers "F.Cu" "F.Mask" "F.Paste")
			(net "P3V3_STBY")
		)
		(pad "2" smd rect
			(at -0.635 2.54 90)
			(size 0.635 1.651)
			(layers "F.Cu" "F.Mask" "F.Paste")
			(net "P3V3_STBY")
		)
		(pad "3" smd rect
			(at 0.635 2.54 90)
			(size 0.635 1.651)
			(layers "F.Cu" "F.Mask" "F.Paste")
			(net "P3V3_STBY")
		)
		(pad "4" smd rect
			(at 1.905 2.54 90)
			(size 0.635 1.651)
			(layers "F.Cu" "F.Mask" "F.Paste")
			(net "Q3203_G")
		)
		(pad "5" smd rect
			(at 1.905 -2.54 90)
			(size 0.635 1.651)
			(layers "F.Cu" "F.Mask" "F.Paste")
			(net "P3V3_GPIO")
		)
		(pad "6" smd rect
			(at 0.635 -2.54 90)
			(size 0.635 1.651)
			(layers "F.Cu" "F.Mask" "F.Paste")
			(net "P3V3_GPIO")
		)
		(pad "7" smd rect
			(at -0.635 -2.54 90)
			(size 0.635 1.651)
			(layers "F.Cu" "F.Mask" "F.Paste")
			(net "P3V3_GPIO")
		)
		(pad "8" smd rect
			(at -1.905 -2.54 90)
			(size 0.635 1.651)
			(layers "F.Cu" "F.Mask" "F.Paste")
			(net "P3V3_GPIO")
		)
	)
	(footprint ""
		(layer "F.Cu")
		(at 35.247326 -146.48688 180)
		(property "Reference" "R248"
			(at 0 0 180)
			(layer "F.SilkS")
			(hide yes)
			(effects
				(font
					(size 1.27 1.27)
				)
			)
		)
		(property "Value" "240R2F-1-GP"
			(at 0.064008 -3.993896 180)
			(unlocked yes)
			(layer "F.Fab")
			(hide yes)
			(effects
				(font
					(size 1.016 1.016)
					(thickness 0.1524)
				)
			)
		)
		(property "Device Type" "R402H16"
			(at 0.064008 -5.517896 180)
			(unlocked yes)
			(layer "F.Fab")
			(hide yes)
			(effects
				(font
					(size 1.016 1.016)
					(thickness 0.1524)
				)
			)
		)
		(duplicate_pad_numbers_are_jumpers no)
		(fp_line
			(start 0.508 -0.9398)
			(end -0.508 -0.9398)
			(stroke
				(width 0.1524)
				(type default)
			)
			(layer "F.SilkS")
		)
		(fp_line
			(start -0.508 -0.9398)
			(end -0.508 0.9398)
			(stroke
				(width 0.1524)
				(type default)
			)
			(layer "F.SilkS")
		)
		(fp_rect
			(start -0.508 0.9398)
			(end 0.508 -0.9398)
			(stroke
				(width 0)
				(type default)
			)
			(fill no)
			(layer "F.CrtYd")
		)
		(fp_rect
			(start -0.508 0.9398)
			(end 0.508 -0.9398)
			(stroke
				(width 0)
				(type default)
			)
			(fill no)
			(layer "F.Fab")
		)
		(pad "1" smd custom
			(at 0 -0.4445 180)
			(size 0.1397 0.1397)
			(layers "F.Cu" "F.Mask" "F.Paste")
			(net "GND")
			(options
				(clearance outline)
				(anchor circle)
			)
			(primitives
				(gr_poly
					(pts
						(arc
							(start -0.1778 -0.2794)
							(mid -0.249642 -0.249642)
							(end -0.2794 -0.1778)
						)
						(arc
							(start -0.2794 0.1778)
							(mid -0.249642 0.249642)
							(end -0.1778 0.2794)
						)
						(arc
							(start 0.1778 0.2794)
							(mid 0.249642 0.249642)
							(end 0.2794 0.1778)
						)
						(arc
							(start 0.2794 -0.1778)
							(mid 0.249642 -0.249642)
							(end 0.1778 -0.2794)
						)
					)
					(width 0)
					(fill yes)
				)
			)
		)
		(pad "2" smd custom
			(at 0 0.4445 180)
			(size 0.1397 0.1397)
			(layers "F.Cu" "F.Mask" "F.Paste")
			(net "PD_ZQ")
			(options
				(clearance outline)
				(anchor circle)
			)
			(primitives
				(gr_poly
					(pts
						(arc
							(start -0.1778 -0.2794)
							(mid -0.249642 -0.249642)
							(end -0.2794 -0.1778)
						)
						(arc
							(start -0.2794 0.1778)
							(mid -0.249642 0.249642)
							(end -0.1778 0.2794)
						)
						(arc
							(start 0.1778 0.2794)
							(mid 0.249642 0.249642)
							(end 0.2794 0.1778)
						)
						(arc
							(start 0.2794 -0.1778)
							(mid 0.249642 -0.249642)
							(end 0.1778 -0.2794)
						)
					)
					(width 0)
					(fill yes)
				)
			)
		)
	)
	(footprint ""
		(layer "F.Cu")
		(at 23.876 -136.779 90)
		(property "Reference" "R366"
			(at 0 0 90)
			(layer "F.SilkS")
			(hide yes)
			(effects
				(font
					(size 1.27 1.27)
				)
			)
		)
		(property "Value" "3K3R2F-2-GP"
			(at 0.064008 -3.993896 90)
			(unlocked yes)
			(layer "F.Fab")
			(hide yes)
			(effects
				(font
					(size 1.016 1.016)
					(thickness 0.1524)
				)
			)
		)
		(property "Device Type" "R402H16"
			(at 0.064008 -5.517896 90)
			(unlocked yes)
			(layer "F.Fab")
			(hide yes)
			(effects
				(font
					(size 1.016 1.016)
					(thickness 0.1524)
				)
			)
		)
		(duplicate_pad_numbers_are_jumpers no)
		(fp_line
			(start 0.508 -0.9398)
			(end -0.508 -0.9398)
			(stroke
				(width 0.1524)
				(type default)
			)
			(layer "F.SilkS")
		)
		(fp_line
			(start -0.508 -0.9398)
			(end -0.508 0.9398)
			(stroke
				(width 0.1524)
				(type default)
			)
			(layer "F.SilkS")
		)
		(fp_rect
			(start -0.508 0.9398)
			(end 0.508 -0.9398)
			(stroke
				(width 0)
				(type default)
			)
			(fill no)
			(layer "F.CrtYd")
		)
		(fp_rect
			(start -0.508 0.9398)
			(end 0.508 -0.9398)
			(stroke
				(width 0)
				(type default)
			)
			(fill no)
			(layer "F.Fab")
		)
		(pad "1" smd custom
			(at 0 -0.4445 90)
			(size 0.1397 0.1397)
			(layers "F.Cu" "F.Mask" "F.Paste")
			(net "P3V3_STBY")
			(options
				(clearance outline)
				(anchor circle)
			)
			(primitives
				(gr_poly
					(pts
						(arc
							(start -0.1778 -0.2794)
							(mid -0.249642 -0.249642)
							(end -0.2794 -0.1778)
						)
						(arc
							(start -0.2794 0.1778)
							(mid -0.249642 0.249642)
							(end -0.1778 0.2794)
						)
						(arc
							(start 0.1778 0.2794)
							(mid 0.249642 0.249642)
							(end 0.2794 0.1778)
						)
						(arc
							(start 0.2794 -0.1778)
							(mid 0.249642 -0.249642)
							(end 0.1778 -0.2794)
						)
					)
					(width 0)
					(fill yes)
				)
			)
		)
		(pad "2" smd custom
			(at 0 0.4445 90)
			(size 0.1397 0.1397)
			(layers "F.Cu" "F.Mask" "F.Paste")
			(net "ROMD6")
			(options
				(clearance outline)
				(anchor circle)
			)
			(primitives
				(gr_poly
					(pts
						(arc
							(start -0.1778 -0.2794)
							(mid -0.249642 -0.249642)
							(end -0.2794 -0.1778)
						)
						(arc
							(start -0.2794 0.1778)
							(mid -0.249642 0.249642)
							(end -0.1778 0.2794)
						)
						(arc
							(start 0.1778 0.2794)
							(mid 0.249642 0.249642)
							(end 0.2794 0.1778)
						)
						(arc
							(start 0.2794 -0.1778)
							(mid 0.249642 -0.249642)
							(end 0.1778 -0.2794)
						)
					)
					(width 0)
					(fill yes)
				)
			)
		)
	)
	(footprint ""
		(layer "F.Cu")
		(at 267.4366 -8.2296)
		(property "Reference" "U79"
			(at 0 0 0)
			(layer "F.SilkS")
			(hide yes)
			(effects
				(font
					(size 1.27 1.27)
				)
			)
		)
		(property "Value" "ADM6315-29D2ARTZ-GP"
			(at -0.0127 -12.8016 0)
			(unlocked yes)
			(layer "F.Fab")
			(hide yes)
			(effects
				(font
					(size 1.016 1.016)
					(thickness 0.1524)
				)
			)
		)
		(property "Device Type" "SOT-143-6H49"
			(at -0.0635 -14.6812 0)
			(unlocked yes)
			(layer "F.Fab")
			(hide yes)
			(effects
				(font
					(size 1.016 1.016)
					(thickness 0.1524)
				)
			)
		)
		(duplicate_pad_numbers_are_jumpers no)
		(fp_line
			(start -1.7907 1.8669)
			(end -1.7907 0.3937)
			(stroke
				(width 0.3302)
				(type default)
			)
			(layer "F.SilkS")
		)
		(fp_line
			(start -1.6891 -1.778)
			(end 1.6891 -1.778)
			(stroke
				(width 0.1524)
				(type default)
			)
			(layer "F.SilkS")
		)
		(fp_line
			(start -1.6891 1.778)
			(end -1.6891 -1.778)
			(stroke
				(width 0.1524)
				(type default)
			)
			(layer "F.SilkS")
		)
		(fp_line
			(start -0.3175 1.8669)
			(end -1.7907 1.8669)
			(stroke
				(width 0.3302)
				(type default)
			)
			(layer "F.SilkS")
		)
		(fp_line
			(start 1.6891 -1.778)
			(end 1.6891 1.778)
			(stroke
				(width 0.1524)
				(type default)
			)
			(layer "F.SilkS")
		)
		(fp_line
			(start 1.6891 1.778)
			(end -1.6891 1.778)
			(stroke
				(width 0.1524)
				(type default)
			)
			(layer "F.SilkS")
		)
		(fp_poly
			(pts
				(xy -0.7239 1.8542) (xy -1.3335 2.4638) (xy -0.1143 2.4638)
			)
			(stroke
				(width 0)
				(type default)
			)
			(fill yes)
			(layer "F.SilkS")
		)
		(fp_rect
			(start -1.9431 2.032)
			(end 1.9431 -2.032)
			(stroke
				(width 0)
				(type default)
			)
			(fill no)
			(layer "F.CrtYd")
		)
		(fp_poly
			(pts
				(xy 1.9431 2.032) (xy 1.9431 -2.032) (xy -1.9431 -2.032) (xy -1.9431 2.032)
			)
			(stroke
				(width 0)
				(type default)
			)
			(fill no)
			(layer "F.Fab")
		)
		(pad "1" smd rect
			(at -0.75311 0.9652)
			(size 1.1176 1.1176)
			(layers "F.Cu" "F.Mask" "F.Paste")
			(net "GND")
		)
		(pad "2" smd rect
			(at 0.9525 0.9652)
			(size 0.7112 1.1176)
			(layers "F.Cu" "F.Mask" "F.Paste")
			(net "ADM6315_PM8536_RST#")
		)
		(pad "3" smd rect
			(at 0.9525 -0.9652)
			(size 0.7112 1.1176)
			(layers "F.Cu" "F.Mask" "F.Paste")
			(net "PM8536_RST#_LS_R")
		)
		(pad "4" smd rect
			(at -0.9525 -0.9652)
			(size 0.7112 1.1176)
			(layers "F.Cu" "F.Mask" "F.Paste")
			(net "P3V3_STBY")
		)
	)
	(footprint ""
		(layer "F.Cu")
		(at 186.629802 -8.098028 -90)
		(property "Reference" "R532"
			(at 0 0 270)
			(layer "F.SilkS")
			(hide yes)
			(effects
				(font
					(size 1.27 1.27)
				)
			)
		)
		(property "Value" "1KR2F-3-GP"
			(at 0.064008 -3.993896 270)
			(unlocked yes)
			(layer "F.Fab")
			(hide yes)
			(effects
				(font
					(size 1.016 1.016)
					(thickness 0.1524)
				)
			)
		)
		(property "Device Type" "R402H16"
			(at 0.064008 -5.517896 270)
			(unlocked yes)
			(layer "F.Fab")
			(hide yes)
			(effects
				(font
					(size 1.016 1.016)
					(thickness 0.1524)
				)
			)
		)
		(duplicate_pad_numbers_are_jumpers no)
		(fp_line
			(start -0.508 -0.9398)
			(end -0.508 0.9398)
			(stroke
				(width 0.1524)
				(type default)
			)
			(layer "F.SilkS")
		)
		(fp_line
			(start 0.508 -0.9398)
			(end -0.508 -0.9398)
			(stroke
				(width 0.1524)
				(type default)
			)
			(layer "F.SilkS")
		)
		(fp_rect
			(start -0.508 0.9398)
			(end 0.508 -0.9398)
			(stroke
				(width 0)
				(type default)
			)
			(fill no)
			(layer "F.CrtYd")
		)
		(fp_rect
			(start -0.508 0.9398)
			(end 0.508 -0.9398)
			(stroke
				(width 0)
				(type default)
			)
			(fill no)
			(layer "F.Fab")
		)
		(pad "1" smd custom
			(at 0 -0.4445 270)
			(size 0.1397 0.1397)
			(layers "F.Cu" "F.Mask" "F.Paste")
			(net "ENCLO_LED_BLUE_OUT")
			(options
				(clearance outline)
				(anchor circle)
			)
			(primitives
				(gr_poly
					(pts
						(arc
							(start -0.1778 -0.2794)
							(mid -0.249642 -0.249642)
							(end -0.2794 -0.1778)
						)
						(arc
							(start -0.2794 0.1778)
							(mid -0.249642 0.249642)
							(end -0.1778 0.2794)
						)
						(arc
							(start 0.1778 0.2794)
							(mid 0.249642 0.249642)
							(end 0.2794 0.1778)
						)
						(arc
							(start 0.2794 -0.1778)
							(mid 0.249642 -0.249642)
							(end 0.1778 -0.2794)
						)
					)
					(width 0)
					(fill yes)
				)
			)
		)
		(pad "2" smd custom
			(at 0 0.4445 270)
			(size 0.1397 0.1397)
			(layers "F.Cu" "F.Mask" "F.Paste")
			(net "ENCLO_LED_RED_G")
			(options
				(clearance outline)
				(anchor circle)
			)
			(primitives
				(gr_poly
					(pts
						(arc
							(start -0.1778 -0.2794)
							(mid -0.249642 -0.249642)
							(end -0.2794 -0.1778)
						)
						(arc
							(start -0.2794 0.1778)
							(mid -0.249642 0.249642)
							(end -0.1778 0.2794)
						)
						(arc
							(start 0.1778 0.2794)
							(mid 0.249642 0.249642)
							(end 0.2794 0.1778)
						)
						(arc
							(start 0.2794 -0.1778)
							(mid 0.249642 -0.249642)
							(end 0.1778 -0.2794)
						)
					)
					(width 0)
					(fill yes)
				)
			)
		)
	)
	(footprint ""
		(layer "F.Cu")
		(at 229.108 -89.916 90)
		(property "Reference" "R177"
			(at 0 0 90)
			(layer "F.SilkS")
			(hide yes)
			(effects
				(font
					(size 1.27 1.27)
				)
			)
		)
		(property "Value" "4K7R2F-GP"
			(at 0.064008 -3.993896 90)
			(unlocked yes)
			(layer "F.Fab")
			(hide yes)
			(effects
				(font
					(size 1.016 1.016)
					(thickness 0.1524)
				)
			)
		)
		(property "Device Type" "R402H16"
			(at 0.064008 -5.517896 90)
			(unlocked yes)
			(layer "F.Fab")
			(hide yes)
			(effects
				(font
					(size 1.016 1.016)
					(thickness 0.1524)
				)
			)
		)
		(duplicate_pad_numbers_are_jumpers no)
		(fp_line
			(start 0.508 -0.9398)
			(end -0.508 -0.9398)
			(stroke
				(width 0.1524)
				(type default)
			)
			(layer "F.SilkS")
		)
		(fp_line
			(start -0.508 -0.9398)
			(end -0.508 0.9398)
			(stroke
				(width 0.1524)
				(type default)
			)
			(layer "F.SilkS")
		)
		(fp_rect
			(start -0.508 0.9398)
			(end 0.508 -0.9398)
			(stroke
				(width 0)
				(type default)
			)
			(fill no)
			(layer "F.CrtYd")
		)
		(fp_rect
			(start -0.508 0.9398)
			(end 0.508 -0.9398)
			(stroke
				(width 0)
				(type default)
			)
			(fill no)
			(layer "F.Fab")
		)
		(pad "1" smd custom
			(at 0 -0.4445 90)
			(size 0.1397 0.1397)
			(layers "F.Cu" "F.Mask" "F.Paste")
			(net "TEMP_3_A1")
			(options
				(clearance outline)
				(anchor circle)
			)
			(primitives
				(gr_poly
					(pts
						(arc
							(start -0.1778 -0.2794)
							(mid -0.249642 -0.249642)
							(end -0.2794 -0.1778)
						)
						(arc
							(start -0.2794 0.1778)
							(mid -0.249642 0.249642)
							(end -0.1778 0.2794)
						)
						(arc
							(start 0.1778 0.2794)
							(mid 0.249642 0.249642)
							(end 0.2794 0.1778)
						)
						(arc
							(start 0.2794 -0.1778)
							(mid 0.249642 -0.249642)
							(end 0.1778 -0.2794)
						)
					)
					(width 0)
					(fill yes)
				)
			)
		)
		(pad "2" smd custom
			(at 0 0.4445 90)
			(size 0.1397 0.1397)
			(layers "F.Cu" "F.Mask" "F.Paste")
			(net "GND")
			(options
				(clearance outline)
				(anchor circle)
			)
			(primitives
				(gr_poly
					(pts
						(arc
							(start -0.1778 -0.2794)
							(mid -0.249642 -0.249642)
							(end -0.2794 -0.1778)
						)
						(arc
							(start -0.2794 0.1778)
							(mid -0.249642 0.249642)
							(end -0.1778 0.2794)
						)
						(arc
							(start 0.1778 0.2794)
							(mid 0.249642 0.249642)
							(end 0.2794 0.1778)
						)
						(arc
							(start 0.2794 -0.1778)
							(mid 0.249642 -0.249642)
							(end 0.1778 -0.2794)
						)
					)
					(width 0)
					(fill yes)
				)
			)
		)
	)
	(footprint ""
		(layer "F.Cu")
		(at 225.679 -23.241 180)
		(property "Reference" "R3722"
			(at 0 0 180)
			(layer "F.SilkS")
			(hide yes)
			(effects
				(font
					(size 1.27 1.27)
				)
			)
		)
		(property "Value" "4K7R2F-GP"
			(at 0.064008 -3.993896 180)
			(unlocked yes)
			(layer "F.Fab")
			(hide yes)
			(effects
				(font
					(size 1.016 1.016)
					(thickness 0.1524)
				)
			)
		)
		(property "Device Type" "R402H16"
			(at 0.064008 -5.517896 180)
			(unlocked yes)
			(layer "F.Fab")
			(hide yes)
			(effects
				(font
					(size 1.016 1.016)
					(thickness 0.1524)
				)
			)
		)
		(duplicate_pad_numbers_are_jumpers no)
		(fp_line
			(start 0.508 -0.9398)
			(end -0.508 -0.9398)
			(stroke
				(width 0.1524)
				(type default)
			)
			(layer "F.SilkS")
		)
		(fp_line
			(start -0.508 -0.9398)
			(end -0.508 0.9398)
			(stroke
				(width 0.1524)
				(type default)
			)
			(layer "F.SilkS")
		)
		(fp_rect
			(start -0.508 0.9398)
			(end 0.508 -0.9398)
			(stroke
				(width 0)
				(type default)
			)
			(fill no)
			(layer "F.CrtYd")
		)
		(fp_rect
			(start -0.508 0.9398)
			(end 0.508 -0.9398)
			(stroke
				(width 0)
				(type default)
			)
			(fill no)
			(layer "F.Fab")
		)
		(pad "1" smd custom
			(at 0 -0.4445 180)
			(size 0.1397 0.1397)
			(layers "F.Cu" "F.Mask" "F.Paste")
			(net "HOST5_RST_N_LS")
			(options
				(clearance outline)
				(anchor circle)
			)
			(primitives
				(gr_poly
					(pts
						(arc
							(start -0.1778 -0.2794)
							(mid -0.249642 -0.249642)
							(end -0.2794 -0.1778)
						)
						(arc
							(start -0.2794 0.1778)
							(mid -0.249642 0.249642)
							(end -0.1778 0.2794)
						)
						(arc
							(start 0.1778 0.2794)
							(mid 0.249642 0.249642)
							(end 0.2794 0.1778)
						)
						(arc
							(start 0.2794 -0.1778)
							(mid 0.249642 -0.249642)
							(end 0.1778 -0.2794)
						)
					)
					(width 0)
					(fill yes)
				)
			)
		)
		(pad "2" smd custom
			(at 0 0.4445 180)
			(size 0.1397 0.1397)
			(layers "F.Cu" "F.Mask" "F.Paste")
			(net "GND")
			(options
				(clearance outline)
				(anchor circle)
			)
			(primitives
				(gr_poly
					(pts
						(arc
							(start -0.1778 -0.2794)
							(mid -0.249642 -0.249642)
							(end -0.2794 -0.1778)
						)
						(arc
							(start -0.2794 0.1778)
							(mid -0.249642 0.249642)
							(end -0.1778 0.2794)
						)
						(arc
							(start 0.1778 0.2794)
							(mid 0.249642 0.249642)
							(end 0.2794 0.1778)
						)
						(arc
							(start 0.2794 -0.1778)
							(mid 0.249642 -0.249642)
							(end 0.1778 -0.2794)
						)
					)
					(width 0)
					(fill yes)
				)
			)
		)
	)
	(footprint ""
		(layer "F.Cu")
		(at 145.177002 -67.058032 -90)
		(property "Reference" "PC201"
			(at 0 0 270)
			(layer "F.SilkS")
			(hide yes)
			(effects
				(font
					(size 1.27 1.27)
				)
			)
		)
		(property "Value" "SC22U25V6KX-GP-U"
			(at -2.860802 -5.279644 270)
			(unlocked yes)
			(layer "F.Fab")
			(hide yes)
			(effects
				(font
					(size 1.016 1.016)
					(thickness 0.1524)
				)
			)
		)
		(property "Device Type" "C1206-TO0D3H75"
			(at -2.860802 -6.803644 270)
			(unlocked yes)
			(layer "F.Fab")
			(hide yes)
			(effects
				(font
					(size 1.016 1.016)
					(thickness 0.1524)
				)
			)
		)
		(duplicate_pad_numbers_are_jumpers no)
		(fp_line
			(start -1.3081 2.3749)
			(end -1.3081 -2.3749)
			(stroke
				(width 0.1524)
				(type default)
			)
			(layer "F.SilkS")
		)
		(fp_line
			(start 1.3081 2.3749)
			(end -1.3081 2.3749)
			(stroke
				(width 0.1524)
				(type default)
			)
			(layer "F.SilkS")
		)
		(fp_line
			(start -1.3081 -2.3749)
			(end 1.3081 -2.3749)
			(stroke
				(width 0.1524)
				(type default)
			)
			(layer "F.SilkS")
		)
		(fp_line
			(start 1.3081 -2.3749)
			(end 1.3081 2.3749)
			(stroke
				(width 0.1524)
				(type default)
			)
			(layer "F.SilkS")
		)
		(fp_rect
			(start -0.8001 1.6002)
			(end 0.8001 -1.6002)
			(stroke
				(width 0)
				(type default)
			)
			(fill no)
			(layer "F.CrtYd")
		)
		(fp_poly
			(pts
				(xy -1.5621 2.4511) (xy -1.5621 1.6002) (xy 0.8001 1.6002) (xy 0.8001 -1.6002) (xy -0.8001 -1.6002)
				(xy -0.8001 1.5875) (xy -1.5621 1.5875) (xy -1.5621 -2.4511) (xy 1.5621 -2.4511) (xy 1.5621 2.4511)
			)
			(stroke
				(width 0)
				(type default)
			)
			(fill no)
			(layer "F.CrtYd")
		)
		(fp_rect
			(start -1.5621 2.4511)
			(end 1.5621 -2.4511)
			(stroke
				(width 0)
				(type default)
			)
			(fill no)
			(layer "F.Fab")
		)
		(pad "1" smd rect
			(at 0 -1.392936 270)
			(size 2.1082 1.4478)
			(layers "F.Cu" "F.Mask" "F.Paste")
			(net "P0V9_VIN")
		)
		(pad "2" smd rect
			(at 0 1.392936 270)
			(size 2.1082 1.4478)
			(layers "F.Cu" "F.Mask" "F.Paste")
			(net "GND")
		)
	)
	(footprint ""
		(layer "F.Cu")
		(at 18.8722 -194.1576 180)
		(property "Reference" "R9028"
			(at 0 0 180)
			(layer "F.SilkS")
			(hide yes)
			(effects
				(font
					(size 1.27 1.27)
				)
			)
		)
		(property "Value" "43K2R2F-L-GP"
			(at 0.064008 -3.993896 180)
			(unlocked yes)
			(layer "F.Fab")
			(hide yes)
			(effects
				(font
					(size 1.016 1.016)
					(thickness 0.1524)
				)
			)
		)
		(property "Device Type" "R402H16"
			(at 0.064008 -5.517896 180)
			(unlocked yes)
			(layer "F.Fab")
			(hide yes)
			(effects
				(font
					(size 1.016 1.016)
					(thickness 0.1524)
				)
			)
		)
		(duplicate_pad_numbers_are_jumpers no)
		(fp_line
			(start 0.508 -0.9398)
			(end -0.508 -0.9398)
			(stroke
				(width 0.1524)
				(type default)
			)
			(layer "F.SilkS")
		)
		(fp_line
			(start -0.508 -0.9398)
			(end -0.508 0.9398)
			(stroke
				(width 0.1524)
				(type default)
			)
			(layer "F.SilkS")
		)
		(fp_rect
			(start -0.508 0.9398)
			(end 0.508 -0.9398)
			(stroke
				(width 0)
				(type default)
			)
			(fill no)
			(layer "F.CrtYd")
		)
		(fp_rect
			(start -0.508 0.9398)
			(end 0.508 -0.9398)
			(stroke
				(width 0)
				(type default)
			)
			(fill no)
			(layer "F.Fab")
		)
		(pad "1" smd custom
			(at 0 -0.4445 180)
			(size 0.1397 0.1397)
			(layers "F.Cu" "F.Mask" "F.Paste")
			(net "MB0_PSET_R")
			(options
				(clearance outline)
				(anchor circle)
			)
			(primitives
				(gr_poly
					(pts
						(arc
							(start -0.1778 -0.2794)
							(mid -0.249642 -0.249642)
							(end -0.2794 -0.1778)
						)
						(arc
							(start -0.2794 0.1778)
							(mid -0.249642 0.249642)
							(end -0.1778 0.2794)
						)
						(arc
							(start 0.1778 0.2794)
							(mid 0.249642 0.249642)
							(end 0.2794 0.1778)
						)
						(arc
							(start 0.2794 -0.1778)
							(mid 0.249642 -0.249642)
							(end 0.1778 -0.2794)
						)
					)
					(width 0)
					(fill yes)
				)
			)
		)
		(pad "2" smd custom
			(at 0 0.4445 180)
			(size 0.1397 0.1397)
			(layers "F.Cu" "F.Mask" "F.Paste")
			(net "AGND_CURRENT_MON")
			(options
				(clearance outline)
				(anchor circle)
			)
			(primitives
				(gr_poly
					(pts
						(arc
							(start -0.1778 -0.2794)
							(mid -0.249642 -0.249642)
							(end -0.2794 -0.1778)
						)
						(arc
							(start -0.2794 0.1778)
							(mid -0.249642 0.249642)
							(end -0.1778 0.2794)
						)
						(arc
							(start 0.1778 0.2794)
							(mid 0.249642 0.249642)
							(end 0.2794 0.1778)
						)
						(arc
							(start 0.2794 -0.1778)
							(mid 0.249642 -0.249642)
							(end 0.1778 -0.2794)
						)
					)
					(width 0)
					(fill yes)
				)
			)
		)
	)
	(footprint ""
		(layer "F.Cu")
		(at 140.843 -41.4782 180)
		(property "Reference" "R761"
			(at 0 0 180)
			(layer "F.SilkS")
			(hide yes)
			(effects
				(font
					(size 1.27 1.27)
				)
			)
		)
		(property "Value" "0R2J-2-GP"
			(at 0.064008 -3.993896 180)
			(unlocked yes)
			(layer "F.Fab")
			(hide yes)
			(effects
				(font
					(size 1.016 1.016)
					(thickness 0.1524)
				)
			)
		)
		(property "Device Type" "R402H16"
			(at 0.064008 -5.517896 180)
			(unlocked yes)
			(layer "F.Fab")
			(hide yes)
			(effects
				(font
					(size 1.016 1.016)
					(thickness 0.1524)
				)
			)
		)
		(duplicate_pad_numbers_are_jumpers no)
		(fp_line
			(start 0.508 -0.9398)
			(end -0.508 -0.9398)
			(stroke
				(width 0.1524)
				(type default)
			)
			(layer "F.SilkS")
		)
		(fp_line
			(start -0.508 -0.9398)
			(end -0.508 0.9398)
			(stroke
				(width 0.1524)
				(type default)
			)
			(layer "F.SilkS")
		)
		(fp_rect
			(start -0.508 0.9398)
			(end 0.508 -0.9398)
			(stroke
				(width 0)
				(type default)
			)
			(fill no)
			(layer "F.CrtYd")
		)
		(fp_rect
			(start -0.508 0.9398)
			(end 0.508 -0.9398)
			(stroke
				(width 0)
				(type default)
			)
			(fill no)
			(layer "F.Fab")
		)
		(pad "1" smd custom
			(at 0 -0.4445 180)
			(size 0.1397 0.1397)
			(layers "F.Cu" "F.Mask" "F.Paste")
			(net "EJTAG_TMS_R")
			(options
				(clearance outline)
				(anchor circle)
			)
			(primitives
				(gr_poly
					(pts
						(arc
							(start -0.1778 -0.2794)
							(mid -0.249642 -0.249642)
							(end -0.2794 -0.1778)
						)
						(arc
							(start -0.2794 0.1778)
							(mid -0.249642 0.249642)
							(end -0.1778 0.2794)
						)
						(arc
							(start 0.1778 0.2794)
							(mid 0.249642 0.249642)
							(end 0.2794 0.1778)
						)
						(arc
							(start 0.2794 -0.1778)
							(mid 0.249642 -0.249642)
							(end 0.1778 -0.2794)
						)
					)
					(width 0)
					(fill yes)
				)
			)
		)
		(pad "2" smd custom
			(at 0 0.4445 180)
			(size 0.1397 0.1397)
			(layers "F.Cu" "F.Mask" "F.Paste")
			(net "EJTAG_TMS")
			(options
				(clearance outline)
				(anchor circle)
			)
			(primitives
				(gr_poly
					(pts
						(arc
							(start -0.1778 -0.2794)
							(mid -0.249642 -0.249642)
							(end -0.2794 -0.1778)
						)
						(arc
							(start -0.2794 0.1778)
							(mid -0.249642 0.249642)
							(end -0.1778 0.2794)
						)
						(arc
							(start 0.1778 0.2794)
							(mid 0.249642 0.249642)
							(end 0.2794 0.1778)
						)
						(arc
							(start 0.2794 -0.1778)
							(mid 0.249642 -0.249642)
							(end 0.1778 -0.2794)
						)
					)
					(width 0)
					(fill yes)
				)
			)
		)
	)
	(footprint ""
		(layer "F.Cu")
		(at 27.6352 -53.8988 90)
		(property "Reference" "R539"
			(at 0 0 90)
			(layer "F.SilkS")
			(hide yes)
			(effects
				(font
					(size 1.27 1.27)
				)
			)
		)
		(property "Value" "0R2J-2-GP"
			(at 0.064008 -3.993896 90)
			(unlocked yes)
			(layer "F.Fab")
			(hide yes)
			(effects
				(font
					(size 1.016 1.016)
					(thickness 0.1524)
				)
			)
		)
		(property "Device Type" "R402H16"
			(at 0.064008 -5.517896 90)
			(unlocked yes)
			(layer "F.Fab")
			(hide yes)
			(effects
				(font
					(size 1.016 1.016)
					(thickness 0.1524)
				)
			)
		)
		(duplicate_pad_numbers_are_jumpers no)
		(fp_line
			(start 0.508 -0.9398)
			(end -0.508 -0.9398)
			(stroke
				(width 0.1524)
				(type default)
			)
			(layer "F.SilkS")
		)
		(fp_line
			(start -0.508 -0.9398)
			(end -0.508 0.9398)
			(stroke
				(width 0.1524)
				(type default)
			)
			(layer "F.SilkS")
		)
		(fp_rect
			(start -0.508 0.9398)
			(end 0.508 -0.9398)
			(stroke
				(width 0)
				(type default)
			)
			(fill no)
			(layer "F.CrtYd")
		)
		(fp_rect
			(start -0.508 0.9398)
			(end 0.508 -0.9398)
			(stroke
				(width 0)
				(type default)
			)
			(fill no)
			(layer "F.Fab")
		)
		(pad "1" smd custom
			(at 0 -0.4445 90)
			(size 0.1397 0.1397)
			(layers "F.Cu" "F.Mask" "F.Paste")
			(net "LED_MDI0_1G_N")
			(options
				(clearance outline)
				(anchor circle)
			)
			(primitives
				(gr_poly
					(pts
						(arc
							(start -0.1778 -0.2794)
							(mid -0.249642 -0.249642)
							(end -0.2794 -0.1778)
						)
						(arc
							(start -0.2794 0.1778)
							(mid -0.249642 0.249642)
							(end -0.1778 0.2794)
						)
						(arc
							(start 0.1778 0.2794)
							(mid 0.249642 0.249642)
							(end 0.2794 0.1778)
						)
						(arc
							(start 0.2794 -0.1778)
							(mid 0.249642 -0.249642)
							(end 0.1778 -0.2794)
						)
					)
					(width 0)
					(fill yes)
				)
			)
		)
		(pad "2" smd custom
			(at 0 0.4445 90)
			(size 0.1397 0.1397)
			(layers "F.Cu" "F.Mask" "F.Paste")
			(net "LED_MDI0_1G_N_R")
			(options
				(clearance outline)
				(anchor circle)
			)
			(primitives
				(gr_poly
					(pts
						(arc
							(start -0.1778 -0.2794)
							(mid -0.249642 -0.249642)
							(end -0.2794 -0.1778)
						)
						(arc
							(start -0.2794 0.1778)
							(mid -0.249642 0.249642)
							(end -0.1778 0.2794)
						)
						(arc
							(start 0.1778 0.2794)
							(mid 0.249642 0.249642)
							(end 0.2794 0.1778)
						)
						(arc
							(start 0.2794 -0.1778)
							(mid 0.249642 -0.249642)
							(end 0.1778 -0.2794)
						)
					)
					(width 0)
					(fill yes)
				)
			)
		)
	)
	(footprint ""
		(layer "F.Cu")
		(at 72.5678 -160.0708 -90)
		(property "Reference" "PR23"
			(at 0 0 270)
			(layer "F.SilkS")
			(hide yes)
			(effects
				(font
					(size 1.27 1.27)
				)
			)
		)
		(property "Value" "0R3J-0-U-GP"
			(at -0.0254 -2.5146 270)
			(unlocked yes)
			(layer "F.Fab")
			(hide yes)
			(effects
				(font
					(size 1.016 1.016)
					(thickness 0.1524)
				)
			)
		)
		(property "Device Type" "R603H22"
			(at -0.0254 -4.0386 270)
			(unlocked yes)
			(layer "F.Fab")
			(hide yes)
			(effects
				(font
					(size 1.016 1.016)
					(thickness 0.1524)
				)
			)
		)
		(duplicate_pad_numbers_are_jumpers no)
		(fp_line
			(start -0.4826 0)
			(end -0.2032 0)
			(stroke
				(width 0.2032)
				(type default)
			)
			(layer "F.SilkS")
		)
		(fp_line
			(start 0.2032 0)
			(end 0.4826 0)
			(stroke
				(width 0.2032)
				(type default)
			)
			(layer "F.SilkS")
		)
		(fp_rect
			(start -0.5842 1.3335)
			(end 0.5842 -1.3335)
			(stroke
				(width 0)
				(type default)
			)
			(fill no)
			(layer "F.CrtYd")
		)
		(fp_rect
			(start -0.5842 1.3335)
			(end 0.5842 -1.3335)
			(stroke
				(width 0)
				(type default)
			)
			(fill no)
			(layer "F.Fab")
		)
		(pad "1" smd custom
			(at 0 -0.762 270)
			(size 0.2159 0.2159)
			(layers "F.Cu" "F.Mask" "F.Paste")
			(net "P3V3_STBY")
			(options
				(clearance outline)
				(anchor circle)
			)
			(primitives
				(gr_poly
					(pts
						(arc
							(start -0.3302 -0.4318)
							(mid -0.402042 -0.402042)
							(end -0.4318 -0.3302)
						)
						(arc
							(start -0.4318 0.3302)
							(mid -0.402042 0.402042)
							(end -0.3302 0.4318)
						)
						(arc
							(start 0.3302 0.4318)
							(mid 0.402042 0.402042)
							(end 0.4318 0.3302)
						)
						(arc
							(start 0.4318 -0.3302)
							(mid 0.402042 -0.402042)
							(end 0.3302 -0.4318)
						)
					)
					(width 0)
					(fill yes)
				)
			)
		)
		(pad "2" smd custom
			(at 0 0.762 270)
			(size 0.2159 0.2159)
			(layers "F.Cu" "F.Mask" "F.Paste")
			(net "VR_P1V538_STBY_IN")
			(options
				(clearance outline)
				(anchor circle)
			)
			(primitives
				(gr_poly
					(pts
						(arc
							(start -0.3302 -0.4318)
							(mid -0.402042 -0.402042)
							(end -0.4318 -0.3302)
						)
						(arc
							(start -0.4318 0.3302)
							(mid -0.402042 0.402042)
							(end -0.3302 0.4318)
						)
						(arc
							(start 0.3302 0.4318)
							(mid 0.402042 0.402042)
							(end 0.4318 0.3302)
						)
						(arc
							(start 0.4318 -0.3302)
							(mid 0.402042 -0.402042)
							(end 0.3302 -0.4318)
						)
					)
					(width 0)
					(fill yes)
				)
			)
		)
	)
	(footprint ""
		(layer "F.Cu")
		(at 50.292 -185.293 90)
		(property "Reference" "R897"
			(at 0 0 90)
			(layer "F.SilkS")
			(hide yes)
			(effects
				(font
					(size 1.27 1.27)
				)
			)
		)
		(property "Value" "4K7R2J-2-GP"
			(at 0.064008 -3.993896 90)
			(unlocked yes)
			(layer "F.Fab")
			(hide yes)
			(effects
				(font
					(size 1.016 1.016)
					(thickness 0.1524)
				)
			)
		)
		(property "Device Type" "R402H16"
			(at 0.064008 -5.517896 90)
			(unlocked yes)
			(layer "F.Fab")
			(hide yes)
			(effects
				(font
					(size 1.016 1.016)
					(thickness 0.1524)
				)
			)
		)
		(duplicate_pad_numbers_are_jumpers no)
		(fp_line
			(start 0.508 -0.9398)
			(end -0.508 -0.9398)
			(stroke
				(width 0.1524)
				(type default)
			)
			(layer "F.SilkS")
		)
		(fp_line
			(start -0.508 -0.9398)
			(end -0.508 0.9398)
			(stroke
				(width 0.1524)
				(type default)
			)
			(layer "F.SilkS")
		)
		(fp_rect
			(start -0.508 0.9398)
			(end 0.508 -0.9398)
			(stroke
				(width 0)
				(type default)
			)
			(fill no)
			(layer "F.CrtYd")
		)
		(fp_rect
			(start -0.508 0.9398)
			(end 0.508 -0.9398)
			(stroke
				(width 0)
				(type default)
			)
			(fill no)
			(layer "F.Fab")
		)
		(pad "1" smd custom
			(at 0 -0.4445 90)
			(size 0.1397 0.1397)
			(layers "F.Cu" "F.Mask" "F.Paste")
			(net "P3V3_STBY")
			(options
				(clearance outline)
				(anchor circle)
			)
			(primitives
				(gr_poly
					(pts
						(arc
							(start -0.1778 -0.2794)
							(mid -0.249642 -0.249642)
							(end -0.2794 -0.1778)
						)
						(arc
							(start -0.2794 0.1778)
							(mid -0.249642 0.249642)
							(end -0.1778 0.2794)
						)
						(arc
							(start 0.1778 0.2794)
							(mid 0.249642 0.249642)
							(end 0.2794 0.1778)
						)
						(arc
							(start 0.2794 -0.1778)
							(mid 0.249642 -0.249642)
							(end 0.1778 -0.2794)
						)
					)
					(width 0)
					(fill yes)
				)
			)
		)
		(pad "2" smd custom
			(at 0 0.4445 90)
			(size 0.1397 0.1397)
			(layers "F.Cu" "F.Mask" "F.Paste")
			(net "BUF_I2C8_CLKBUF1_SDA_R")
			(options
				(clearance outline)
				(anchor circle)
			)
			(primitives
				(gr_poly
					(pts
						(arc
							(start -0.1778 -0.2794)
							(mid -0.249642 -0.249642)
							(end -0.2794 -0.1778)
						)
						(arc
							(start -0.2794 0.1778)
							(mid -0.249642 0.249642)
							(end -0.1778 0.2794)
						)
						(arc
							(start 0.1778 0.2794)
							(mid 0.249642 0.249642)
							(end 0.2794 0.1778)
						)
						(arc
							(start 0.2794 -0.1778)
							(mid 0.249642 -0.249642)
							(end 0.1778 -0.2794)
						)
					)
					(width 0)
					(fill yes)
				)
			)
		)
	)
	(footprint ""
		(layer "F.Cu")
		(at 161.544 -85.2424)
		(property "Reference" "R3102"
			(at 0 0 0)
			(layer "F.SilkS")
			(hide yes)
			(effects
				(font
					(size 1.27 1.27)
				)
			)
		)
		(property "Value" "27R2F-GP"
			(at 0.064008 -3.993896 0)
			(unlocked yes)
			(layer "F.Fab")
			(hide yes)
			(effects
				(font
					(size 1.016 1.016)
					(thickness 0.1524)
				)
			)
		)
		(property "Device Type" "R402H16"
			(at 0.064008 -5.517896 0)
			(unlocked yes)
			(layer "F.Fab")
			(hide yes)
			(effects
				(font
					(size 1.016 1.016)
					(thickness 0.1524)
				)
			)
		)
		(duplicate_pad_numbers_are_jumpers no)
		(fp_line
			(start -0.508 -0.9398)
			(end -0.508 0.9398)
			(stroke
				(width 0.1524)
				(type default)
			)
			(layer "F.SilkS")
		)
		(fp_line
			(start 0.508 -0.9398)
			(end -0.508 -0.9398)
			(stroke
				(width 0.1524)
				(type default)
			)
			(layer "F.SilkS")
		)
		(fp_rect
			(start -0.508 0.9398)
			(end 0.508 -0.9398)
			(stroke
				(width 0)
				(type default)
			)
			(fill no)
			(layer "F.CrtYd")
		)
		(fp_rect
			(start -0.508 0.9398)
			(end 0.508 -0.9398)
			(stroke
				(width 0)
				(type default)
			)
			(fill no)
			(layer "F.Fab")
		)
		(pad "1" smd custom
			(at 0 -0.4445)
			(size 0.1397 0.1397)
			(layers "F.Cu" "F.Mask" "F.Paste")
			(net "PCIE_REFCLK_D_P_R")
			(options
				(clearance outline)
				(anchor circle)
			)
			(primitives
				(gr_poly
					(pts
						(arc
							(start -0.1778 -0.2794)
							(mid -0.249642 -0.249642)
							(end -0.2794 -0.1778)
						)
						(arc
							(start -0.2794 0.1778)
							(mid -0.249642 0.249642)
							(end -0.1778 0.2794)
						)
						(arc
							(start 0.1778 0.2794)
							(mid 0.249642 0.249642)
							(end 0.2794 0.1778)
						)
						(arc
							(start 0.2794 -0.1778)
							(mid 0.249642 -0.249642)
							(end 0.1778 -0.2794)
						)
					)
					(width 0)
					(fill yes)
				)
			)
		)
		(pad "2" smd custom
			(at 0 0.4445)
			(size 0.1397 0.1397)
			(layers "F.Cu" "F.Mask" "F.Paste")
			(net "PCIE_REFCLK_D_P")
			(options
				(clearance outline)
				(anchor circle)
			)
			(primitives
				(gr_poly
					(pts
						(arc
							(start -0.1778 -0.2794)
							(mid -0.249642 -0.249642)
							(end -0.2794 -0.1778)
						)
						(arc
							(start -0.2794 0.1778)
							(mid -0.249642 0.249642)
							(end -0.1778 0.2794)
						)
						(arc
							(start 0.1778 0.2794)
							(mid 0.249642 0.249642)
							(end 0.2794 0.1778)
						)
						(arc
							(start 0.2794 -0.1778)
							(mid 0.249642 -0.249642)
							(end 0.1778 -0.2794)
						)
					)
					(width 0)
					(fill yes)
				)
			)
		)
	)
	(footprint ""
		(layer "F.Cu")
		(at 52.7558 -113.284 -90)
		(property "Reference" "R441"
			(at 0 0 270)
			(layer "F.SilkS")
			(hide yes)
			(effects
				(font
					(size 1.27 1.27)
				)
			)
		)
		(property "Value" "4K7R2F-GP"
			(at 0.064008 -3.993896 270)
			(unlocked yes)
			(layer "F.Fab")
			(hide yes)
			(effects
				(font
					(size 1.016 1.016)
					(thickness 0.1524)
				)
			)
		)
		(property "Device Type" "R402H16"
			(at 0.064008 -5.517896 270)
			(unlocked yes)
			(layer "F.Fab")
			(hide yes)
			(effects
				(font
					(size 1.016 1.016)
					(thickness 0.1524)
				)
			)
		)
		(duplicate_pad_numbers_are_jumpers no)
		(fp_line
			(start -0.508 -0.9398)
			(end -0.508 0.9398)
			(stroke
				(width 0.1524)
				(type default)
			)
			(layer "F.SilkS")
		)
		(fp_line
			(start 0.508 -0.9398)
			(end -0.508 -0.9398)
			(stroke
				(width 0.1524)
				(type default)
			)
			(layer "F.SilkS")
		)
		(fp_rect
			(start -0.508 0.9398)
			(end 0.508 -0.9398)
			(stroke
				(width 0)
				(type default)
			)
			(fill no)
			(layer "F.CrtYd")
		)
		(fp_rect
			(start -0.508 0.9398)
			(end 0.508 -0.9398)
			(stroke
				(width 0)
				(type default)
			)
			(fill no)
			(layer "F.Fab")
		)
		(pad "1" smd custom
			(at 0 -0.4445 270)
			(size 0.1397 0.1397)
			(layers "F.Cu" "F.Mask" "F.Paste")
			(net "BMC_I2C13_MINI7_SDA_S")
			(options
				(clearance outline)
				(anchor circle)
			)
			(primitives
				(gr_poly
					(pts
						(arc
							(start -0.1778 -0.2794)
							(mid -0.249642 -0.249642)
							(end -0.2794 -0.1778)
						)
						(arc
							(start -0.2794 0.1778)
							(mid -0.249642 0.249642)
							(end -0.1778 0.2794)
						)
						(arc
							(start 0.1778 0.2794)
							(mid 0.249642 0.249642)
							(end 0.2794 0.1778)
						)
						(arc
							(start 0.2794 -0.1778)
							(mid 0.249642 -0.249642)
							(end 0.1778 -0.2794)
						)
					)
					(width 0)
					(fill yes)
				)
			)
		)
		(pad "2" smd custom
			(at 0 0.4445 270)
			(size 0.1397 0.1397)
			(layers "F.Cu" "F.Mask" "F.Paste")
			(net "P3V3_STBY")
			(options
				(clearance outline)
				(anchor circle)
			)
			(primitives
				(gr_poly
					(pts
						(arc
							(start -0.1778 -0.2794)
							(mid -0.249642 -0.249642)
							(end -0.2794 -0.1778)
						)
						(arc
							(start -0.2794 0.1778)
							(mid -0.249642 0.249642)
							(end -0.1778 0.2794)
						)
						(arc
							(start 0.1778 0.2794)
							(mid 0.249642 0.249642)
							(end 0.2794 0.1778)
						)
						(arc
							(start 0.2794 -0.1778)
							(mid 0.249642 -0.249642)
							(end 0.1778 -0.2794)
						)
					)
					(width 0)
					(fill yes)
				)
			)
		)
	)
	(footprint ""
		(layer "F.Cu")
		(at 180.600096 -17.500092 -90)
		(property "Reference" "LED18"
			(at 0 0 270)
			(layer "F.SilkS")
			(hide yes)
			(effects
				(font
					(size 1.27 1.27)
				)
			)
		)
		(property "Value" "LED-YG-51-GP"
			(at -2.6924 -1.4224 270)
			(unlocked yes)
			(layer "F.Fab")
			(hide yes)
			(effects
				(font
					(size 1.016 1.016)
					(thickness 0.1524)
				)
			)
		)
		(property "Device Type" "LED1608AKH40"
			(at -2.6924 -2.9464 270)
			(unlocked yes)
			(layer "F.Fab")
			(hide yes)
			(effects
				(font
					(size 1.016 1.016)
					(thickness 0.1524)
				)
			)
		)
		(duplicate_pad_numbers_are_jumpers no)
		(fp_line
			(start -0.7493 1.651)
			(end -0.7493 1.1811)
			(stroke
				(width 0.3302)
				(type default)
			)
			(layer "F.SilkS")
		)
		(fp_line
			(start 0.7493 1.651)
			(end 0.7493 1.1811)
			(stroke
				(width 0.3302)
				(type default)
			)
			(layer "F.SilkS")
		)
		(fp_line
			(start -0.5969 1.5494)
			(end 0.5842 1.5494)
			(stroke
				(width 0.508)
				(type default)
			)
			(layer "F.SilkS")
		)
		(fp_line
			(start -0.6604 1.3716)
			(end -0.6604 -1.3716)
			(stroke
				(width 0.1524)
				(type default)
			)
			(layer "F.SilkS")
		)
		(fp_line
			(start 0.6604 1.3716)
			(end -0.6604 1.3716)
			(stroke
				(width 0.1524)
				(type default)
			)
			(layer "F.SilkS")
		)
		(fp_line
			(start -0.6604 -1.3716)
			(end 0.6604 -1.3716)
			(stroke
				(width 0.1524)
				(type default)
			)
			(layer "F.SilkS")
		)
		(fp_line
			(start 0.6604 -1.3716)
			(end 0.6604 1.3716)
			(stroke
				(width 0.1524)
				(type default)
			)
			(layer "F.SilkS")
		)
		(fp_rect
			(start -0.6223 1.3335)
			(end 0.6223 -1.3335)
			(stroke
				(width 0)
				(type default)
			)
			(fill no)
			(layer "F.CrtYd")
		)
		(fp_rect
			(start -0.6223 1.3335)
			(end 0.6223 -1.3335)
			(stroke
				(width 0)
				(type default)
			)
			(fill no)
			(layer "F.Fab")
		)
		(pad "A" smd custom
			(at 0 -0.762 270)
			(size 0.2159 0.2159)
			(layers "F.Cu" "F.Mask" "F.Paste")
			(net "LED_R_9")
			(options
				(clearance outline)
				(anchor circle)
			)
			(primitives
				(gr_poly
					(pts
						(arc
							(start -0.3302 -0.4318)
							(mid -0.402042 -0.402042)
							(end -0.4318 -0.3302)
						)
						(arc
							(start -0.4318 0.3302)
							(mid -0.402042 0.402042)
							(end -0.3302 0.4318)
						)
						(arc
							(start 0.3302 0.4318)
							(mid 0.402042 0.402042)
							(end 0.4318 0.3302)
						)
						(arc
							(start 0.4318 -0.3302)
							(mid 0.402042 -0.402042)
							(end 0.3302 -0.4318)
						)
					)
					(width 0)
					(fill yes)
				)
			)
		)
		(pad "K" smd custom
			(at 0 0.762 270)
			(size 0.2159 0.2159)
			(layers "F.Cu" "F.Mask" "F.Paste")
			(net "LED_Q_9")
			(options
				(clearance outline)
				(anchor circle)
			)
			(primitives
				(gr_poly
					(pts
						(arc
							(start -0.3302 -0.4318)
							(mid -0.402042 -0.402042)
							(end -0.4318 -0.3302)
						)
						(arc
							(start -0.4318 0.3302)
							(mid -0.402042 0.402042)
							(end -0.3302 0.4318)
						)
						(arc
							(start 0.3302 0.4318)
							(mid 0.402042 0.402042)
							(end 0.4318 0.3302)
						)
						(arc
							(start 0.4318 -0.3302)
							(mid 0.402042 -0.402042)
							(end 0.3302 -0.4318)
						)
					)
					(width 0)
					(fill yes)
				)
			)
		)
	)
	(footprint ""
		(layer "F.Cu")
		(at 62.0522 -58.928 180)
		(property "Reference" "C284"
			(at 0 0 180)
			(layer "F.SilkS")
			(hide yes)
			(effects
				(font
					(size 1.27 1.27)
				)
			)
		)
		(property "Value" "SCD01U16V2KX-3GP"
			(at 1.1811 -2.7051 180)
			(unlocked yes)
			(layer "F.Fab")
			(hide yes)
			(effects
				(font
					(size 1.016 1.016)
					(thickness 0.1524)
				)
			)
		)
		(property "Device Type" "C402H22"
			(at 1.1811 -4.2291 180)
			(unlocked yes)
			(layer "F.Fab")
			(hide yes)
			(effects
				(font
					(size 1.016 1.016)
					(thickness 0.1524)
				)
			)
		)
		(duplicate_pad_numbers_are_jumpers no)
		(fp_rect
			(start -0.4318 0.9525)
			(end 0.4318 -0.9525)
			(stroke
				(width 0)
				(type default)
			)
			(fill no)
			(layer "F.CrtYd")
		)
		(fp_rect
			(start -0.4318 0.9525)
			(end 0.4318 -0.9525)
			(stroke
				(width 0)
				(type default)
			)
			(fill no)
			(layer "F.Fab")
		)
		(pad "1" smd custom
			(at 0 -0.4445 180)
			(size 0.1524 0.1524)
			(layers "F.Cu" "F.Mask" "F.Paste")
			(net "P3V3_STBY")
			(options
				(clearance outline)
				(anchor circle)
			)
			(primitives
				(gr_poly
					(pts
						(arc
							(start 0.3048 -0.2032)
							(mid 0.275042 -0.275042)
							(end 0.2032 -0.3048)
						)
						(arc
							(start -0.2032 -0.3048)
							(mid -0.275042 -0.275042)
							(end -0.3048 -0.2032)
						)
						(arc
							(start -0.3048 0.2032)
							(mid -0.275042 0.275042)
							(end -0.2032 0.3048)
						)
						(arc
							(start 0.2032 0.3048)
							(mid 0.275042 0.275042)
							(end 0.3048 0.2032)
						)
					)
					(width 0)
					(fill yes)
				)
			)
		)
		(pad "2" smd custom
			(at 0 0.4445 180)
			(size 0.1524 0.1524)
			(layers "F.Cu" "F.Mask" "F.Paste")
			(net "GND")
			(options
				(clearance outline)
				(anchor circle)
			)
			(primitives
				(gr_poly
					(pts
						(arc
							(start 0.3048 -0.2032)
							(mid 0.275042 -0.275042)
							(end 0.2032 -0.3048)
						)
						(arc
							(start -0.2032 -0.3048)
							(mid -0.275042 -0.275042)
							(end -0.3048 -0.2032)
						)
						(arc
							(start -0.3048 0.2032)
							(mid -0.275042 0.275042)
							(end -0.2032 0.3048)
						)
						(arc
							(start 0.2032 0.3048)
							(mid 0.275042 0.275042)
							(end 0.3048 0.2032)
						)
					)
					(width 0)
					(fill yes)
				)
			)
		)
	)
	(footprint ""
		(layer "F.Cu")
		(at 152.527 -91.8464 90)
		(property "Reference" "X3"
			(at 0 0 90)
			(layer "F.SilkS")
			(hide yes)
			(effects
				(font
					(size 1.27 1.27)
				)
			)
		)
		(property "Value" "XTAL-25MHZ-266-GP"
			(at 0 -4.182618 90)
			(unlocked yes)
			(layer "F.Fab")
			(hide yes)
			(effects
				(font
					(size 1.016 1.016)
					(thickness 0.1524)
				)
			)
		)
		(property "Device Type" "OSC-3225-4P-4H32"
			(at 0 -5.706618 90)
			(unlocked yes)
			(layer "F.Fab")
			(hide yes)
			(effects
				(font
					(size 1.016 1.016)
					(thickness 0.1524)
				)
			)
		)
		(duplicate_pad_numbers_are_jumpers no)
		(fp_line
			(start 2.1209 -1.5494)
			(end -2.1209 -1.5494)
			(stroke
				(width 0.1524)
				(type default)
			)
			(layer "F.SilkS")
		)
		(fp_line
			(start -2.1209 -1.5494)
			(end -2.1209 1.5494)
			(stroke
				(width 0.1524)
				(type default)
			)
			(layer "F.SilkS")
		)
		(fp_line
			(start 2.1209 1.5494)
			(end 2.1209 -1.5494)
			(stroke
				(width 0.1524)
				(type default)
			)
			(layer "F.SilkS")
		)
		(fp_line
			(start -2.1209 1.5494)
			(end 2.1209 1.5494)
			(stroke
				(width 0.1524)
				(type default)
			)
			(layer "F.SilkS")
		)
		(fp_line
			(start -1.3208 1.651)
			(end -2.2098 1.651)
			(stroke
				(width 0.3302)
				(type default)
			)
			(layer "F.SilkS")
		)
		(fp_line
			(start -2.2098 1.651)
			(end -2.2098 0.6858)
			(stroke
				(width 0.3302)
				(type default)
			)
			(layer "F.SilkS")
		)
		(fp_poly
			(pts
				(xy -2.6289 1.1938) (xy -2.6289 0.3302) (xy -2.1971 0.762)
			)
			(stroke
				(width 0)
				(type default)
			)
			(fill yes)
			(layer "F.SilkS")
		)
		(fp_rect
			(start -1.6002 1.2446)
			(end 1.6002 -1.2446)
			(stroke
				(width 0)
				(type default)
			)
			(fill no)
			(layer "F.CrtYd")
		)
		(fp_poly
			(pts
				(xy -2.3749 1.8034) (xy -2.3749 -1.8034) (xy 2.3749 -1.8034) (xy 2.3749 1.8034) (xy 0.00254 1.8034)
				(xy 0.00254 1.2446) (xy 1.6002 1.2446) (xy 1.6002 -1.2446) (xy -1.6002 -1.2446) (xy -1.6002 1.2446)
				(xy -0.00254 1.2446) (xy -0.00254 1.8034)
			)
			(stroke
				(width 0)
				(type default)
			)
			(fill no)
			(layer "F.CrtYd")
		)
		(fp_rect
			(start -2.3749 1.8034)
			(end 2.3749 -1.8034)
			(stroke
				(width 0)
				(type default)
			)
			(fill no)
			(layer "F.Fab")
		)
		(pad "1" smd rect
			(at -1.171448 0.756412 90)
			(size 1.397 1.0668)
			(layers "F.Cu" "F.Mask" "F.Paste")
			(net "XTAL_X2")
		)
		(pad "2" smd rect
			(at 1.171448 0.756412 90)
			(size 1.397 1.0668)
			(layers "F.Cu" "F.Mask" "F.Paste")
			(net "GND")
		)
		(pad "3" smd rect
			(at 1.171448 -0.756412 90)
			(size 1.397 1.0668)
			(layers "F.Cu" "F.Mask" "F.Paste")
			(net "XTAL_X1")
		)
		(pad "4" smd rect
			(at -1.171448 -0.756412 90)
			(size 1.397 1.0668)
			(layers "F.Cu" "F.Mask" "F.Paste")
			(net "GND")
		)
		(zone
			(layer "F.Cu")
			(hatch none 0.5)
			(connect_pads
				(clearance 0)
			)
			(min_thickness 0.25)
			(keepout
				(tracks not_allowed)
				(vias allowed)
				(pads allowed)
				(copperpour not_allowed)
				(footprints allowed)
			)
			(placement
				(enabled no)
				(sheetname "")
			)
			(fill
				(thermal_gap 0.5)
				(thermal_bridge_width 0.5)
				(island_removal_mode 0)
			)
			(polygon
				(pts
					(xy 152.5778 -91.7956) (xy 152.5778 -91.8972) (xy 152.4762 -91.8972) (xy 152.4762 -91.7956)
				)
			)
		)
		(zone
			(layer "F.Cu")
			(hatch none 0.5)
			(connect_pads
				(clearance 0)
			)
			(min_thickness 0.25)
			(keepout
				(tracks allowed)
				(vias not_allowed)
				(pads allowed)
				(copperpour not_allowed)
				(footprints allowed)
			)
			(placement
				(enabled no)
				(sheetname "")
			)
			(fill
				(thermal_gap 0.5)
				(thermal_bridge_width 0.5)
				(island_removal_mode 0)
			)
			(polygon
				(pts
					(xy 151.237188 -91.373452) (xy 151.237188 -92.319348) (xy 152.303988 -92.319348) (xy 152.303988 -93.716348)
					(xy 152.750012 -93.716348) (xy 152.750012 -92.319348) (xy 153.816812 -92.319348) (xy 153.816812 -91.373452)
					(xy 152.750012 -91.373452) (xy 152.750012 -89.976452) (xy 152.303988 -89.976452) (xy 152.303988 -91.373452)
				)
			)
		)
	)
	(footprint ""
		(layer "F.Cu")
		(at 59.182 -47.244 90)
		(property "Reference" "PL2"
			(at 0 0 90)
			(layer "F.SilkS")
			(hide yes)
			(effects
				(font
					(size 1.27 1.27)
				)
			)
		)
		(property "Value" "BLM21PG220SN1DGP"
			(at 0.0254 -5.6896 90)
			(unlocked yes)
			(layer "F.Fab")
			(hide yes)
			(effects
				(font
					(size 1.016 1.016)
					(thickness 0.1524)
				)
			)
		)
		(property "Device Type" "L20125H42"
			(at 0.0254 -7.5946 90)
			(unlocked yes)
			(layer "F.Fab")
			(hide yes)
			(effects
				(font
					(size 1.016 1.016)
					(thickness 0.1524)
				)
			)
		)
		(duplicate_pad_numbers_are_jumpers no)
		(fp_line
			(start 0.9144 -1.7018)
			(end -0.9144 -1.7018)
			(stroke
				(width 0.1524)
				(type default)
			)
			(layer "F.SilkS")
		)
		(fp_line
			(start -0.9144 -1.7018)
			(end -0.9144 1.7018)
			(stroke
				(width 0.1524)
				(type default)
			)
			(layer "F.SilkS")
		)
		(fp_line
			(start 0.9144 1.7018)
			(end 0.9144 -1.7018)
			(stroke
				(width 0.1524)
				(type default)
			)
			(layer "F.SilkS")
		)
		(fp_line
			(start -0.9144 1.7018)
			(end 0.9144 1.7018)
			(stroke
				(width 0.1524)
				(type default)
			)
			(layer "F.SilkS")
		)
		(fp_rect
			(start -1.0033 1.778)
			(end 1.0033 -1.778)
			(stroke
				(width 0)
				(type default)
			)
			(fill no)
			(layer "F.CrtYd")
		)
		(fp_poly
			(pts
				(xy -1.0033 -1.778) (xy 1.0033 -1.778) (xy 1.0033 1.778) (xy -1.0033 1.778)
			)
			(stroke
				(width 0)
				(type default)
			)
			(fill no)
			(layer "F.Fab")
		)
		(pad "1" smd rect
			(at 0 -0.9652 90)
			(size 1.397 1.143)
			(layers "F.Cu" "F.Mask" "F.Paste")
			(net "P12V")
		)
		(pad "2" smd rect
			(at 0 0.9652 90)
			(size 1.397 1.143)
			(layers "F.Cu" "F.Mask" "F.Paste")
			(net "P3V3_STBY_VIN")
		)
	)
	(footprint ""
		(layer "F.Cu")
		(at 48.641 -152.4)
		(property "Reference" "R164"
			(at 0 0 0)
			(layer "F.SilkS")
			(hide yes)
			(effects
				(font
					(size 1.27 1.27)
				)
			)
		)
		(property "Value" "4K7R2F-GP"
			(at 0.064008 -3.993896 0)
			(unlocked yes)
			(layer "F.Fab")
			(hide yes)
			(effects
				(font
					(size 1.016 1.016)
					(thickness 0.1524)
				)
			)
		)
		(property "Device Type" "R402H16"
			(at 0.064008 -5.517896 0)
			(unlocked yes)
			(layer "F.Fab")
			(hide yes)
			(effects
				(font
					(size 1.016 1.016)
					(thickness 0.1524)
				)
			)
		)
		(duplicate_pad_numbers_are_jumpers no)
		(fp_line
			(start -0.508 -0.9398)
			(end -0.508 0.9398)
			(stroke
				(width 0.1524)
				(type default)
			)
			(layer "F.SilkS")
		)
		(fp_line
			(start 0.508 -0.9398)
			(end -0.508 -0.9398)
			(stroke
				(width 0.1524)
				(type default)
			)
			(layer "F.SilkS")
		)
		(fp_rect
			(start -0.508 0.9398)
			(end 0.508 -0.9398)
			(stroke
				(width 0)
				(type default)
			)
			(fill no)
			(layer "F.CrtYd")
		)
		(fp_rect
			(start -0.508 0.9398)
			(end 0.508 -0.9398)
			(stroke
				(width 0)
				(type default)
			)
			(fill no)
			(layer "F.Fab")
		)
		(pad "1" smd custom
			(at 0 -0.4445)
			(size 0.1397 0.1397)
			(layers "F.Cu" "F.Mask" "F.Paste")
			(net "P3V3_STBY")
			(options
				(clearance outline)
				(anchor circle)
			)
			(primitives
				(gr_poly
					(pts
						(arc
							(start -0.1778 -0.2794)
							(mid -0.249642 -0.249642)
							(end -0.2794 -0.1778)
						)
						(arc
							(start -0.2794 0.1778)
							(mid -0.249642 0.249642)
							(end -0.1778 0.2794)
						)
						(arc
							(start 0.1778 0.2794)
							(mid 0.249642 0.249642)
							(end 0.2794 0.1778)
						)
						(arc
							(start 0.2794 -0.1778)
							(mid 0.249642 -0.249642)
							(end 0.1778 -0.2794)
						)
					)
					(width 0)
					(fill yes)
				)
			)
		)
		(pad "2" smd custom
			(at 0 0.4445)
			(size 0.1397 0.1397)
			(layers "F.Cu" "F.Mask" "F.Paste")
			(net "TEMP_2_A2")
			(options
				(clearance outline)
				(anchor circle)
			)
			(primitives
				(gr_poly
					(pts
						(arc
							(start -0.1778 -0.2794)
							(mid -0.249642 -0.249642)
							(end -0.2794 -0.1778)
						)
						(arc
							(start -0.2794 0.1778)
							(mid -0.249642 0.249642)
							(end -0.1778 0.2794)
						)
						(arc
							(start 0.1778 0.2794)
							(mid 0.249642 0.249642)
							(end 0.2794 0.1778)
						)
						(arc
							(start 0.2794 -0.1778)
							(mid 0.249642 -0.249642)
							(end 0.1778 -0.2794)
						)
					)
					(width 0)
					(fill yes)
				)
			)
		)
	)
	(footprint ""
		(layer "F.Cu")
		(at 339.34146 -43.307)
		(property "Reference" "SW1"
			(at 0 0 0)
			(layer "F.SilkS")
			(hide yes)
			(effects
				(font
					(size 1.27 1.27)
				)
			)
		)
		(property "Value" "SW-TACT-4P-196-GP"
			(at -5.5118 0.2032 0)
			(unlocked yes)
			(layer "F.Fab")
			(hide yes)
			(effects
				(font
					(size 1.016 1.016)
					(thickness 0.1524)
				)
			)
		)
		(property "Device Type" "DTS-63N-V"
			(at -5.5118 -1.3208 0)
			(unlocked yes)
			(layer "F.Fab")
			(hide yes)
			(effects
				(font
					(size 1.016 1.016)
					(thickness 0.1524)
				)
			)
		)
		(duplicate_pad_numbers_are_jumpers no)
		(fp_line
			(start -4.4958 -3.6322)
			(end -4.4958 -2.3622)
			(stroke
				(width 0.4064)
				(type default)
			)
			(layer "F.SilkS")
		)
		(fp_line
			(start -4.2164 -3.3528)
			(end -4.2164 3.3528)
			(stroke
				(width 0.1524)
				(type default)
			)
			(layer "F.SilkS")
		)
		(fp_line
			(start -4.2164 3.3528)
			(end 4.2164 3.3528)
			(stroke
				(width 0.1524)
				(type default)
			)
			(layer "F.SilkS")
		)
		(fp_line
			(start -3.2258 -3.6322)
			(end -4.4958 -3.6322)
			(stroke
				(width 0.4064)
				(type default)
			)
			(layer "F.SilkS")
		)
		(fp_line
			(start 0 -2.54)
			(end 0 -0.762)
			(stroke
				(width 0.1524)
				(type default)
			)
			(layer "F.SilkS")
		)
		(fp_line
			(start 0 -0.762)
			(end 0.508 0.508)
			(stroke
				(width 0.1524)
				(type default)
			)
			(layer "F.SilkS")
		)
		(fp_line
			(start 0 0.762)
			(end 0 2.54)
			(stroke
				(width 0.1524)
				(type default)
			)
			(layer "F.SilkS")
		)
		(fp_line
			(start 4.2164 -3.3528)
			(end -4.2164 -3.3528)
			(stroke
				(width 0.1524)
				(type default)
			)
			(layer "F.SilkS")
		)
		(fp_line
			(start 4.2164 3.3528)
			(end 4.2164 -3.3528)
			(stroke
				(width 0.1524)
				(type default)
			)
			(layer "F.SilkS")
		)
		(fp_circle
			(center -3.24993 -2.249932)
			(end -2.18313 -2.249932)
			(stroke
				(width 0.3048)
				(type default)
			)
			(fill no)
			(layer "F.SilkS")
		)
		(fp_circle
			(center -3.24993 2.249932)
			(end -2.18313 2.249932)
			(stroke
				(width 0.3048)
				(type default)
			)
			(fill no)
			(layer "F.SilkS")
		)
		(fp_circle
			(center 0 -0.762)
			(end 0.0762 -0.762)
			(stroke
				(width 0.1524)
				(type default)
			)
			(fill no)
			(layer "F.SilkS")
		)
		(fp_circle
			(center 0 0.762)
			(end 0.0762 0.762)
			(stroke
				(width 0.1524)
				(type default)
			)
			(fill no)
			(layer "F.SilkS")
		)
		(fp_circle
			(center 3.24993 -2.249932)
			(end 4.31673 -2.249932)
			(stroke
				(width 0.3048)
				(type default)
			)
			(fill no)
			(layer "F.SilkS")
		)
		(fp_circle
			(center 3.24993 2.249932)
			(end 4.31673 2.249932)
			(stroke
				(width 0.3048)
				(type default)
			)
			(fill no)
			(layer "F.SilkS")
		)
		(fp_poly
			(pts
				(xy -3.0988 3.0988) (xy -3.0988 2.605532) (xy -3.9497 2.605532) (xy -3.9497 1.894332) (xy -3.0988 1.894332)
				(xy -3.0988 -1.894332) (xy -3.9497 -1.894332) (xy -3.9497 -2.605532) (xy -3.0988 -2.605532) (xy -3.0988 -3.0988)
				(xy 3.0988 -3.0988) (xy 3.0988 -2.605532) (xy 3.9497 -2.605532) (xy 3.9497 -1.894332) (xy 3.0988 -1.894332)
				(xy 3.0988 1.894332) (xy 3.9497 1.894332) (xy 3.9497 2.605532) (xy 3.0988 2.605532) (xy 3.0988 3.0988)
			)
			(stroke
				(width 0)
				(type default)
			)
			(fill no)
			(layer "F.CrtYd")
		)
		(fp_poly
			(pts
				(xy -4.4704 3.6068) (xy -4.4704 -3.6068) (xy 4.4704 -3.6068) (xy 4.4704 3.6068) (xy 0.00254 3.6068)
				(xy 0.00254 3.0988) (xy 3.0988 3.0988) (xy 3.0988 2.605532) (xy 3.9497 2.605532) (xy 3.9497 1.894332)
				(xy 3.0988 1.894332) (xy 3.0988 -1.894332) (xy 3.9497 -1.894332) (xy 3.9497 -2.605532) (xy 3.0988 -2.605532)
				(xy 3.0988 -3.0988) (xy -3.0988 -3.0988) (xy -3.0988 -2.605532) (xy -3.9497 -2.605532) (xy -3.9497 -1.894332)
				(xy -3.0988 -1.894332) (xy -3.0988 1.894332) (xy -3.9497 1.894332) (xy -3.9497 2.605532) (xy -3.0988 2.605532)
				(xy -3.0988 3.0988) (xy -0.00254 3.0988) (xy -0.00254 3.6068)
			)
			(stroke
				(width 0)
				(type default)
			)
			(fill no)
			(layer "F.CrtYd")
		)
		(fp_rect
			(start -4.4704 3.6068)
			(end 4.4704 -3.6068)
			(stroke
				(width 0)
				(type default)
			)
			(fill no)
			(layer "F.Fab")
		)
		(pad "1" thru_hole circle
			(at -3.24993 -2.249932)
			(size 1.4224 1.4224)
			(drill 1.016)
			(layers "*.Cu" "*.Mask")
			(remove_unused_layers no)
			(net "GND")
			(clearance 0.1524)
			(thermal_gap 0.1524)
		)
		(pad "2" thru_hole circle
			(at 3.24993 -2.249932)
			(size 1.4224 1.4224)
			(drill 1.016)
			(layers "*.Cu" "*.Mask")
			(remove_unused_layers no)
			(net "GND")
			(clearance 0.1524)
			(thermal_gap 0.1524)
		)
		(pad "3" thru_hole circle
			(at -3.24993 2.249932)
			(size 1.4224 1.4224)
			(drill 1.016)
			(layers "*.Cu" "*.Mask")
			(remove_unused_layers no)
			(net "RST_BTN#")
			(clearance 0.1524)
			(thermal_gap 0.1524)
		)
		(pad "4" thru_hole circle
			(at 3.24993 2.249932)
			(size 1.4224 1.4224)
			(drill 1.016)
			(layers "*.Cu" "*.Mask")
			(remove_unused_layers no)
			(net "RST_BTN#")
			(clearance 0.1524)
			(thermal_gap 0.1524)
		)
	)
	(footprint ""
		(layer "F.Cu")
		(at 305.930046 -33.51022)
		(property "Reference" "C17"
			(at 0 0 0)
			(layer "F.SilkS")
			(hide yes)
			(effects
				(font
					(size 1.27 1.27)
				)
			)
		)
		(property "Value" "SCD22U10V2KX-1GP"
			(at 1.1811 -2.7051 0)
			(unlocked yes)
			(layer "F.Fab")
			(hide yes)
			(effects
				(font
					(size 1.016 1.016)
					(thickness 0.1524)
				)
			)
		)
		(property "Device Type" "C402H22"
			(at 1.1811 -4.2291 0)
			(unlocked yes)
			(layer "F.Fab")
			(hide yes)
			(effects
				(font
					(size 1.016 1.016)
					(thickness 0.1524)
				)
			)
		)
		(duplicate_pad_numbers_are_jumpers no)
		(fp_rect
			(start -0.4318 0.9525)
			(end 0.4318 -0.9525)
			(stroke
				(width 0)
				(type default)
			)
			(fill no)
			(layer "F.CrtYd")
		)
		(fp_rect
			(start -0.4318 0.9525)
			(end 0.4318 -0.9525)
			(stroke
				(width 0)
				(type default)
			)
			(fill no)
			(layer "F.Fab")
		)
		(pad "1" smd custom
			(at 0 -0.4445)
			(size 0.1524 0.1524)
			(layers "F.Cu" "F.Mask" "F.Paste")
			(net "PCIE_TX_CAP_P8")
			(options
				(clearance outline)
				(anchor circle)
			)
			(primitives
				(gr_poly
					(pts
						(arc
							(start 0.3048 -0.2032)
							(mid 0.275042 -0.275042)
							(end 0.2032 -0.3048)
						)
						(arc
							(start -0.2032 -0.3048)
							(mid -0.275042 -0.275042)
							(end -0.3048 -0.2032)
						)
						(arc
							(start -0.3048 0.2032)
							(mid -0.275042 0.275042)
							(end -0.2032 0.3048)
						)
						(arc
							(start 0.2032 0.3048)
							(mid 0.275042 0.275042)
							(end 0.3048 0.2032)
						)
					)
					(width 0)
					(fill yes)
				)
			)
		)
		(pad "2" smd custom
			(at 0 0.4445)
			(size 0.1524 0.1524)
			(layers "F.Cu" "F.Mask" "F.Paste")
			(net "PCIE_TX_P8")
			(options
				(clearance outline)
				(anchor circle)
			)
			(primitives
				(gr_poly
					(pts
						(arc
							(start 0.3048 -0.2032)
							(mid 0.275042 -0.275042)
							(end 0.2032 -0.3048)
						)
						(arc
							(start -0.2032 -0.3048)
							(mid -0.275042 -0.275042)
							(end -0.3048 -0.2032)
						)
						(arc
							(start -0.3048 0.2032)
							(mid -0.275042 0.275042)
							(end -0.2032 0.3048)
						)
						(arc
							(start 0.2032 0.3048)
							(mid 0.275042 0.275042)
							(end 0.3048 0.2032)
						)
					)
					(width 0)
					(fill yes)
				)
			)
		)
	)
	(footprint ""
		(layer "F.Cu")
		(at 89.1921 -212.420454 180)
		(property "Reference" "C346"
			(at 0 0 180)
			(layer "F.SilkS")
			(hide yes)
			(effects
				(font
					(size 1.27 1.27)
				)
			)
		)
		(property "Value" "SCD22U10V2KX-1GP"
			(at 1.1811 -2.7051 180)
			(unlocked yes)
			(layer "F.Fab")
			(hide yes)
			(effects
				(font
					(size 1.016 1.016)
					(thickness 0.1524)
				)
			)
		)
		(property "Device Type" "C402H22"
			(at 1.1811 -4.2291 180)
			(unlocked yes)
			(layer "F.Fab")
			(hide yes)
			(effects
				(font
					(size 1.016 1.016)
					(thickness 0.1524)
				)
			)
		)
		(duplicate_pad_numbers_are_jumpers no)
		(fp_rect
			(start -0.4318 0.9525)
			(end 0.4318 -0.9525)
			(stroke
				(width 0)
				(type default)
			)
			(fill no)
			(layer "F.CrtYd")
		)
		(fp_rect
			(start -0.4318 0.9525)
			(end 0.4318 -0.9525)
			(stroke
				(width 0)
				(type default)
			)
			(fill no)
			(layer "F.Fab")
		)
		(pad "1" smd custom
			(at 0 -0.4445 180)
			(size 0.1524 0.1524)
			(layers "F.Cu" "F.Mask" "F.Paste")
			(net "PCIE_TX_CAP_P65")
			(options
				(clearance outline)
				(anchor circle)
			)
			(primitives
				(gr_poly
					(pts
						(arc
							(start 0.3048 -0.2032)
							(mid 0.275042 -0.275042)
							(end 0.2032 -0.3048)
						)
						(arc
							(start -0.2032 -0.3048)
							(mid -0.275042 -0.275042)
							(end -0.3048 -0.2032)
						)
						(arc
							(start -0.3048 0.2032)
							(mid -0.275042 0.275042)
							(end -0.2032 0.3048)
						)
						(arc
							(start 0.2032 0.3048)
							(mid 0.275042 0.275042)
							(end 0.3048 0.2032)
						)
					)
					(width 0)
					(fill yes)
				)
			)
		)
		(pad "2" smd custom
			(at 0 0.4445 180)
			(size 0.1524 0.1524)
			(layers "F.Cu" "F.Mask" "F.Paste")
			(net "PCIE_TX_P65")
			(options
				(clearance outline)
				(anchor circle)
			)
			(primitives
				(gr_poly
					(pts
						(arc
							(start 0.3048 -0.2032)
							(mid 0.275042 -0.275042)
							(end 0.2032 -0.3048)
						)
						(arc
							(start -0.2032 -0.3048)
							(mid -0.275042 -0.275042)
							(end -0.3048 -0.2032)
						)
						(arc
							(start -0.3048 0.2032)
							(mid -0.275042 0.275042)
							(end -0.2032 0.3048)
						)
						(arc
							(start 0.2032 0.3048)
							(mid 0.275042 0.275042)
							(end 0.3048 0.2032)
						)
					)
					(width 0)
					(fill yes)
				)
			)
		)
	)
	(footprint ""
		(layer "F.Cu")
		(at 132.310886 -82.941414 180)
		(property "Reference" "R1848"
			(at 0 0 180)
			(layer "F.SilkS")
			(hide yes)
			(effects
				(font
					(size 1.27 1.27)
				)
			)
		)
		(property "Value" "10MR3F-GP"
			(at -0.0254 -2.5146 180)
			(unlocked yes)
			(layer "F.Fab")
			(hide yes)
			(effects
				(font
					(size 1.016 1.016)
					(thickness 0.1524)
				)
			)
		)
		(property "Device Type" "R603H22"
			(at -0.0254 -4.0386 180)
			(unlocked yes)
			(layer "F.Fab")
			(hide yes)
			(effects
				(font
					(size 1.016 1.016)
					(thickness 0.1524)
				)
			)
		)
		(duplicate_pad_numbers_are_jumpers no)
		(fp_line
			(start 0.2032 0)
			(end 0.4826 0)
			(stroke
				(width 0.2032)
				(type default)
			)
			(layer "F.SilkS")
		)
		(fp_line
			(start -0.4826 0)
			(end -0.2032 0)
			(stroke
				(width 0.2032)
				(type default)
			)
			(layer "F.SilkS")
		)
		(fp_rect
			(start -0.5842 1.3335)
			(end 0.5842 -1.3335)
			(stroke
				(width 0)
				(type default)
			)
			(fill no)
			(layer "F.CrtYd")
		)
		(fp_rect
			(start -0.5842 1.3335)
			(end 0.5842 -1.3335)
			(stroke
				(width 0)
				(type default)
			)
			(fill no)
			(layer "F.Fab")
		)
		(pad "1" smd custom
			(at 0 -0.762 180)
			(size 0.2159 0.2159)
			(layers "F.Cu" "F.Mask" "F.Paste")
			(net "RTC_OSCI")
			(options
				(clearance outline)
				(anchor circle)
			)
			(primitives
				(gr_poly
					(pts
						(arc
							(start -0.3302 -0.4318)
							(mid -0.402042 -0.402042)
							(end -0.4318 -0.3302)
						)
						(arc
							(start -0.4318 0.3302)
							(mid -0.402042 0.402042)
							(end -0.3302 0.4318)
						)
						(arc
							(start 0.3302 0.4318)
							(mid 0.402042 0.402042)
							(end 0.4318 0.3302)
						)
						(arc
							(start 0.4318 -0.3302)
							(mid 0.402042 -0.402042)
							(end 0.3302 -0.4318)
						)
					)
					(width 0)
					(fill yes)
				)
			)
		)
		(pad "2" smd custom
			(at 0 0.762 180)
			(size 0.2159 0.2159)
			(layers "F.Cu" "F.Mask" "F.Paste")
			(net "RTC_OSCO")
			(options
				(clearance outline)
				(anchor circle)
			)
			(primitives
				(gr_poly
					(pts
						(arc
							(start -0.3302 -0.4318)
							(mid -0.402042 -0.402042)
							(end -0.4318 -0.3302)
						)
						(arc
							(start -0.4318 0.3302)
							(mid -0.402042 0.402042)
							(end -0.3302 0.4318)
						)
						(arc
							(start 0.3302 0.4318)
							(mid 0.402042 0.402042)
							(end 0.4318 0.3302)
						)
						(arc
							(start 0.4318 -0.3302)
							(mid 0.402042 -0.402042)
							(end 0.3302 -0.4318)
						)
					)
					(width 0)
					(fill yes)
				)
			)
		)
	)
	(footprint ""
		(layer "F.Cu")
		(at 24.395684 -107.95762)
		(property "Reference" "R9047"
			(at 0 0 0)
			(layer "F.SilkS")
			(hide yes)
			(effects
				(font
					(size 1.27 1.27)
				)
			)
		)
		(property "Value" "56R2F"
			(at 0.064008 -3.993896 0)
			(unlocked yes)
			(layer "F.Fab")
			(hide yes)
			(effects
				(font
					(size 1.016 1.016)
					(thickness 0.1524)
				)
			)
		)
		(property "Device Type" "R402H14"
			(at 0.064008 -5.517896 0)
			(unlocked yes)
			(layer "F.Fab")
			(hide yes)
			(effects
				(font
					(size 1.016 1.016)
					(thickness 0.1524)
				)
			)
		)
		(duplicate_pad_numbers_are_jumpers no)
		(fp_line
			(start -0.508 -0.9398)
			(end -0.508 0.9398)
			(stroke
				(width 0.1524)
				(type default)
			)
			(layer "F.SilkS")
		)
		(fp_line
			(start 0.508 -0.9398)
			(end -0.508 -0.9398)
			(stroke
				(width 0.1524)
				(type default)
			)
			(layer "F.SilkS")
		)
		(fp_rect
			(start -0.508 0.9398)
			(end 0.508 -0.9398)
			(stroke
				(width 0)
				(type default)
			)
			(fill no)
			(layer "F.CrtYd")
		)
		(fp_rect
			(start -0.508 0.9398)
			(end 0.508 -0.9398)
			(stroke
				(width 0)
				(type default)
			)
			(fill no)
			(layer "F.Fab")
		)
		(pad "1" smd custom
			(at 0 -0.4445)
			(size 0.1397 0.1397)
			(layers "F.Cu" "F.Mask" "F.Paste")
			(net "BMC_REFCLK_N")
			(options
				(clearance outline)
				(anchor circle)
			)
			(primitives
				(gr_poly
					(pts
						(arc
							(start -0.1778 -0.2794)
							(mid -0.249642 -0.249642)
							(end -0.2794 -0.1778)
						)
						(arc
							(start -0.2794 0.1778)
							(mid -0.249642 0.249642)
							(end -0.1778 0.2794)
						)
						(arc
							(start 0.1778 0.2794)
							(mid 0.249642 0.249642)
							(end 0.2794 0.1778)
						)
						(arc
							(start 0.2794 -0.1778)
							(mid 0.249642 -0.249642)
							(end 0.1778 -0.2794)
						)
					)
					(width 0)
					(fill yes)
				)
			)
		)
		(pad "2" smd custom
			(at 0 0.4445)
			(size 0.1397 0.1397)
			(layers "F.Cu" "F.Mask" "F.Paste")
			(net "GND")
			(options
				(clearance outline)
				(anchor circle)
			)
			(primitives
				(gr_poly
					(pts
						(arc
							(start -0.1778 -0.2794)
							(mid -0.249642 -0.249642)
							(end -0.2794 -0.1778)
						)
						(arc
							(start -0.2794 0.1778)
							(mid -0.249642 0.249642)
							(end -0.1778 0.2794)
						)
						(arc
							(start 0.1778 0.2794)
							(mid 0.249642 0.249642)
							(end 0.2794 0.1778)
						)
						(arc
							(start 0.2794 -0.1778)
							(mid 0.249642 -0.249642)
							(end 0.1778 -0.2794)
						)
					)
					(width 0)
					(fill yes)
				)
			)
		)
	)
	(footprint ""
		(layer "F.Cu")
		(at 49.788572 -50.306224)
		(property "Reference" "R498"
			(at 0 0 0)
			(layer "F.SilkS")
			(hide yes)
			(effects
				(font
					(size 1.27 1.27)
				)
			)
		)
		(property "Value" "33K2R2F-GP"
			(at 0.064008 -3.993896 0)
			(unlocked yes)
			(layer "F.Fab")
			(hide yes)
			(effects
				(font
					(size 1.016 1.016)
					(thickness 0.1524)
				)
			)
		)
		(property "Device Type" "R402H16"
			(at 0.064008 -5.517896 0)
			(unlocked yes)
			(layer "F.Fab")
			(hide yes)
			(effects
				(font
					(size 1.016 1.016)
					(thickness 0.1524)
				)
			)
		)
		(duplicate_pad_numbers_are_jumpers no)
		(fp_line
			(start -0.508 -0.9398)
			(end -0.508 0.9398)
			(stroke
				(width 0.1524)
				(type default)
			)
			(layer "F.SilkS")
		)
		(fp_line
			(start 0.508 -0.9398)
			(end -0.508 -0.9398)
			(stroke
				(width 0.1524)
				(type default)
			)
			(layer "F.SilkS")
		)
		(fp_rect
			(start -0.508 0.9398)
			(end 0.508 -0.9398)
			(stroke
				(width 0)
				(type default)
			)
			(fill no)
			(layer "F.CrtYd")
		)
		(fp_rect
			(start -0.508 0.9398)
			(end 0.508 -0.9398)
			(stroke
				(width 0)
				(type default)
			)
			(fill no)
			(layer "F.Fab")
		)
		(pad "1" smd custom
			(at 0 -0.4445)
			(size 0.1397 0.1397)
			(layers "F.Cu" "F.Mask" "F.Paste")
			(net "NVM_SK_R")
			(options
				(clearance outline)
				(anchor circle)
			)
			(primitives
				(gr_poly
					(pts
						(arc
							(start -0.1778 -0.2794)
							(mid -0.249642 -0.249642)
							(end -0.2794 -0.1778)
						)
						(arc
							(start -0.2794 0.1778)
							(mid -0.249642 0.249642)
							(end -0.1778 0.2794)
						)
						(arc
							(start 0.1778 0.2794)
							(mid 0.249642 0.249642)
							(end 0.2794 0.1778)
						)
						(arc
							(start 0.2794 -0.1778)
							(mid 0.249642 -0.249642)
							(end 0.1778 -0.2794)
						)
					)
					(width 0)
					(fill yes)
				)
			)
		)
		(pad "2" smd custom
			(at 0 0.4445)
			(size 0.1397 0.1397)
			(layers "F.Cu" "F.Mask" "F.Paste")
			(net "GND")
			(options
				(clearance outline)
				(anchor circle)
			)
			(primitives
				(gr_poly
					(pts
						(arc
							(start -0.1778 -0.2794)
							(mid -0.249642 -0.249642)
							(end -0.2794 -0.1778)
						)
						(arc
							(start -0.2794 0.1778)
							(mid -0.249642 0.249642)
							(end -0.1778 0.2794)
						)
						(arc
							(start 0.1778 0.2794)
							(mid 0.249642 0.249642)
							(end 0.2794 0.1778)
						)
						(arc
							(start 0.2794 -0.1778)
							(mid 0.249642 -0.249642)
							(end 0.1778 -0.2794)
						)
					)
					(width 0)
					(fill yes)
				)
			)
		)
	)
	(footprint ""
		(layer "F.Cu")
		(at 9.4742 -179.9336)
		(property "Reference" "CA1"
			(at 0 0 0)
			(layer "F.SilkS")
			(hide yes)
			(effects
				(font
					(size 1.27 1.27)
				)
			)
		)
		(property "Value" "SC2D2U25V5KX-2-GP"
			(at -0.0762 -6.1214 0)
			(unlocked yes)
			(layer "F.Fab")
			(hide yes)
			(effects
				(font
					(size 1.016 1.016)
					(thickness 0.1524)
				)
			)
		)
		(property "Device Type" "C805H54"
			(at -0.0762 -8.1534 0)
			(unlocked yes)
			(layer "F.Fab")
			(hide yes)
			(effects
				(font
					(size 1.016 1.016)
					(thickness 0.1524)
				)
			)
		)
		(duplicate_pad_numbers_are_jumpers no)
		(fp_line
			(start 0.635 0)
			(end -0.635 0)
			(stroke
				(width 0.508)
				(type default)
			)
			(layer "F.SilkS")
		)
		(fp_rect
			(start -0.9652 1.778)
			(end 0.9652 -1.778)
			(stroke
				(width 0)
				(type default)
			)
			(fill no)
			(layer "F.CrtYd")
		)
		(fp_poly
			(pts
				(xy -0.9652 -1.778) (xy 0.9652 -1.778) (xy 0.9652 1.778) (xy -0.9652 1.778)
			)
			(stroke
				(width 0)
				(type default)
			)
			(fill no)
			(layer "F.Fab")
		)
		(pad "1" smd rect
			(at 0 -0.9652)
			(size 1.397 1.143)
			(layers "F.Cu" "F.Mask" "F.Paste")
			(net "MB0_P12V_PWRGOOD")
		)
		(pad "2" smd rect
			(at 0 0.9652)
			(size 1.397 1.143)
			(layers "F.Cu" "F.Mask" "F.Paste")
			(net "AGND_CURRENT_MON")
		)
	)
	(footprint ""
		(layer "F.Cu")
		(at 16.256 -125.095 180)
		(property "Reference" "R17"
			(at 0 0 180)
			(layer "F.SilkS")
			(hide yes)
			(effects
				(font
					(size 1.27 1.27)
				)
			)
		)
		(property "Value" "0R2J-2-GP"
			(at 0.064008 -3.993896 180)
			(unlocked yes)
			(layer "F.Fab")
			(hide yes)
			(effects
				(font
					(size 1.016 1.016)
					(thickness 0.1524)
				)
			)
		)
		(property "Device Type" "R402H16"
			(at 0.064008 -5.517896 180)
			(unlocked yes)
			(layer "F.Fab")
			(hide yes)
			(effects
				(font
					(size 1.016 1.016)
					(thickness 0.1524)
				)
			)
		)
		(duplicate_pad_numbers_are_jumpers no)
		(fp_line
			(start 0.508 -0.9398)
			(end -0.508 -0.9398)
			(stroke
				(width 0.1524)
				(type default)
			)
			(layer "F.SilkS")
		)
		(fp_line
			(start -0.508 -0.9398)
			(end -0.508 0.9398)
			(stroke
				(width 0.1524)
				(type default)
			)
			(layer "F.SilkS")
		)
		(fp_rect
			(start -0.508 0.9398)
			(end 0.508 -0.9398)
			(stroke
				(width 0)
				(type default)
			)
			(fill no)
			(layer "F.CrtYd")
		)
		(fp_rect
			(start -0.508 0.9398)
			(end 0.508 -0.9398)
			(stroke
				(width 0)
				(type default)
			)
			(fill no)
			(layer "F.Fab")
		)
		(pad "1" smd custom
			(at 0 -0.4445 180)
			(size 0.1397 0.1397)
			(layers "F.Cu" "F.Mask" "F.Paste")
			(net "BMC_I2C2_MINI2_SDA")
			(options
				(clearance outline)
				(anchor circle)
			)
			(primitives
				(gr_poly
					(pts
						(arc
							(start -0.1778 -0.2794)
							(mid -0.249642 -0.249642)
							(end -0.2794 -0.1778)
						)
						(arc
							(start -0.2794 0.1778)
							(mid -0.249642 0.249642)
							(end -0.1778 0.2794)
						)
						(arc
							(start 0.1778 0.2794)
							(mid 0.249642 0.249642)
							(end 0.2794 0.1778)
						)
						(arc
							(start 0.2794 -0.1778)
							(mid 0.249642 -0.249642)
							(end 0.1778 -0.2794)
						)
					)
					(width 0)
					(fill yes)
				)
			)
		)
		(pad "2" smd custom
			(at 0 0.4445 180)
			(size 0.1397 0.1397)
			(layers "F.Cu" "F.Mask" "F.Paste")
			(net "BMC_I2C2_MINI2_SDA_S")
			(options
				(clearance outline)
				(anchor circle)
			)
			(primitives
				(gr_poly
					(pts
						(arc
							(start -0.1778 -0.2794)
							(mid -0.249642 -0.249642)
							(end -0.2794 -0.1778)
						)
						(arc
							(start -0.2794 0.1778)
							(mid -0.249642 0.249642)
							(end -0.1778 0.2794)
						)
						(arc
							(start 0.1778 0.2794)
							(mid 0.249642 0.249642)
							(end 0.2794 0.1778)
						)
						(arc
							(start 0.2794 -0.1778)
							(mid 0.249642 -0.249642)
							(end 0.1778 -0.2794)
						)
					)
					(width 0)
					(fill yes)
				)
			)
		)
	)
	(footprint ""
		(layer "F.Cu")
		(at 225.59518 -205.29042 -90)
		(property "Reference" "R9041"
			(at 0 0 270)
			(layer "F.SilkS")
			(hide yes)
			(effects
				(font
					(size 1.27 1.27)
				)
			)
		)
		(property "Value" "4K7R2F-GP"
			(at 0.064008 -3.993896 270)
			(unlocked yes)
			(layer "F.Fab")
			(hide yes)
			(effects
				(font
					(size 1.016 1.016)
					(thickness 0.1524)
				)
			)
		)
		(property "Device Type" "R402H16"
			(at 0.064008 -5.517896 270)
			(unlocked yes)
			(layer "F.Fab")
			(hide yes)
			(effects
				(font
					(size 1.016 1.016)
					(thickness 0.1524)
				)
			)
		)
		(duplicate_pad_numbers_are_jumpers no)
		(fp_line
			(start -0.508 -0.9398)
			(end -0.508 0.9398)
			(stroke
				(width 0.1524)
				(type default)
			)
			(layer "F.SilkS")
		)
		(fp_line
			(start 0.508 -0.9398)
			(end -0.508 -0.9398)
			(stroke
				(width 0.1524)
				(type default)
			)
			(layer "F.SilkS")
		)
		(fp_rect
			(start -0.508 0.9398)
			(end 0.508 -0.9398)
			(stroke
				(width 0)
				(type default)
			)
			(fill no)
			(layer "F.CrtYd")
		)
		(fp_rect
			(start -0.508 0.9398)
			(end 0.508 -0.9398)
			(stroke
				(width 0)
				(type default)
			)
			(fill no)
			(layer "F.Fab")
		)
		(pad "1" smd custom
			(at 0 -0.4445 270)
			(size 0.1397 0.1397)
			(layers "F.Cu" "F.Mask" "F.Paste")
			(net "SSD_PERST#12")
			(options
				(clearance outline)
				(anchor circle)
			)
			(primitives
				(gr_poly
					(pts
						(arc
							(start -0.1778 -0.2794)
							(mid -0.249642 -0.249642)
							(end -0.2794 -0.1778)
						)
						(arc
							(start -0.2794 0.1778)
							(mid -0.249642 0.249642)
							(end -0.1778 0.2794)
						)
						(arc
							(start 0.1778 0.2794)
							(mid 0.249642 0.249642)
							(end 0.2794 0.1778)
						)
						(arc
							(start 0.2794 -0.1778)
							(mid 0.249642 -0.249642)
							(end 0.1778 -0.2794)
						)
					)
					(width 0)
					(fill yes)
				)
			)
		)
		(pad "2" smd custom
			(at 0 0.4445 270)
			(size 0.1397 0.1397)
			(layers "F.Cu" "F.Mask" "F.Paste")
			(net "GND")
			(options
				(clearance outline)
				(anchor circle)
			)
			(primitives
				(gr_poly
					(pts
						(arc
							(start -0.1778 -0.2794)
							(mid -0.249642 -0.249642)
							(end -0.2794 -0.1778)
						)
						(arc
							(start -0.2794 0.1778)
							(mid -0.249642 0.249642)
							(end -0.1778 0.2794)
						)
						(arc
							(start 0.1778 0.2794)
							(mid 0.249642 0.249642)
							(end 0.2794 0.1778)
						)
						(arc
							(start 0.2794 -0.1778)
							(mid 0.249642 -0.249642)
							(end 0.1778 -0.2794)
						)
					)
					(width 0)
					(fill yes)
				)
			)
		)
	)
	(footprint ""
		(layer "F.Cu")
		(at 25.420066 -107.954318 180)
		(property "Reference" "R9045"
			(at 0 0 180)
			(layer "F.SilkS")
			(hide yes)
			(effects
				(font
					(size 1.27 1.27)
				)
			)
		)
		(property "Value" "470R2F-GP"
			(at 0.064008 -3.993896 180)
			(unlocked yes)
			(layer "F.Fab")
			(hide yes)
			(effects
				(font
					(size 1.016 1.016)
					(thickness 0.1524)
				)
			)
		)
		(property "Device Type" "R402H16"
			(at 0.064008 -5.517896 180)
			(unlocked yes)
			(layer "F.Fab")
			(hide yes)
			(effects
				(font
					(size 1.016 1.016)
					(thickness 0.1524)
				)
			)
		)
		(duplicate_pad_numbers_are_jumpers no)
		(fp_line
			(start 0.508 -0.9398)
			(end -0.508 -0.9398)
			(stroke
				(width 0.1524)
				(type default)
			)
			(layer "F.SilkS")
		)
		(fp_line
			(start -0.508 -0.9398)
			(end -0.508 0.9398)
			(stroke
				(width 0.1524)
				(type default)
			)
			(layer "F.SilkS")
		)
		(fp_rect
			(start -0.508 0.9398)
			(end 0.508 -0.9398)
			(stroke
				(width 0)
				(type default)
			)
			(fill no)
			(layer "F.CrtYd")
		)
		(fp_rect
			(start -0.508 0.9398)
			(end 0.508 -0.9398)
			(stroke
				(width 0)
				(type default)
			)
			(fill no)
			(layer "F.Fab")
		)
		(pad "1" smd custom
			(at 0 -0.4445 180)
			(size 0.1397 0.1397)
			(layers "F.Cu" "F.Mask" "F.Paste")
			(net "P3V3_STBY")
			(options
				(clearance outline)
				(anchor circle)
			)
			(primitives
				(gr_poly
					(pts
						(arc
							(start -0.1778 -0.2794)
							(mid -0.249642 -0.249642)
							(end -0.2794 -0.1778)
						)
						(arc
							(start -0.2794 0.1778)
							(mid -0.249642 0.249642)
							(end -0.1778 0.2794)
						)
						(arc
							(start 0.1778 0.2794)
							(mid 0.249642 0.249642)
							(end 0.2794 0.1778)
						)
						(arc
							(start 0.2794 -0.1778)
							(mid 0.249642 -0.249642)
							(end 0.1778 -0.2794)
						)
					)
					(width 0)
					(fill yes)
				)
			)
		)
		(pad "2" smd custom
			(at 0 0.4445 180)
			(size 0.1397 0.1397)
			(layers "F.Cu" "F.Mask" "F.Paste")
			(net "BMC_REFCLK_N")
			(options
				(clearance outline)
				(anchor circle)
			)
			(primitives
				(gr_poly
					(pts
						(arc
							(start -0.1778 -0.2794)
							(mid -0.249642 -0.249642)
							(end -0.2794 -0.1778)
						)
						(arc
							(start -0.2794 0.1778)
							(mid -0.249642 0.249642)
							(end -0.1778 0.2794)
						)
						(arc
							(start 0.1778 0.2794)
							(mid 0.249642 0.249642)
							(end 0.2794 0.1778)
						)
						(arc
							(start 0.2794 -0.1778)
							(mid 0.249642 -0.249642)
							(end 0.1778 -0.2794)
						)
					)
					(width 0)
					(fill yes)
				)
			)
		)
	)
	(footprint ""
		(layer "F.Cu")
		(at 115.7732 -26.5938 180)
		(property "Reference" "R644"
			(at 0 0 180)
			(layer "F.SilkS")
			(hide yes)
			(effects
				(font
					(size 1.27 1.27)
				)
			)
		)
		(property "Value" "4K7R2F-GP"
			(at 0.064008 -3.993896 180)
			(unlocked yes)
			(layer "F.Fab")
			(hide yes)
			(effects
				(font
					(size 1.016 1.016)
					(thickness 0.1524)
				)
			)
		)
		(property "Device Type" "R402H16"
			(at 0.064008 -5.517896 180)
			(unlocked yes)
			(layer "F.Fab")
			(hide yes)
			(effects
				(font
					(size 1.016 1.016)
					(thickness 0.1524)
				)
			)
		)
		(duplicate_pad_numbers_are_jumpers no)
		(fp_line
			(start 0.508 -0.9398)
			(end -0.508 -0.9398)
			(stroke
				(width 0.1524)
				(type default)
			)
			(layer "F.SilkS")
		)
		(fp_line
			(start -0.508 -0.9398)
			(end -0.508 0.9398)
			(stroke
				(width 0.1524)
				(type default)
			)
			(layer "F.SilkS")
		)
		(fp_rect
			(start -0.508 0.9398)
			(end 0.508 -0.9398)
			(stroke
				(width 0)
				(type default)
			)
			(fill no)
			(layer "F.CrtYd")
		)
		(fp_rect
			(start -0.508 0.9398)
			(end 0.508 -0.9398)
			(stroke
				(width 0)
				(type default)
			)
			(fill no)
			(layer "F.Fab")
		)
		(pad "1" smd custom
			(at 0 -0.4445 180)
			(size 0.1397 0.1397)
			(layers "F.Cu" "F.Mask" "F.Paste")
			(net "HOST_I2C_RESET_N")
			(options
				(clearance outline)
				(anchor circle)
			)
			(primitives
				(gr_poly
					(pts
						(arc
							(start -0.1778 -0.2794)
							(mid -0.249642 -0.249642)
							(end -0.2794 -0.1778)
						)
						(arc
							(start -0.2794 0.1778)
							(mid -0.249642 0.249642)
							(end -0.1778 0.2794)
						)
						(arc
							(start 0.1778 0.2794)
							(mid 0.249642 0.249642)
							(end 0.2794 0.1778)
						)
						(arc
							(start 0.2794 -0.1778)
							(mid 0.249642 -0.249642)
							(end 0.1778 -0.2794)
						)
					)
					(width 0)
					(fill yes)
				)
			)
		)
		(pad "2" smd custom
			(at 0 0.4445 180)
			(size 0.1397 0.1397)
			(layers "F.Cu" "F.Mask" "F.Paste")
			(net "P3V3_STBY")
			(options
				(clearance outline)
				(anchor circle)
			)
			(primitives
				(gr_poly
					(pts
						(arc
							(start -0.1778 -0.2794)
							(mid -0.249642 -0.249642)
							(end -0.2794 -0.1778)
						)
						(arc
							(start -0.2794 0.1778)
							(mid -0.249642 0.249642)
							(end -0.1778 0.2794)
						)
						(arc
							(start 0.1778 0.2794)
							(mid 0.249642 0.249642)
							(end 0.2794 0.1778)
						)
						(arc
							(start 0.2794 -0.1778)
							(mid 0.249642 -0.249642)
							(end 0.1778 -0.2794)
						)
					)
					(width 0)
					(fill yes)
				)
			)
		)
	)
	(footprint ""
		(layer "F.Cu")
		(at 9.906 -123.063 90)
		(property "Reference" "R293"
			(at 0 0 90)
			(layer "F.SilkS")
			(hide yes)
			(effects
				(font
					(size 1.27 1.27)
				)
			)
		)
		(property "Value" "4K7R2F-GP"
			(at 0.064008 -3.993896 90)
			(unlocked yes)
			(layer "F.Fab")
			(hide yes)
			(effects
				(font
					(size 1.016 1.016)
					(thickness 0.1524)
				)
			)
		)
		(property "Device Type" "R402H16"
			(at 0.064008 -5.517896 90)
			(unlocked yes)
			(layer "F.Fab")
			(hide yes)
			(effects
				(font
					(size 1.016 1.016)
					(thickness 0.1524)
				)
			)
		)
		(duplicate_pad_numbers_are_jumpers no)
		(fp_line
			(start 0.508 -0.9398)
			(end -0.508 -0.9398)
			(stroke
				(width 0.1524)
				(type default)
			)
			(layer "F.SilkS")
		)
		(fp_line
			(start -0.508 -0.9398)
			(end -0.508 0.9398)
			(stroke
				(width 0.1524)
				(type default)
			)
			(layer "F.SilkS")
		)
		(fp_rect
			(start -0.508 0.9398)
			(end 0.508 -0.9398)
			(stroke
				(width 0)
				(type default)
			)
			(fill no)
			(layer "F.CrtYd")
		)
		(fp_rect
			(start -0.508 0.9398)
			(end 0.508 -0.9398)
			(stroke
				(width 0)
				(type default)
			)
			(fill no)
			(layer "F.Fab")
		)
		(pad "1" smd custom
			(at 0 -0.4445 90)
			(size 0.1397 0.1397)
			(layers "F.Cu" "F.Mask" "F.Paste")
			(net "P3V3_STBY")
			(options
				(clearance outline)
				(anchor circle)
			)
			(primitives
				(gr_poly
					(pts
						(arc
							(start -0.1778 -0.2794)
							(mid -0.249642 -0.249642)
							(end -0.2794 -0.1778)
						)
						(arc
							(start -0.2794 0.1778)
							(mid -0.249642 0.249642)
							(end -0.1778 0.2794)
						)
						(arc
							(start 0.1778 0.2794)
							(mid 0.249642 0.249642)
							(end 0.2794 0.1778)
						)
						(arc
							(start 0.2794 -0.1778)
							(mid 0.249642 -0.249642)
							(end 0.1778 -0.2794)
						)
					)
					(width 0)
					(fill yes)
				)
			)
		)
		(pad "2" smd custom
			(at 0 0.4445 90)
			(size 0.1397 0.1397)
			(layers "F.Cu" "F.Mask" "F.Paste")
			(net "I2C1_LS_G2")
			(options
				(clearance outline)
				(anchor circle)
			)
			(primitives
				(gr_poly
					(pts
						(arc
							(start -0.1778 -0.2794)
							(mid -0.249642 -0.249642)
							(end -0.2794 -0.1778)
						)
						(arc
							(start -0.2794 0.1778)
							(mid -0.249642 0.249642)
							(end -0.1778 0.2794)
						)
						(arc
							(start 0.1778 0.2794)
							(mid 0.249642 0.249642)
							(end 0.2794 0.1778)
						)
						(arc
							(start 0.2794 -0.1778)
							(mid 0.249642 -0.249642)
							(end 0.1778 -0.2794)
						)
					)
					(width 0)
					(fill yes)
				)
			)
		)
	)
	(footprint ""
		(layer "F.Cu")
		(at 157.592268 -212.420454 180)
		(property "Reference" "C168"
			(at 0 0 180)
			(layer "F.SilkS")
			(hide yes)
			(effects
				(font
					(size 1.27 1.27)
				)
			)
		)
		(property "Value" "SCD22U10V2KX-1GP"
			(at 1.1811 -2.7051 180)
			(unlocked yes)
			(layer "F.Fab")
			(hide yes)
			(effects
				(font
					(size 1.016 1.016)
					(thickness 0.1524)
				)
			)
		)
		(property "Device Type" "C402H22"
			(at 1.1811 -4.2291 180)
			(unlocked yes)
			(layer "F.Fab")
			(hide yes)
			(effects
				(font
					(size 1.016 1.016)
					(thickness 0.1524)
				)
			)
		)
		(duplicate_pad_numbers_are_jumpers no)
		(fp_rect
			(start -0.4318 0.9525)
			(end 0.4318 -0.9525)
			(stroke
				(width 0)
				(type default)
			)
			(fill no)
			(layer "F.CrtYd")
		)
		(fp_rect
			(start -0.4318 0.9525)
			(end 0.4318 -0.9525)
			(stroke
				(width 0)
				(type default)
			)
			(fill no)
			(layer "F.Fab")
		)
		(pad "1" smd custom
			(at 0 -0.4445 180)
			(size 0.1524 0.1524)
			(layers "F.Cu" "F.Mask" "F.Paste")
			(net "PCIE_TX_CAP_P53")
			(options
				(clearance outline)
				(anchor circle)
			)
			(primitives
				(gr_poly
					(pts
						(arc
							(start 0.3048 -0.2032)
							(mid 0.275042 -0.275042)
							(end 0.2032 -0.3048)
						)
						(arc
							(start -0.2032 -0.3048)
							(mid -0.275042 -0.275042)
							(end -0.3048 -0.2032)
						)
						(arc
							(start -0.3048 0.2032)
							(mid -0.275042 0.275042)
							(end -0.2032 0.3048)
						)
						(arc
							(start 0.2032 0.3048)
							(mid 0.275042 0.275042)
							(end 0.3048 0.2032)
						)
					)
					(width 0)
					(fill yes)
				)
			)
		)
		(pad "2" smd custom
			(at 0 0.4445 180)
			(size 0.1524 0.1524)
			(layers "F.Cu" "F.Mask" "F.Paste")
			(net "PCIE_TX_P53")
			(options
				(clearance outline)
				(anchor circle)
			)
			(primitives
				(gr_poly
					(pts
						(arc
							(start 0.3048 -0.2032)
							(mid 0.275042 -0.275042)
							(end 0.2032 -0.3048)
						)
						(arc
							(start -0.2032 -0.3048)
							(mid -0.275042 -0.275042)
							(end -0.3048 -0.2032)
						)
						(arc
							(start -0.3048 0.2032)
							(mid -0.275042 0.275042)
							(end -0.2032 0.3048)
						)
						(arc
							(start 0.2032 0.3048)
							(mid 0.275042 0.275042)
							(end 0.3048 0.2032)
						)
					)
					(width 0)
					(fill yes)
				)
			)
		)
	)
	(footprint ""
		(layer "F.Cu")
		(at 37.94252 -44.661074 180)
		(property "Reference" "U22"
			(at 0 0 180)
			(layer "F.SilkS")
			(hide yes)
			(effects
				(font
					(size 1.27 1.27)
				)
			)
		)
		(property "Value" "AZC099-04S-1-GP"
			(at -0.0254 -11.9634 180)
			(unlocked yes)
			(layer "F.Fab")
			(hide yes)
			(effects
				(font
					(size 1.016 1.016)
					(thickness 0.1524)
				)
			)
		)
		(property "Device Type" "SOT-6H58"
			(at -0.0254 -13.5636 180)
			(unlocked yes)
			(layer "F.Fab")
			(hide yes)
			(effects
				(font
					(size 1.016 1.016)
					(thickness 0.1524)
				)
			)
		)
		(duplicate_pad_numbers_are_jumpers no)
		(fp_line
			(start 1.7145 0.5842)
			(end 1.7145 -0.5842)
			(stroke
				(width 0.1524)
				(type default)
			)
			(layer "F.SilkS")
		)
		(fp_line
			(start 1.7145 -0.5842)
			(end -1.9685 -0.5842)
			(stroke
				(width 0.1524)
				(type default)
			)
			(layer "F.SilkS")
		)
		(fp_line
			(start -1.5621 0)
			(end -1.9685 0.4064)
			(stroke
				(width 0.1524)
				(type default)
			)
			(layer "F.SilkS")
		)
		(fp_line
			(start -1.9685 0.5842)
			(end 1.7145 0.5842)
			(stroke
				(width 0.1524)
				(type default)
			)
			(layer "F.SilkS")
		)
		(fp_line
			(start -1.9685 0.5842)
			(end -1.9685 2.3622)
			(stroke
				(width 0.508)
				(type default)
			)
			(layer "F.SilkS")
		)
		(fp_line
			(start -1.9685 -0.4064)
			(end -1.5621 0)
			(stroke
				(width 0.1524)
				(type default)
			)
			(layer "F.SilkS")
		)
		(fp_line
			(start -1.9685 -0.5842)
			(end -1.9685 0.5842)
			(stroke
				(width 0.1524)
				(type default)
			)
			(layer "F.SilkS")
		)
		(fp_poly
			(pts
				(xy -1.27 -0.635) (xy 1.27 -0.635) (xy 1.27 0.635) (xy -1.27 0.635)
			)
			(stroke
				(width 0)
				(type default)
			)
			(fill yes)
			(layer "F.SilkS")
		)
		(fp_rect
			(start -1.9685 2.3622)
			(end 1.9685 -2.3622)
			(stroke
				(width 0)
				(type default)
			)
			(fill no)
			(layer "F.CrtYd")
		)
		(fp_poly
			(pts
				(xy -1.9685 -2.3622) (xy 1.9685 -2.3622) (xy 1.9685 2.3622) (xy -1.9685 2.3622)
			)
			(stroke
				(width 0)
				(type default)
			)
			(fill no)
			(layer "F.Fab")
		)
		(pad "1" smd rect
			(at -0.9525 1.3462 180)
			(size 0.5842 1.016)
			(layers "F.Cu" "F.Mask" "F.Paste")
			(net "USB_P1_F_DP1")
		)
		(pad "2" smd rect
			(at 0 1.3462 180)
			(size 0.5842 1.016)
			(layers "F.Cu" "F.Mask" "F.Paste")
			(net "GND")
		)
		(pad "3" smd rect
			(at 0.9525 1.3462 180)
			(size 0.5842 1.016)
			(layers "F.Cu" "F.Mask" "F.Paste")
			(net "Net_2090")
		)
		(pad "4" smd rect
			(at 0.9525 -1.3462 180)
			(size 0.5842 1.016)
			(layers "F.Cu" "F.Mask" "F.Paste")
			(net "Net_2091")
		)
		(pad "5" smd rect
			(at 0 -1.3462 180)
			(size 0.5842 1.016)
			(layers "F.Cu" "F.Mask" "F.Paste")
			(net "P5V_USB")
		)
		(pad "6" smd rect
			(at -0.9525 -1.3462 180)
			(size 0.5842 1.016)
			(layers "F.Cu" "F.Mask" "F.Paste")
			(net "USB_P1_F_DN1")
		)
	)
	(footprint ""
		(layer "F.Cu")
		(at 133.864604 -67.249294)
		(property "Reference" "U9"
			(at 0 0 0)
			(layer "F.SilkS")
			(hide yes)
			(effects
				(font
					(size 1.27 1.27)
				)
			)
		)
		(property "Value" "N25Q128A11ESE40F-GP"
			(at 0 -13.1572 0)
			(unlocked yes)
			(layer "F.Fab")
			(hide yes)
			(effects
				(font
					(size 1.016 1.016)
					(thickness 0.1524)
				)
			)
		)
		(property "Device Type" "SOIC8-1H86"
			(at 0 -14.6812 0)
			(unlocked yes)
			(layer "F.Fab")
			(hide yes)
			(effects
				(font
					(size 1.016 1.016)
					(thickness 0.1524)
				)
			)
		)
		(duplicate_pad_numbers_are_jumpers no)
		(fp_line
			(start -3.2258 -2.3876)
			(end -3.2258 4.572)
			(stroke
				(width 0.1524)
				(type default)
			)
			(layer "F.SilkS")
		)
		(fp_line
			(start -3.048 4.572)
			(end -3.048 2.3876)
			(stroke
				(width 0.508)
				(type default)
			)
			(layer "F.SilkS")
		)
		(fp_line
			(start -2.3114 0)
			(end -3.2258 -0.9144)
			(stroke
				(width 0.1524)
				(type default)
			)
			(layer "F.SilkS")
		)
		(fp_line
			(start -2.3114 0)
			(end -3.2258 0.9144)
			(stroke
				(width 0.1524)
				(type default)
			)
			(layer "F.SilkS")
		)
		(fp_line
			(start 2.1336 -2.3876)
			(end -3.2258 -2.3876)
			(stroke
				(width 0.1524)
				(type default)
			)
			(layer "F.SilkS")
		)
		(fp_line
			(start 2.1336 -2.3876)
			(end 2.1336 2.3876)
			(stroke
				(width 0.1524)
				(type default)
			)
			(layer "F.SilkS")
		)
		(fp_line
			(start 2.1336 2.3876)
			(end -3.048 2.3876)
			(stroke
				(width 0.1524)
				(type default)
			)
			(layer "F.SilkS")
		)
		(fp_poly
			(pts
				(xy -2.2352 2.3876) (xy 2.1336 2.3876) (xy 2.1336 -2.3876) (xy -2.2352 -2.3876)
			)
			(stroke
				(width 0)
				(type default)
			)
			(fill yes)
			(layer "F.SilkS")
		)
		(fp_poly
			(pts
				(xy -3.302 4.826) (xy 3.302 4.826) (xy 3.302 -4.826) (xy -3.302 -4.826)
			)
			(stroke
				(width 0)
				(type default)
			)
			(fill no)
			(layer "F.CrtYd")
		)
		(fp_poly
			(pts
				(xy -3.302 -4.826) (xy 3.302 -4.826) (xy 3.302 4.826) (xy -3.302 4.826)
			)
			(stroke
				(width 0)
				(type default)
			)
			(fill no)
			(layer "F.Fab")
		)
		(pad "1" smd rect
			(at -1.905 3.4925)
			(size 0.635 1.651)
			(layers "F.Cu" "F.Mask" "F.Paste")
			(net "SPI_CSB0_0")
		)
		(pad "2" smd rect
			(at -0.635 3.4925)
			(size 0.635 1.651)
			(layers "F.Cu" "F.Mask" "F.Paste")
			(net "SPI_DATA0_1_R")
		)
		(pad "3" smd rect
			(at 0.635 3.4925)
			(size 0.635 1.651)
			(layers "F.Cu" "F.Mask" "F.Paste")
			(net "SPI_DATA0_2_R")
		)
		(pad "4" smd rect
			(at 1.905 3.4925)
			(size 0.635 1.651)
			(layers "F.Cu" "F.Mask" "F.Paste")
			(net "GND")
		)
		(pad "5" smd rect
			(at 1.905 -3.4925)
			(size 0.635 1.651)
			(layers "F.Cu" "F.Mask" "F.Paste")
			(net "SPI_DATA0_0_R")
		)
		(pad "6" smd rect
			(at 0.635 -3.4925)
			(size 0.635 1.651)
			(layers "F.Cu" "F.Mask" "F.Paste")
			(net "SPI_CLK0_R")
		)
		(pad "7" smd rect
			(at -0.635 -3.4925)
			(size 0.635 1.651)
			(layers "F.Cu" "F.Mask" "F.Paste")
			(net "SPI_DATA0_3_R")
		)
		(pad "8" smd rect
			(at -1.905 -3.4925)
			(size 0.635 1.651)
			(layers "F.Cu" "F.Mask" "F.Paste")
			(net "P1V8_STBY")
		)
	)
	(footprint ""
		(layer "F.Cu")
		(at 136.324848 -40.39489 90)
		(property "Reference" "R758"
			(at 0 0 90)
			(layer "F.SilkS")
			(hide yes)
			(effects
				(font
					(size 1.27 1.27)
				)
			)
		)
		(property "Value" "0R2J-2-GP"
			(at 0.064008 -3.993896 90)
			(unlocked yes)
			(layer "F.Fab")
			(hide yes)
			(effects
				(font
					(size 1.016 1.016)
					(thickness 0.1524)
				)
			)
		)
		(property "Device Type" "R402H16"
			(at 0.064008 -5.517896 90)
			(unlocked yes)
			(layer "F.Fab")
			(hide yes)
			(effects
				(font
					(size 1.016 1.016)
					(thickness 0.1524)
				)
			)
		)
		(duplicate_pad_numbers_are_jumpers no)
		(fp_line
			(start 0.508 -0.9398)
			(end -0.508 -0.9398)
			(stroke
				(width 0.1524)
				(type default)
			)
			(layer "F.SilkS")
		)
		(fp_line
			(start -0.508 -0.9398)
			(end -0.508 0.9398)
			(stroke
				(width 0.1524)
				(type default)
			)
			(layer "F.SilkS")
		)
		(fp_rect
			(start -0.508 0.9398)
			(end 0.508 -0.9398)
			(stroke
				(width 0)
				(type default)
			)
			(fill no)
			(layer "F.CrtYd")
		)
		(fp_rect
			(start -0.508 0.9398)
			(end 0.508 -0.9398)
			(stroke
				(width 0)
				(type default)
			)
			(fill no)
			(layer "F.Fab")
		)
		(pad "1" smd custom
			(at 0 -0.4445 90)
			(size 0.1397 0.1397)
			(layers "F.Cu" "F.Mask" "F.Paste")
			(net "DUT_TDO_R")
			(options
				(clearance outline)
				(anchor circle)
			)
			(primitives
				(gr_poly
					(pts
						(arc
							(start -0.1778 -0.2794)
							(mid -0.249642 -0.249642)
							(end -0.2794 -0.1778)
						)
						(arc
							(start -0.2794 0.1778)
							(mid -0.249642 0.249642)
							(end -0.1778 0.2794)
						)
						(arc
							(start 0.1778 0.2794)
							(mid 0.249642 0.249642)
							(end 0.2794 0.1778)
						)
						(arc
							(start 0.2794 -0.1778)
							(mid 0.249642 -0.249642)
							(end 0.1778 -0.2794)
						)
					)
					(width 0)
					(fill yes)
				)
			)
		)
		(pad "2" smd custom
			(at 0 0.4445 90)
			(size 0.1397 0.1397)
			(layers "F.Cu" "F.Mask" "F.Paste")
			(net "DUT_TDO")
			(options
				(clearance outline)
				(anchor circle)
			)
			(primitives
				(gr_poly
					(pts
						(arc
							(start -0.1778 -0.2794)
							(mid -0.249642 -0.249642)
							(end -0.2794 -0.1778)
						)
						(arc
							(start -0.2794 0.1778)
							(mid -0.249642 0.249642)
							(end -0.1778 0.2794)
						)
						(arc
							(start 0.1778 0.2794)
							(mid 0.249642 0.249642)
							(end 0.2794 0.1778)
						)
						(arc
							(start 0.2794 -0.1778)
							(mid 0.249642 -0.249642)
							(end 0.1778 -0.2794)
						)
					)
					(width 0)
					(fill yes)
				)
			)
		)
	)
	(footprint ""
		(layer "F.Cu")
		(at 17.7292 -194.5386 180)
		(property "Reference" "C7316"
			(at 0 0 180)
			(layer "F.SilkS")
			(hide yes)
			(effects
				(font
					(size 1.27 1.27)
				)
			)
		)
		(property "Value" "SCD1U25V3JX-GP"
			(at 0 -2.8194 180)
			(unlocked yes)
			(layer "F.Fab")
			(hide yes)
			(effects
				(font
					(size 1.016 1.016)
					(thickness 0.1524)
				)
			)
		)
		(property "Device Type" "C603H36"
			(at 0 -4.3434 180)
			(unlocked yes)
			(layer "F.Fab")
			(hide yes)
			(effects
				(font
					(size 1.016 1.016)
					(thickness 0.1524)
				)
			)
		)
		(duplicate_pad_numbers_are_jumpers no)
		(fp_line
			(start 0.508 0)
			(end -0.508 0)
			(stroke
				(width 0.2032)
				(type default)
			)
			(layer "F.SilkS")
		)
		(fp_rect
			(start -0.5842 1.3335)
			(end 0.5842 -1.3335)
			(stroke
				(width 0)
				(type default)
			)
			(fill no)
			(layer "F.CrtYd")
		)
		(fp_rect
			(start -0.5842 1.3335)
			(end 0.5842 -1.3335)
			(stroke
				(width 0)
				(type default)
			)
			(fill no)
			(layer "F.Fab")
		)
		(pad "1" smd custom
			(at 0 -0.762 180)
			(size 0.2159 0.2159)
			(layers "F.Cu" "F.Mask" "F.Paste")
			(net "MB0_PSET_R")
			(options
				(clearance outline)
				(anchor circle)
			)
			(primitives
				(gr_poly
					(pts
						(arc
							(start -0.3302 -0.4318)
							(mid -0.402042 -0.402042)
							(end -0.4318 -0.3302)
						)
						(arc
							(start -0.4318 0.3302)
							(mid -0.402042 0.402042)
							(end -0.3302 0.4318)
						)
						(arc
							(start 0.3302 0.4318)
							(mid 0.402042 0.402042)
							(end 0.4318 0.3302)
						)
						(arc
							(start 0.4318 -0.3302)
							(mid 0.402042 -0.402042)
							(end 0.3302 -0.4318)
						)
					)
					(width 0)
					(fill yes)
				)
			)
		)
		(pad "2" smd custom
			(at 0 0.762 180)
			(size 0.2159 0.2159)
			(layers "F.Cu" "F.Mask" "F.Paste")
			(net "AGND_CURRENT_MON")
			(options
				(clearance outline)
				(anchor circle)
			)
			(primitives
				(gr_poly
					(pts
						(arc
							(start -0.3302 -0.4318)
							(mid -0.402042 -0.402042)
							(end -0.4318 -0.3302)
						)
						(arc
							(start -0.4318 0.3302)
							(mid -0.402042 0.402042)
							(end -0.3302 0.4318)
						)
						(arc
							(start 0.3302 0.4318)
							(mid 0.402042 0.402042)
							(end 0.4318 0.3302)
						)
						(arc
							(start 0.4318 -0.3302)
							(mid 0.402042 -0.402042)
							(end 0.3302 -0.4318)
						)
					)
					(width 0)
					(fill yes)
				)
			)
		)
	)
	(footprint ""
		(layer "F.Cu")
		(at 335.026 -72.771 90)
		(property "Reference" "PC189"
			(at 0 0 90)
			(layer "F.SilkS")
			(hide yes)
			(effects
				(font
					(size 1.27 1.27)
				)
			)
		)
		(property "Value" "SC1KP50V2KX-1GP"
			(at 1.1811 -2.7051 90)
			(unlocked yes)
			(layer "F.Fab")
			(hide yes)
			(effects
				(font
					(size 1.016 1.016)
					(thickness 0.1524)
				)
			)
		)
		(property "Device Type" "C402H22"
			(at 1.1811 -4.2291 90)
			(unlocked yes)
			(layer "F.Fab")
			(hide yes)
			(effects
				(font
					(size 1.016 1.016)
					(thickness 0.1524)
				)
			)
		)
		(duplicate_pad_numbers_are_jumpers no)
		(fp_rect
			(start -0.4318 0.9525)
			(end 0.4318 -0.9525)
			(stroke
				(width 0)
				(type default)
			)
			(fill no)
			(layer "F.CrtYd")
		)
		(fp_rect
			(start -0.4318 0.9525)
			(end 0.4318 -0.9525)
			(stroke
				(width 0)
				(type default)
			)
			(fill no)
			(layer "F.Fab")
		)
		(pad "1" smd custom
			(at 0 -0.4445 90)
			(size 0.1524 0.1524)
			(layers "F.Cu" "F.Mask" "F.Paste")
			(net "P0V9_E_SW_R")
			(options
				(clearance outline)
				(anchor circle)
			)
			(primitives
				(gr_poly
					(pts
						(arc
							(start 0.3048 -0.2032)
							(mid 0.275042 -0.275042)
							(end 0.2032 -0.3048)
						)
						(arc
							(start -0.2032 -0.3048)
							(mid -0.275042 -0.275042)
							(end -0.3048 -0.2032)
						)
						(arc
							(start -0.3048 0.2032)
							(mid -0.275042 0.275042)
							(end -0.2032 0.3048)
						)
						(arc
							(start 0.2032 0.3048)
							(mid 0.275042 0.275042)
							(end 0.3048 0.2032)
						)
					)
					(width 0)
					(fill yes)
				)
			)
		)
		(pad "2" smd custom
			(at 0 0.4445 90)
			(size 0.1524 0.1524)
			(layers "F.Cu" "F.Mask" "F.Paste")
			(net "P0V9_E_VFB")
			(options
				(clearance outline)
				(anchor circle)
			)
			(primitives
				(gr_poly
					(pts
						(arc
							(start 0.3048 -0.2032)
							(mid 0.275042 -0.275042)
							(end 0.2032 -0.3048)
						)
						(arc
							(start -0.2032 -0.3048)
							(mid -0.275042 -0.275042)
							(end -0.3048 -0.2032)
						)
						(arc
							(start -0.3048 0.2032)
							(mid -0.275042 0.275042)
							(end -0.2032 0.3048)
						)
						(arc
							(start 0.2032 0.3048)
							(mid 0.275042 0.275042)
							(end 0.3048 0.2032)
						)
					)
					(width 0)
					(fill yes)
				)
			)
		)
	)
	(footprint ""
		(layer "F.Cu")
		(at 121.6152 -30.734)
		(property "Reference" "R805"
			(at 0 0 0)
			(layer "F.SilkS")
			(hide yes)
			(effects
				(font
					(size 1.27 1.27)
				)
			)
		)
		(property "Value" "4K7R2F-GP"
			(at 0.064008 -3.993896 0)
			(unlocked yes)
			(layer "F.Fab")
			(hide yes)
			(effects
				(font
					(size 1.016 1.016)
					(thickness 0.1524)
				)
			)
		)
		(property "Device Type" "R402H16"
			(at 0.064008 -5.517896 0)
			(unlocked yes)
			(layer "F.Fab")
			(hide yes)
			(effects
				(font
					(size 1.016 1.016)
					(thickness 0.1524)
				)
			)
		)
		(duplicate_pad_numbers_are_jumpers no)
		(fp_line
			(start -0.508 -0.9398)
			(end -0.508 0.9398)
			(stroke
				(width 0.1524)
				(type default)
			)
			(layer "F.SilkS")
		)
		(fp_line
			(start 0.508 -0.9398)
			(end -0.508 -0.9398)
			(stroke
				(width 0.1524)
				(type default)
			)
			(layer "F.SilkS")
		)
		(fp_rect
			(start -0.508 0.9398)
			(end 0.508 -0.9398)
			(stroke
				(width 0)
				(type default)
			)
			(fill no)
			(layer "F.CrtYd")
		)
		(fp_rect
			(start -0.508 0.9398)
			(end 0.508 -0.9398)
			(stroke
				(width 0)
				(type default)
			)
			(fill no)
			(layer "F.Fab")
		)
		(pad "1" smd custom
			(at 0 -0.4445)
			(size 0.1397 0.1397)
			(layers "F.Cu" "F.Mask" "F.Paste")
			(net "P3V3_STBY")
			(options
				(clearance outline)
				(anchor circle)
			)
			(primitives
				(gr_poly
					(pts
						(arc
							(start -0.1778 -0.2794)
							(mid -0.249642 -0.249642)
							(end -0.2794 -0.1778)
						)
						(arc
							(start -0.2794 0.1778)
							(mid -0.249642 0.249642)
							(end -0.1778 0.2794)
						)
						(arc
							(start 0.1778 0.2794)
							(mid 0.249642 0.249642)
							(end 0.2794 0.1778)
						)
						(arc
							(start 0.2794 -0.1778)
							(mid 0.249642 -0.249642)
							(end 0.1778 -0.2794)
						)
					)
					(width 0)
					(fill yes)
				)
			)
		)
		(pad "2" smd custom
			(at 0 0.4445)
			(size 0.1397 0.1397)
			(layers "F.Cu" "F.Mask" "F.Paste")
			(net "U54_INT_N")
			(options
				(clearance outline)
				(anchor circle)
			)
			(primitives
				(gr_poly
					(pts
						(arc
							(start -0.1778 -0.2794)
							(mid -0.249642 -0.249642)
							(end -0.2794 -0.1778)
						)
						(arc
							(start -0.2794 0.1778)
							(mid -0.249642 0.249642)
							(end -0.1778 0.2794)
						)
						(arc
							(start 0.1778 0.2794)
							(mid 0.249642 0.249642)
							(end 0.2794 0.1778)
						)
						(arc
							(start 0.2794 -0.1778)
							(mid 0.249642 -0.249642)
							(end 0.1778 -0.2794)
						)
					)
					(width 0)
					(fill yes)
				)
			)
		)
	)
	(footprint ""
		(layer "F.Cu")
		(at 217.781124 -190.601092 180)
		(property "Reference" "R552"
			(at 0 0 180)
			(layer "F.SilkS")
			(hide yes)
			(effects
				(font
					(size 1.27 1.27)
				)
			)
		)
		(property "Value" "10KR2F-2-GP"
			(at 0.064008 -3.993896 180)
			(unlocked yes)
			(layer "F.Fab")
			(hide yes)
			(effects
				(font
					(size 1.016 1.016)
					(thickness 0.1524)
				)
			)
		)
		(property "Device Type" "R402H16"
			(at 0.064008 -5.517896 180)
			(unlocked yes)
			(layer "F.Fab")
			(hide yes)
			(effects
				(font
					(size 1.016 1.016)
					(thickness 0.1524)
				)
			)
		)
		(duplicate_pad_numbers_are_jumpers no)
		(fp_line
			(start 0.508 -0.9398)
			(end -0.508 -0.9398)
			(stroke
				(width 0.1524)
				(type default)
			)
			(layer "F.SilkS")
		)
		(fp_line
			(start -0.508 -0.9398)
			(end -0.508 0.9398)
			(stroke
				(width 0.1524)
				(type default)
			)
			(layer "F.SilkS")
		)
		(fp_rect
			(start -0.508 0.9398)
			(end 0.508 -0.9398)
			(stroke
				(width 0)
				(type default)
			)
			(fill no)
			(layer "F.CrtYd")
		)
		(fp_rect
			(start -0.508 0.9398)
			(end 0.508 -0.9398)
			(stroke
				(width 0)
				(type default)
			)
			(fill no)
			(layer "F.Fab")
		)
		(pad "1" smd custom
			(at 0 -0.4445 180)
			(size 0.1397 0.1397)
			(layers "F.Cu" "F.Mask" "F.Paste")
			(net "GND")
			(options
				(clearance outline)
				(anchor circle)
			)
			(primitives
				(gr_poly
					(pts
						(arc
							(start -0.1778 -0.2794)
							(mid -0.249642 -0.249642)
							(end -0.2794 -0.1778)
						)
						(arc
							(start -0.2794 0.1778)
							(mid -0.249642 0.249642)
							(end -0.1778 0.2794)
						)
						(arc
							(start 0.1778 0.2794)
							(mid 0.249642 0.249642)
							(end 0.2794 0.1778)
						)
						(arc
							(start 0.2794 -0.1778)
							(mid 0.249642 -0.249642)
							(end 0.1778 -0.2794)
						)
					)
					(width 0)
					(fill yes)
				)
			)
		)
		(pad "2" smd custom
			(at 0 0.4445 180)
			(size 0.1397 0.1397)
			(layers "F.Cu" "F.Mask" "F.Paste")
			(net "IOEXP3_AD1")
			(options
				(clearance outline)
				(anchor circle)
			)
			(primitives
				(gr_poly
					(pts
						(arc
							(start -0.1778 -0.2794)
							(mid -0.249642 -0.249642)
							(end -0.2794 -0.1778)
						)
						(arc
							(start -0.2794 0.1778)
							(mid -0.249642 0.249642)
							(end -0.1778 0.2794)
						)
						(arc
							(start 0.1778 0.2794)
							(mid 0.249642 0.249642)
							(end 0.2794 0.1778)
						)
						(arc
							(start 0.2794 -0.1778)
							(mid 0.249642 -0.249642)
							(end 0.1778 -0.2794)
						)
					)
					(width 0)
					(fill yes)
				)
			)
		)
	)
	(footprint ""
		(layer "F.Cu")
		(at 273.304 -17.399 90)
		(property "Reference" "SR723"
			(at 0 0 90)
			(layer "F.SilkS")
			(hide yes)
			(effects
				(font
					(size 1.27 1.27)
				)
			)
		)
		(property "Value" "150R2F-1-GP"
			(at 0.064008 -3.993896 90)
			(unlocked yes)
			(layer "F.Fab")
			(hide yes)
			(effects
				(font
					(size 1.016 1.016)
					(thickness 0.1524)
				)
			)
		)
		(property "Device Type" "R402H16"
			(at 0.064008 -5.517896 90)
			(unlocked yes)
			(layer "F.Fab")
			(hide yes)
			(effects
				(font
					(size 1.016 1.016)
					(thickness 0.1524)
				)
			)
		)
		(duplicate_pad_numbers_are_jumpers no)
		(fp_line
			(start 0.508 -0.9398)
			(end -0.508 -0.9398)
			(stroke
				(width 0.1524)
				(type default)
			)
			(layer "F.SilkS")
		)
		(fp_line
			(start -0.508 -0.9398)
			(end -0.508 0.9398)
			(stroke
				(width 0.1524)
				(type default)
			)
			(layer "F.SilkS")
		)
		(fp_rect
			(start -0.508 0.9398)
			(end 0.508 -0.9398)
			(stroke
				(width 0)
				(type default)
			)
			(fill no)
			(layer "F.CrtYd")
		)
		(fp_rect
			(start -0.508 0.9398)
			(end 0.508 -0.9398)
			(stroke
				(width 0)
				(type default)
			)
			(fill no)
			(layer "F.Fab")
		)
		(pad "1" smd custom
			(at 0 -0.4445 90)
			(size 0.1397 0.1397)
			(layers "F.Cu" "F.Mask" "F.Paste")
			(net "P3V3_STBY")
			(options
				(clearance outline)
				(anchor circle)
			)
			(primitives
				(gr_poly
					(pts
						(arc
							(start -0.1778 -0.2794)
							(mid -0.249642 -0.249642)
							(end -0.2794 -0.1778)
						)
						(arc
							(start -0.2794 0.1778)
							(mid -0.249642 0.249642)
							(end -0.1778 0.2794)
						)
						(arc
							(start 0.1778 0.2794)
							(mid 0.249642 0.249642)
							(end 0.2794 0.1778)
						)
						(arc
							(start 0.2794 -0.1778)
							(mid 0.249642 -0.249642)
							(end 0.1778 -0.2794)
						)
					)
					(width 0)
					(fill yes)
				)
			)
		)
		(pad "2" smd custom
			(at 0 0.4445 90)
			(size 0.1397 0.1397)
			(layers "F.Cu" "F.Mask" "F.Paste")
			(net "LED_R_14")
			(options
				(clearance outline)
				(anchor circle)
			)
			(primitives
				(gr_poly
					(pts
						(arc
							(start -0.1778 -0.2794)
							(mid -0.249642 -0.249642)
							(end -0.2794 -0.1778)
						)
						(arc
							(start -0.2794 0.1778)
							(mid -0.249642 0.249642)
							(end -0.1778 0.2794)
						)
						(arc
							(start 0.1778 0.2794)
							(mid 0.249642 0.249642)
							(end 0.2794 0.1778)
						)
						(arc
							(start 0.2794 -0.1778)
							(mid 0.249642 -0.249642)
							(end 0.1778 -0.2794)
						)
					)
					(width 0)
					(fill yes)
				)
			)
		)
	)
	(footprint ""
		(layer "F.Cu")
		(at 330.6572 -207.8736 -90)
		(property "Reference" "C4156"
			(at 0 0 270)
			(layer "F.SilkS")
			(hide yes)
			(effects
				(font
					(size 1.27 1.27)
				)
			)
		)
		(property "Value" "SCD1U25V3KX-GP"
			(at 0 -2.8194 270)
			(unlocked yes)
			(layer "F.Fab")
			(hide yes)
			(effects
				(font
					(size 1.016 1.016)
					(thickness 0.1524)
				)
			)
		)
		(property "Device Type" "C603H36"
			(at 0 -4.3434 270)
			(unlocked yes)
			(layer "F.Fab")
			(hide yes)
			(effects
				(font
					(size 1.016 1.016)
					(thickness 0.1524)
				)
			)
		)
		(duplicate_pad_numbers_are_jumpers no)
		(fp_line
			(start 0.508 0)
			(end -0.508 0)
			(stroke
				(width 0.2032)
				(type default)
			)
			(layer "F.SilkS")
		)
		(fp_rect
			(start -0.5842 1.3335)
			(end 0.5842 -1.3335)
			(stroke
				(width 0)
				(type default)
			)
			(fill no)
			(layer "F.CrtYd")
		)
		(fp_rect
			(start -0.5842 1.3335)
			(end 0.5842 -1.3335)
			(stroke
				(width 0)
				(type default)
			)
			(fill no)
			(layer "F.Fab")
		)
		(pad "1" smd custom
			(at 0 -0.762 270)
			(size 0.2159 0.2159)
			(layers "F.Cu" "F.Mask" "F.Paste")
			(net "GND")
			(options
				(clearance outline)
				(anchor circle)
			)
			(primitives
				(gr_poly
					(pts
						(arc
							(start -0.3302 -0.4318)
							(mid -0.402042 -0.402042)
							(end -0.4318 -0.3302)
						)
						(arc
							(start -0.4318 0.3302)
							(mid -0.402042 0.402042)
							(end -0.3302 0.4318)
						)
						(arc
							(start 0.3302 0.4318)
							(mid 0.402042 0.402042)
							(end 0.4318 0.3302)
						)
						(arc
							(start 0.4318 -0.3302)
							(mid 0.402042 -0.402042)
							(end 0.3302 -0.4318)
						)
					)
					(width 0)
					(fill yes)
				)
			)
		)
		(pad "2" smd custom
			(at 0 0.762 270)
			(size 0.2159 0.2159)
			(layers "F.Cu" "F.Mask" "F.Paste")
			(net "SSD_PWREN9_R")
			(options
				(clearance outline)
				(anchor circle)
			)
			(primitives
				(gr_poly
					(pts
						(arc
							(start -0.3302 -0.4318)
							(mid -0.402042 -0.402042)
							(end -0.4318 -0.3302)
						)
						(arc
							(start -0.4318 0.3302)
							(mid -0.402042 0.402042)
							(end -0.3302 0.4318)
						)
						(arc
							(start 0.3302 0.4318)
							(mid 0.402042 0.402042)
							(end 0.4318 0.3302)
						)
						(arc
							(start 0.4318 -0.3302)
							(mid 0.402042 -0.402042)
							(end 0.3302 -0.4318)
						)
					)
					(width 0)
					(fill yes)
				)
			)
		)
	)
	(footprint ""
		(layer "F.Cu")
		(at 122.0978 -91.7702 180)
		(property "Reference" "R861"
			(at 0 0 180)
			(layer "F.SilkS")
			(hide yes)
			(effects
				(font
					(size 1.27 1.27)
				)
			)
		)
		(property "Value" "0R2J-2-GP"
			(at 0.064008 -3.993896 180)
			(unlocked yes)
			(layer "F.Fab")
			(hide yes)
			(effects
				(font
					(size 1.016 1.016)
					(thickness 0.1524)
				)
			)
		)
		(property "Device Type" "R402H16"
			(at 0.064008 -5.517896 180)
			(unlocked yes)
			(layer "F.Fab")
			(hide yes)
			(effects
				(font
					(size 1.016 1.016)
					(thickness 0.1524)
				)
			)
		)
		(duplicate_pad_numbers_are_jumpers no)
		(fp_line
			(start 0.508 -0.9398)
			(end -0.508 -0.9398)
			(stroke
				(width 0.1524)
				(type default)
			)
			(layer "F.SilkS")
		)
		(fp_line
			(start -0.508 -0.9398)
			(end -0.508 0.9398)
			(stroke
				(width 0.1524)
				(type default)
			)
			(layer "F.SilkS")
		)
		(fp_rect
			(start -0.508 0.9398)
			(end 0.508 -0.9398)
			(stroke
				(width 0)
				(type default)
			)
			(fill no)
			(layer "F.CrtYd")
		)
		(fp_rect
			(start -0.508 0.9398)
			(end 0.508 -0.9398)
			(stroke
				(width 0)
				(type default)
			)
			(fill no)
			(layer "F.Fab")
		)
		(pad "1" smd custom
			(at 0 -0.4445 180)
			(size 0.1397 0.1397)
			(layers "F.Cu" "F.Mask" "F.Paste")
			(net "BMC_I2C10_8536_SCL")
			(options
				(clearance outline)
				(anchor circle)
			)
			(primitives
				(gr_poly
					(pts
						(arc
							(start -0.1778 -0.2794)
							(mid -0.249642 -0.249642)
							(end -0.2794 -0.1778)
						)
						(arc
							(start -0.2794 0.1778)
							(mid -0.249642 0.249642)
							(end -0.1778 0.2794)
						)
						(arc
							(start 0.1778 0.2794)
							(mid 0.249642 0.249642)
							(end 0.2794 0.1778)
						)
						(arc
							(start 0.2794 -0.1778)
							(mid 0.249642 -0.249642)
							(end 0.1778 -0.2794)
						)
					)
					(width 0)
					(fill yes)
				)
			)
		)
		(pad "2" smd custom
			(at 0 0.4445 180)
			(size 0.1397 0.1397)
			(layers "F.Cu" "F.Mask" "F.Paste")
			(net "BMC_I2C10_8536_SCL_R")
			(options
				(clearance outline)
				(anchor circle)
			)
			(primitives
				(gr_poly
					(pts
						(arc
							(start -0.1778 -0.2794)
							(mid -0.249642 -0.249642)
							(end -0.2794 -0.1778)
						)
						(arc
							(start -0.2794 0.1778)
							(mid -0.249642 0.249642)
							(end -0.1778 0.2794)
						)
						(arc
							(start 0.1778 0.2794)
							(mid 0.249642 0.249642)
							(end 0.2794 0.1778)
						)
						(arc
							(start 0.2794 -0.1778)
							(mid 0.249642 -0.249642)
							(end 0.1778 -0.2794)
						)
					)
					(width 0)
					(fill yes)
				)
			)
		)
	)
	(footprint ""
		(layer "F.Cu")
		(at 6.858 -91.694 180)
		(property "Reference" "R528"
			(at 0 0 180)
			(layer "F.SilkS")
			(hide yes)
			(effects
				(font
					(size 1.27 1.27)
				)
			)
		)
		(property "Value" "33R2J-2-GP"
			(at 0.064008 -3.993896 180)
			(unlocked yes)
			(layer "F.Fab")
			(hide yes)
			(effects
				(font
					(size 1.016 1.016)
					(thickness 0.1524)
				)
			)
		)
		(property "Device Type" "R402H16"
			(at 0.064008 -5.517896 180)
			(unlocked yes)
			(layer "F.Fab")
			(hide yes)
			(effects
				(font
					(size 1.016 1.016)
					(thickness 0.1524)
				)
			)
		)
		(duplicate_pad_numbers_are_jumpers no)
		(fp_line
			(start 0.508 -0.9398)
			(end -0.508 -0.9398)
			(stroke
				(width 0.1524)
				(type default)
			)
			(layer "F.SilkS")
		)
		(fp_line
			(start -0.508 -0.9398)
			(end -0.508 0.9398)
			(stroke
				(width 0.1524)
				(type default)
			)
			(layer "F.SilkS")
		)
		(fp_rect
			(start -0.508 0.9398)
			(end 0.508 -0.9398)
			(stroke
				(width 0)
				(type default)
			)
			(fill no)
			(layer "F.CrtYd")
		)
		(fp_rect
			(start -0.508 0.9398)
			(end 0.508 -0.9398)
			(stroke
				(width 0)
				(type default)
			)
			(fill no)
			(layer "F.Fab")
		)
		(pad "1" smd custom
			(at 0 -0.4445 180)
			(size 0.1397 0.1397)
			(layers "F.Cu" "F.Mask" "F.Paste")
			(net "50M_CLK_OUT")
			(options
				(clearance outline)
				(anchor circle)
			)
			(primitives
				(gr_poly
					(pts
						(arc
							(start -0.1778 -0.2794)
							(mid -0.249642 -0.249642)
							(end -0.2794 -0.1778)
						)
						(arc
							(start -0.2794 0.1778)
							(mid -0.249642 0.249642)
							(end -0.1778 0.2794)
						)
						(arc
							(start 0.1778 0.2794)
							(mid 0.249642 0.249642)
							(end 0.2794 0.1778)
						)
						(arc
							(start 0.2794 -0.1778)
							(mid 0.249642 -0.249642)
							(end 0.1778 -0.2794)
						)
					)
					(width 0)
					(fill yes)
				)
			)
		)
		(pad "2" smd custom
			(at 0 0.4445 180)
			(size 0.1397 0.1397)
			(layers "F.Cu" "F.Mask" "F.Paste")
			(net "50M_CLK_OUT_R")
			(options
				(clearance outline)
				(anchor circle)
			)
			(primitives
				(gr_poly
					(pts
						(arc
							(start -0.1778 -0.2794)
							(mid -0.249642 -0.249642)
							(end -0.2794 -0.1778)
						)
						(arc
							(start -0.2794 0.1778)
							(mid -0.249642 0.249642)
							(end -0.1778 0.2794)
						)
						(arc
							(start 0.1778 0.2794)
							(mid 0.249642 0.249642)
							(end 0.2794 0.1778)
						)
						(arc
							(start 0.2794 -0.1778)
							(mid 0.249642 -0.249642)
							(end 0.1778 -0.2794)
						)
					)
					(width 0)
					(fill yes)
				)
			)
		)
	)
	(footprint ""
		(layer "F.Cu")
		(at 48.39208 -212.420454 180)
		(property "Reference" "C366"
			(at 0 0 180)
			(layer "F.SilkS")
			(hide yes)
			(effects
				(font
					(size 1.27 1.27)
				)
			)
		)
		(property "Value" "SCD22U10V2KX-1GP"
			(at 1.1811 -2.7051 180)
			(unlocked yes)
			(layer "F.Fab")
			(hide yes)
			(effects
				(font
					(size 1.016 1.016)
					(thickness 0.1524)
				)
			)
		)
		(property "Device Type" "C402H22"
			(at 1.1811 -4.2291 180)
			(unlocked yes)
			(layer "F.Fab")
			(hide yes)
			(effects
				(font
					(size 1.016 1.016)
					(thickness 0.1524)
				)
			)
		)
		(duplicate_pad_numbers_are_jumpers no)
		(fp_rect
			(start -0.4318 0.9525)
			(end 0.4318 -0.9525)
			(stroke
				(width 0)
				(type default)
			)
			(fill no)
			(layer "F.CrtYd")
		)
		(fp_rect
			(start -0.4318 0.9525)
			(end 0.4318 -0.9525)
			(stroke
				(width 0)
				(type default)
			)
			(fill no)
			(layer "F.Fab")
		)
		(pad "1" smd custom
			(at 0 -0.4445 180)
			(size 0.1524 0.1524)
			(layers "F.Cu" "F.Mask" "F.Paste")
			(net "PCIE_TX_CAP_P75")
			(options
				(clearance outline)
				(anchor circle)
			)
			(primitives
				(gr_poly
					(pts
						(arc
							(start 0.3048 -0.2032)
							(mid 0.275042 -0.275042)
							(end 0.2032 -0.3048)
						)
						(arc
							(start -0.2032 -0.3048)
							(mid -0.275042 -0.275042)
							(end -0.3048 -0.2032)
						)
						(arc
							(start -0.3048 0.2032)
							(mid -0.275042 0.275042)
							(end -0.2032 0.3048)
						)
						(arc
							(start 0.2032 0.3048)
							(mid 0.275042 0.275042)
							(end 0.3048 0.2032)
						)
					)
					(width 0)
					(fill yes)
				)
			)
		)
		(pad "2" smd custom
			(at 0 0.4445 180)
			(size 0.1524 0.1524)
			(layers "F.Cu" "F.Mask" "F.Paste")
			(net "PCIE_TX_P75")
			(options
				(clearance outline)
				(anchor circle)
			)
			(primitives
				(gr_poly
					(pts
						(arc
							(start 0.3048 -0.2032)
							(mid 0.275042 -0.275042)
							(end 0.2032 -0.3048)
						)
						(arc
							(start -0.2032 -0.3048)
							(mid -0.275042 -0.275042)
							(end -0.3048 -0.2032)
						)
						(arc
							(start -0.3048 0.2032)
							(mid -0.275042 0.275042)
							(end -0.2032 0.3048)
						)
						(arc
							(start 0.2032 0.3048)
							(mid 0.275042 0.275042)
							(end 0.3048 0.2032)
						)
					)
					(width 0)
					(fill yes)
				)
			)
		)
	)
	(footprint ""
		(layer "F.Cu")
		(at 194.5386 -6.6548 90)
		(property "Reference" "R944"
			(at 0 0 90)
			(layer "F.SilkS")
			(hide yes)
			(effects
				(font
					(size 1.27 1.27)
				)
			)
		)
		(property "Value" "100KR2F-L1-GP"
			(at 0.064008 -3.993896 90)
			(unlocked yes)
			(layer "F.Fab")
			(hide yes)
			(effects
				(font
					(size 1.016 1.016)
					(thickness 0.1524)
				)
			)
		)
		(property "Device Type" "R402H16"
			(at 0.064008 -5.517896 90)
			(unlocked yes)
			(layer "F.Fab")
			(hide yes)
			(effects
				(font
					(size 1.016 1.016)
					(thickness 0.1524)
				)
			)
		)
		(duplicate_pad_numbers_are_jumpers no)
		(fp_line
			(start 0.508 -0.9398)
			(end -0.508 -0.9398)
			(stroke
				(width 0.1524)
				(type default)
			)
			(layer "F.SilkS")
		)
		(fp_line
			(start -0.508 -0.9398)
			(end -0.508 0.9398)
			(stroke
				(width 0.1524)
				(type default)
			)
			(layer "F.SilkS")
		)
		(fp_rect
			(start -0.508 0.9398)
			(end 0.508 -0.9398)
			(stroke
				(width 0)
				(type default)
			)
			(fill no)
			(layer "F.CrtYd")
		)
		(fp_rect
			(start -0.508 0.9398)
			(end 0.508 -0.9398)
			(stroke
				(width 0)
				(type default)
			)
			(fill no)
			(layer "F.Fab")
		)
		(pad "1" smd custom
			(at 0 -0.4445 90)
			(size 0.1397 0.1397)
			(layers "F.Cu" "F.Mask" "F.Paste")
			(net "WP_ENABLE")
			(options
				(clearance outline)
				(anchor circle)
			)
			(primitives
				(gr_poly
					(pts
						(arc
							(start -0.1778 -0.2794)
							(mid -0.249642 -0.249642)
							(end -0.2794 -0.1778)
						)
						(arc
							(start -0.2794 0.1778)
							(mid -0.249642 0.249642)
							(end -0.1778 0.2794)
						)
						(arc
							(start 0.1778 0.2794)
							(mid 0.249642 0.249642)
							(end 0.2794 0.1778)
						)
						(arc
							(start 0.2794 -0.1778)
							(mid 0.249642 -0.249642)
							(end 0.1778 -0.2794)
						)
					)
					(width 0)
					(fill yes)
				)
			)
		)
		(pad "2" smd custom
			(at 0 0.4445 90)
			(size 0.1397 0.1397)
			(layers "F.Cu" "F.Mask" "F.Paste")
			(net "GND")
			(options
				(clearance outline)
				(anchor circle)
			)
			(primitives
				(gr_poly
					(pts
						(arc
							(start -0.1778 -0.2794)
							(mid -0.249642 -0.249642)
							(end -0.2794 -0.1778)
						)
						(arc
							(start -0.2794 0.1778)
							(mid -0.249642 0.249642)
							(end -0.1778 0.2794)
						)
						(arc
							(start 0.1778 0.2794)
							(mid 0.249642 0.249642)
							(end 0.2794 0.1778)
						)
						(arc
							(start 0.2794 -0.1778)
							(mid 0.249642 -0.249642)
							(end 0.1778 -0.2794)
						)
					)
					(width 0)
					(fill yes)
				)
			)
		)
	)
	(footprint ""
		(layer "F.Cu")
		(at 133.7818 -210.7438 -90)
		(property "Reference" "C4144"
			(at 0 0 270)
			(layer "F.SilkS")
			(hide yes)
			(effects
				(font
					(size 1.27 1.27)
				)
			)
		)
		(property "Value" "SCD1U25V3KX-GP"
			(at 0 -2.8194 270)
			(unlocked yes)
			(layer "F.Fab")
			(hide yes)
			(effects
				(font
					(size 1.016 1.016)
					(thickness 0.1524)
				)
			)
		)
		(property "Device Type" "C603H36"
			(at 0 -4.3434 270)
			(unlocked yes)
			(layer "F.Fab")
			(hide yes)
			(effects
				(font
					(size 1.016 1.016)
					(thickness 0.1524)
				)
			)
		)
		(duplicate_pad_numbers_are_jumpers no)
		(fp_line
			(start 0.508 0)
			(end -0.508 0)
			(stroke
				(width 0.2032)
				(type default)
			)
			(layer "F.SilkS")
		)
		(fp_rect
			(start -0.5842 1.3335)
			(end 0.5842 -1.3335)
			(stroke
				(width 0)
				(type default)
			)
			(fill no)
			(layer "F.CrtYd")
		)
		(fp_rect
			(start -0.5842 1.3335)
			(end 0.5842 -1.3335)
			(stroke
				(width 0)
				(type default)
			)
			(fill no)
			(layer "F.Fab")
		)
		(pad "1" smd custom
			(at 0 -0.762 270)
			(size 0.2159 0.2159)
			(layers "F.Cu" "F.Mask" "F.Paste")
			(net "GND")
			(options
				(clearance outline)
				(anchor circle)
			)
			(primitives
				(gr_poly
					(pts
						(arc
							(start -0.3302 -0.4318)
							(mid -0.402042 -0.402042)
							(end -0.4318 -0.3302)
						)
						(arc
							(start -0.4318 0.3302)
							(mid -0.402042 0.402042)
							(end -0.3302 0.4318)
						)
						(arc
							(start 0.3302 0.4318)
							(mid 0.402042 0.402042)
							(end 0.4318 0.3302)
						)
						(arc
							(start 0.4318 -0.3302)
							(mid 0.402042 -0.402042)
							(end 0.3302 -0.4318)
						)
					)
					(width 0)
					(fill yes)
				)
			)
		)
		(pad "2" smd custom
			(at 0 0.762 270)
			(size 0.2159 0.2159)
			(layers "F.Cu" "F.Mask" "F.Paste")
			(net "SSD_PWREN6_R")
			(options
				(clearance outline)
				(anchor circle)
			)
			(primitives
				(gr_poly
					(pts
						(arc
							(start -0.3302 -0.4318)
							(mid -0.402042 -0.402042)
							(end -0.4318 -0.3302)
						)
						(arc
							(start -0.4318 0.3302)
							(mid -0.402042 0.402042)
							(end -0.3302 0.4318)
						)
						(arc
							(start 0.3302 0.4318)
							(mid 0.402042 0.402042)
							(end 0.4318 0.3302)
						)
						(arc
							(start 0.4318 -0.3302)
							(mid 0.402042 -0.402042)
							(end 0.3302 -0.4318)
						)
					)
					(width 0)
					(fill yes)
				)
			)
		)
	)
	(footprint ""
		(layer "F.Cu")
		(at 335.185512 -178.782218)
		(property "Reference" "U201"
			(at 0 0 0)
			(layer "F.SilkS")
			(hide yes)
			(effects
				(font
					(size 1.27 1.27)
				)
			)
		)
		(property "Value" "MAX7311AUG-GP"
			(at 0 -12.1412 0)
			(unlocked yes)
			(layer "F.Fab")
			(hide yes)
			(effects
				(font
					(size 1.016 1.016)
					(thickness 0.1524)
				)
			)
		)
		(property "Device Type" "TSOIC24H44"
			(at 0 -13.6652 0)
			(unlocked yes)
			(layer "F.Fab")
			(hide yes)
			(effects
				(font
					(size 1.016 1.016)
					(thickness 0.1524)
				)
			)
		)
		(duplicate_pad_numbers_are_jumpers no)
		(fp_line
			(start -4.1148 -1.778)
			(end -4.1148 1.778)
			(stroke
				(width 0.1524)
				(type default)
			)
			(layer "F.SilkS")
		)
		(fp_line
			(start -4.1148 -1.778)
			(end 3.683 -1.778)
			(stroke
				(width 0.1524)
				(type default)
			)
			(layer "F.SilkS")
		)
		(fp_line
			(start -4.0386 1.778)
			(end -4.0386 3.556)
			(stroke
				(width 0.3556)
				(type default)
			)
			(layer "F.SilkS")
		)
		(fp_line
			(start -3.8354 0)
			(end -4.1148 -0.2794)
			(stroke
				(width 0.1524)
				(type default)
			)
			(layer "F.SilkS")
		)
		(fp_line
			(start -3.8354 0)
			(end -4.1148 0.2794)
			(stroke
				(width 0.1524)
				(type default)
			)
			(layer "F.SilkS")
		)
		(fp_line
			(start 3.683 -1.778)
			(end 3.683 1.778)
			(stroke
				(width 0.1524)
				(type default)
			)
			(layer "F.SilkS")
		)
		(fp_line
			(start 3.683 1.778)
			(end -4.1148 1.778)
			(stroke
				(width 0.1524)
				(type default)
			)
			(layer "F.SilkS")
		)
		(fp_poly
			(pts
				(xy -3.7592 -1.778) (xy 3.683 -1.778) (xy 3.683 1.778) (xy -3.7592 1.778)
			)
			(stroke
				(width 0)
				(type default)
			)
			(fill yes)
			(layer "F.SilkS")
		)
		(fp_poly
			(pts
				(xy -4.22656 3.81) (xy 4.22656 3.81) (xy 4.22656 -3.81) (xy -4.22656 -3.81)
			)
			(stroke
				(width 0)
				(type default)
			)
			(fill no)
			(layer "F.CrtYd")
		)
		(fp_poly
			(pts
				(xy -4.22656 -3.81) (xy 4.22656 -3.81) (xy 4.22656 3.81) (xy -4.22656 3.81)
			)
			(stroke
				(width 0)
				(type default)
			)
			(fill no)
			(layer "F.Fab")
		)
		(pad "1" smd rect
			(at -3.57632 2.8194)
			(size 0.3556 1.524)
			(layers "F.Cu" "F.Mask" "F.Paste")
			(net "IOEXP_INT#_4")
		)
		(pad "2" smd rect
			(at -2.92608 2.8194)
			(size 0.3556 1.524)
			(layers "F.Cu" "F.Mask" "F.Paste")
			(net "IOEXP4_AD1")
		)
		(pad "3" smd rect
			(at -2.27584 2.8194)
			(size 0.3556 1.524)
			(layers "F.Cu" "F.Mask" "F.Paste")
			(net "IOEXP4_AD2")
		)
		(pad "4" smd rect
			(at -1.6256 2.8194)
			(size 0.3556 1.524)
			(layers "F.Cu" "F.Mask" "F.Paste")
			(net "SSD_PRSNT#4")
		)
		(pad "5" smd rect
			(at -0.97536 2.8194)
			(size 0.3556 1.524)
			(layers "F.Cu" "F.Mask" "F.Paste")
			(net "SSD_ATNLED#4")
		)
		(pad "6" smd rect
			(at -0.32512 2.8194)
			(size 0.3556 1.524)
			(layers "F.Cu" "F.Mask" "F.Paste")
			(net "SSD_PWREN4")
		)
		(pad "7" smd rect
			(at 0.32512 2.8194)
			(size 0.3556 1.524)
			(layers "F.Cu" "F.Mask" "F.Paste")
			(net "SSD_PERST#4")
		)
		(pad "8" smd rect
			(at 0.97536 2.8194)
			(size 0.3556 1.524)
			(layers "F.Cu" "F.Mask" "F.Paste")
			(net "SSD_PRSNT#9")
		)
		(pad "9" smd rect
			(at 1.6256 2.8194)
			(size 0.3556 1.524)
			(layers "F.Cu" "F.Mask" "F.Paste")
			(net "SSD_ATNLED#9")
		)
		(pad "10" smd rect
			(at 2.27584 2.8194)
			(size 0.3556 1.524)
			(layers "F.Cu" "F.Mask" "F.Paste")
			(net "SSD_PWREN9")
		)
		(pad "11" smd rect
			(at 2.92608 2.8194)
			(size 0.3556 1.524)
			(layers "F.Cu" "F.Mask" "F.Paste")
			(net "SSD_PERST#9")
		)
		(pad "12" smd rect
			(at 3.57632 2.8194)
			(size 0.3556 1.524)
			(layers "F.Cu" "F.Mask" "F.Paste")
			(net "GND")
		)
		(pad "13" smd rect
			(at 3.57632 -2.8194)
			(size 0.3556 1.524)
			(layers "F.Cu" "F.Mask" "F.Paste")
			(net "SSD_PRSNT#14")
		)
		(pad "14" smd rect
			(at 2.92608 -2.8194)
			(size 0.3556 1.524)
			(layers "F.Cu" "F.Mask" "F.Paste")
			(net "SSD_ATNLED#14")
		)
		(pad "15" smd rect
			(at 2.27584 -2.8194)
			(size 0.3556 1.524)
			(layers "F.Cu" "F.Mask" "F.Paste")
			(net "SSD_PWREN14")
		)
		(pad "16" smd rect
			(at 1.6256 -2.8194)
			(size 0.3556 1.524)
			(layers "F.Cu" "F.Mask" "F.Paste")
			(net "SSD_PERST#14")
		)
		(pad "17" smd rect
			(at 0.97536 -2.8194)
			(size 0.3556 1.524)
			(layers "F.Cu" "F.Mask" "F.Paste")
			(net "IOEXP4_GPIO12")
		)
		(pad "18" smd rect
			(at 0.32512 -2.8194)
			(size 0.3556 1.524)
			(layers "F.Cu" "F.Mask" "F.Paste")
			(net "IOEXP4_GPIO13")
		)
		(pad "19" smd rect
			(at -0.32512 -2.8194)
			(size 0.3556 1.524)
			(layers "F.Cu" "F.Mask" "F.Paste")
			(net "IOEXP4_GPIO14")
		)
		(pad "20" smd rect
			(at -0.97536 -2.8194)
			(size 0.3556 1.524)
			(layers "F.Cu" "F.Mask" "F.Paste")
			(net "BMC_PERST#15")
		)
		(pad "21" smd rect
			(at -1.6256 -2.8194)
			(size 0.3556 1.524)
			(layers "F.Cu" "F.Mask" "F.Paste")
			(net "IOEXP4_AD0")
		)
		(pad "22" smd rect
			(at -2.27584 -2.8194)
			(size 0.3556 1.524)
			(layers "F.Cu" "F.Mask" "F.Paste")
			(net "I2C_GPIO_SCL_4")
		)
		(pad "23" smd rect
			(at -2.92608 -2.8194)
			(size 0.3556 1.524)
			(layers "F.Cu" "F.Mask" "F.Paste")
			(net "I2C_GPIO_SDA_4")
		)
		(pad "24" smd rect
			(at -3.57632 -2.8194)
			(size 0.3556 1.524)
			(layers "F.Cu" "F.Mask" "F.Paste")
			(net "P3V3_STBY")
		)
	)
	(footprint ""
		(layer "F.Cu")
		(at 26.621232 -102.182168)
		(property "Reference" "U42"
			(at 0 0 0)
			(layer "F.SilkS")
			(hide yes)
			(effects
				(font
					(size 1.27 1.27)
				)
			)
		)
		(property "Value" "SN74LVC1G07DCKRG4-2-GP"
			(at -2.3368 -8.6868 0)
			(unlocked yes)
			(layer "F.Fab")
			(hide yes)
			(effects
				(font
					(size 1.016 1.016)
					(thickness 0.1524)
				)
			)
		)
		(property "Device Type" "SC70-5H44"
			(at -2.3114 -10.414 0)
			(unlocked yes)
			(layer "F.Fab")
			(hide yes)
			(effects
				(font
					(size 1.016 1.016)
					(thickness 0.1524)
				)
			)
		)
		(duplicate_pad_numbers_are_jumpers no)
		(fp_line
			(start -1.27 -1.7018)
			(end 1.27 -1.7018)
			(stroke
				(width 0.1524)
				(type default)
			)
			(layer "F.SilkS")
		)
		(fp_line
			(start -1.27 1.7018)
			(end -1.27 -1.7018)
			(stroke
				(width 0.1524)
				(type default)
			)
			(layer "F.SilkS")
		)
		(fp_line
			(start 0.6604 -1.8034)
			(end 1.3843 -1.8034)
			(stroke
				(width 0.3302)
				(type default)
			)
			(layer "F.SilkS")
		)
		(fp_line
			(start 1.27 -1.7018)
			(end 1.27 1.7018)
			(stroke
				(width 0.1524)
				(type default)
			)
			(layer "F.SilkS")
		)
		(fp_line
			(start 1.27 1.7018)
			(end -1.27 1.7018)
			(stroke
				(width 0.1524)
				(type default)
			)
			(layer "F.SilkS")
		)
		(fp_line
			(start 1.3843 -1.8034)
			(end 1.3843 -1.1176)
			(stroke
				(width 0.3302)
				(type default)
			)
			(layer "F.SilkS")
		)
		(fp_rect
			(start -1.524 1.9558)
			(end 1.524 -1.9558)
			(stroke
				(width 0)
				(type default)
			)
			(fill no)
			(layer "F.CrtYd")
		)
		(fp_poly
			(pts
				(xy -1.524 -1.9558) (xy 1.524 -1.9558) (xy 1.524 1.9558) (xy -1.524 1.9558)
			)
			(stroke
				(width 0)
				(type default)
			)
			(fill no)
			(layer "F.Fab")
		)
		(pad "1" smd rect
			(at 0.65024 -0.8255)
			(size 0.4064 1.2192)
			(layers "F.Cu" "F.Mask" "F.Paste")
			(net "Net_285")
		)
		(pad "2" smd rect
			(at 0 -0.8255)
			(size 0.4064 1.2192)
			(layers "F.Cu" "F.Mask" "F.Paste")
			(net "FM_BMC_RESET_N")
		)
		(pad "3" smd rect
			(at -0.65024 -0.8255)
			(size 0.4064 1.2192)
			(layers "F.Cu" "F.Mask" "F.Paste")
			(net "GND")
		)
		(pad "4" smd rect
			(at -0.65024 0.8255)
			(size 0.4064 1.2192)
			(layers "F.Cu" "F.Mask" "F.Paste")
			(net "FM_TPM_PRES_RST_N_C")
		)
		(pad "5" smd rect
			(at 0.65024 0.8255)
			(size 0.4064 1.2192)
			(layers "F.Cu" "F.Mask" "F.Paste")
			(net "P3V3_STBY")
		)
	)
	(footprint ""
		(layer "F.Cu")
		(at 78.938628 -74.5617 90)
		(property "Reference" "R962"
			(at 0 0 90)
			(layer "F.SilkS")
			(hide yes)
			(effects
				(font
					(size 1.27 1.27)
				)
			)
		)
		(property "Value" "4K7R2F-GP"
			(at 0.064008 -3.993896 90)
			(unlocked yes)
			(layer "F.Fab")
			(hide yes)
			(effects
				(font
					(size 1.016 1.016)
					(thickness 0.1524)
				)
			)
		)
		(property "Device Type" "R402H16"
			(at 0.064008 -5.517896 90)
			(unlocked yes)
			(layer "F.Fab")
			(hide yes)
			(effects
				(font
					(size 1.016 1.016)
					(thickness 0.1524)
				)
			)
		)
		(duplicate_pad_numbers_are_jumpers no)
		(fp_line
			(start 0.508 -0.9398)
			(end -0.508 -0.9398)
			(stroke
				(width 0.1524)
				(type default)
			)
			(layer "F.SilkS")
		)
		(fp_line
			(start -0.508 -0.9398)
			(end -0.508 0.9398)
			(stroke
				(width 0.1524)
				(type default)
			)
			(layer "F.SilkS")
		)
		(fp_rect
			(start -0.508 0.9398)
			(end 0.508 -0.9398)
			(stroke
				(width 0)
				(type default)
			)
			(fill no)
			(layer "F.CrtYd")
		)
		(fp_rect
			(start -0.508 0.9398)
			(end 0.508 -0.9398)
			(stroke
				(width 0)
				(type default)
			)
			(fill no)
			(layer "F.Fab")
		)
		(pad "1" smd custom
			(at 0 -0.4445 90)
			(size 0.1397 0.1397)
			(layers "F.Cu" "F.Mask" "F.Paste")
			(net "FLA_CS_R")
			(options
				(clearance outline)
				(anchor circle)
			)
			(primitives
				(gr_poly
					(pts
						(arc
							(start -0.1778 -0.2794)
							(mid -0.249642 -0.249642)
							(end -0.2794 -0.1778)
						)
						(arc
							(start -0.2794 0.1778)
							(mid -0.249642 0.249642)
							(end -0.1778 0.2794)
						)
						(arc
							(start 0.1778 0.2794)
							(mid 0.249642 0.249642)
							(end 0.2794 0.1778)
						)
						(arc
							(start 0.2794 -0.1778)
							(mid 0.249642 -0.249642)
							(end 0.1778 -0.2794)
						)
					)
					(width 0)
					(fill yes)
				)
			)
		)
		(pad "2" smd custom
			(at 0 0.4445 90)
			(size 0.1397 0.1397)
			(layers "F.Cu" "F.Mask" "F.Paste")
			(net "P3V3_STBY")
			(options
				(clearance outline)
				(anchor circle)
			)
			(primitives
				(gr_poly
					(pts
						(arc
							(start -0.1778 -0.2794)
							(mid -0.249642 -0.249642)
							(end -0.2794 -0.1778)
						)
						(arc
							(start -0.2794 0.1778)
							(mid -0.249642 0.249642)
							(end -0.1778 0.2794)
						)
						(arc
							(start 0.1778 0.2794)
							(mid 0.249642 0.249642)
							(end 0.2794 0.1778)
						)
						(arc
							(start 0.2794 -0.1778)
							(mid 0.249642 -0.249642)
							(end 0.1778 -0.2794)
						)
					)
					(width 0)
					(fill yes)
				)
			)
		)
	)
	(footprint ""
		(layer "F.Cu")
		(at 7.0612 -175.6156 90)
		(property "Reference" "Q95"
			(at 0 0 90)
			(layer "F.SilkS")
			(hide yes)
			(effects
				(font
					(size 1.27 1.27)
				)
			)
		)
		(property "Value" "2N7002K-1-GP"
			(at 0.127 -8.9662 90)
			(unlocked yes)
			(layer "F.Fab")
			(hide yes)
			(effects
				(font
					(size 1.016 1.016)
					(thickness 0.1524)
				)
			)
		)
		(property "Device Type" "SOT23DGS2D4H44"
			(at 0.127 -10.4902 90)
			(unlocked yes)
			(layer "F.Fab")
			(hide yes)
			(effects
				(font
					(size 1.016 1.016)
					(thickness 0.1524)
				)
			)
		)
		(duplicate_pad_numbers_are_jumpers no)
		(fp_line
			(start 1.651 -1.778)
			(end -1.651 -1.778)
			(stroke
				(width 0.1524)
				(type default)
			)
			(layer "F.SilkS")
		)
		(fp_line
			(start -1.651 -1.778)
			(end -1.651 1.778)
			(stroke
				(width 0.1524)
				(type default)
			)
			(layer "F.SilkS")
		)
		(fp_line
			(start 1.651 1.778)
			(end 1.651 -1.778)
			(stroke
				(width 0.1524)
				(type default)
			)
			(layer "F.SilkS")
		)
		(fp_line
			(start -1.651 1.778)
			(end 1.651 1.778)
			(stroke
				(width 0.1524)
				(type default)
			)
			(layer "F.SilkS")
		)
		(fp_poly
			(pts
				(xy -1.778 1.8796) (xy -1.778 -1.8796) (xy 1.778 -1.8796) (xy 1.778 1.8796)
			)
			(stroke
				(width 0)
				(type default)
			)
			(fill no)
			(layer "F.CrtYd")
		)
		(fp_poly
			(pts
				(xy -1.778 1.8796) (xy -1.778 -1.8796) (xy 1.778 -1.8796) (xy 1.778 1.8796)
			)
			(stroke
				(width 0)
				(type default)
			)
			(fill no)
			(layer "F.Fab")
		)
		(pad "D" smd custom
			(at 0 -0.9525 90)
			(size 0.1905 0.1905)
			(layers "F.Cu" "F.Mask" "F.Paste")
			(net "Q95_D")
			(options
				(clearance outline)
				(anchor circle)
			)
			(primitives
				(gr_poly
					(pts
						(arc
							(start -0.1778 0.5715)
							(mid -0.321484 0.511984)
							(end -0.381 0.3683)
						)
						(arc
							(start -0.381 -0.3683)
							(mid -0.321484 -0.511984)
							(end -0.1778 -0.5715)
						)
						(arc
							(start 0.1778 -0.5715)
							(mid 0.321484 -0.511984)
							(end 0.381 -0.3683)
						)
						(arc
							(start 0.381 0.3683)
							(mid 0.321484 0.511984)
							(end 0.1778 0.5715)
						)
					)
					(width 0)
					(fill yes)
				)
			)
		)
		(pad "G" smd custom
			(at -0.98425 0.9525 90)
			(size 0.1905 0.1905)
			(layers "F.Cu" "F.Mask" "F.Paste")
			(net "Q95_G")
			(options
				(clearance outline)
				(anchor circle)
			)
			(primitives
				(gr_poly
					(pts
						(arc
							(start -0.1778 0.5715)
							(mid -0.321484 0.511984)
							(end -0.381 0.3683)
						)
						(arc
							(start -0.381 -0.3683)
							(mid -0.321484 -0.511984)
							(end -0.1778 -0.5715)
						)
						(arc
							(start 0.1778 -0.5715)
							(mid 0.321484 -0.511984)
							(end 0.381 -0.3683)
						)
						(arc
							(start 0.381 0.3683)
							(mid 0.321484 0.511984)
							(end 0.1778 0.5715)
						)
					)
					(width 0)
					(fill yes)
				)
			)
		)
		(pad "S" smd custom
			(at 0.98425 0.9525 90)
			(size 0.1905 0.1905)
			(layers "F.Cu" "F.Mask" "F.Paste")
			(net "GND")
			(options
				(clearance outline)
				(anchor circle)
			)
			(primitives
				(gr_poly
					(pts
						(arc
							(start -0.1778 0.5715)
							(mid -0.321484 0.511984)
							(end -0.381 0.3683)
						)
						(arc
							(start -0.381 -0.3683)
							(mid -0.321484 -0.511984)
							(end -0.1778 -0.5715)
						)
						(arc
							(start 0.1778 -0.5715)
							(mid 0.321484 -0.511984)
							(end 0.381 -0.3683)
						)
						(arc
							(start 0.381 0.3683)
							(mid 0.321484 0.511984)
							(end 0.1778 0.5715)
						)
					)
					(width 0)
					(fill yes)
				)
			)
		)
	)
	(footprint ""
		(layer "F.Cu")
		(at 26.035 -76.9366 -90)
		(property "Reference" "R392"
			(at 0 0 270)
			(layer "F.SilkS")
			(hide yes)
			(effects
				(font
					(size 1.27 1.27)
				)
			)
		)
		(property "Value" "10KR2F-2-GP"
			(at 0.064008 -3.993896 270)
			(unlocked yes)
			(layer "F.Fab")
			(hide yes)
			(effects
				(font
					(size 1.016 1.016)
					(thickness 0.1524)
				)
			)
		)
		(property "Device Type" "R402H16"
			(at 0.064008 -5.517896 270)
			(unlocked yes)
			(layer "F.Fab")
			(hide yes)
			(effects
				(font
					(size 1.016 1.016)
					(thickness 0.1524)
				)
			)
		)
		(duplicate_pad_numbers_are_jumpers no)
		(fp_line
			(start -0.508 -0.9398)
			(end -0.508 0.9398)
			(stroke
				(width 0.1524)
				(type default)
			)
			(layer "F.SilkS")
		)
		(fp_line
			(start 0.508 -0.9398)
			(end -0.508 -0.9398)
			(stroke
				(width 0.1524)
				(type default)
			)
			(layer "F.SilkS")
		)
		(fp_rect
			(start -0.508 0.9398)
			(end 0.508 -0.9398)
			(stroke
				(width 0)
				(type default)
			)
			(fill no)
			(layer "F.CrtYd")
		)
		(fp_rect
			(start -0.508 0.9398)
			(end 0.508 -0.9398)
			(stroke
				(width 0)
				(type default)
			)
			(fill no)
			(layer "F.Fab")
		)
		(pad "1" smd custom
			(at 0 -0.4445 270)
			(size 0.1397 0.1397)
			(layers "F.Cu" "F.Mask" "F.Paste")
			(net "P3V3_STBY")
			(options
				(clearance outline)
				(anchor circle)
			)
			(primitives
				(gr_poly
					(pts
						(arc
							(start -0.1778 -0.2794)
							(mid -0.249642 -0.249642)
							(end -0.2794 -0.1778)
						)
						(arc
							(start -0.2794 0.1778)
							(mid -0.249642 0.249642)
							(end -0.1778 0.2794)
						)
						(arc
							(start 0.1778 0.2794)
							(mid 0.249642 0.249642)
							(end 0.2794 0.1778)
						)
						(arc
							(start 0.2794 -0.1778)
							(mid 0.249642 -0.249642)
							(end 0.1778 -0.2794)
						)
					)
					(width 0)
					(fill yes)
				)
			)
		)
		(pad "2" smd custom
			(at 0 0.4445 270)
			(size 0.1397 0.1397)
			(layers "F.Cu" "F.Mask" "F.Paste")
			(net "RMII_BMC_PHY_TXD0")
			(options
				(clearance outline)
				(anchor circle)
			)
			(primitives
				(gr_poly
					(pts
						(arc
							(start -0.1778 -0.2794)
							(mid -0.249642 -0.249642)
							(end -0.2794 -0.1778)
						)
						(arc
							(start -0.2794 0.1778)
							(mid -0.249642 0.249642)
							(end -0.1778 0.2794)
						)
						(arc
							(start 0.1778 0.2794)
							(mid 0.249642 0.249642)
							(end 0.2794 0.1778)
						)
						(arc
							(start 0.2794 -0.1778)
							(mid 0.249642 -0.249642)
							(end 0.1778 -0.2794)
						)
					)
					(width 0)
					(fill yes)
				)
			)
		)
	)
	(footprint ""
		(layer "F.Cu")
		(at 310.007 -63.9826)
		(property "Reference" "PG51"
			(at 0 0 0)
			(layer "F.SilkS")
			(hide yes)
			(effects
				(font
					(size 1.27 1.27)
				)
			)
		)
		(property "Value" "GAP-CLOSE-PWR-3-GP"
			(at 0.0254 -6.5786 0)
			(unlocked yes)
			(layer "F.Fab")
			(hide yes)
			(effects
				(font
					(size 1.016 1.016)
					(thickness 0.1524)
				)
			)
		)
		(property "Device Type" "GAP-CLOSE-PWR-3"
			(at 0.0254 -8.255 0)
			(unlocked yes)
			(layer "F.Fab")
			(hide yes)
			(effects
				(font
					(size 1.016 1.016)
					(thickness 0.1524)
				)
			)
		)
		(duplicate_pad_numbers_are_jumpers no)
		(fp_rect
			(start -0.7112 0.4572)
			(end 0.7112 -0.4572)
			(stroke
				(width 0)
				(type default)
			)
			(fill no)
			(layer "F.CrtYd")
		)
		(fp_poly
			(pts
				(xy -0.7112 -0.4572) (xy 0.7112 -0.4572) (xy 0.7112 0.4572) (xy -0.7112 0.4572)
			)
			(stroke
				(width 0)
				(type default)
			)
			(fill no)
			(layer "F.Fab")
		)
		(pad "1" smd rect
			(at -0.3048 0)
			(size 0.6604 0.762)
			(layers "F.Cu" "F.Mask" "F.Paste")
			(net "DUT_VDD")
		)
		(pad "2" smd rect
			(at 0.3048 0)
			(size 0.6604 0.762)
			(layers "F.Cu" "F.Mask" "F.Paste")
			(net "P0V9_E")
		)
	)
	(footprint ""
		(layer "F.Cu")
		(at 228.3968 -16.1036 180)
		(property "Reference" "R7909"
			(at 0 0 180)
			(layer "F.SilkS")
			(hide yes)
			(effects
				(font
					(size 1.27 1.27)
				)
			)
		)
		(property "Value" "0R2J-2-GP"
			(at 0.064008 -3.993896 180)
			(unlocked yes)
			(layer "F.Fab")
			(hide yes)
			(effects
				(font
					(size 1.016 1.016)
					(thickness 0.1524)
				)
			)
		)
		(property "Device Type" "R402H16"
			(at 0.064008 -5.517896 180)
			(unlocked yes)
			(layer "F.Fab")
			(hide yes)
			(effects
				(font
					(size 1.016 1.016)
					(thickness 0.1524)
				)
			)
		)
		(duplicate_pad_numbers_are_jumpers no)
		(fp_line
			(start 0.508 -0.9398)
			(end -0.508 -0.9398)
			(stroke
				(width 0.1524)
				(type default)
			)
			(layer "F.SilkS")
		)
		(fp_line
			(start -0.508 -0.9398)
			(end -0.508 0.9398)
			(stroke
				(width 0.1524)
				(type default)
			)
			(layer "F.SilkS")
		)
		(fp_rect
			(start -0.508 0.9398)
			(end 0.508 -0.9398)
			(stroke
				(width 0)
				(type default)
			)
			(fill no)
			(layer "F.CrtYd")
		)
		(fp_rect
			(start -0.508 0.9398)
			(end 0.508 -0.9398)
			(stroke
				(width 0)
				(type default)
			)
			(fill no)
			(layer "F.Fab")
		)
		(pad "1" smd custom
			(at 0 -0.4445 180)
			(size 0.1397 0.1397)
			(layers "F.Cu" "F.Mask" "F.Paste")
			(net "U82_RST#")
			(options
				(clearance outline)
				(anchor circle)
			)
			(primitives
				(gr_poly
					(pts
						(arc
							(start -0.1778 -0.2794)
							(mid -0.249642 -0.249642)
							(end -0.2794 -0.1778)
						)
						(arc
							(start -0.2794 0.1778)
							(mid -0.249642 0.249642)
							(end -0.1778 0.2794)
						)
						(arc
							(start 0.1778 0.2794)
							(mid 0.249642 0.249642)
							(end 0.2794 0.1778)
						)
						(arc
							(start 0.2794 -0.1778)
							(mid 0.249642 -0.249642)
							(end 0.1778 -0.2794)
						)
					)
					(width 0)
					(fill yes)
				)
			)
		)
		(pad "2" smd custom
			(at 0 0.4445 180)
			(size 0.1397 0.1397)
			(layers "F.Cu" "F.Mask" "F.Paste")
			(net "HOST1_RST_N_LS")
			(options
				(clearance outline)
				(anchor circle)
			)
			(primitives
				(gr_poly
					(pts
						(arc
							(start -0.1778 -0.2794)
							(mid -0.249642 -0.249642)
							(end -0.2794 -0.1778)
						)
						(arc
							(start -0.2794 0.1778)
							(mid -0.249642 0.249642)
							(end -0.1778 0.2794)
						)
						(arc
							(start 0.1778 0.2794)
							(mid 0.249642 0.249642)
							(end 0.2794 0.1778)
						)
						(arc
							(start 0.2794 -0.1778)
							(mid 0.249642 -0.249642)
							(end 0.1778 -0.2794)
						)
					)
					(width 0)
					(fill yes)
				)
			)
		)
	)
	(footprint ""
		(layer "F.Cu")
		(at 170.60799 -212.420454 180)
		(property "Reference" "C141"
			(at 0 0 180)
			(layer "F.SilkS")
			(hide yes)
			(effects
				(font
					(size 1.27 1.27)
				)
			)
		)
		(property "Value" "SCD22U10V2KX-1GP"
			(at 1.1811 -2.7051 180)
			(unlocked yes)
			(layer "F.Fab")
			(hide yes)
			(effects
				(font
					(size 1.016 1.016)
					(thickness 0.1524)
				)
			)
		)
		(property "Device Type" "C402H22"
			(at 1.1811 -4.2291 180)
			(unlocked yes)
			(layer "F.Fab")
			(hide yes)
			(effects
				(font
					(size 1.016 1.016)
					(thickness 0.1524)
				)
			)
		)
		(duplicate_pad_numbers_are_jumpers no)
		(fp_rect
			(start -0.4318 0.9525)
			(end 0.4318 -0.9525)
			(stroke
				(width 0)
				(type default)
			)
			(fill no)
			(layer "F.CrtYd")
		)
		(fp_rect
			(start -0.4318 0.9525)
			(end 0.4318 -0.9525)
			(stroke
				(width 0)
				(type default)
			)
			(fill no)
			(layer "F.Fab")
		)
		(pad "1" smd custom
			(at 0 -0.4445 180)
			(size 0.1524 0.1524)
			(layers "F.Cu" "F.Mask" "F.Paste")
			(net "PCIE_TX_CAP_N50")
			(options
				(clearance outline)
				(anchor circle)
			)
			(primitives
				(gr_poly
					(pts
						(arc
							(start 0.3048 -0.2032)
							(mid 0.275042 -0.275042)
							(end 0.2032 -0.3048)
						)
						(arc
							(start -0.2032 -0.3048)
							(mid -0.275042 -0.275042)
							(end -0.3048 -0.2032)
						)
						(arc
							(start -0.3048 0.2032)
							(mid -0.275042 0.275042)
							(end -0.2032 0.3048)
						)
						(arc
							(start 0.2032 0.3048)
							(mid 0.275042 0.275042)
							(end 0.3048 0.2032)
						)
					)
					(width 0)
					(fill yes)
				)
			)
		)
		(pad "2" smd custom
			(at 0 0.4445 180)
			(size 0.1524 0.1524)
			(layers "F.Cu" "F.Mask" "F.Paste")
			(net "PCIE_TX_N50")
			(options
				(clearance outline)
				(anchor circle)
			)
			(primitives
				(gr_poly
					(pts
						(arc
							(start 0.3048 -0.2032)
							(mid 0.275042 -0.275042)
							(end 0.2032 -0.3048)
						)
						(arc
							(start -0.2032 -0.3048)
							(mid -0.275042 -0.275042)
							(end -0.3048 -0.2032)
						)
						(arc
							(start -0.3048 0.2032)
							(mid -0.275042 0.275042)
							(end -0.2032 0.3048)
						)
						(arc
							(start 0.2032 0.3048)
							(mid 0.275042 0.275042)
							(end 0.3048 0.2032)
						)
					)
					(width 0)
					(fill yes)
				)
			)
		)
	)
	(footprint ""
		(layer "F.Cu")
		(at 49.911 -198.247 -90)
		(property "Reference" "C702"
			(at 0 0 270)
			(layer "F.SilkS")
			(hide yes)
			(effects
				(font
					(size 1.27 1.27)
				)
			)
		)
		(property "Value" "SC220P50V3JN-GP"
			(at 0 -2.8194 270)
			(unlocked yes)
			(layer "F.Fab")
			(hide yes)
			(effects
				(font
					(size 1.016 1.016)
					(thickness 0.1524)
				)
			)
		)
		(property "Device Type" "C603H36"
			(at 0 -4.3434 270)
			(unlocked yes)
			(layer "F.Fab")
			(hide yes)
			(effects
				(font
					(size 1.016 1.016)
					(thickness 0.1524)
				)
			)
		)
		(duplicate_pad_numbers_are_jumpers no)
		(fp_line
			(start 0.508 0)
			(end -0.508 0)
			(stroke
				(width 0.2032)
				(type default)
			)
			(layer "F.SilkS")
		)
		(fp_rect
			(start -0.5842 1.3335)
			(end 0.5842 -1.3335)
			(stroke
				(width 0)
				(type default)
			)
			(fill no)
			(layer "F.CrtYd")
		)
		(fp_rect
			(start -0.5842 1.3335)
			(end 0.5842 -1.3335)
			(stroke
				(width 0)
				(type default)
			)
			(fill no)
			(layer "F.Fab")
		)
		(pad "1" smd custom
			(at 0 -0.762 270)
			(size 0.2159 0.2159)
			(layers "F.Cu" "F.Mask" "F.Paste")
			(net "BUF_I2C7_B_DPB_SDA_R")
			(options
				(clearance outline)
				(anchor circle)
			)
			(primitives
				(gr_poly
					(pts
						(arc
							(start -0.3302 -0.4318)
							(mid -0.402042 -0.402042)
							(end -0.4318 -0.3302)
						)
						(arc
							(start -0.4318 0.3302)
							(mid -0.402042 0.402042)
							(end -0.3302 0.4318)
						)
						(arc
							(start 0.3302 0.4318)
							(mid 0.402042 0.402042)
							(end 0.4318 0.3302)
						)
						(arc
							(start 0.4318 -0.3302)
							(mid 0.402042 -0.402042)
							(end 0.3302 -0.4318)
						)
					)
					(width 0)
					(fill yes)
				)
			)
		)
		(pad "2" smd custom
			(at 0 0.762 270)
			(size 0.2159 0.2159)
			(layers "F.Cu" "F.Mask" "F.Paste")
			(net "GND")
			(options
				(clearance outline)
				(anchor circle)
			)
			(primitives
				(gr_poly
					(pts
						(arc
							(start -0.3302 -0.4318)
							(mid -0.402042 -0.402042)
							(end -0.4318 -0.3302)
						)
						(arc
							(start -0.4318 0.3302)
							(mid -0.402042 0.402042)
							(end -0.3302 0.4318)
						)
						(arc
							(start 0.3302 0.4318)
							(mid 0.402042 0.402042)
							(end 0.4318 0.3302)
						)
						(arc
							(start 0.4318 -0.3302)
							(mid 0.402042 -0.402042)
							(end 0.3302 -0.4318)
						)
					)
					(width 0)
					(fill yes)
				)
			)
		)
	)
	(footprint ""
		(layer "F.Cu")
		(at 264.392156 -212.420454 180)
		(property "Reference" "C107"
			(at 0 0 180)
			(layer "F.SilkS")
			(hide yes)
			(effects
				(font
					(size 1.27 1.27)
				)
			)
		)
		(property "Value" "SCD22U10V2KX-1GP"
			(at 1.1811 -2.7051 180)
			(unlocked yes)
			(layer "F.Fab")
			(hide yes)
			(effects
				(font
					(size 1.016 1.016)
					(thickness 0.1524)
				)
			)
		)
		(property "Device Type" "C402H22"
			(at 1.1811 -4.2291 180)
			(unlocked yes)
			(layer "F.Fab")
			(hide yes)
			(effects
				(font
					(size 1.016 1.016)
					(thickness 0.1524)
				)
			)
		)
		(duplicate_pad_numbers_are_jumpers no)
		(fp_rect
			(start -0.4318 0.9525)
			(end 0.4318 -0.9525)
			(stroke
				(width 0)
				(type default)
			)
			(fill no)
			(layer "F.CrtYd")
		)
		(fp_rect
			(start -0.4318 0.9525)
			(end 0.4318 -0.9525)
			(stroke
				(width 0)
				(type default)
			)
			(fill no)
			(layer "F.Fab")
		)
		(pad "1" smd custom
			(at 0 -0.4445 180)
			(size 0.1524 0.1524)
			(layers "F.Cu" "F.Mask" "F.Paste")
			(net "PCIE_TX_CAP_P37")
			(options
				(clearance outline)
				(anchor circle)
			)
			(primitives
				(gr_poly
					(pts
						(arc
							(start 0.3048 -0.2032)
							(mid 0.275042 -0.275042)
							(end 0.2032 -0.3048)
						)
						(arc
							(start -0.2032 -0.3048)
							(mid -0.275042 -0.275042)
							(end -0.3048 -0.2032)
						)
						(arc
							(start -0.3048 0.2032)
							(mid -0.275042 0.275042)
							(end -0.2032 0.3048)
						)
						(arc
							(start 0.2032 0.3048)
							(mid 0.275042 0.275042)
							(end 0.3048 0.2032)
						)
					)
					(width 0)
					(fill yes)
				)
			)
		)
		(pad "2" smd custom
			(at 0 0.4445 180)
			(size 0.1524 0.1524)
			(layers "F.Cu" "F.Mask" "F.Paste")
			(net "PCIE_TX_P37")
			(options
				(clearance outline)
				(anchor circle)
			)
			(primitives
				(gr_poly
					(pts
						(arc
							(start 0.3048 -0.2032)
							(mid 0.275042 -0.275042)
							(end 0.2032 -0.3048)
						)
						(arc
							(start -0.2032 -0.3048)
							(mid -0.275042 -0.275042)
							(end -0.3048 -0.2032)
						)
						(arc
							(start -0.3048 0.2032)
							(mid -0.275042 0.275042)
							(end -0.2032 0.3048)
						)
						(arc
							(start 0.2032 0.3048)
							(mid 0.275042 0.275042)
							(end 0.3048 0.2032)
						)
					)
					(width 0)
					(fill yes)
				)
			)
		)
	)
	(footprint ""
		(layer "F.Cu")
		(at 33.6296 -186.7662 180)
		(property "Reference" "C258"
			(at 0 0 180)
			(layer "F.SilkS")
			(hide yes)
			(effects
				(font
					(size 1.27 1.27)
				)
			)
		)
		(property "Value" "SC220P50V3JN-GP"
			(at 0 -2.8194 180)
			(unlocked yes)
			(layer "F.Fab")
			(hide yes)
			(effects
				(font
					(size 1.016 1.016)
					(thickness 0.1524)
				)
			)
		)
		(property "Device Type" "C603H36"
			(at 0 -4.3434 180)
			(unlocked yes)
			(layer "F.Fab")
			(hide yes)
			(effects
				(font
					(size 1.016 1.016)
					(thickness 0.1524)
				)
			)
		)
		(duplicate_pad_numbers_are_jumpers no)
		(fp_line
			(start 0.508 0)
			(end -0.508 0)
			(stroke
				(width 0.2032)
				(type default)
			)
			(layer "F.SilkS")
		)
		(fp_rect
			(start -0.5842 1.3335)
			(end 0.5842 -1.3335)
			(stroke
				(width 0)
				(type default)
			)
			(fill no)
			(layer "F.CrtYd")
		)
		(fp_rect
			(start -0.5842 1.3335)
			(end 0.5842 -1.3335)
			(stroke
				(width 0)
				(type default)
			)
			(fill no)
			(layer "F.Fab")
		)
		(pad "1" smd custom
			(at 0 -0.762 180)
			(size 0.2159 0.2159)
			(layers "F.Cu" "F.Mask" "F.Paste")
			(net "BUF_I2C5_SCL_R")
			(options
				(clearance outline)
				(anchor circle)
			)
			(primitives
				(gr_poly
					(pts
						(arc
							(start -0.3302 -0.4318)
							(mid -0.402042 -0.402042)
							(end -0.4318 -0.3302)
						)
						(arc
							(start -0.4318 0.3302)
							(mid -0.402042 0.402042)
							(end -0.3302 0.4318)
						)
						(arc
							(start 0.3302 0.4318)
							(mid 0.402042 0.402042)
							(end 0.4318 0.3302)
						)
						(arc
							(start 0.4318 -0.3302)
							(mid 0.402042 -0.402042)
							(end 0.3302 -0.4318)
						)
					)
					(width 0)
					(fill yes)
				)
			)
		)
		(pad "2" smd custom
			(at 0 0.762 180)
			(size 0.2159 0.2159)
			(layers "F.Cu" "F.Mask" "F.Paste")
			(net "GND")
			(options
				(clearance outline)
				(anchor circle)
			)
			(primitives
				(gr_poly
					(pts
						(arc
							(start -0.3302 -0.4318)
							(mid -0.402042 -0.402042)
							(end -0.4318 -0.3302)
						)
						(arc
							(start -0.4318 0.3302)
							(mid -0.402042 0.402042)
							(end -0.3302 0.4318)
						)
						(arc
							(start 0.3302 0.4318)
							(mid 0.402042 0.402042)
							(end 0.4318 0.3302)
						)
						(arc
							(start 0.4318 -0.3302)
							(mid 0.402042 -0.402042)
							(end 0.3302 -0.4318)
						)
					)
					(width 0)
					(fill yes)
				)
			)
		)
	)
	(footprint ""
		(layer "F.Cu")
		(at 37.211 -202.565 180)
		(property "Reference" "R877"
			(at 0 0 180)
			(layer "F.SilkS")
			(hide yes)
			(effects
				(font
					(size 1.27 1.27)
				)
			)
		)
		(property "Value" "10KR2F-2-GP"
			(at 0.064008 -3.993896 180)
			(unlocked yes)
			(layer "F.Fab")
			(hide yes)
			(effects
				(font
					(size 1.016 1.016)
					(thickness 0.1524)
				)
			)
		)
		(property "Device Type" "R402H16"
			(at 0.064008 -5.517896 180)
			(unlocked yes)
			(layer "F.Fab")
			(hide yes)
			(effects
				(font
					(size 1.016 1.016)
					(thickness 0.1524)
				)
			)
		)
		(duplicate_pad_numbers_are_jumpers no)
		(fp_line
			(start 0.508 -0.9398)
			(end -0.508 -0.9398)
			(stroke
				(width 0.1524)
				(type default)
			)
			(layer "F.SilkS")
		)
		(fp_line
			(start -0.508 -0.9398)
			(end -0.508 0.9398)
			(stroke
				(width 0.1524)
				(type default)
			)
			(layer "F.SilkS")
		)
		(fp_rect
			(start -0.508 0.9398)
			(end 0.508 -0.9398)
			(stroke
				(width 0)
				(type default)
			)
			(fill no)
			(layer "F.CrtYd")
		)
		(fp_rect
			(start -0.508 0.9398)
			(end 0.508 -0.9398)
			(stroke
				(width 0)
				(type default)
			)
			(fill no)
			(layer "F.Fab")
		)
		(pad "1" smd custom
			(at 0 -0.4445 180)
			(size 0.1397 0.1397)
			(layers "F.Cu" "F.Mask" "F.Paste")
			(net "I2C6_BUF_READY")
			(options
				(clearance outline)
				(anchor circle)
			)
			(primitives
				(gr_poly
					(pts
						(arc
							(start -0.1778 -0.2794)
							(mid -0.249642 -0.249642)
							(end -0.2794 -0.1778)
						)
						(arc
							(start -0.2794 0.1778)
							(mid -0.249642 0.249642)
							(end -0.1778 0.2794)
						)
						(arc
							(start 0.1778 0.2794)
							(mid 0.249642 0.249642)
							(end 0.2794 0.1778)
						)
						(arc
							(start 0.2794 -0.1778)
							(mid 0.249642 -0.249642)
							(end 0.1778 -0.2794)
						)
					)
					(width 0)
					(fill yes)
				)
			)
		)
		(pad "2" smd custom
			(at 0 0.4445 180)
			(size 0.1397 0.1397)
			(layers "F.Cu" "F.Mask" "F.Paste")
			(net "P3V3_STBY")
			(options
				(clearance outline)
				(anchor circle)
			)
			(primitives
				(gr_poly
					(pts
						(arc
							(start -0.1778 -0.2794)
							(mid -0.249642 -0.249642)
							(end -0.2794 -0.1778)
						)
						(arc
							(start -0.2794 0.1778)
							(mid -0.249642 0.249642)
							(end -0.1778 0.2794)
						)
						(arc
							(start 0.1778 0.2794)
							(mid 0.249642 0.249642)
							(end 0.2794 0.1778)
						)
						(arc
							(start 0.2794 -0.1778)
							(mid 0.249642 -0.249642)
							(end 0.1778 -0.2794)
						)
					)
					(width 0)
					(fill yes)
				)
			)
		)
	)
	(footprint ""
		(layer "F.Cu")
		(at 32.639 -115.824)
		(property "Reference" "TP244"
			(at 0 0 0)
			(layer "F.SilkS")
			(hide yes)
			(effects
				(font
					(size 1.27 1.27)
				)
			)
		)
		(property "Value" "TPAD28-2-GP"
			(at -0.0127 -1.6637 0)
			(unlocked yes)
			(layer "F.Fab")
			(hide yes)
			(effects
				(font
					(size 1.016 1.016)
					(thickness 0.1524)
				)
			)
		)
		(property "Device Type" "TPAD28"
			(at -0.0127 -3.1877 0)
			(unlocked yes)
			(layer "F.Fab")
			(hide yes)
			(effects
				(font
					(size 1.016 1.016)
					(thickness 0.1524)
				)
			)
		)
		(duplicate_pad_numbers_are_jumpers no)
		(fp_poly
			(pts
				(arc
					(start 0.3556 0)
					(mid -0.3556 0)
					(end 0.3556 0)
				)
			)
			(stroke
				(width 0)
				(type default)
			)
			(fill no)
			(layer "F.CrtYd")
		)
		(fp_poly
			(pts
				(arc
					(start 0.6096 0)
					(mid -0.6096 0)
					(end 0.6096 0)
				)
			)
			(stroke
				(width 0)
				(type default)
			)
			(fill no)
			(layer "F.Fab")
		)
		(pad "1" smd circle
			(at 0 0)
			(size 0.7112 0.7112)
			(layers "F.Cu" "F.Mask" "F.Paste")
			(net "TP_GPIOD5")
		)
	)
	(footprint ""
		(layer "F.Cu")
		(at 19.4183 -178.3461)
		(property "Reference" "R692"
			(at 0 0 0)
			(layer "F.SilkS")
			(hide yes)
			(effects
				(font
					(size 1.27 1.27)
				)
			)
		)
		(property "Value" "1K33R3F-GP"
			(at -0.0254 -2.5146 0)
			(unlocked yes)
			(layer "F.Fab")
			(hide yes)
			(effects
				(font
					(size 1.016 1.016)
					(thickness 0.1524)
				)
			)
		)
		(property "Device Type" "R603H22"
			(at -0.0254 -4.0386 0)
			(unlocked yes)
			(layer "F.Fab")
			(hide yes)
			(effects
				(font
					(size 1.016 1.016)
					(thickness 0.1524)
				)
			)
		)
		(duplicate_pad_numbers_are_jumpers no)
		(fp_line
			(start -0.4826 0)
			(end -0.2032 0)
			(stroke
				(width 0.2032)
				(type default)
			)
			(layer "F.SilkS")
		)
		(fp_line
			(start 0.2032 0)
			(end 0.4826 0)
			(stroke
				(width 0.2032)
				(type default)
			)
			(layer "F.SilkS")
		)
		(fp_rect
			(start -0.5842 1.3335)
			(end 0.5842 -1.3335)
			(stroke
				(width 0)
				(type default)
			)
			(fill no)
			(layer "F.CrtYd")
		)
		(fp_rect
			(start -0.5842 1.3335)
			(end 0.5842 -1.3335)
			(stroke
				(width 0)
				(type default)
			)
			(fill no)
			(layer "F.Fab")
		)
		(pad "1" smd custom
			(at 0 -0.762)
			(size 0.2159 0.2159)
			(layers "F.Cu" "F.Mask" "F.Paste")
			(net "MB0_HS_ENABLE")
			(options
				(clearance outline)
				(anchor circle)
			)
			(primitives
				(gr_poly
					(pts
						(arc
							(start -0.3302 -0.4318)
							(mid -0.402042 -0.402042)
							(end -0.4318 -0.3302)
						)
						(arc
							(start -0.4318 0.3302)
							(mid -0.402042 0.402042)
							(end -0.3302 0.4318)
						)
						(arc
							(start 0.3302 0.4318)
							(mid 0.402042 0.402042)
							(end 0.4318 0.3302)
						)
						(arc
							(start 0.4318 -0.3302)
							(mid 0.402042 -0.402042)
							(end 0.3302 -0.4318)
						)
					)
					(width 0)
					(fill yes)
				)
			)
		)
		(pad "2" smd custom
			(at 0 0.762)
			(size 0.2159 0.2159)
			(layers "F.Cu" "F.Mask" "F.Paste")
			(net "GND")
			(options
				(clearance outline)
				(anchor circle)
			)
			(primitives
				(gr_poly
					(pts
						(arc
							(start -0.3302 -0.4318)
							(mid -0.402042 -0.402042)
							(end -0.4318 -0.3302)
						)
						(arc
							(start -0.4318 0.3302)
							(mid -0.402042 0.402042)
							(end -0.3302 0.4318)
						)
						(arc
							(start 0.3302 0.4318)
							(mid 0.402042 0.402042)
							(end 0.4318 0.3302)
						)
						(arc
							(start 0.4318 -0.3302)
							(mid 0.402042 -0.402042)
							(end 0.3302 -0.4318)
						)
					)
					(width 0)
					(fill yes)
				)
			)
		)
	)
	(footprint ""
		(layer "F.Cu")
		(at 78.3082 -84.9122 180)
		(property "Reference" "R477"
			(at 0 0 180)
			(layer "F.SilkS")
			(hide yes)
			(effects
				(font
					(size 1.27 1.27)
				)
			)
		)
		(property "Value" "4K7R2F-GP"
			(at 0.064008 -3.993896 180)
			(unlocked yes)
			(layer "F.Fab")
			(hide yes)
			(effects
				(font
					(size 1.016 1.016)
					(thickness 0.1524)
				)
			)
		)
		(property "Device Type" "R402H16"
			(at 0.064008 -5.517896 180)
			(unlocked yes)
			(layer "F.Fab")
			(hide yes)
			(effects
				(font
					(size 1.016 1.016)
					(thickness 0.1524)
				)
			)
		)
		(duplicate_pad_numbers_are_jumpers no)
		(fp_line
			(start 0.508 -0.9398)
			(end -0.508 -0.9398)
			(stroke
				(width 0.1524)
				(type default)
			)
			(layer "F.SilkS")
		)
		(fp_line
			(start -0.508 -0.9398)
			(end -0.508 0.9398)
			(stroke
				(width 0.1524)
				(type default)
			)
			(layer "F.SilkS")
		)
		(fp_rect
			(start -0.508 0.9398)
			(end 0.508 -0.9398)
			(stroke
				(width 0)
				(type default)
			)
			(fill no)
			(layer "F.CrtYd")
		)
		(fp_rect
			(start -0.508 0.9398)
			(end 0.508 -0.9398)
			(stroke
				(width 0)
				(type default)
			)
			(fill no)
			(layer "F.Fab")
		)
		(pad "1" smd custom
			(at 0 -0.4445 180)
			(size 0.1397 0.1397)
			(layers "F.Cu" "F.Mask" "F.Paste")
			(net "DIVIDER_1_IN")
			(options
				(clearance outline)
				(anchor circle)
			)
			(primitives
				(gr_poly
					(pts
						(arc
							(start -0.1778 -0.2794)
							(mid -0.249642 -0.249642)
							(end -0.2794 -0.1778)
						)
						(arc
							(start -0.2794 0.1778)
							(mid -0.249642 0.249642)
							(end -0.1778 0.2794)
						)
						(arc
							(start 0.1778 0.2794)
							(mid 0.249642 0.249642)
							(end 0.2794 0.1778)
						)
						(arc
							(start 0.2794 -0.1778)
							(mid 0.249642 -0.249642)
							(end 0.1778 -0.2794)
						)
					)
					(width 0)
					(fill yes)
				)
			)
		)
		(pad "2" smd custom
			(at 0 0.4445 180)
			(size 0.1397 0.1397)
			(layers "F.Cu" "F.Mask" "F.Paste")
			(net "DIVIDER_2_IN")
			(options
				(clearance outline)
				(anchor circle)
			)
			(primitives
				(gr_poly
					(pts
						(arc
							(start -0.1778 -0.2794)
							(mid -0.249642 -0.249642)
							(end -0.2794 -0.1778)
						)
						(arc
							(start -0.2794 0.1778)
							(mid -0.249642 0.249642)
							(end -0.1778 0.2794)
						)
						(arc
							(start 0.1778 0.2794)
							(mid 0.249642 0.249642)
							(end 0.2794 0.1778)
						)
						(arc
							(start 0.2794 -0.1778)
							(mid 0.249642 -0.249642)
							(end 0.1778 -0.2794)
						)
					)
					(width 0)
					(fill yes)
				)
			)
		)
	)
	(footprint ""
		(layer "F.Cu")
		(at 125.978412 -208.897474)
		(property "Reference" "R549"
			(at 0 0 0)
			(layer "F.SilkS")
			(hide yes)
			(effects
				(font
					(size 1.27 1.27)
				)
			)
		)
		(property "Value" "10KR2F-2-GP"
			(at 0.064008 -3.993896 0)
			(unlocked yes)
			(layer "F.Fab")
			(hide yes)
			(effects
				(font
					(size 1.016 1.016)
					(thickness 0.1524)
				)
			)
		)
		(property "Device Type" "R402H16"
			(at 0.064008 -5.517896 0)
			(unlocked yes)
			(layer "F.Fab")
			(hide yes)
			(effects
				(font
					(size 1.016 1.016)
					(thickness 0.1524)
				)
			)
		)
		(duplicate_pad_numbers_are_jumpers no)
		(fp_line
			(start -0.508 -0.9398)
			(end -0.508 0.9398)
			(stroke
				(width 0.1524)
				(type default)
			)
			(layer "F.SilkS")
		)
		(fp_line
			(start 0.508 -0.9398)
			(end -0.508 -0.9398)
			(stroke
				(width 0.1524)
				(type default)
			)
			(layer "F.SilkS")
		)
		(fp_rect
			(start -0.508 0.9398)
			(end 0.508 -0.9398)
			(stroke
				(width 0)
				(type default)
			)
			(fill no)
			(layer "F.CrtYd")
		)
		(fp_rect
			(start -0.508 0.9398)
			(end 0.508 -0.9398)
			(stroke
				(width 0)
				(type default)
			)
			(fill no)
			(layer "F.Fab")
		)
		(pad "1" smd custom
			(at 0 -0.4445)
			(size 0.1397 0.1397)
			(layers "F.Cu" "F.Mask" "F.Paste")
			(net "GND")
			(options
				(clearance outline)
				(anchor circle)
			)
			(primitives
				(gr_poly
					(pts
						(arc
							(start -0.1778 -0.2794)
							(mid -0.249642 -0.249642)
							(end -0.2794 -0.1778)
						)
						(arc
							(start -0.2794 0.1778)
							(mid -0.249642 0.249642)
							(end -0.1778 0.2794)
						)
						(arc
							(start 0.1778 0.2794)
							(mid 0.249642 0.249642)
							(end 0.2794 0.1778)
						)
						(arc
							(start 0.2794 -0.1778)
							(mid 0.249642 -0.249642)
							(end 0.1778 -0.2794)
						)
					)
					(width 0)
					(fill yes)
				)
			)
		)
		(pad "2" smd custom
			(at 0 0.4445)
			(size 0.1397 0.1397)
			(layers "F.Cu" "F.Mask" "F.Paste")
			(net "IOEXP2_AD0")
			(options
				(clearance outline)
				(anchor circle)
			)
			(primitives
				(gr_poly
					(pts
						(arc
							(start -0.1778 -0.2794)
							(mid -0.249642 -0.249642)
							(end -0.2794 -0.1778)
						)
						(arc
							(start -0.2794 0.1778)
							(mid -0.249642 0.249642)
							(end -0.1778 0.2794)
						)
						(arc
							(start 0.1778 0.2794)
							(mid 0.249642 0.249642)
							(end 0.2794 0.1778)
						)
						(arc
							(start 0.2794 -0.1778)
							(mid 0.249642 -0.249642)
							(end 0.1778 -0.2794)
						)
					)
					(width 0)
					(fill yes)
				)
			)
		)
	)
	(footprint ""
		(layer "F.Cu")
		(at 43.379136 -46.783244)
		(property "Reference" "L8"
			(at 0 0 0)
			(layer "F.SilkS")
			(hide yes)
			(effects
				(font
					(size 1.27 1.27)
				)
			)
		)
		(property "Value" "DLW21HN900SQ2LGP-U"
			(at -0.0889 -2.7813 0)
			(unlocked yes)
			(layer "F.Fab")
			(hide yes)
			(effects
				(font
					(size 1.016 1.016)
					(thickness 0.1524)
				)
			)
		)
		(property "Device Type" "L2012-4P-1MH40"
			(at -0.0889 -4.3053 0)
			(unlocked yes)
			(layer "F.Fab")
			(hide yes)
			(effects
				(font
					(size 1.016 1.016)
					(thickness 0.1524)
				)
			)
		)
		(duplicate_pad_numbers_are_jumpers no)
		(fp_line
			(start -1.5494 -1.0668)
			(end 1.5494 -1.0668)
			(stroke
				(width 0.1524)
				(type default)
			)
			(layer "F.SilkS")
		)
		(fp_line
			(start -1.5494 1.0668)
			(end -1.5494 -1.0668)
			(stroke
				(width 0.1524)
				(type default)
			)
			(layer "F.SilkS")
		)
		(fp_line
			(start 1.0668 1.1811)
			(end 0.6858 1.1811)
			(stroke
				(width 0.3302)
				(type default)
			)
			(layer "F.SilkS")
		)
		(fp_line
			(start 1.5494 -1.0668)
			(end 1.5494 1.0668)
			(stroke
				(width 0.1524)
				(type default)
			)
			(layer "F.SilkS")
		)
		(fp_line
			(start 1.5494 1.0668)
			(end -1.5494 1.0668)
			(stroke
				(width 0.1524)
				(type default)
			)
			(layer "F.SilkS")
		)
		(fp_poly
			(pts
				(xy 1.500124 1.768856) (xy 0.230124 1.768856) (xy 0.865124 1.133856)
			)
			(stroke
				(width 0)
				(type default)
			)
			(fill yes)
			(layer "F.SilkS")
		)
		(fp_rect
			(start -1.0033 0.5969)
			(end 1.0033 -0.5969)
			(stroke
				(width 0)
				(type default)
			)
			(fill no)
			(layer "F.CrtYd")
		)
		(fp_poly
			(pts
				(xy -1.8034 1.3208) (xy -1.8034 -1.3208) (xy 1.8034 -1.3208) (xy 1.8034 0.0508) (xy 1.0033 0.0508)
				(xy 1.0033 -0.5969) (xy -1.0033 -0.5969) (xy -1.0033 0.5969) (xy 1.0033 0.5969) (xy 1.0033 0.0762)
				(xy 1.8034 0.0762) (xy 1.8034 1.3208)
			)
			(stroke
				(width 0)
				(type default)
			)
			(fill no)
			(layer "F.CrtYd")
		)
		(fp_rect
			(start -1.8034 1.3208)
			(end 1.8034 -1.3208)
			(stroke
				(width 0)
				(type default)
			)
			(fill no)
			(layer "F.Fab")
		)
		(pad "1" smd rect
			(at 0.8382 0.4826)
			(size 0.9144 0.6604)
			(layers "F.Cu" "F.Mask" "F.Paste")
			(net "USB_DP_R")
		)
		(pad "2" smd rect
			(at -0.8382 0.4826)
			(size 0.9144 0.6604)
			(layers "F.Cu" "F.Mask" "F.Paste")
			(net "USB_P1_F_DP1")
		)
		(pad "3" smd rect
			(at -0.8382 -0.4826)
			(size 0.9144 0.6604)
			(layers "F.Cu" "F.Mask" "F.Paste")
			(net "USB_P1_F_DN1")
		)
		(pad "4" smd rect
			(at 0.8382 -0.4826)
			(size 0.9144 0.6604)
			(layers "F.Cu" "F.Mask" "F.Paste")
			(net "USB_DN_R")
		)
		(zone
			(layer "F.Cu")
			(hatch none 0.5)
			(connect_pads
				(clearance 0)
			)
			(min_thickness 0.25)
			(keepout
				(tracks not_allowed)
				(vias allowed)
				(pads allowed)
				(copperpour not_allowed)
				(footprints allowed)
			)
			(placement
				(enabled no)
				(sheetname "")
			)
			(fill
				(thermal_gap 0.5)
				(thermal_bridge_width 0.5)
				(island_removal_mode 0)
			)
			(polygon
				(pts
					(xy 42.998136 -45.970444) (xy 42.998136 -46.630844) (xy 42.083736 -46.630844) (xy 42.083736 -46.935644)
					(xy 42.998136 -46.935644) (xy 42.998136 -47.596044) (xy 43.760136 -47.596044) (xy 43.760136 -46.935644)
					(xy 44.674536 -46.935644) (xy 44.674536 -46.630844) (xy 43.760136 -46.630844) (xy 43.760136 -45.970444)
				)
			)
		)
		(zone
			(layer "F.Cu")
			(hatch none 0.5)
			(connect_pads
				(clearance 0)
			)
			(min_thickness 0.25)
			(keepout
				(tracks allowed)
				(vias not_allowed)
				(pads allowed)
				(copperpour not_allowed)
				(footprints allowed)
			)
			(placement
				(enabled no)
				(sheetname "")
			)
			(fill
				(thermal_gap 0.5)
				(thermal_bridge_width 0.5)
				(island_removal_mode 0)
			)
			(polygon
				(pts
					(xy 42.998136 -45.970444) (xy 42.998136 -46.630844) (xy 42.083736 -46.630844) (xy 42.083736 -46.935644)
					(xy 42.998136 -46.935644) (xy 42.998136 -47.596044) (xy 43.760136 -47.596044) (xy 43.760136 -46.935644)
					(xy 44.674536 -46.935644) (xy 44.674536 -46.630844) (xy 43.760136 -46.630844) (xy 43.760136 -45.970444)
				)
			)
		)
	)
	(footprint ""
		(layer "F.Cu")
		(at 273.699986 -1.397 -90)
		(property "Reference" "R2916"
			(at 0 0 270)
			(layer "F.SilkS")
			(hide yes)
			(effects
				(font
					(size 1.27 1.27)
				)
			)
		)
		(property "Value" "0R2J-2-GP"
			(at 0.064008 -3.993896 270)
			(unlocked yes)
			(layer "F.Fab")
			(hide yes)
			(effects
				(font
					(size 1.016 1.016)
					(thickness 0.1524)
				)
			)
		)
		(property "Device Type" "R402H16"
			(at 0.064008 -5.517896 270)
			(unlocked yes)
			(layer "F.Fab")
			(hide yes)
			(effects
				(font
					(size 1.016 1.016)
					(thickness 0.1524)
				)
			)
		)
		(duplicate_pad_numbers_are_jumpers no)
		(fp_line
			(start -0.508 -0.9398)
			(end -0.508 0.9398)
			(stroke
				(width 0.1524)
				(type default)
			)
			(layer "F.SilkS")
		)
		(fp_line
			(start 0.508 -0.9398)
			(end -0.508 -0.9398)
			(stroke
				(width 0.1524)
				(type default)
			)
			(layer "F.SilkS")
		)
		(fp_rect
			(start -0.508 0.9398)
			(end 0.508 -0.9398)
			(stroke
				(width 0)
				(type default)
			)
			(fill no)
			(layer "F.CrtYd")
		)
		(fp_rect
			(start -0.508 0.9398)
			(end 0.508 -0.9398)
			(stroke
				(width 0)
				(type default)
			)
			(fill no)
			(layer "F.Fab")
		)
		(pad "1" smd custom
			(at 0 -0.4445 270)
			(size 0.1397 0.1397)
			(layers "F.Cu" "F.Mask" "F.Paste")
			(net "BMC_I2C13_MINI7_SDA")
			(options
				(clearance outline)
				(anchor circle)
			)
			(primitives
				(gr_poly
					(pts
						(arc
							(start -0.1778 -0.2794)
							(mid -0.249642 -0.249642)
							(end -0.2794 -0.1778)
						)
						(arc
							(start -0.2794 0.1778)
							(mid -0.249642 0.249642)
							(end -0.1778 0.2794)
						)
						(arc
							(start 0.1778 0.2794)
							(mid 0.249642 0.249642)
							(end 0.2794 0.1778)
						)
						(arc
							(start 0.2794 -0.1778)
							(mid 0.249642 -0.249642)
							(end 0.1778 -0.2794)
						)
					)
					(width 0)
					(fill yes)
				)
			)
		)
		(pad "2" smd custom
			(at 0 0.4445 270)
			(size 0.1397 0.1397)
			(layers "F.Cu" "F.Mask" "F.Paste")
			(net "8644_CBL_PRSNT_R_7")
			(options
				(clearance outline)
				(anchor circle)
			)
			(primitives
				(gr_poly
					(pts
						(arc
							(start -0.1778 -0.2794)
							(mid -0.249642 -0.249642)
							(end -0.2794 -0.1778)
						)
						(arc
							(start -0.2794 0.1778)
							(mid -0.249642 0.249642)
							(end -0.1778 0.2794)
						)
						(arc
							(start 0.1778 0.2794)
							(mid 0.249642 0.249642)
							(end 0.2794 0.1778)
						)
						(arc
							(start 0.2794 -0.1778)
							(mid 0.249642 -0.249642)
							(end 0.1778 -0.2794)
						)
					)
					(width 0)
					(fill yes)
				)
			)
		)
	)
	(footprint ""
		(layer "F.Cu")
		(at 326.807322 -33.45942)
		(property "Reference" "C51"
			(at 0 0 0)
			(layer "F.SilkS")
			(hide yes)
			(effects
				(font
					(size 1.27 1.27)
				)
			)
		)
		(property "Value" "SCD22U10V2KX-1GP"
			(at 1.1811 -2.7051 0)
			(unlocked yes)
			(layer "F.Fab")
			(hide yes)
			(effects
				(font
					(size 1.016 1.016)
					(thickness 0.1524)
				)
			)
		)
		(property "Device Type" "C402H22"
			(at 1.1811 -4.2291 0)
			(unlocked yes)
			(layer "F.Fab")
			(hide yes)
			(effects
				(font
					(size 1.016 1.016)
					(thickness 0.1524)
				)
			)
		)
		(duplicate_pad_numbers_are_jumpers no)
		(fp_rect
			(start -0.4318 0.9525)
			(end 0.4318 -0.9525)
			(stroke
				(width 0)
				(type default)
			)
			(fill no)
			(layer "F.CrtYd")
		)
		(fp_rect
			(start -0.4318 0.9525)
			(end 0.4318 -0.9525)
			(stroke
				(width 0)
				(type default)
			)
			(fill no)
			(layer "F.Fab")
		)
		(pad "1" smd custom
			(at 0 -0.4445)
			(size 0.1524 0.1524)
			(layers "F.Cu" "F.Mask" "F.Paste")
			(net "PCIE_TX_CAP_N14")
			(options
				(clearance outline)
				(anchor circle)
			)
			(primitives
				(gr_poly
					(pts
						(arc
							(start 0.3048 -0.2032)
							(mid 0.275042 -0.275042)
							(end 0.2032 -0.3048)
						)
						(arc
							(start -0.2032 -0.3048)
							(mid -0.275042 -0.275042)
							(end -0.3048 -0.2032)
						)
						(arc
							(start -0.3048 0.2032)
							(mid -0.275042 0.275042)
							(end -0.2032 0.3048)
						)
						(arc
							(start 0.2032 0.3048)
							(mid 0.275042 0.275042)
							(end 0.3048 0.2032)
						)
					)
					(width 0)
					(fill yes)
				)
			)
		)
		(pad "2" smd custom
			(at 0 0.4445)
			(size 0.1524 0.1524)
			(layers "F.Cu" "F.Mask" "F.Paste")
			(net "PCIE_TX_N14")
			(options
				(clearance outline)
				(anchor circle)
			)
			(primitives
				(gr_poly
					(pts
						(arc
							(start 0.3048 -0.2032)
							(mid 0.275042 -0.275042)
							(end 0.2032 -0.3048)
						)
						(arc
							(start -0.2032 -0.3048)
							(mid -0.275042 -0.275042)
							(end -0.3048 -0.2032)
						)
						(arc
							(start -0.3048 0.2032)
							(mid -0.275042 0.275042)
							(end -0.2032 0.3048)
						)
						(arc
							(start 0.2032 0.3048)
							(mid 0.275042 0.275042)
							(end 0.3048 0.2032)
						)
					)
					(width 0)
					(fill yes)
				)
			)
		)
	)
	(footprint ""
		(layer "F.Cu")
		(at 160.528 -95.9104 180)
		(property "Reference" "R89"
			(at 0 0 180)
			(layer "F.SilkS")
			(hide yes)
			(effects
				(font
					(size 1.27 1.27)
				)
			)
		)
		(property "Value" "0R2J-2-GP"
			(at 0.064008 -3.993896 180)
			(unlocked yes)
			(layer "F.Fab")
			(hide yes)
			(effects
				(font
					(size 1.016 1.016)
					(thickness 0.1524)
				)
			)
		)
		(property "Device Type" "R402H16"
			(at 0.064008 -5.517896 180)
			(unlocked yes)
			(layer "F.Fab")
			(hide yes)
			(effects
				(font
					(size 1.016 1.016)
					(thickness 0.1524)
				)
			)
		)
		(duplicate_pad_numbers_are_jumpers no)
		(fp_line
			(start 0.508 -0.9398)
			(end -0.508 -0.9398)
			(stroke
				(width 0.1524)
				(type default)
			)
			(layer "F.SilkS")
		)
		(fp_line
			(start -0.508 -0.9398)
			(end -0.508 0.9398)
			(stroke
				(width 0.1524)
				(type default)
			)
			(layer "F.SilkS")
		)
		(fp_rect
			(start -0.508 0.9398)
			(end 0.508 -0.9398)
			(stroke
				(width 0)
				(type default)
			)
			(fill no)
			(layer "F.CrtYd")
		)
		(fp_rect
			(start -0.508 0.9398)
			(end 0.508 -0.9398)
			(stroke
				(width 0)
				(type default)
			)
			(fill no)
			(layer "F.Fab")
		)
		(pad "1" smd custom
			(at 0 -0.4445 180)
			(size 0.1397 0.1397)
			(layers "F.Cu" "F.Mask" "F.Paste")
			(net "CLKGEN_OE3_R")
			(options
				(clearance outline)
				(anchor circle)
			)
			(primitives
				(gr_poly
					(pts
						(arc
							(start -0.1778 -0.2794)
							(mid -0.249642 -0.249642)
							(end -0.2794 -0.1778)
						)
						(arc
							(start -0.2794 0.1778)
							(mid -0.249642 0.249642)
							(end -0.1778 0.2794)
						)
						(arc
							(start 0.1778 0.2794)
							(mid 0.249642 0.249642)
							(end 0.2794 0.1778)
						)
						(arc
							(start 0.2794 -0.1778)
							(mid 0.249642 -0.249642)
							(end 0.1778 -0.2794)
						)
					)
					(width 0)
					(fill yes)
				)
			)
		)
		(pad "2" smd custom
			(at 0 0.4445 180)
			(size 0.1397 0.1397)
			(layers "F.Cu" "F.Mask" "F.Paste")
			(net "CLKGEN_OE3")
			(options
				(clearance outline)
				(anchor circle)
			)
			(primitives
				(gr_poly
					(pts
						(arc
							(start -0.1778 -0.2794)
							(mid -0.249642 -0.249642)
							(end -0.2794 -0.1778)
						)
						(arc
							(start -0.2794 0.1778)
							(mid -0.249642 0.249642)
							(end -0.1778 0.2794)
						)
						(arc
							(start 0.1778 0.2794)
							(mid 0.249642 0.249642)
							(end 0.2794 0.1778)
						)
						(arc
							(start 0.2794 -0.1778)
							(mid 0.249642 -0.249642)
							(end 0.1778 -0.2794)
						)
					)
					(width 0)
					(fill yes)
				)
			)
		)
	)
	(footprint ""
		(layer "F.Cu")
		(at 101.192076 -212.420454 180)
		(property "Reference" "C154"
			(at 0 0 180)
			(layer "F.SilkS")
			(hide yes)
			(effects
				(font
					(size 1.27 1.27)
				)
			)
		)
		(property "Value" "SCD22U10V2KX-1GP"
			(at 1.1811 -2.7051 180)
			(unlocked yes)
			(layer "F.Fab")
			(hide yes)
			(effects
				(font
					(size 1.016 1.016)
					(thickness 0.1524)
				)
			)
		)
		(property "Device Type" "C402H22"
			(at 1.1811 -4.2291 180)
			(unlocked yes)
			(layer "F.Fab")
			(hide yes)
			(effects
				(font
					(size 1.016 1.016)
					(thickness 0.1524)
				)
			)
		)
		(duplicate_pad_numbers_are_jumpers no)
		(fp_rect
			(start -0.4318 0.9525)
			(end 0.4318 -0.9525)
			(stroke
				(width 0)
				(type default)
			)
			(fill no)
			(layer "F.CrtYd")
		)
		(fp_rect
			(start -0.4318 0.9525)
			(end 0.4318 -0.9525)
			(stroke
				(width 0)
				(type default)
			)
			(fill no)
			(layer "F.Fab")
		)
		(pad "1" smd custom
			(at 0 -0.4445 180)
			(size 0.1524 0.1524)
			(layers "F.Cu" "F.Mask" "F.Paste")
			(net "PCIE_TX_CAP_P62")
			(options
				(clearance outline)
				(anchor circle)
			)
			(primitives
				(gr_poly
					(pts
						(arc
							(start 0.3048 -0.2032)
							(mid 0.275042 -0.275042)
							(end 0.2032 -0.3048)
						)
						(arc
							(start -0.2032 -0.3048)
							(mid -0.275042 -0.275042)
							(end -0.3048 -0.2032)
						)
						(arc
							(start -0.3048 0.2032)
							(mid -0.275042 0.275042)
							(end -0.2032 0.3048)
						)
						(arc
							(start 0.2032 0.3048)
							(mid 0.275042 0.275042)
							(end 0.3048 0.2032)
						)
					)
					(width 0)
					(fill yes)
				)
			)
		)
		(pad "2" smd custom
			(at 0 0.4445 180)
			(size 0.1524 0.1524)
			(layers "F.Cu" "F.Mask" "F.Paste")
			(net "PCIE_TX_P62")
			(options
				(clearance outline)
				(anchor circle)
			)
			(primitives
				(gr_poly
					(pts
						(arc
							(start 0.3048 -0.2032)
							(mid 0.275042 -0.275042)
							(end 0.2032 -0.3048)
						)
						(arc
							(start -0.2032 -0.3048)
							(mid -0.275042 -0.275042)
							(end -0.3048 -0.2032)
						)
						(arc
							(start -0.3048 0.2032)
							(mid -0.275042 0.275042)
							(end -0.2032 0.3048)
						)
						(arc
							(start 0.2032 0.3048)
							(mid 0.275042 0.275042)
							(end 0.3048 0.2032)
						)
					)
					(width 0)
					(fill yes)
				)
			)
		)
	)
	(footprint ""
		(layer "F.Cu")
		(at 126.627128 -33.159192 -90)
		(property "Reference" "R667"
			(at 0 0 270)
			(layer "F.SilkS")
			(hide yes)
			(effects
				(font
					(size 1.27 1.27)
				)
			)
		)
		(property "Value" "0R2J-2-GP"
			(at 0.064008 -3.993896 270)
			(unlocked yes)
			(layer "F.Fab")
			(hide yes)
			(effects
				(font
					(size 1.016 1.016)
					(thickness 0.1524)
				)
			)
		)
		(property "Device Type" "R402H16"
			(at 0.064008 -5.517896 270)
			(unlocked yes)
			(layer "F.Fab")
			(hide yes)
			(effects
				(font
					(size 1.016 1.016)
					(thickness 0.1524)
				)
			)
		)
		(duplicate_pad_numbers_are_jumpers no)
		(fp_line
			(start -0.508 -0.9398)
			(end -0.508 0.9398)
			(stroke
				(width 0.1524)
				(type default)
			)
			(layer "F.SilkS")
		)
		(fp_line
			(start 0.508 -0.9398)
			(end -0.508 -0.9398)
			(stroke
				(width 0.1524)
				(type default)
			)
			(layer "F.SilkS")
		)
		(fp_rect
			(start -0.508 0.9398)
			(end 0.508 -0.9398)
			(stroke
				(width 0)
				(type default)
			)
			(fill no)
			(layer "F.CrtYd")
		)
		(fp_rect
			(start -0.508 0.9398)
			(end 0.508 -0.9398)
			(stroke
				(width 0)
				(type default)
			)
			(fill no)
			(layer "F.Fab")
		)
		(pad "1" smd custom
			(at 0 -0.4445 270)
			(size 0.1397 0.1397)
			(layers "F.Cu" "F.Mask" "F.Paste")
			(net "8644_USB_DN1")
			(options
				(clearance outline)
				(anchor circle)
			)
			(primitives
				(gr_poly
					(pts
						(arc
							(start -0.1778 -0.2794)
							(mid -0.249642 -0.249642)
							(end -0.2794 -0.1778)
						)
						(arc
							(start -0.2794 0.1778)
							(mid -0.249642 0.249642)
							(end -0.1778 0.2794)
						)
						(arc
							(start 0.1778 0.2794)
							(mid 0.249642 0.249642)
							(end 0.2794 0.1778)
						)
						(arc
							(start 0.2794 -0.1778)
							(mid 0.249642 -0.249642)
							(end 0.1778 -0.2794)
						)
					)
					(width 0)
					(fill yes)
				)
			)
		)
		(pad "2" smd custom
			(at 0 0.4445 270)
			(size 0.1397 0.1397)
			(layers "F.Cu" "F.Mask" "F.Paste")
			(net "P3V3_STBY")
			(options
				(clearance outline)
				(anchor circle)
			)
			(primitives
				(gr_poly
					(pts
						(arc
							(start -0.1778 -0.2794)
							(mid -0.249642 -0.249642)
							(end -0.2794 -0.1778)
						)
						(arc
							(start -0.2794 0.1778)
							(mid -0.249642 0.249642)
							(end -0.1778 0.2794)
						)
						(arc
							(start 0.1778 0.2794)
							(mid 0.249642 0.249642)
							(end 0.2794 0.1778)
						)
						(arc
							(start 0.2794 -0.1778)
							(mid 0.249642 -0.249642)
							(end 0.1778 -0.2794)
						)
					)
					(width 0)
					(fill yes)
				)
			)
		)
	)
	(footprint ""
		(layer "F.Cu")
		(at 151.730202 -65.432432 90)
		(property "Reference" "PC191"
			(at 0 0 90)
			(layer "F.SilkS")
			(hide yes)
			(effects
				(font
					(size 1.27 1.27)
				)
			)
		)
		(property "Value" "SCD1U50V3KX-GP"
			(at 0 -2.8194 90)
			(unlocked yes)
			(layer "F.Fab")
			(hide yes)
			(effects
				(font
					(size 1.016 1.016)
					(thickness 0.1524)
				)
			)
		)
		(property "Device Type" "C603H36"
			(at 0 -4.3434 90)
			(unlocked yes)
			(layer "F.Fab")
			(hide yes)
			(effects
				(font
					(size 1.016 1.016)
					(thickness 0.1524)
				)
			)
		)
		(duplicate_pad_numbers_are_jumpers no)
		(fp_line
			(start 0.508 0)
			(end -0.508 0)
			(stroke
				(width 0.2032)
				(type default)
			)
			(layer "F.SilkS")
		)
		(fp_rect
			(start -0.5842 1.3335)
			(end 0.5842 -1.3335)
			(stroke
				(width 0)
				(type default)
			)
			(fill no)
			(layer "F.CrtYd")
		)
		(fp_rect
			(start -0.5842 1.3335)
			(end 0.5842 -1.3335)
			(stroke
				(width 0)
				(type default)
			)
			(fill no)
			(layer "F.Fab")
		)
		(pad "1" smd custom
			(at 0 -0.762 90)
			(size 0.2159 0.2159)
			(layers "F.Cu" "F.Mask" "F.Paste")
			(net "P0V9_VIN")
			(options
				(clearance outline)
				(anchor circle)
			)
			(primitives
				(gr_poly
					(pts
						(arc
							(start -0.3302 -0.4318)
							(mid -0.402042 -0.402042)
							(end -0.4318 -0.3302)
						)
						(arc
							(start -0.4318 0.3302)
							(mid -0.402042 0.402042)
							(end -0.3302 0.4318)
						)
						(arc
							(start 0.3302 0.4318)
							(mid 0.402042 0.402042)
							(end 0.4318 0.3302)
						)
						(arc
							(start 0.4318 -0.3302)
							(mid 0.402042 -0.402042)
							(end 0.3302 -0.4318)
						)
					)
					(width 0)
					(fill yes)
				)
			)
		)
		(pad "2" smd custom
			(at 0 0.762 90)
			(size 0.2159 0.2159)
			(layers "F.Cu" "F.Mask" "F.Paste")
			(net "GND")
			(options
				(clearance outline)
				(anchor circle)
			)
			(primitives
				(gr_poly
					(pts
						(arc
							(start -0.3302 -0.4318)
							(mid -0.402042 -0.402042)
							(end -0.4318 -0.3302)
						)
						(arc
							(start -0.4318 0.3302)
							(mid -0.402042 0.402042)
							(end -0.3302 0.4318)
						)
						(arc
							(start 0.3302 0.4318)
							(mid 0.402042 0.402042)
							(end 0.4318 0.3302)
						)
						(arc
							(start 0.4318 -0.3302)
							(mid 0.402042 -0.402042)
							(end 0.3302 -0.4318)
						)
					)
					(width 0)
					(fill yes)
				)
			)
		)
	)
	(footprint ""
		(layer "F.Cu")
		(at 117.3226 -17.0688 180)
		(property "Reference" "R753"
			(at 0 0 180)
			(layer "F.SilkS")
			(hide yes)
			(effects
				(font
					(size 1.27 1.27)
				)
			)
		)
		(property "Value" "4K7R2F-GP"
			(at 0.064008 -3.993896 180)
			(unlocked yes)
			(layer "F.Fab")
			(hide yes)
			(effects
				(font
					(size 1.016 1.016)
					(thickness 0.1524)
				)
			)
		)
		(property "Device Type" "R402H16"
			(at 0.064008 -5.517896 180)
			(unlocked yes)
			(layer "F.Fab")
			(hide yes)
			(effects
				(font
					(size 1.016 1.016)
					(thickness 0.1524)
				)
			)
		)
		(duplicate_pad_numbers_are_jumpers no)
		(fp_line
			(start 0.508 -0.9398)
			(end -0.508 -0.9398)
			(stroke
				(width 0.1524)
				(type default)
			)
			(layer "F.SilkS")
		)
		(fp_line
			(start -0.508 -0.9398)
			(end -0.508 0.9398)
			(stroke
				(width 0.1524)
				(type default)
			)
			(layer "F.SilkS")
		)
		(fp_rect
			(start -0.508 0.9398)
			(end 0.508 -0.9398)
			(stroke
				(width 0)
				(type default)
			)
			(fill no)
			(layer "F.CrtYd")
		)
		(fp_rect
			(start -0.508 0.9398)
			(end 0.508 -0.9398)
			(stroke
				(width 0)
				(type default)
			)
			(fill no)
			(layer "F.Fab")
		)
		(pad "1" smd custom
			(at 0 -0.4445 180)
			(size 0.1397 0.1397)
			(layers "F.Cu" "F.Mask" "F.Paste")
			(net "GND")
			(options
				(clearance outline)
				(anchor circle)
			)
			(primitives
				(gr_poly
					(pts
						(arc
							(start -0.1778 -0.2794)
							(mid -0.249642 -0.249642)
							(end -0.2794 -0.1778)
						)
						(arc
							(start -0.2794 0.1778)
							(mid -0.249642 0.249642)
							(end -0.1778 0.2794)
						)
						(arc
							(start 0.1778 0.2794)
							(mid 0.249642 0.249642)
							(end 0.2794 0.1778)
						)
						(arc
							(start 0.2794 -0.1778)
							(mid 0.249642 -0.249642)
							(end 0.1778 -0.2794)
						)
					)
					(width 0)
					(fill yes)
				)
			)
		)
		(pad "2" smd custom
			(at 0 0.4445 180)
			(size 0.1397 0.1397)
			(layers "F.Cu" "F.Mask" "F.Paste")
			(net "U54_A0")
			(options
				(clearance outline)
				(anchor circle)
			)
			(primitives
				(gr_poly
					(pts
						(arc
							(start -0.1778 -0.2794)
							(mid -0.249642 -0.249642)
							(end -0.2794 -0.1778)
						)
						(arc
							(start -0.2794 0.1778)
							(mid -0.249642 0.249642)
							(end -0.1778 0.2794)
						)
						(arc
							(start 0.1778 0.2794)
							(mid 0.249642 0.249642)
							(end 0.2794 0.1778)
						)
						(arc
							(start 0.2794 -0.1778)
							(mid 0.249642 -0.249642)
							(end 0.1778 -0.2794)
						)
					)
					(width 0)
					(fill yes)
				)
			)
		)
	)
	(footprint ""
		(layer "F.Cu")
		(at 122.377454 -83.58759 90)
		(property "Reference" "TP800"
			(at 0 0 90)
			(layer "F.SilkS")
			(hide yes)
			(effects
				(font
					(size 1.27 1.27)
				)
			)
		)
		(property "Value" "TPAD28-2-GP"
			(at -0.0127 -1.6637 90)
			(unlocked yes)
			(layer "F.Fab")
			(hide yes)
			(effects
				(font
					(size 1.016 1.016)
					(thickness 0.1524)
				)
			)
		)
		(property "Device Type" "TPAD28"
			(at -0.0127 -3.1877 90)
			(unlocked yes)
			(layer "F.Fab")
			(hide yes)
			(effects
				(font
					(size 1.016 1.016)
					(thickness 0.1524)
				)
			)
		)
		(duplicate_pad_numbers_are_jumpers no)
		(fp_poly
			(pts
				(arc
					(start 0 0.3556)
					(mid 0 -0.3556)
					(end 0 0.3556)
				)
			)
			(stroke
				(width 0)
				(type default)
			)
			(fill no)
			(layer "F.CrtYd")
		)
		(fp_poly
			(pts
				(arc
					(start 0 0.6096)
					(mid 0 -0.6096)
					(end 0 0.6096)
				)
			)
			(stroke
				(width 0)
				(type default)
			)
			(fill no)
			(layer "F.Fab")
		)
		(pad "1" smd circle
			(at 0 0 90)
			(size 0.7112 0.7112)
			(layers "F.Cu" "F.Mask" "F.Paste")
			(net "RTC_CLK_OUT")
		)
	)
	(footprint ""
		(layer "F.Cu")
		(at 70.993 -30.988 90)
		(property "Reference" "C267"
			(at 0 0 90)
			(layer "F.SilkS")
			(hide yes)
			(effects
				(font
					(size 1.27 1.27)
				)
			)
		)
		(property "Value" "SC100P50V2JN-3GP"
			(at 1.1811 -2.7051 90)
			(unlocked yes)
			(layer "F.Fab")
			(hide yes)
			(effects
				(font
					(size 1.016 1.016)
					(thickness 0.1524)
				)
			)
		)
		(property "Device Type" "C402H22"
			(at 1.1811 -4.2291 90)
			(unlocked yes)
			(layer "F.Fab")
			(hide yes)
			(effects
				(font
					(size 1.016 1.016)
					(thickness 0.1524)
				)
			)
		)
		(duplicate_pad_numbers_are_jumpers no)
		(fp_rect
			(start -0.4318 0.9525)
			(end 0.4318 -0.9525)
			(stroke
				(width 0)
				(type default)
			)
			(fill no)
			(layer "F.CrtYd")
		)
		(fp_rect
			(start -0.4318 0.9525)
			(end 0.4318 -0.9525)
			(stroke
				(width 0)
				(type default)
			)
			(fill no)
			(layer "F.Fab")
		)
		(pad "1" smd custom
			(at 0 -0.4445 90)
			(size 0.1524 0.1524)
			(layers "F.Cu" "F.Mask" "F.Paste")
			(net "P3V3_STBY_VFB")
			(options
				(clearance outline)
				(anchor circle)
			)
			(primitives
				(gr_poly
					(pts
						(arc
							(start 0.3048 -0.2032)
							(mid 0.275042 -0.275042)
							(end 0.2032 -0.3048)
						)
						(arc
							(start -0.2032 -0.3048)
							(mid -0.275042 -0.275042)
							(end -0.3048 -0.2032)
						)
						(arc
							(start -0.3048 0.2032)
							(mid -0.275042 0.275042)
							(end -0.2032 0.3048)
						)
						(arc
							(start 0.2032 0.3048)
							(mid 0.275042 0.275042)
							(end 0.3048 0.2032)
						)
					)
					(width 0)
					(fill yes)
				)
			)
		)
		(pad "2" smd custom
			(at 0 0.4445 90)
			(size 0.1524 0.1524)
			(layers "F.Cu" "F.Mask" "F.Paste")
			(net "P3V3_STBY_VFB_R")
			(options
				(clearance outline)
				(anchor circle)
			)
			(primitives
				(gr_poly
					(pts
						(arc
							(start 0.3048 -0.2032)
							(mid 0.275042 -0.275042)
							(end 0.2032 -0.3048)
						)
						(arc
							(start -0.2032 -0.3048)
							(mid -0.275042 -0.275042)
							(end -0.3048 -0.2032)
						)
						(arc
							(start -0.3048 0.2032)
							(mid -0.275042 0.275042)
							(end -0.2032 0.3048)
						)
						(arc
							(start 0.2032 0.3048)
							(mid 0.275042 0.275042)
							(end 0.3048 0.2032)
						)
					)
					(width 0)
					(fill yes)
				)
			)
		)
	)
	(footprint ""
		(layer "F.Cu")
		(at 61.708538 -23.136606 90)
		(property "Reference" "CN2"
			(at 0 0 90)
			(layer "F.SilkS")
			(hide yes)
			(effects
				(font
					(size 1.27 1.27)
				)
			)
		)
		(property "Value" "PIN-CONN24A-4-GP"
			(at -10.5156 -7.239 90)
			(unlocked yes)
			(layer "F.Fab")
			(hide yes)
			(effects
				(font
					(size 1.016 1.016)
					(thickness 0.1524)
				)
			)
		)
		(property "Device Type" "232-97-12GBE8"
			(at -10.5156 -8.763 90)
			(unlocked yes)
			(layer "F.Fab")
			(hide yes)
			(effects
				(font
					(size 1.016 1.016)
					(thickness 0.1524)
				)
			)
		)
		(duplicate_pad_numbers_are_jumpers no)
		(fp_line
			(start 7.7724 -3.5052)
			(end -7.7724 -3.5052)
			(stroke
				(width 0.1524)
				(type default)
			)
			(layer "F.SilkS")
		)
		(fp_line
			(start -7.7724 -3.5052)
			(end -7.7724 3.5052)
			(stroke
				(width 0.1524)
				(type default)
			)
			(layer "F.SilkS")
		)
		(fp_line
			(start 7.7724 3.5052)
			(end 7.7724 -3.5052)
			(stroke
				(width 0.1524)
				(type default)
			)
			(layer "F.SilkS")
		)
		(fp_line
			(start -7.7724 3.5052)
			(end 7.7724 3.5052)
			(stroke
				(width 0.1524)
				(type default)
			)
			(layer "F.SilkS")
		)
		(fp_line
			(start -7.4041 3.5941)
			(end -6.5405 3.5941)
			(stroke
				(width 0.3302)
				(type default)
			)
			(layer "F.SilkS")
		)
		(fp_poly
			(pts
				(xy -6.985 3.5814) (xy -7.62 4.2164) (xy -6.35 4.2164)
			)
			(stroke
				(width 0)
				(type default)
			)
			(fill yes)
			(layer "F.SilkS")
		)
		(fp_poly
			(pts
				(xy -7.3406 0.224536) (xy 7.3406 0.224536) (xy 7.3406 -0.224536) (xy -7.3406 -0.224536)
			)
			(stroke
				(width 0)
				(type default)
			)
			(fill yes)
			(layer "F.SilkS")
		)
		(fp_rect
			(start -7.5184 2.7432)
			(end 7.5184 -2.7432)
			(stroke
				(width 0)
				(type default)
			)
			(fill no)
			(layer "F.CrtYd")
		)
		(fp_poly
			(pts
				(xy 8.0264 -2.7432) (xy -7.5184 -2.7432) (xy -7.5184 2.7432) (xy 7.5184 2.7432) (xy 7.5184 -2.7305)
				(xy 8.0264 -2.7305) (xy 8.0264 3.7592) (xy -8.0264 3.7592) (xy -8.0264 -3.7592) (xy 8.0264 -3.7592)
			)
			(stroke
				(width 0)
				(type default)
			)
			(fill no)
			(layer "F.CrtYd")
		)
		(fp_rect
			(start -8.0264 3.7592)
			(end 8.0264 -3.7592)
			(stroke
				(width 0)
				(type default)
			)
			(fill no)
			(layer "F.Fab")
		)
		(pad "1" smd rect
			(at -6.985 1.837436 90)
			(size 0.7112 2.8194)
			(layers "F.Cu" "F.Mask" "F.Paste")
			(net "GND")
		)
		(pad "2" smd rect
			(at -6.985 -1.837436 90)
			(size 0.7112 2.8194)
			(layers "F.Cu" "F.Mask" "F.Paste")
			(net "GND")
		)
		(pad "3" smd rect
			(at -5.715 1.837436 90)
			(size 0.7112 2.8194)
			(layers "F.Cu" "F.Mask" "F.Paste")
			(net "MNG_TX_DN")
		)
		(pad "4" smd rect
			(at -5.715 -1.837436 90)
			(size 0.7112 2.8194)
			(layers "F.Cu" "F.Mask" "F.Paste")
			(net "MNG_TX_DP")
		)
		(pad "5" smd rect
			(at -4.445 1.837436 90)
			(size 0.7112 2.8194)
			(layers "F.Cu" "F.Mask" "F.Paste")
			(net "GND")
		)
		(pad "6" smd rect
			(at -4.445 -1.837436 90)
			(size 0.7112 2.8194)
			(layers "F.Cu" "F.Mask" "F.Paste")
			(net "GND")
		)
		(pad "7" smd rect
			(at -3.175 1.837436 90)
			(size 0.7112 2.8194)
			(layers "F.Cu" "F.Mask" "F.Paste")
			(net "MNG_RX_DN")
		)
		(pad "8" smd rect
			(at -3.175 -1.837436 90)
			(size 0.7112 2.8194)
			(layers "F.Cu" "F.Mask" "F.Paste")
			(net "MNG_RX_DP")
		)
		(pad "9" smd rect
			(at -1.905 1.837436 90)
			(size 0.7112 2.8194)
			(layers "F.Cu" "F.Mask" "F.Paste")
			(net "GND")
		)
		(pad "10" smd rect
			(at -1.905 -1.837436 90)
			(size 0.7112 2.8194)
			(layers "F.Cu" "F.Mask" "F.Paste")
			(net "GND")
		)
		(pad "11" smd rect
			(at -0.635 1.837436 90)
			(size 0.7112 2.8194)
			(layers "F.Cu" "F.Mask" "F.Paste")
			(net "TRAY_ID1")
		)
		(pad "12" smd rect
			(at -0.635 -1.837436 90)
			(size 0.7112 2.8194)
			(layers "F.Cu" "F.Mask" "F.Paste")
			(net "TRAY_ID2")
		)
		(pad "13" smd rect
			(at 0.635 1.837436 90)
			(size 0.7112 2.8194)
			(layers "F.Cu" "F.Mask" "F.Paste")
			(net "BMC_INT_N")
		)
		(pad "14" smd rect
			(at 0.635 -1.837436 90)
			(size 0.7112 2.8194)
			(layers "F.Cu" "F.Mask" "F.Paste")
			(net "TRAY_ID0")
		)
		(pad "15" smd rect
			(at 1.905 1.837436 90)
			(size 0.7112 2.8194)
			(layers "F.Cu" "F.Mask" "F.Paste")
			(net "IPMB_DAT")
		)
		(pad "16" smd rect
			(at 1.905 -1.837436 90)
			(size 0.7112 2.8194)
			(layers "F.Cu" "F.Mask" "F.Paste")
			(net "IPMB_CLK")
		)
		(pad "17" smd rect
			(at 3.175 1.837436 90)
			(size 0.7112 2.8194)
			(layers "F.Cu" "F.Mask" "F.Paste")
			(net "TRAY_RESET_N")
		)
		(pad "18" smd rect
			(at 3.175 -1.837436 90)
			(size 0.7112 2.8194)
			(layers "F.Cu" "F.Mask" "F.Paste")
			(net "BP_PRSNT_N")
		)
		(pad "19" smd rect
			(at 4.445 1.837436 90)
			(size 0.7112 2.8194)
			(layers "F.Cu" "F.Mask" "F.Paste")
			(net "MBP_UART_TX")
		)
		(pad "20" smd rect
			(at 4.445 -1.837436 90)
			(size 0.7112 2.8194)
			(layers "F.Cu" "F.Mask" "F.Paste")
			(net "MBP_UART_RX")
		)
		(pad "21" smd rect
			(at 5.715 1.837436 90)
			(size 0.7112 2.8194)
			(layers "F.Cu" "F.Mask" "F.Paste")
			(net "Net_85")
		)
		(pad "22" smd rect
			(at 5.715 -1.837436 90)
			(size 0.7112 2.8194)
			(layers "F.Cu" "F.Mask" "F.Paste")
			(net "Net_84")
		)
		(pad "23" smd rect
			(at 6.985 1.837436 90)
			(size 0.7112 2.8194)
			(layers "F.Cu" "F.Mask" "F.Paste")
			(net "TRAY_POWER_CRIT_N")
		)
		(pad "24" smd rect
			(at 6.985 -1.837436 90)
			(size 0.7112 2.8194)
			(layers "F.Cu" "F.Mask" "F.Paste")
			(net "CN2_P23")
		)
		(zone
			(layer "F.Cu")
			(hatch none 0.5)
			(connect_pads
				(clearance 0)
			)
			(min_thickness 0.25)
			(keepout
				(tracks not_allowed)
				(vias allowed)
				(pads allowed)
				(copperpour not_allowed)
				(footprints allowed)
			)
			(placement
				(enabled no)
				(sheetname "")
			)
			(fill
				(thermal_gap 0.5)
				(thermal_bridge_width 0.5)
				(island_removal_mode 0)
			)
			(polygon
				(pts
					(xy 62.136274 -15.796006) (xy 62.136274 -30.477206) (xy 61.280802 -30.477206) (xy 61.280802 -15.796006)
				)
			)
		)
		(zone
			(layer "F.Cu")
			(hatch none 0.5)
			(connect_pads
				(clearance 0)
			)
			(min_thickness 0.25)
			(keepout
				(tracks allowed)
				(vias not_allowed)
				(pads allowed)
				(copperpour not_allowed)
				(footprints allowed)
			)
			(placement
				(enabled no)
				(sheetname "")
			)
			(fill
				(thermal_gap 0.5)
				(thermal_bridge_width 0.5)
				(island_removal_mode 0)
			)
			(polygon
				(pts
					(xy 62.136274 -15.796006) (xy 62.136274 -30.477206) (xy 61.280802 -30.477206) (xy 61.280802 -15.796006)
				)
			)
		)
	)
	(footprint ""
		(layer "F.Cu")
		(at 161.80816 -212.420454 180)
		(property "Reference" "C165"
			(at 0 0 180)
			(layer "F.SilkS")
			(hide yes)
			(effects
				(font
					(size 1.27 1.27)
				)
			)
		)
		(property "Value" "SCD22U10V2KX-1GP"
			(at 1.1811 -2.7051 180)
			(unlocked yes)
			(layer "F.Fab")
			(hide yes)
			(effects
				(font
					(size 1.016 1.016)
					(thickness 0.1524)
				)
			)
		)
		(property "Device Type" "C402H22"
			(at 1.1811 -4.2291 180)
			(unlocked yes)
			(layer "F.Fab")
			(hide yes)
			(effects
				(font
					(size 1.016 1.016)
					(thickness 0.1524)
				)
			)
		)
		(duplicate_pad_numbers_are_jumpers no)
		(fp_rect
			(start -0.4318 0.9525)
			(end 0.4318 -0.9525)
			(stroke
				(width 0)
				(type default)
			)
			(fill no)
			(layer "F.CrtYd")
		)
		(fp_rect
			(start -0.4318 0.9525)
			(end 0.4318 -0.9525)
			(stroke
				(width 0)
				(type default)
			)
			(fill no)
			(layer "F.Fab")
		)
		(pad "1" smd custom
			(at 0 -0.4445 180)
			(size 0.1524 0.1524)
			(layers "F.Cu" "F.Mask" "F.Paste")
			(net "PCIE_TX_CAP_N52")
			(options
				(clearance outline)
				(anchor circle)
			)
			(primitives
				(gr_poly
					(pts
						(arc
							(start 0.3048 -0.2032)
							(mid 0.275042 -0.275042)
							(end 0.2032 -0.3048)
						)
						(arc
							(start -0.2032 -0.3048)
							(mid -0.275042 -0.275042)
							(end -0.3048 -0.2032)
						)
						(arc
							(start -0.3048 0.2032)
							(mid -0.275042 0.275042)
							(end -0.2032 0.3048)
						)
						(arc
							(start 0.2032 0.3048)
							(mid 0.275042 0.275042)
							(end 0.3048 0.2032)
						)
					)
					(width 0)
					(fill yes)
				)
			)
		)
		(pad "2" smd custom
			(at 0 0.4445 180)
			(size 0.1524 0.1524)
			(layers "F.Cu" "F.Mask" "F.Paste")
			(net "PCIE_TX_N52")
			(options
				(clearance outline)
				(anchor circle)
			)
			(primitives
				(gr_poly
					(pts
						(arc
							(start 0.3048 -0.2032)
							(mid 0.275042 -0.275042)
							(end 0.2032 -0.3048)
						)
						(arc
							(start -0.2032 -0.3048)
							(mid -0.275042 -0.275042)
							(end -0.3048 -0.2032)
						)
						(arc
							(start -0.3048 0.2032)
							(mid -0.275042 0.275042)
							(end -0.2032 0.3048)
						)
						(arc
							(start 0.2032 0.3048)
							(mid 0.275042 0.275042)
							(end 0.3048 0.2032)
						)
					)
					(width 0)
					(fill yes)
				)
			)
		)
	)
	(footprint ""
		(layer "F.Cu")
		(at 186.6392 -3.556 90)
		(property "Reference" "R496"
			(at 0 0 90)
			(layer "F.SilkS")
			(hide yes)
			(effects
				(font
					(size 1.27 1.27)
				)
			)
		)
		(property "Value" "0R2J-2-GP"
			(at 0.064008 -3.993896 90)
			(unlocked yes)
			(layer "F.Fab")
			(hide yes)
			(effects
				(font
					(size 1.016 1.016)
					(thickness 0.1524)
				)
			)
		)
		(property "Device Type" "R402H16"
			(at 0.064008 -5.517896 90)
			(unlocked yes)
			(layer "F.Fab")
			(hide yes)
			(effects
				(font
					(size 1.016 1.016)
					(thickness 0.1524)
				)
			)
		)
		(duplicate_pad_numbers_are_jumpers no)
		(fp_line
			(start 0.508 -0.9398)
			(end -0.508 -0.9398)
			(stroke
				(width 0.1524)
				(type default)
			)
			(layer "F.SilkS")
		)
		(fp_line
			(start -0.508 -0.9398)
			(end -0.508 0.9398)
			(stroke
				(width 0.1524)
				(type default)
			)
			(layer "F.SilkS")
		)
		(fp_rect
			(start -0.508 0.9398)
			(end 0.508 -0.9398)
			(stroke
				(width 0)
				(type default)
			)
			(fill no)
			(layer "F.CrtYd")
		)
		(fp_rect
			(start -0.508 0.9398)
			(end 0.508 -0.9398)
			(stroke
				(width 0)
				(type default)
			)
			(fill no)
			(layer "F.Fab")
		)
		(pad "1" smd custom
			(at 0 -0.4445 90)
			(size 0.1397 0.1397)
			(layers "F.Cu" "F.Mask" "F.Paste")
			(net "HB_OUT_BMC")
			(options
				(clearance outline)
				(anchor circle)
			)
			(primitives
				(gr_poly
					(pts
						(arc
							(start -0.1778 -0.2794)
							(mid -0.249642 -0.249642)
							(end -0.2794 -0.1778)
						)
						(arc
							(start -0.2794 0.1778)
							(mid -0.249642 0.249642)
							(end -0.1778 0.2794)
						)
						(arc
							(start 0.1778 0.2794)
							(mid 0.249642 0.249642)
							(end 0.2794 0.1778)
						)
						(arc
							(start 0.2794 -0.1778)
							(mid 0.249642 -0.249642)
							(end 0.1778 -0.2794)
						)
					)
					(width 0)
					(fill yes)
				)
			)
		)
		(pad "2" smd custom
			(at 0 0.4445 90)
			(size 0.1397 0.1397)
			(layers "F.Cu" "F.Mask" "F.Paste")
			(net "Q21_G")
			(options
				(clearance outline)
				(anchor circle)
			)
			(primitives
				(gr_poly
					(pts
						(arc
							(start -0.1778 -0.2794)
							(mid -0.249642 -0.249642)
							(end -0.2794 -0.1778)
						)
						(arc
							(start -0.2794 0.1778)
							(mid -0.249642 0.249642)
							(end -0.1778 0.2794)
						)
						(arc
							(start 0.1778 0.2794)
							(mid 0.249642 0.249642)
							(end 0.2794 0.1778)
						)
						(arc
							(start 0.2794 -0.1778)
							(mid 0.249642 -0.249642)
							(end 0.1778 -0.2794)
						)
					)
					(width 0)
					(fill yes)
				)
			)
		)
	)
	(footprint ""
		(layer "F.Cu")
		(at 43.228768 -118.307104)
		(property "Reference" "TP218"
			(at 0 0 0)
			(layer "F.SilkS")
			(hide yes)
			(effects
				(font
					(size 1.27 1.27)
				)
			)
		)
		(property "Value" "TPAD28-2-GP"
			(at -0.0127 -1.6637 0)
			(unlocked yes)
			(layer "F.Fab")
			(hide yes)
			(effects
				(font
					(size 1.016 1.016)
					(thickness 0.1524)
				)
			)
		)
		(property "Device Type" "TPAD28"
			(at -0.0127 -3.1877 0)
			(unlocked yes)
			(layer "F.Fab")
			(hide yes)
			(effects
				(font
					(size 1.016 1.016)
					(thickness 0.1524)
				)
			)
		)
		(duplicate_pad_numbers_are_jumpers no)
		(fp_poly
			(pts
				(arc
					(start 0.3556 0)
					(mid -0.3556 0)
					(end 0.3556 0)
				)
			)
			(stroke
				(width 0)
				(type default)
			)
			(fill no)
			(layer "F.CrtYd")
		)
		(fp_poly
			(pts
				(arc
					(start 0.6096 0)
					(mid -0.6096 0)
					(end 0.6096 0)
				)
			)
			(stroke
				(width 0)
				(type default)
			)
			(fill no)
			(layer "F.Fab")
		)
		(pad "1" smd circle
			(at 0 0)
			(size 0.7112 0.7112)
			(layers "F.Cu" "F.Mask" "F.Paste")
			(net "GPIOH0")
		)
	)
	(footprint ""
		(layer "F.Cu")
		(at 128.373124 -202.793092)
		(property "Reference" "U199"
			(at 0 0 0)
			(layer "F.SilkS")
			(hide yes)
			(effects
				(font
					(size 1.27 1.27)
				)
			)
		)
		(property "Value" "MAX7311AUG-GP"
			(at 0 -12.1412 0)
			(unlocked yes)
			(layer "F.Fab")
			(hide yes)
			(effects
				(font
					(size 1.016 1.016)
					(thickness 0.1524)
				)
			)
		)
		(property "Device Type" "TSOIC24H44"
			(at 0 -13.6652 0)
			(unlocked yes)
			(layer "F.Fab")
			(hide yes)
			(effects
				(font
					(size 1.016 1.016)
					(thickness 0.1524)
				)
			)
		)
		(duplicate_pad_numbers_are_jumpers no)
		(fp_line
			(start -4.1148 -1.778)
			(end -4.1148 1.778)
			(stroke
				(width 0.1524)
				(type default)
			)
			(layer "F.SilkS")
		)
		(fp_line
			(start -4.1148 -1.778)
			(end 3.683 -1.778)
			(stroke
				(width 0.1524)
				(type default)
			)
			(layer "F.SilkS")
		)
		(fp_line
			(start -4.0386 1.778)
			(end -4.0386 3.556)
			(stroke
				(width 0.3556)
				(type default)
			)
			(layer "F.SilkS")
		)
		(fp_line
			(start -3.8354 0)
			(end -4.1148 -0.2794)
			(stroke
				(width 0.1524)
				(type default)
			)
			(layer "F.SilkS")
		)
		(fp_line
			(start -3.8354 0)
			(end -4.1148 0.2794)
			(stroke
				(width 0.1524)
				(type default)
			)
			(layer "F.SilkS")
		)
		(fp_line
			(start 3.683 -1.778)
			(end 3.683 1.778)
			(stroke
				(width 0.1524)
				(type default)
			)
			(layer "F.SilkS")
		)
		(fp_line
			(start 3.683 1.778)
			(end -4.1148 1.778)
			(stroke
				(width 0.1524)
				(type default)
			)
			(layer "F.SilkS")
		)
		(fp_poly
			(pts
				(xy -3.7592 -1.778) (xy 3.683 -1.778) (xy 3.683 1.778) (xy -3.7592 1.778)
			)
			(stroke
				(width 0)
				(type default)
			)
			(fill yes)
			(layer "F.SilkS")
		)
		(fp_poly
			(pts
				(xy -4.22656 3.81) (xy 4.22656 3.81) (xy 4.22656 -3.81) (xy -4.22656 -3.81)
			)
			(stroke
				(width 0)
				(type default)
			)
			(fill no)
			(layer "F.CrtYd")
		)
		(fp_poly
			(pts
				(xy -4.22656 -3.81) (xy 4.22656 -3.81) (xy 4.22656 3.81) (xy -4.22656 3.81)
			)
			(stroke
				(width 0)
				(type default)
			)
			(fill no)
			(layer "F.Fab")
		)
		(pad "1" smd rect
			(at -3.57632 2.8194)
			(size 0.3556 1.524)
			(layers "F.Cu" "F.Mask" "F.Paste")
			(net "IOEXP_INT#_2")
		)
		(pad "2" smd rect
			(at -2.92608 2.8194)
			(size 0.3556 1.524)
			(layers "F.Cu" "F.Mask" "F.Paste")
			(net "IOEXP2_AD1")
		)
		(pad "3" smd rect
			(at -2.27584 2.8194)
			(size 0.3556 1.524)
			(layers "F.Cu" "F.Mask" "F.Paste")
			(net "IOEXP2_AD2")
		)
		(pad "4" smd rect
			(at -1.6256 2.8194)
			(size 0.3556 1.524)
			(layers "F.Cu" "F.Mask" "F.Paste")
			(net "SSD_PRSNT#1")
		)
		(pad "5" smd rect
			(at -0.97536 2.8194)
			(size 0.3556 1.524)
			(layers "F.Cu" "F.Mask" "F.Paste")
			(net "SSD_ATNLED#1")
		)
		(pad "6" smd rect
			(at -0.32512 2.8194)
			(size 0.3556 1.524)
			(layers "F.Cu" "F.Mask" "F.Paste")
			(net "SSD_PWREN1")
		)
		(pad "7" smd rect
			(at 0.32512 2.8194)
			(size 0.3556 1.524)
			(layers "F.Cu" "F.Mask" "F.Paste")
			(net "SSD_PERST#1")
		)
		(pad "8" smd rect
			(at 0.97536 2.8194)
			(size 0.3556 1.524)
			(layers "F.Cu" "F.Mask" "F.Paste")
			(net "SSD_PRSNT#2")
		)
		(pad "9" smd rect
			(at 1.6256 2.8194)
			(size 0.3556 1.524)
			(layers "F.Cu" "F.Mask" "F.Paste")
			(net "SSD_ATNLED#2")
		)
		(pad "10" smd rect
			(at 2.27584 2.8194)
			(size 0.3556 1.524)
			(layers "F.Cu" "F.Mask" "F.Paste")
			(net "SSD_PWREN2")
		)
		(pad "11" smd rect
			(at 2.92608 2.8194)
			(size 0.3556 1.524)
			(layers "F.Cu" "F.Mask" "F.Paste")
			(net "SSD_PERST#2")
		)
		(pad "12" smd rect
			(at 3.57632 2.8194)
			(size 0.3556 1.524)
			(layers "F.Cu" "F.Mask" "F.Paste")
			(net "GND")
		)
		(pad "13" smd rect
			(at 3.57632 -2.8194)
			(size 0.3556 1.524)
			(layers "F.Cu" "F.Mask" "F.Paste")
			(net "SSD_PRSNT#6")
		)
		(pad "14" smd rect
			(at 2.92608 -2.8194)
			(size 0.3556 1.524)
			(layers "F.Cu" "F.Mask" "F.Paste")
			(net "SSD_ATNLED#6")
		)
		(pad "15" smd rect
			(at 2.27584 -2.8194)
			(size 0.3556 1.524)
			(layers "F.Cu" "F.Mask" "F.Paste")
			(net "SSD_PWREN6")
		)
		(pad "16" smd rect
			(at 1.6256 -2.8194)
			(size 0.3556 1.524)
			(layers "F.Cu" "F.Mask" "F.Paste")
			(net "SSD_PERST#6")
		)
		(pad "17" smd rect
			(at 0.97536 -2.8194)
			(size 0.3556 1.524)
			(layers "F.Cu" "F.Mask" "F.Paste")
			(net "SSD_PRSNT#7")
		)
		(pad "18" smd rect
			(at 0.32512 -2.8194)
			(size 0.3556 1.524)
			(layers "F.Cu" "F.Mask" "F.Paste")
			(net "SSD_ATNLED#7")
		)
		(pad "19" smd rect
			(at -0.32512 -2.8194)
			(size 0.3556 1.524)
			(layers "F.Cu" "F.Mask" "F.Paste")
			(net "SSD_PWREN7")
		)
		(pad "20" smd rect
			(at -0.97536 -2.8194)
			(size 0.3556 1.524)
			(layers "F.Cu" "F.Mask" "F.Paste")
			(net "SSD_PERST#7")
		)
		(pad "21" smd rect
			(at -1.6256 -2.8194)
			(size 0.3556 1.524)
			(layers "F.Cu" "F.Mask" "F.Paste")
			(net "IOEXP2_AD0")
		)
		(pad "22" smd rect
			(at -2.27584 -2.8194)
			(size 0.3556 1.524)
			(layers "F.Cu" "F.Mask" "F.Paste")
			(net "I2C_GPIO_SCL_2")
		)
		(pad "23" smd rect
			(at -2.92608 -2.8194)
			(size 0.3556 1.524)
			(layers "F.Cu" "F.Mask" "F.Paste")
			(net "I2C_GPIO_SDA_2")
		)
		(pad "24" smd rect
			(at -3.57632 -2.8194)
			(size 0.3556 1.524)
			(layers "F.Cu" "F.Mask" "F.Paste")
			(net "P3V3_STBY")
		)
	)
	(footprint ""
		(layer "F.Cu")
		(at 48.641 -148.59 180)
		(property "Reference" "R589"
			(at 0 0 180)
			(layer "F.SilkS")
			(hide yes)
			(effects
				(font
					(size 1.27 1.27)
				)
			)
		)
		(property "Value" "4K7R2F-GP"
			(at 0.064008 -3.993896 180)
			(unlocked yes)
			(layer "F.Fab")
			(hide yes)
			(effects
				(font
					(size 1.016 1.016)
					(thickness 0.1524)
				)
			)
		)
		(property "Device Type" "R402H16"
			(at 0.064008 -5.517896 180)
			(unlocked yes)
			(layer "F.Fab")
			(hide yes)
			(effects
				(font
					(size 1.016 1.016)
					(thickness 0.1524)
				)
			)
		)
		(duplicate_pad_numbers_are_jumpers no)
		(fp_line
			(start 0.508 -0.9398)
			(end -0.508 -0.9398)
			(stroke
				(width 0.1524)
				(type default)
			)
			(layer "F.SilkS")
		)
		(fp_line
			(start -0.508 -0.9398)
			(end -0.508 0.9398)
			(stroke
				(width 0.1524)
				(type default)
			)
			(layer "F.SilkS")
		)
		(fp_rect
			(start -0.508 0.9398)
			(end 0.508 -0.9398)
			(stroke
				(width 0)
				(type default)
			)
			(fill no)
			(layer "F.CrtYd")
		)
		(fp_rect
			(start -0.508 0.9398)
			(end 0.508 -0.9398)
			(stroke
				(width 0)
				(type default)
			)
			(fill no)
			(layer "F.Fab")
		)
		(pad "1" smd custom
			(at 0 -0.4445 180)
			(size 0.1397 0.1397)
			(layers "F.Cu" "F.Mask" "F.Paste")
			(net "P3V3_STBY")
			(options
				(clearance outline)
				(anchor circle)
			)
			(primitives
				(gr_poly
					(pts
						(arc
							(start -0.1778 -0.2794)
							(mid -0.249642 -0.249642)
							(end -0.2794 -0.1778)
						)
						(arc
							(start -0.2794 0.1778)
							(mid -0.249642 0.249642)
							(end -0.1778 0.2794)
						)
						(arc
							(start 0.1778 0.2794)
							(mid 0.249642 0.249642)
							(end 0.2794 0.1778)
						)
						(arc
							(start 0.2794 -0.1778)
							(mid 0.249642 -0.249642)
							(end 0.1778 -0.2794)
						)
					)
					(width 0)
					(fill yes)
				)
			)
		)
		(pad "2" smd custom
			(at 0 0.4445 180)
			(size 0.1397 0.1397)
			(layers "F.Cu" "F.Mask" "F.Paste")
			(net "TEMP_2_A0")
			(options
				(clearance outline)
				(anchor circle)
			)
			(primitives
				(gr_poly
					(pts
						(arc
							(start -0.1778 -0.2794)
							(mid -0.249642 -0.249642)
							(end -0.2794 -0.1778)
						)
						(arc
							(start -0.2794 0.1778)
							(mid -0.249642 0.249642)
							(end -0.1778 0.2794)
						)
						(arc
							(start 0.1778 0.2794)
							(mid 0.249642 0.249642)
							(end 0.2794 0.1778)
						)
						(arc
							(start 0.2794 -0.1778)
							(mid 0.249642 -0.249642)
							(end 0.1778 -0.2794)
						)
					)
					(width 0)
					(fill yes)
				)
			)
		)
	)
	(footprint ""
		(layer "F.Cu")
		(at 62.3062 -154.2796 180)
		(property "Reference" "PG68"
			(at 0 0 180)
			(layer "F.SilkS")
			(hide yes)
			(effects
				(font
					(size 1.27 1.27)
				)
			)
		)
		(property "Value" "GAP-CLOSE-PWR-3-GP"
			(at 0.0254 -6.5786 180)
			(unlocked yes)
			(layer "F.Fab")
			(hide yes)
			(effects
				(font
					(size 1.016 1.016)
					(thickness 0.1524)
				)
			)
		)
		(property "Device Type" "GAP-CLOSE-PWR-3"
			(at 0.0254 -8.255 180)
			(unlocked yes)
			(layer "F.Fab")
			(hide yes)
			(effects
				(font
					(size 1.016 1.016)
					(thickness 0.1524)
				)
			)
		)
		(duplicate_pad_numbers_are_jumpers no)
		(fp_rect
			(start -0.7112 0.4572)
			(end 0.7112 -0.4572)
			(stroke
				(width 0)
				(type default)
			)
			(fill no)
			(layer "F.CrtYd")
		)
		(fp_poly
			(pts
				(xy -0.7112 -0.4572) (xy 0.7112 -0.4572) (xy 0.7112 0.4572) (xy -0.7112 0.4572)
			)
			(stroke
				(width 0)
				(type default)
			)
			(fill no)
			(layer "F.Fab")
		)
		(pad "1" smd rect
			(at -0.3048 0 180)
			(size 0.6604 0.762)
			(layers "F.Cu" "F.Mask" "F.Paste")
			(net "P1V53_PWR")
		)
		(pad "2" smd rect
			(at 0.3048 0 180)
			(size 0.6604 0.762)
			(layers "F.Cu" "F.Mask" "F.Paste")
			(net "P1V53_STBY")
		)
	)
	(footprint ""
		(layer "F.Cu")
		(at 219.329 -8.128 -90)
		(property "Reference" "R660"
			(at 0 0 270)
			(layer "F.SilkS")
			(hide yes)
			(effects
				(font
					(size 1.27 1.27)
				)
			)
		)
		(property "Value" "100KR2F-L1-GP"
			(at 0.064008 -3.993896 270)
			(unlocked yes)
			(layer "F.Fab")
			(hide yes)
			(effects
				(font
					(size 1.016 1.016)
					(thickness 0.1524)
				)
			)
		)
		(property "Device Type" "R402H16"
			(at 0.064008 -5.517896 270)
			(unlocked yes)
			(layer "F.Fab")
			(hide yes)
			(effects
				(font
					(size 1.016 1.016)
					(thickness 0.1524)
				)
			)
		)
		(duplicate_pad_numbers_are_jumpers no)
		(fp_line
			(start -0.508 -0.9398)
			(end -0.508 0.9398)
			(stroke
				(width 0.1524)
				(type default)
			)
			(layer "F.SilkS")
		)
		(fp_line
			(start 0.508 -0.9398)
			(end -0.508 -0.9398)
			(stroke
				(width 0.1524)
				(type default)
			)
			(layer "F.SilkS")
		)
		(fp_rect
			(start -0.508 0.9398)
			(end 0.508 -0.9398)
			(stroke
				(width 0)
				(type default)
			)
			(fill no)
			(layer "F.CrtYd")
		)
		(fp_rect
			(start -0.508 0.9398)
			(end 0.508 -0.9398)
			(stroke
				(width 0)
				(type default)
			)
			(fill no)
			(layer "F.Fab")
		)
		(pad "1" smd custom
			(at 0 -0.4445 270)
			(size 0.1397 0.1397)
			(layers "F.Cu" "F.Mask" "F.Paste")
			(net "EEPROM_A2")
			(options
				(clearance outline)
				(anchor circle)
			)
			(primitives
				(gr_poly
					(pts
						(arc
							(start -0.1778 -0.2794)
							(mid -0.249642 -0.249642)
							(end -0.2794 -0.1778)
						)
						(arc
							(start -0.2794 0.1778)
							(mid -0.249642 0.249642)
							(end -0.1778 0.2794)
						)
						(arc
							(start 0.1778 0.2794)
							(mid 0.249642 0.249642)
							(end 0.2794 0.1778)
						)
						(arc
							(start 0.2794 -0.1778)
							(mid 0.249642 -0.249642)
							(end 0.1778 -0.2794)
						)
					)
					(width 0)
					(fill yes)
				)
			)
		)
		(pad "2" smd custom
			(at 0 0.4445 270)
			(size 0.1397 0.1397)
			(layers "F.Cu" "F.Mask" "F.Paste")
			(net "GND")
			(options
				(clearance outline)
				(anchor circle)
			)
			(primitives
				(gr_poly
					(pts
						(arc
							(start -0.1778 -0.2794)
							(mid -0.249642 -0.249642)
							(end -0.2794 -0.1778)
						)
						(arc
							(start -0.2794 0.1778)
							(mid -0.249642 0.249642)
							(end -0.1778 0.2794)
						)
						(arc
							(start 0.1778 0.2794)
							(mid 0.249642 0.249642)
							(end 0.2794 0.1778)
						)
						(arc
							(start 0.2794 -0.1778)
							(mid 0.249642 -0.249642)
							(end 0.1778 -0.2794)
						)
					)
					(width 0)
					(fill yes)
				)
			)
		)
	)
	(footprint ""
		(layer "F.Cu")
		(at 145.8214 -60.5536 -90)
		(property "Reference" "PR175"
			(at 0 0 270)
			(layer "F.SilkS")
			(hide yes)
			(effects
				(font
					(size 1.27 1.27)
				)
			)
		)
		(property "Value" "100KR2F-L1-GP"
			(at 0.064008 -3.993896 270)
			(unlocked yes)
			(layer "F.Fab")
			(hide yes)
			(effects
				(font
					(size 1.016 1.016)
					(thickness 0.1524)
				)
			)
		)
		(property "Device Type" "R402H16"
			(at 0.064008 -5.517896 270)
			(unlocked yes)
			(layer "F.Fab")
			(hide yes)
			(effects
				(font
					(size 1.016 1.016)
					(thickness 0.1524)
				)
			)
		)
		(duplicate_pad_numbers_are_jumpers no)
		(fp_line
			(start -0.508 -0.9398)
			(end -0.508 0.9398)
			(stroke
				(width 0.1524)
				(type default)
			)
			(layer "F.SilkS")
		)
		(fp_line
			(start 0.508 -0.9398)
			(end -0.508 -0.9398)
			(stroke
				(width 0.1524)
				(type default)
			)
			(layer "F.SilkS")
		)
		(fp_rect
			(start -0.508 0.9398)
			(end 0.508 -0.9398)
			(stroke
				(width 0)
				(type default)
			)
			(fill no)
			(layer "F.CrtYd")
		)
		(fp_rect
			(start -0.508 0.9398)
			(end 0.508 -0.9398)
			(stroke
				(width 0)
				(type default)
			)
			(fill no)
			(layer "F.Fab")
		)
		(pad "1" smd custom
			(at 0 -0.4445 270)
			(size 0.1397 0.1397)
			(layers "F.Cu" "F.Mask" "F.Paste")
			(net "P0V9_VREG")
			(options
				(clearance outline)
				(anchor circle)
			)
			(primitives
				(gr_poly
					(pts
						(arc
							(start -0.1778 -0.2794)
							(mid -0.249642 -0.249642)
							(end -0.2794 -0.1778)
						)
						(arc
							(start -0.2794 0.1778)
							(mid -0.249642 0.249642)
							(end -0.1778 0.2794)
						)
						(arc
							(start 0.1778 0.2794)
							(mid 0.249642 0.249642)
							(end 0.2794 0.1778)
						)
						(arc
							(start 0.2794 -0.1778)
							(mid 0.249642 -0.249642)
							(end 0.1778 -0.2794)
						)
					)
					(width 0)
					(fill yes)
				)
			)
		)
		(pad "2" smd custom
			(at 0 0.4445 270)
			(size 0.1397 0.1397)
			(layers "F.Cu" "F.Mask" "F.Paste")
			(net "P0V9_RF")
			(options
				(clearance outline)
				(anchor circle)
			)
			(primitives
				(gr_poly
					(pts
						(arc
							(start -0.1778 -0.2794)
							(mid -0.249642 -0.249642)
							(end -0.2794 -0.1778)
						)
						(arc
							(start -0.2794 0.1778)
							(mid -0.249642 0.249642)
							(end -0.1778 0.2794)
						)
						(arc
							(start 0.1778 0.2794)
							(mid 0.249642 0.249642)
							(end 0.2794 0.1778)
						)
						(arc
							(start 0.2794 -0.1778)
							(mid 0.249642 -0.249642)
							(end 0.1778 -0.2794)
						)
					)
					(width 0)
					(fill yes)
				)
			)
		)
	)
	(footprint ""
		(layer "F.Cu")
		(at 181.61 -19.812 -90)
		(property "Reference" "C410"
			(at 0 0 270)
			(layer "F.SilkS")
			(hide yes)
			(effects
				(font
					(size 1.27 1.27)
				)
			)
		)
		(property "Value" "SCD22U10V2KX-1GP"
			(at 1.1811 -2.7051 270)
			(unlocked yes)
			(layer "F.Fab")
			(hide yes)
			(effects
				(font
					(size 1.016 1.016)
					(thickness 0.1524)
				)
			)
		)
		(property "Device Type" "C402H22"
			(at 1.1811 -4.2291 270)
			(unlocked yes)
			(layer "F.Fab")
			(hide yes)
			(effects
				(font
					(size 1.016 1.016)
					(thickness 0.1524)
				)
			)
		)
		(duplicate_pad_numbers_are_jumpers no)
		(fp_rect
			(start -0.4318 0.9525)
			(end 0.4318 -0.9525)
			(stroke
				(width 0)
				(type default)
			)
			(fill no)
			(layer "F.CrtYd")
		)
		(fp_rect
			(start -0.4318 0.9525)
			(end 0.4318 -0.9525)
			(stroke
				(width 0)
				(type default)
			)
			(fill no)
			(layer "F.Fab")
		)
		(pad "1" smd custom
			(at 0 -0.4445 270)
			(size 0.1524 0.1524)
			(layers "F.Cu" "F.Mask" "F.Paste")
			(net "PCIE_TX_CAP_N95")
			(options
				(clearance outline)
				(anchor circle)
			)
			(primitives
				(gr_poly
					(pts
						(arc
							(start 0.3048 -0.2032)
							(mid 0.275042 -0.275042)
							(end 0.2032 -0.3048)
						)
						(arc
							(start -0.2032 -0.3048)
							(mid -0.275042 -0.275042)
							(end -0.3048 -0.2032)
						)
						(arc
							(start -0.3048 0.2032)
							(mid -0.275042 0.275042)
							(end -0.2032 0.3048)
						)
						(arc
							(start 0.2032 0.3048)
							(mid 0.275042 0.275042)
							(end 0.3048 0.2032)
						)
					)
					(width 0)
					(fill yes)
				)
			)
		)
		(pad "2" smd custom
			(at 0 0.4445 270)
			(size 0.1524 0.1524)
			(layers "F.Cu" "F.Mask" "F.Paste")
			(net "PCIE_TX_N95")
			(options
				(clearance outline)
				(anchor circle)
			)
			(primitives
				(gr_poly
					(pts
						(arc
							(start 0.3048 -0.2032)
							(mid 0.275042 -0.275042)
							(end 0.2032 -0.3048)
						)
						(arc
							(start -0.2032 -0.3048)
							(mid -0.275042 -0.275042)
							(end -0.3048 -0.2032)
						)
						(arc
							(start -0.3048 0.2032)
							(mid -0.275042 0.275042)
							(end -0.2032 0.3048)
						)
						(arc
							(start 0.2032 0.3048)
							(mid 0.275042 0.275042)
							(end 0.3048 0.2032)
						)
					)
					(width 0)
					(fill yes)
				)
			)
		)
	)
	(footprint ""
		(layer "F.Cu")
		(at 211.900008 -4.064)
		(property "Reference" "R678"
			(at 0 0 0)
			(layer "F.SilkS")
			(hide yes)
			(effects
				(font
					(size 1.27 1.27)
				)
			)
		)
		(property "Value" "100KR2F-L1-GP"
			(at 0.064008 -3.993896 0)
			(unlocked yes)
			(layer "F.Fab")
			(hide yes)
			(effects
				(font
					(size 1.016 1.016)
					(thickness 0.1524)
				)
			)
		)
		(property "Device Type" "R402H16"
			(at 0.064008 -5.517896 0)
			(unlocked yes)
			(layer "F.Fab")
			(hide yes)
			(effects
				(font
					(size 1.016 1.016)
					(thickness 0.1524)
				)
			)
		)
		(duplicate_pad_numbers_are_jumpers no)
		(fp_line
			(start -0.508 -0.9398)
			(end -0.508 0.9398)
			(stroke
				(width 0.1524)
				(type default)
			)
			(layer "F.SilkS")
		)
		(fp_line
			(start 0.508 -0.9398)
			(end -0.508 -0.9398)
			(stroke
				(width 0.1524)
				(type default)
			)
			(layer "F.SilkS")
		)
		(fp_rect
			(start -0.508 0.9398)
			(end 0.508 -0.9398)
			(stroke
				(width 0)
				(type default)
			)
			(fill no)
			(layer "F.CrtYd")
		)
		(fp_rect
			(start -0.508 0.9398)
			(end 0.508 -0.9398)
			(stroke
				(width 0)
				(type default)
			)
			(fill no)
			(layer "F.Fab")
		)
		(pad "1" smd custom
			(at 0 -0.4445)
			(size 0.1397 0.1397)
			(layers "F.Cu" "F.Mask" "F.Paste")
			(net "HOST5_RST_N")
			(options
				(clearance outline)
				(anchor circle)
			)
			(primitives
				(gr_poly
					(pts
						(arc
							(start -0.1778 -0.2794)
							(mid -0.249642 -0.249642)
							(end -0.2794 -0.1778)
						)
						(arc
							(start -0.2794 0.1778)
							(mid -0.249642 0.249642)
							(end -0.1778 0.2794)
						)
						(arc
							(start 0.1778 0.2794)
							(mid 0.249642 0.249642)
							(end 0.2794 0.1778)
						)
						(arc
							(start 0.2794 -0.1778)
							(mid 0.249642 -0.249642)
							(end 0.1778 -0.2794)
						)
					)
					(width 0)
					(fill yes)
				)
			)
		)
		(pad "2" smd custom
			(at 0 0.4445)
			(size 0.1397 0.1397)
			(layers "F.Cu" "F.Mask" "F.Paste")
			(net "GND")
			(options
				(clearance outline)
				(anchor circle)
			)
			(primitives
				(gr_poly
					(pts
						(arc
							(start -0.1778 -0.2794)
							(mid -0.249642 -0.249642)
							(end -0.2794 -0.1778)
						)
						(arc
							(start -0.2794 0.1778)
							(mid -0.249642 0.249642)
							(end -0.1778 0.2794)
						)
						(arc
							(start 0.1778 0.2794)
							(mid 0.249642 0.249642)
							(end 0.2794 0.1778)
						)
						(arc
							(start 0.2794 -0.1778)
							(mid 0.249642 -0.249642)
							(end 0.1778 -0.2794)
						)
					)
					(width 0)
					(fill yes)
				)
			)
		)
	)
	(footprint ""
		(layer "F.Cu")
		(at 22.61362 -69.5452 90)
		(property "Reference" "C631"
			(at 0 0 90)
			(layer "F.SilkS")
			(hide yes)
			(effects
				(font
					(size 1.27 1.27)
				)
			)
		)
		(property "Value" "SCD1U16V2KX-3GP"
			(at 1.1811 -2.7051 90)
			(unlocked yes)
			(layer "F.Fab")
			(hide yes)
			(effects
				(font
					(size 1.016 1.016)
					(thickness 0.1524)
				)
			)
		)
		(property "Device Type" "C402H22"
			(at 1.1811 -4.2291 90)
			(unlocked yes)
			(layer "F.Fab")
			(hide yes)
			(effects
				(font
					(size 1.016 1.016)
					(thickness 0.1524)
				)
			)
		)
		(duplicate_pad_numbers_are_jumpers no)
		(fp_rect
			(start -0.4318 0.9525)
			(end 0.4318 -0.9525)
			(stroke
				(width 0)
				(type default)
			)
			(fill no)
			(layer "F.CrtYd")
		)
		(fp_rect
			(start -0.4318 0.9525)
			(end 0.4318 -0.9525)
			(stroke
				(width 0)
				(type default)
			)
			(fill no)
			(layer "F.Fab")
		)
		(pad "1" smd custom
			(at 0 -0.4445 90)
			(size 0.1524 0.1524)
			(layers "F.Cu" "F.Mask" "F.Paste")
			(net "P3V3_STBY")
			(options
				(clearance outline)
				(anchor circle)
			)
			(primitives
				(gr_poly
					(pts
						(arc
							(start 0.3048 -0.2032)
							(mid 0.275042 -0.275042)
							(end 0.2032 -0.3048)
						)
						(arc
							(start -0.2032 -0.3048)
							(mid -0.275042 -0.275042)
							(end -0.3048 -0.2032)
						)
						(arc
							(start -0.3048 0.2032)
							(mid -0.275042 0.275042)
							(end -0.2032 0.3048)
						)
						(arc
							(start 0.2032 0.3048)
							(mid 0.275042 0.275042)
							(end 0.3048 0.2032)
						)
					)
					(width 0)
					(fill yes)
				)
			)
		)
		(pad "2" smd custom
			(at 0 0.4445 90)
			(size 0.1524 0.1524)
			(layers "F.Cu" "F.Mask" "F.Paste")
			(net "GND")
			(options
				(clearance outline)
				(anchor circle)
			)
			(primitives
				(gr_poly
					(pts
						(arc
							(start 0.3048 -0.2032)
							(mid 0.275042 -0.275042)
							(end 0.2032 -0.3048)
						)
						(arc
							(start -0.2032 -0.3048)
							(mid -0.275042 -0.275042)
							(end -0.3048 -0.2032)
						)
						(arc
							(start -0.3048 0.2032)
							(mid -0.275042 0.275042)
							(end -0.2032 0.3048)
						)
						(arc
							(start 0.2032 0.3048)
							(mid 0.275042 0.275042)
							(end 0.3048 0.2032)
						)
					)
					(width 0)
					(fill yes)
				)
			)
		)
	)
	(footprint ""
		(layer "F.Cu")
		(at 265.408156 -212.420454 180)
		(property "Reference" "C106"
			(at 0 0 180)
			(layer "F.SilkS")
			(hide yes)
			(effects
				(font
					(size 1.27 1.27)
				)
			)
		)
		(property "Value" "SCD22U10V2KX-1GP"
			(at 1.1811 -2.7051 180)
			(unlocked yes)
			(layer "F.Fab")
			(hide yes)
			(effects
				(font
					(size 1.016 1.016)
					(thickness 0.1524)
				)
			)
		)
		(property "Device Type" "C402H22"
			(at 1.1811 -4.2291 180)
			(unlocked yes)
			(layer "F.Fab")
			(hide yes)
			(effects
				(font
					(size 1.016 1.016)
					(thickness 0.1524)
				)
			)
		)
		(duplicate_pad_numbers_are_jumpers no)
		(fp_rect
			(start -0.4318 0.9525)
			(end 0.4318 -0.9525)
			(stroke
				(width 0)
				(type default)
			)
			(fill no)
			(layer "F.CrtYd")
		)
		(fp_rect
			(start -0.4318 0.9525)
			(end 0.4318 -0.9525)
			(stroke
				(width 0)
				(type default)
			)
			(fill no)
			(layer "F.Fab")
		)
		(pad "1" smd custom
			(at 0 -0.4445 180)
			(size 0.1524 0.1524)
			(layers "F.Cu" "F.Mask" "F.Paste")
			(net "PCIE_TX_CAP_N37")
			(options
				(clearance outline)
				(anchor circle)
			)
			(primitives
				(gr_poly
					(pts
						(arc
							(start 0.3048 -0.2032)
							(mid 0.275042 -0.275042)
							(end 0.2032 -0.3048)
						)
						(arc
							(start -0.2032 -0.3048)
							(mid -0.275042 -0.275042)
							(end -0.3048 -0.2032)
						)
						(arc
							(start -0.3048 0.2032)
							(mid -0.275042 0.275042)
							(end -0.2032 0.3048)
						)
						(arc
							(start 0.2032 0.3048)
							(mid 0.275042 0.275042)
							(end 0.3048 0.2032)
						)
					)
					(width 0)
					(fill yes)
				)
			)
		)
		(pad "2" smd custom
			(at 0 0.4445 180)
			(size 0.1524 0.1524)
			(layers "F.Cu" "F.Mask" "F.Paste")
			(net "PCIE_TX_N37")
			(options
				(clearance outline)
				(anchor circle)
			)
			(primitives
				(gr_poly
					(pts
						(arc
							(start 0.3048 -0.2032)
							(mid 0.275042 -0.275042)
							(end 0.2032 -0.3048)
						)
						(arc
							(start -0.2032 -0.3048)
							(mid -0.275042 -0.275042)
							(end -0.3048 -0.2032)
						)
						(arc
							(start -0.3048 0.2032)
							(mid -0.275042 0.275042)
							(end -0.2032 0.3048)
						)
						(arc
							(start 0.2032 0.3048)
							(mid 0.275042 0.275042)
							(end 0.3048 0.2032)
						)
					)
					(width 0)
					(fill yes)
				)
			)
		)
	)
	(footprint ""
		(layer "F.Cu")
		(at 303.784 -33.528)
		(property "Reference" "C25"
			(at 0 0 0)
			(layer "F.SilkS")
			(hide yes)
			(effects
				(font
					(size 1.27 1.27)
				)
			)
		)
		(property "Value" "SCD22U10V2KX-1GP"
			(at 1.1811 -2.7051 0)
			(unlocked yes)
			(layer "F.Fab")
			(hide yes)
			(effects
				(font
					(size 1.016 1.016)
					(thickness 0.1524)
				)
			)
		)
		(property "Device Type" "C402H22"
			(at 1.1811 -4.2291 0)
			(unlocked yes)
			(layer "F.Fab")
			(hide yes)
			(effects
				(font
					(size 1.016 1.016)
					(thickness 0.1524)
				)
			)
		)
		(duplicate_pad_numbers_are_jumpers no)
		(fp_rect
			(start -0.4318 0.9525)
			(end 0.4318 -0.9525)
			(stroke
				(width 0)
				(type default)
			)
			(fill no)
			(layer "F.CrtYd")
		)
		(fp_rect
			(start -0.4318 0.9525)
			(end 0.4318 -0.9525)
			(stroke
				(width 0)
				(type default)
			)
			(fill no)
			(layer "F.Fab")
		)
		(pad "1" smd custom
			(at 0 -0.4445)
			(size 0.1524 0.1524)
			(layers "F.Cu" "F.Mask" "F.Paste")
			(net "PCIE_TX_CAP_P7")
			(options
				(clearance outline)
				(anchor circle)
			)
			(primitives
				(gr_poly
					(pts
						(arc
							(start 0.3048 -0.2032)
							(mid 0.275042 -0.275042)
							(end 0.2032 -0.3048)
						)
						(arc
							(start -0.2032 -0.3048)
							(mid -0.275042 -0.275042)
							(end -0.3048 -0.2032)
						)
						(arc
							(start -0.3048 0.2032)
							(mid -0.275042 0.275042)
							(end -0.2032 0.3048)
						)
						(arc
							(start 0.2032 0.3048)
							(mid 0.275042 0.275042)
							(end 0.3048 0.2032)
						)
					)
					(width 0)
					(fill yes)
				)
			)
		)
		(pad "2" smd custom
			(at 0 0.4445)
			(size 0.1524 0.1524)
			(layers "F.Cu" "F.Mask" "F.Paste")
			(net "PCIE_TX_P7")
			(options
				(clearance outline)
				(anchor circle)
			)
			(primitives
				(gr_poly
					(pts
						(arc
							(start 0.3048 -0.2032)
							(mid 0.275042 -0.275042)
							(end 0.2032 -0.3048)
						)
						(arc
							(start -0.2032 -0.3048)
							(mid -0.275042 -0.275042)
							(end -0.3048 -0.2032)
						)
						(arc
							(start -0.3048 0.2032)
							(mid -0.275042 0.275042)
							(end -0.2032 0.3048)
						)
						(arc
							(start 0.2032 0.3048)
							(mid 0.275042 0.275042)
							(end 0.3048 0.2032)
						)
					)
					(width 0)
					(fill yes)
				)
			)
		)
	)
	(footprint ""
		(layer "F.Cu")
		(at 20.9296 -139.8016 -90)
		(property "Reference" "R614"
			(at 0 0 270)
			(layer "F.SilkS")
			(hide yes)
			(effects
				(font
					(size 1.27 1.27)
				)
			)
		)
		(property "Value" "0R2J-2-GP"
			(at 0.064008 -3.993896 270)
			(unlocked yes)
			(layer "F.Fab")
			(hide yes)
			(effects
				(font
					(size 1.016 1.016)
					(thickness 0.1524)
				)
			)
		)
		(property "Device Type" "R402H16"
			(at 0.064008 -5.517896 270)
			(unlocked yes)
			(layer "F.Fab")
			(hide yes)
			(effects
				(font
					(size 1.016 1.016)
					(thickness 0.1524)
				)
			)
		)
		(duplicate_pad_numbers_are_jumpers no)
		(fp_line
			(start -0.508 -0.9398)
			(end -0.508 0.9398)
			(stroke
				(width 0.1524)
				(type default)
			)
			(layer "F.SilkS")
		)
		(fp_line
			(start 0.508 -0.9398)
			(end -0.508 -0.9398)
			(stroke
				(width 0.1524)
				(type default)
			)
			(layer "F.SilkS")
		)
		(fp_rect
			(start -0.508 0.9398)
			(end 0.508 -0.9398)
			(stroke
				(width 0)
				(type default)
			)
			(fill no)
			(layer "F.CrtYd")
		)
		(fp_rect
			(start -0.508 0.9398)
			(end 0.508 -0.9398)
			(stroke
				(width 0)
				(type default)
			)
			(fill no)
			(layer "F.Fab")
		)
		(pad "1" smd custom
			(at 0 -0.4445 270)
			(size 0.1397 0.1397)
			(layers "F.Cu" "F.Mask" "F.Paste")
			(net "BMC_SELF_HW_RST_R")
			(options
				(clearance outline)
				(anchor circle)
			)
			(primitives
				(gr_poly
					(pts
						(arc
							(start -0.1778 -0.2794)
							(mid -0.249642 -0.249642)
							(end -0.2794 -0.1778)
						)
						(arc
							(start -0.2794 0.1778)
							(mid -0.249642 0.249642)
							(end -0.1778 0.2794)
						)
						(arc
							(start 0.1778 0.2794)
							(mid 0.249642 0.249642)
							(end 0.2794 0.1778)
						)
						(arc
							(start 0.2794 -0.1778)
							(mid 0.249642 -0.249642)
							(end 0.1778 -0.2794)
						)
					)
					(width 0)
					(fill yes)
				)
			)
		)
		(pad "2" smd custom
			(at 0 0.4445 270)
			(size 0.1397 0.1397)
			(layers "F.Cu" "F.Mask" "F.Paste")
			(net "BMC_SELF_HW_RST")
			(options
				(clearance outline)
				(anchor circle)
			)
			(primitives
				(gr_poly
					(pts
						(arc
							(start -0.1778 -0.2794)
							(mid -0.249642 -0.249642)
							(end -0.2794 -0.1778)
						)
						(arc
							(start -0.2794 0.1778)
							(mid -0.249642 0.249642)
							(end -0.1778 0.2794)
						)
						(arc
							(start 0.1778 0.2794)
							(mid 0.249642 0.249642)
							(end 0.2794 0.1778)
						)
						(arc
							(start 0.2794 -0.1778)
							(mid 0.249642 -0.249642)
							(end 0.1778 -0.2794)
						)
					)
					(width 0)
					(fill yes)
				)
			)
		)
	)
	(footprint ""
		(layer "F.Cu")
		(at 51.37404 -73.483724 -90)
		(property "Reference" "R941"
			(at 0 0 270)
			(layer "F.SilkS")
			(hide yes)
			(effects
				(font
					(size 1.27 1.27)
				)
			)
		)
		(property "Value" "0R2J-2-GP"
			(at 0.064008 -3.99415 270)
			(unlocked yes)
			(layer "F.Fab")
			(hide yes)
			(effects
				(font
					(size 1.016 1.016)
					(thickness 0.1524)
				)
			)
		)
		(property "Device Type" "R402H16"
			(at 0.064008 -5.51815 270)
			(unlocked yes)
			(layer "F.Fab")
			(hide yes)
			(effects
				(font
					(size 1.016 1.016)
					(thickness 0.1524)
				)
			)
		)
		(duplicate_pad_numbers_are_jumpers no)
		(fp_line
			(start -0.508254 -0.940054)
			(end -0.508 0.939546)
			(stroke
				(width 0.1524)
				(type default)
			)
			(layer "F.SilkS")
		)
		(fp_line
			(start 0.508 -0.940054)
			(end -0.508254 -0.940054)
			(stroke
				(width 0.1524)
				(type default)
			)
			(layer "F.SilkS")
		)
		(fp_rect
			(start -0.508 0.939546)
			(end 0.508 -0.940054)
			(stroke
				(width 0)
				(type default)
			)
			(fill no)
			(layer "F.CrtYd")
		)
		(fp_rect
			(start -0.508 0.939546)
			(end 0.508 -0.940054)
			(stroke
				(width 0)
				(type default)
			)
			(fill no)
			(layer "F.Fab")
		)
		(pad "1" smd custom
			(at 0 -0.4445 270)
			(size 0.1397 0.1397)
			(layers "F.Cu" "F.Mask" "F.Paste")
			(net "BMC_R_RXD5")
			(options
				(clearance outline)
				(anchor circle)
			)
			(primitives
				(gr_poly
					(pts
						(arc
							(start -0.1778 -0.2794)
							(mid -0.249642 -0.249642)
							(end -0.2794 -0.1778)
						)
						(arc
							(start -0.2794 0.1778)
							(mid -0.249642 0.249642)
							(end -0.1778 0.2794)
						)
						(arc
							(start 0.1778 0.2794)
							(mid 0.249642 0.249642)
							(end 0.2794 0.1778)
						)
						(arc
							(start 0.2794 -0.1778)
							(mid 0.249642 -0.249642)
							(end 0.1778 -0.2794)
						)
					)
					(width 0)
					(fill yes)
				)
			)
		)
		(pad "2" smd custom
			(at 0 0.4445 270)
			(size 0.1397 0.1397)
			(layers "F.Cu" "F.Mask" "F.Paste")
			(net "BMC_RXD5")
			(options
				(clearance outline)
				(anchor circle)
			)
			(primitives
				(gr_poly
					(pts
						(arc
							(start -0.1778 -0.2794)
							(mid -0.249642 -0.249642)
							(end -0.2794 -0.1778)
						)
						(arc
							(start -0.2794 0.1778)
							(mid -0.249642 0.249642)
							(end -0.1778 0.2794)
						)
						(arc
							(start 0.1778 0.2794)
							(mid 0.249642 0.249642)
							(end 0.2794 0.1778)
						)
						(arc
							(start 0.2794 -0.1778)
							(mid 0.249642 -0.249642)
							(end 0.1778 -0.2794)
						)
					)
					(width 0)
					(fill yes)
				)
			)
		)
	)
	(footprint ""
		(layer "F.Cu")
		(at 171.408598 -70.787768 180)
		(property "Reference" "PTC10"
			(at 0 0 180)
			(layer "F.SilkS")
			(hide yes)
			(effects
				(font
					(size 1.27 1.27)
				)
			)
		)
		(property "Value" "SE470UF2VDM-GP"
			(at 0 -9.6012 180)
			(unlocked yes)
			(layer "F.Fab")
			(hide yes)
			(effects
				(font
					(size 1.016 1.016)
					(thickness 0.1524)
				)
			)
		)
		(property "Device Type" "CT7343H83"
			(at 0 -11.1252 180)
			(unlocked yes)
			(layer "F.Fab")
			(hide yes)
			(effects
				(font
					(size 1.016 1.016)
					(thickness 0.1524)
				)
			)
		)
		(duplicate_pad_numbers_are_jumpers no)
		(fp_line
			(start 2.286 4.8768)
			(end -2.286 4.8768)
			(stroke
				(width 0.1524)
				(type default)
			)
			(layer "F.SilkS")
		)
		(fp_line
			(start 2.286 2.032)
			(end 2.286 4.8768)
			(stroke
				(width 0.1524)
				(type default)
			)
			(layer "F.SilkS")
		)
		(fp_line
			(start 2.286 -2.032)
			(end 2.286 -4.8768)
			(stroke
				(width 0.1524)
				(type default)
			)
			(layer "F.SilkS")
		)
		(fp_line
			(start 2.286 -4.8768)
			(end -2.286 -4.8768)
			(stroke
				(width 0.1524)
				(type default)
			)
			(layer "F.SilkS")
		)
		(fp_line
			(start 2.1082 -4.699)
			(end -2.1082 -4.699)
			(stroke
				(width 0.508)
				(type default)
			)
			(layer "F.SilkS")
		)
		(fp_line
			(start -2.286 4.8768)
			(end -2.286 2.032)
			(stroke
				(width 0.1524)
				(type default)
			)
			(layer "F.SilkS")
		)
		(fp_line
			(start -2.286 -4.8768)
			(end -2.286 -2.032)
			(stroke
				(width 0.1524)
				(type default)
			)
			(layer "F.SilkS")
		)
		(fp_rect
			(start -2.1463 3.6449)
			(end 2.1463 -3.6449)
			(stroke
				(width 0)
				(type default)
			)
			(fill no)
			(layer "F.CrtYd")
		)
		(fp_poly
			(pts
				(xy -2.54 4.953) (xy -2.54 4.2926) (xy -3.81 4.2926) (xy -3.81 -4.2926) (xy -2.54 -4.2926) (xy -2.54 -4.953)
				(xy 2.54 -4.953) (xy 2.54 -4.2926) (xy 3.81 -4.2926) (xy 3.81 -1.6256) (xy 2.1463 -1.6256) (xy 2.1463 -3.6449)
				(xy -2.1463 -3.6449) (xy -2.1463 3.6449) (xy 2.1463 3.6449) (xy 2.1463 -1.6129) (xy 3.81 -1.6129)
				(xy 3.81 4.2926) (xy 2.54 4.2926) (xy 2.54 4.953)
			)
			(stroke
				(width 0)
				(type default)
			)
			(fill no)
			(layer "F.CrtYd")
		)
		(fp_rect
			(start 2.54 4.2926)
			(end 3.81 -4.2926)
			(stroke
				(width 0)
				(type default)
			)
			(fill no)
			(layer "F.Fab")
		)
		(fp_rect
			(start -2.54 4.953)
			(end 2.54 -4.953)
			(stroke
				(width 0)
				(type default)
			)
			(fill no)
			(layer "F.Fab")
		)
		(fp_rect
			(start -3.81 4.2926)
			(end -2.54 -4.2926)
			(stroke
				(width 0)
				(type default)
			)
			(fill no)
			(layer "F.Fab")
		)
		(pad "1" smd rect
			(at 0 -3.1496 180)
			(size 2.413 2.286)
			(layers "F.Cu" "F.Mask" "F.Paste")
			(net "P0V9")
		)
		(pad "2" smd rect
			(at 0 3.1496 180)
			(size 2.413 2.286)
			(layers "F.Cu" "F.Mask" "F.Paste")
			(net "GND")
		)
		(zone
			(layer "F.Cu")
			(hatch none 0.5)
			(connect_pads
				(clearance 0)
			)
			(min_thickness 0.25)
			(keepout
				(tracks allowed)
				(vias not_allowed)
				(pads allowed)
				(copperpour not_allowed)
				(footprints allowed)
			)
			(placement
				(enabled no)
				(sheetname "")
			)
			(fill
				(thermal_gap 0.5)
				(thermal_bridge_width 0.5)
				(island_removal_mode 0)
			)
			(polygon
				(pts
					(xy 169.897298 -69.098668) (xy 169.897298 -66.190368) (xy 172.919898 -66.190368) (xy 172.919898 -69.085968)
					(xy 172.919898 -69.416168) (xy 169.897298 -69.416168)
				)
			)
		)
		(zone
			(layer "F.Cu")
			(hatch none 0.5)
			(connect_pads
				(clearance 0)
			)
			(min_thickness 0.25)
			(keepout
				(tracks allowed)
				(vias not_allowed)
				(pads allowed)
				(copperpour not_allowed)
				(footprints allowed)
			)
			(placement
				(enabled no)
				(sheetname "")
			)
			(fill
				(thermal_gap 0.5)
				(thermal_bridge_width 0.5)
				(island_removal_mode 0)
			)
			(polygon
				(pts
					(xy 172.919898 -75.385168) (xy 169.897298 -75.385168) (xy 169.897298 -72.489568) (xy 169.897298 -72.159368)
					(xy 172.919898 -72.159368) (xy 172.919898 -72.489568)
				)
			)
		)
	)
	(footprint ""
		(layer "F.Cu")
		(at 70.1802 -162.2806 -90)
		(property "Reference" "PR43"
			(at 0 0 270)
			(layer "F.SilkS")
			(hide yes)
			(effects
				(font
					(size 1.27 1.27)
				)
			)
		)
		(property "Value" "10KR2F-2-GP"
			(at 0.064008 -3.993896 270)
			(unlocked yes)
			(layer "F.Fab")
			(hide yes)
			(effects
				(font
					(size 1.016 1.016)
					(thickness 0.1524)
				)
			)
		)
		(property "Device Type" "R402H16"
			(at 0.064008 -5.517896 270)
			(unlocked yes)
			(layer "F.Fab")
			(hide yes)
			(effects
				(font
					(size 1.016 1.016)
					(thickness 0.1524)
				)
			)
		)
		(duplicate_pad_numbers_are_jumpers no)
		(fp_line
			(start -0.508 -0.9398)
			(end -0.508 0.9398)
			(stroke
				(width 0.1524)
				(type default)
			)
			(layer "F.SilkS")
		)
		(fp_line
			(start 0.508 -0.9398)
			(end -0.508 -0.9398)
			(stroke
				(width 0.1524)
				(type default)
			)
			(layer "F.SilkS")
		)
		(fp_rect
			(start -0.508 0.9398)
			(end 0.508 -0.9398)
			(stroke
				(width 0)
				(type default)
			)
			(fill no)
			(layer "F.CrtYd")
		)
		(fp_rect
			(start -0.508 0.9398)
			(end 0.508 -0.9398)
			(stroke
				(width 0)
				(type default)
			)
			(fill no)
			(layer "F.Fab")
		)
		(pad "1" smd custom
			(at 0 -0.4445 270)
			(size 0.1397 0.1397)
			(layers "F.Cu" "F.Mask" "F.Paste")
			(net "P3V3_STBY")
			(options
				(clearance outline)
				(anchor circle)
			)
			(primitives
				(gr_poly
					(pts
						(arc
							(start -0.1778 -0.2794)
							(mid -0.249642 -0.249642)
							(end -0.2794 -0.1778)
						)
						(arc
							(start -0.2794 0.1778)
							(mid -0.249642 0.249642)
							(end -0.1778 0.2794)
						)
						(arc
							(start 0.1778 0.2794)
							(mid 0.249642 0.249642)
							(end 0.2794 0.1778)
						)
						(arc
							(start 0.2794 -0.1778)
							(mid 0.249642 -0.249642)
							(end 0.1778 -0.2794)
						)
					)
					(width 0)
					(fill yes)
				)
			)
		)
		(pad "2" smd custom
			(at 0 0.4445 270)
			(size 0.1397 0.1397)
			(layers "F.Cu" "F.Mask" "F.Paste")
			(net "PWRGD_P1V538_STBY")
			(options
				(clearance outline)
				(anchor circle)
			)
			(primitives
				(gr_poly
					(pts
						(arc
							(start -0.1778 -0.2794)
							(mid -0.249642 -0.249642)
							(end -0.2794 -0.1778)
						)
						(arc
							(start -0.2794 0.1778)
							(mid -0.249642 0.249642)
							(end -0.1778 0.2794)
						)
						(arc
							(start 0.1778 0.2794)
							(mid 0.249642 0.249642)
							(end 0.2794 0.1778)
						)
						(arc
							(start 0.2794 -0.1778)
							(mid 0.249642 -0.249642)
							(end 0.1778 -0.2794)
						)
					)
					(width 0)
					(fill yes)
				)
			)
		)
	)
	(footprint ""
		(layer "F.Cu")
		(at 20.267168 -95.233998 180)
		(property "Reference" "Q20"
			(at 0 0 180)
			(layer "F.SilkS")
			(hide yes)
			(effects
				(font
					(size 1.27 1.27)
				)
			)
		)
		(property "Value" "2N7002-7F-GP"
			(at 0.127 -8.9662 180)
			(unlocked yes)
			(layer "F.Fab")
			(hide yes)
			(effects
				(font
					(size 1.016 1.016)
					(thickness 0.1524)
				)
			)
		)
		(property "Device Type" "SOT23DGS2D4H44"
			(at 0.127 -10.4902 180)
			(unlocked yes)
			(layer "F.Fab")
			(hide yes)
			(effects
				(font
					(size 1.016 1.016)
					(thickness 0.1524)
				)
			)
		)
		(duplicate_pad_numbers_are_jumpers no)
		(fp_line
			(start 1.651 1.778)
			(end 1.651 -1.778)
			(stroke
				(width 0.1524)
				(type default)
			)
			(layer "F.SilkS")
		)
		(fp_line
			(start 1.651 -1.778)
			(end -1.651 -1.778)
			(stroke
				(width 0.1524)
				(type default)
			)
			(layer "F.SilkS")
		)
		(fp_line
			(start -1.651 1.778)
			(end 1.651 1.778)
			(stroke
				(width 0.1524)
				(type default)
			)
			(layer "F.SilkS")
		)
		(fp_line
			(start -1.651 -1.778)
			(end -1.651 1.778)
			(stroke
				(width 0.1524)
				(type default)
			)
			(layer "F.SilkS")
		)
		(fp_poly
			(pts
				(xy -1.778 1.8796) (xy -1.778 -1.8796) (xy 1.778 -1.8796) (xy 1.778 1.8796)
			)
			(stroke
				(width 0)
				(type default)
			)
			(fill no)
			(layer "F.CrtYd")
		)
		(fp_poly
			(pts
				(xy -1.778 1.8796) (xy -1.778 -1.8796) (xy 1.778 -1.8796) (xy 1.778 1.8796)
			)
			(stroke
				(width 0)
				(type default)
			)
			(fill no)
			(layer "F.Fab")
		)
		(pad "D" smd custom
			(at 0 -0.9525 180)
			(size 0.1905 0.1905)
			(layers "F.Cu" "F.Mask" "F.Paste")
			(net "FM_TPM_PRES_RST_N")
			(options
				(clearance outline)
				(anchor circle)
			)
			(primitives
				(gr_poly
					(pts
						(arc
							(start -0.1778 0.5715)
							(mid -0.321484 0.511984)
							(end -0.381 0.3683)
						)
						(arc
							(start -0.381 -0.3683)
							(mid -0.321484 -0.511984)
							(end -0.1778 -0.5715)
						)
						(arc
							(start 0.1778 -0.5715)
							(mid 0.321484 -0.511984)
							(end 0.381 -0.3683)
						)
						(arc
							(start 0.381 0.3683)
							(mid 0.321484 0.511984)
							(end 0.1778 0.5715)
						)
					)
					(width 0)
					(fill yes)
				)
			)
		)
		(pad "G" smd custom
			(at -0.98425 0.9525 180)
			(size 0.1905 0.1905)
			(layers "F.Cu" "F.Mask" "F.Paste")
			(net "Q20_G")
			(options
				(clearance outline)
				(anchor circle)
			)
			(primitives
				(gr_poly
					(pts
						(arc
							(start -0.1778 0.5715)
							(mid -0.321484 0.511984)
							(end -0.381 0.3683)
						)
						(arc
							(start -0.381 -0.3683)
							(mid -0.321484 -0.511984)
							(end -0.1778 -0.5715)
						)
						(arc
							(start 0.1778 -0.5715)
							(mid 0.321484 -0.511984)
							(end 0.381 -0.3683)
						)
						(arc
							(start 0.381 0.3683)
							(mid 0.321484 0.511984)
							(end 0.1778 0.5715)
						)
					)
					(width 0)
					(fill yes)
				)
			)
		)
		(pad "S" smd custom
			(at 0.98425 0.9525 180)
			(size 0.1905 0.1905)
			(layers "F.Cu" "F.Mask" "F.Paste")
			(net "GND")
			(options
				(clearance outline)
				(anchor circle)
			)
			(primitives
				(gr_poly
					(pts
						(arc
							(start -0.1778 0.5715)
							(mid -0.321484 0.511984)
							(end -0.381 0.3683)
						)
						(arc
							(start -0.381 -0.3683)
							(mid -0.321484 -0.511984)
							(end -0.1778 -0.5715)
						)
						(arc
							(start 0.1778 -0.5715)
							(mid 0.321484 -0.511984)
							(end 0.381 -0.3683)
						)
						(arc
							(start 0.381 0.3683)
							(mid 0.321484 0.511984)
							(end 0.1778 0.5715)
						)
					)
					(width 0)
					(fill yes)
				)
			)
		)
	)
	(footprint ""
		(layer "F.Cu")
		(at 188.1124 -5.1562 -90)
		(property "Reference" "C269"
			(at 0 0 270)
			(layer "F.SilkS")
			(hide yes)
			(effects
				(font
					(size 1.27 1.27)
				)
			)
		)
		(property "Value" "SCD1U16V2KX-3GP"
			(at 1.1811 -2.7051 270)
			(unlocked yes)
			(layer "F.Fab")
			(hide yes)
			(effects
				(font
					(size 1.016 1.016)
					(thickness 0.1524)
				)
			)
		)
		(property "Device Type" "C402H22"
			(at 1.1811 -4.2291 270)
			(unlocked yes)
			(layer "F.Fab")
			(hide yes)
			(effects
				(font
					(size 1.016 1.016)
					(thickness 0.1524)
				)
			)
		)
		(duplicate_pad_numbers_are_jumpers no)
		(fp_rect
			(start -0.4318 0.9525)
			(end 0.4318 -0.9525)
			(stroke
				(width 0)
				(type default)
			)
			(fill no)
			(layer "F.CrtYd")
		)
		(fp_rect
			(start -0.4318 0.9525)
			(end 0.4318 -0.9525)
			(stroke
				(width 0)
				(type default)
			)
			(fill no)
			(layer "F.Fab")
		)
		(pad "1" smd custom
			(at 0 -0.4445 270)
			(size 0.1524 0.1524)
			(layers "F.Cu" "F.Mask" "F.Paste")
			(net "P3V3_STBY")
			(options
				(clearance outline)
				(anchor circle)
			)
			(primitives
				(gr_poly
					(pts
						(arc
							(start 0.3048 -0.2032)
							(mid 0.275042 -0.275042)
							(end 0.2032 -0.3048)
						)
						(arc
							(start -0.2032 -0.3048)
							(mid -0.275042 -0.275042)
							(end -0.3048 -0.2032)
						)
						(arc
							(start -0.3048 0.2032)
							(mid -0.275042 0.275042)
							(end -0.2032 0.3048)
						)
						(arc
							(start 0.2032 0.3048)
							(mid 0.275042 0.275042)
							(end 0.3048 0.2032)
						)
					)
					(width 0)
					(fill yes)
				)
			)
		)
		(pad "2" smd custom
			(at 0 0.4445 270)
			(size 0.1524 0.1524)
			(layers "F.Cu" "F.Mask" "F.Paste")
			(net "GND")
			(options
				(clearance outline)
				(anchor circle)
			)
			(primitives
				(gr_poly
					(pts
						(arc
							(start 0.3048 -0.2032)
							(mid 0.275042 -0.275042)
							(end 0.2032 -0.3048)
						)
						(arc
							(start -0.2032 -0.3048)
							(mid -0.275042 -0.275042)
							(end -0.3048 -0.2032)
						)
						(arc
							(start -0.3048 0.2032)
							(mid -0.275042 0.275042)
							(end -0.2032 0.3048)
						)
						(arc
							(start 0.2032 0.3048)
							(mid 0.275042 0.275042)
							(end 0.3048 0.2032)
						)
					)
					(width 0)
					(fill yes)
				)
			)
		)
	)
	(footprint ""
		(layer "F.Cu")
		(at 17.63268 -135.085074 90)
		(property "Reference" "R342"
			(at 0 0 90)
			(layer "F.SilkS")
			(hide yes)
			(effects
				(font
					(size 1.27 1.27)
				)
			)
		)
		(property "Value" "3K3R2F-2-GP"
			(at 0.064008 -3.993896 90)
			(unlocked yes)
			(layer "F.Fab")
			(hide yes)
			(effects
				(font
					(size 1.016 1.016)
					(thickness 0.1524)
				)
			)
		)
		(property "Device Type" "R402H16"
			(at 0.064008 -5.517896 90)
			(unlocked yes)
			(layer "F.Fab")
			(hide yes)
			(effects
				(font
					(size 1.016 1.016)
					(thickness 0.1524)
				)
			)
		)
		(duplicate_pad_numbers_are_jumpers no)
		(fp_line
			(start 0.508 -0.9398)
			(end -0.508 -0.9398)
			(stroke
				(width 0.1524)
				(type default)
			)
			(layer "F.SilkS")
		)
		(fp_line
			(start -0.508 -0.9398)
			(end -0.508 0.9398)
			(stroke
				(width 0.1524)
				(type default)
			)
			(layer "F.SilkS")
		)
		(fp_rect
			(start -0.508 0.9398)
			(end 0.508 -0.9398)
			(stroke
				(width 0)
				(type default)
			)
			(fill no)
			(layer "F.CrtYd")
		)
		(fp_rect
			(start -0.508 0.9398)
			(end 0.508 -0.9398)
			(stroke
				(width 0)
				(type default)
			)
			(fill no)
			(layer "F.Fab")
		)
		(pad "1" smd custom
			(at 0 -0.4445 90)
			(size 0.1397 0.1397)
			(layers "F.Cu" "F.Mask" "F.Paste")
			(net "P3V3_STBY")
			(options
				(clearance outline)
				(anchor circle)
			)
			(primitives
				(gr_poly
					(pts
						(arc
							(start -0.1778 -0.2794)
							(mid -0.249642 -0.249642)
							(end -0.2794 -0.1778)
						)
						(arc
							(start -0.2794 0.1778)
							(mid -0.249642 0.249642)
							(end -0.1778 0.2794)
						)
						(arc
							(start 0.1778 0.2794)
							(mid 0.249642 0.249642)
							(end 0.2794 0.1778)
						)
						(arc
							(start 0.2794 -0.1778)
							(mid 0.249642 -0.249642)
							(end 0.1778 -0.2794)
						)
					)
					(width 0)
					(fill yes)
				)
			)
		)
		(pad "2" smd custom
			(at 0 0.4445 90)
			(size 0.1397 0.1397)
			(layers "F.Cu" "F.Mask" "F.Paste")
			(net "ROMD0_R")
			(options
				(clearance outline)
				(anchor circle)
			)
			(primitives
				(gr_poly
					(pts
						(arc
							(start -0.1778 -0.2794)
							(mid -0.249642 -0.249642)
							(end -0.2794 -0.1778)
						)
						(arc
							(start -0.2794 0.1778)
							(mid -0.249642 0.249642)
							(end -0.1778 0.2794)
						)
						(arc
							(start 0.1778 0.2794)
							(mid 0.249642 0.249642)
							(end 0.2794 0.1778)
						)
						(arc
							(start 0.2794 -0.1778)
							(mid 0.249642 -0.249642)
							(end 0.1778 -0.2794)
						)
					)
					(width 0)
					(fill yes)
				)
			)
		)
	)
	(footprint ""
		(layer "F.Cu")
		(at 60.452 -35.433 -90)
		(property "Reference" "PR29"
			(at 0 0 270)
			(layer "F.SilkS")
			(hide yes)
			(effects
				(font
					(size 1.27 1.27)
				)
			)
		)
		(property "Value" "475KR2F-GP"
			(at 0.064008 -3.993896 270)
			(unlocked yes)
			(layer "F.Fab")
			(hide yes)
			(effects
				(font
					(size 1.016 1.016)
					(thickness 0.1524)
				)
			)
		)
		(property "Device Type" "R402H16"
			(at 0.064008 -5.517896 270)
			(unlocked yes)
			(layer "F.Fab")
			(hide yes)
			(effects
				(font
					(size 1.016 1.016)
					(thickness 0.1524)
				)
			)
		)
		(duplicate_pad_numbers_are_jumpers no)
		(fp_line
			(start -0.508 -0.9398)
			(end -0.508 0.9398)
			(stroke
				(width 0.1524)
				(type default)
			)
			(layer "F.SilkS")
		)
		(fp_line
			(start 0.508 -0.9398)
			(end -0.508 -0.9398)
			(stroke
				(width 0.1524)
				(type default)
			)
			(layer "F.SilkS")
		)
		(fp_rect
			(start -0.508 0.9398)
			(end 0.508 -0.9398)
			(stroke
				(width 0)
				(type default)
			)
			(fill no)
			(layer "F.CrtYd")
		)
		(fp_rect
			(start -0.508 0.9398)
			(end 0.508 -0.9398)
			(stroke
				(width 0)
				(type default)
			)
			(fill no)
			(layer "F.Fab")
		)
		(pad "1" smd custom
			(at 0 -0.4445 270)
			(size 0.1397 0.1397)
			(layers "F.Cu" "F.Mask" "F.Paste")
			(net "P3V3_STBY_MODE")
			(options
				(clearance outline)
				(anchor circle)
			)
			(primitives
				(gr_poly
					(pts
						(arc
							(start -0.1778 -0.2794)
							(mid -0.249642 -0.249642)
							(end -0.2794 -0.1778)
						)
						(arc
							(start -0.2794 0.1778)
							(mid -0.249642 0.249642)
							(end -0.1778 0.2794)
						)
						(arc
							(start 0.1778 0.2794)
							(mid 0.249642 0.249642)
							(end 0.2794 0.1778)
						)
						(arc
							(start 0.2794 -0.1778)
							(mid 0.249642 -0.249642)
							(end 0.1778 -0.2794)
						)
					)
					(width 0)
					(fill yes)
				)
			)
		)
		(pad "2" smd custom
			(at 0 0.4445 270)
			(size 0.1397 0.1397)
			(layers "F.Cu" "F.Mask" "F.Paste")
			(net "P3V3_STBY_PG")
			(options
				(clearance outline)
				(anchor circle)
			)
			(primitives
				(gr_poly
					(pts
						(arc
							(start -0.1778 -0.2794)
							(mid -0.249642 -0.249642)
							(end -0.2794 -0.1778)
						)
						(arc
							(start -0.2794 0.1778)
							(mid -0.249642 0.249642)
							(end -0.1778 0.2794)
						)
						(arc
							(start 0.1778 0.2794)
							(mid 0.249642 0.249642)
							(end 0.2794 0.1778)
						)
						(arc
							(start 0.2794 -0.1778)
							(mid 0.249642 -0.249642)
							(end 0.1778 -0.2794)
						)
					)
					(width 0)
					(fill yes)
				)
			)
		)
	)
	(footprint ""
		(layer "F.Cu")
		(at 155.408122 -212.420454 180)
		(property "Reference" "C251"
			(at 0 0 180)
			(layer "F.SilkS")
			(hide yes)
			(effects
				(font
					(size 1.27 1.27)
				)
			)
		)
		(property "Value" "SCD22U10V2KX-1GP"
			(at 1.1811 -2.7051 180)
			(unlocked yes)
			(layer "F.Fab")
			(hide yes)
			(effects
				(font
					(size 1.016 1.016)
					(thickness 0.1524)
				)
			)
		)
		(property "Device Type" "C402H22"
			(at 1.1811 -4.2291 180)
			(unlocked yes)
			(layer "F.Fab")
			(hide yes)
			(effects
				(font
					(size 1.016 1.016)
					(thickness 0.1524)
				)
			)
		)
		(duplicate_pad_numbers_are_jumpers no)
		(fp_rect
			(start -0.4318 0.9525)
			(end 0.4318 -0.9525)
			(stroke
				(width 0)
				(type default)
			)
			(fill no)
			(layer "F.CrtYd")
		)
		(fp_rect
			(start -0.4318 0.9525)
			(end 0.4318 -0.9525)
			(stroke
				(width 0)
				(type default)
			)
			(fill no)
			(layer "F.Fab")
		)
		(pad "1" smd custom
			(at 0 -0.4445 180)
			(size 0.1524 0.1524)
			(layers "F.Cu" "F.Mask" "F.Paste")
			(net "PCIE_TX_CAP_N54")
			(options
				(clearance outline)
				(anchor circle)
			)
			(primitives
				(gr_poly
					(pts
						(arc
							(start 0.3048 -0.2032)
							(mid 0.275042 -0.275042)
							(end 0.2032 -0.3048)
						)
						(arc
							(start -0.2032 -0.3048)
							(mid -0.275042 -0.275042)
							(end -0.3048 -0.2032)
						)
						(arc
							(start -0.3048 0.2032)
							(mid -0.275042 0.275042)
							(end -0.2032 0.3048)
						)
						(arc
							(start 0.2032 0.3048)
							(mid 0.275042 0.275042)
							(end 0.3048 0.2032)
						)
					)
					(width 0)
					(fill yes)
				)
			)
		)
		(pad "2" smd custom
			(at 0 0.4445 180)
			(size 0.1524 0.1524)
			(layers "F.Cu" "F.Mask" "F.Paste")
			(net "PCIE_TX_N54")
			(options
				(clearance outline)
				(anchor circle)
			)
			(primitives
				(gr_poly
					(pts
						(arc
							(start 0.3048 -0.2032)
							(mid 0.275042 -0.275042)
							(end 0.2032 -0.3048)
						)
						(arc
							(start -0.2032 -0.3048)
							(mid -0.275042 -0.275042)
							(end -0.3048 -0.2032)
						)
						(arc
							(start -0.3048 0.2032)
							(mid -0.275042 0.275042)
							(end -0.2032 0.3048)
						)
						(arc
							(start 0.2032 0.3048)
							(mid 0.275042 0.275042)
							(end 0.3048 0.2032)
						)
					)
					(width 0)
					(fill yes)
				)
			)
		)
	)
	(footprint ""
		(layer "F.Cu")
		(at 20.955 -137.7442 -90)
		(property "Reference" "R640"
			(at 0 0 270)
			(layer "F.SilkS")
			(hide yes)
			(effects
				(font
					(size 1.27 1.27)
				)
			)
		)
		(property "Value" "0R2J-2-GP"
			(at 0.064008 -3.993896 270)
			(unlocked yes)
			(layer "F.Fab")
			(hide yes)
			(effects
				(font
					(size 1.016 1.016)
					(thickness 0.1524)
				)
			)
		)
		(property "Device Type" "R402H16"
			(at 0.064008 -5.517896 270)
			(unlocked yes)
			(layer "F.Fab")
			(hide yes)
			(effects
				(font
					(size 1.016 1.016)
					(thickness 0.1524)
				)
			)
		)
		(duplicate_pad_numbers_are_jumpers no)
		(fp_line
			(start -0.508 -0.9398)
			(end -0.508 0.9398)
			(stroke
				(width 0.1524)
				(type default)
			)
			(layer "F.SilkS")
		)
		(fp_line
			(start 0.508 -0.9398)
			(end -0.508 -0.9398)
			(stroke
				(width 0.1524)
				(type default)
			)
			(layer "F.SilkS")
		)
		(fp_rect
			(start -0.508 0.9398)
			(end 0.508 -0.9398)
			(stroke
				(width 0)
				(type default)
			)
			(fill no)
			(layer "F.CrtYd")
		)
		(fp_rect
			(start -0.508 0.9398)
			(end 0.508 -0.9398)
			(stroke
				(width 0)
				(type default)
			)
			(fill no)
			(layer "F.Fab")
		)
		(pad "1" smd custom
			(at 0 -0.4445 270)
			(size 0.1397 0.1397)
			(layers "F.Cu" "F.Mask" "F.Paste")
			(net "GPIOR1_R")
			(options
				(clearance outline)
				(anchor circle)
			)
			(primitives
				(gr_poly
					(pts
						(arc
							(start -0.1778 -0.2794)
							(mid -0.249642 -0.249642)
							(end -0.2794 -0.1778)
						)
						(arc
							(start -0.2794 0.1778)
							(mid -0.249642 0.249642)
							(end -0.1778 0.2794)
						)
						(arc
							(start 0.1778 0.2794)
							(mid 0.249642 0.249642)
							(end 0.2794 0.1778)
						)
						(arc
							(start 0.2794 -0.1778)
							(mid 0.249642 -0.249642)
							(end 0.1778 -0.2794)
						)
					)
					(width 0)
					(fill yes)
				)
			)
		)
		(pad "2" smd custom
			(at 0 0.4445 270)
			(size 0.1397 0.1397)
			(layers "F.Cu" "F.Mask" "F.Paste")
			(net "TRAY_ID1")
			(options
				(clearance outline)
				(anchor circle)
			)
			(primitives
				(gr_poly
					(pts
						(arc
							(start -0.1778 -0.2794)
							(mid -0.249642 -0.249642)
							(end -0.2794 -0.1778)
						)
						(arc
							(start -0.2794 0.1778)
							(mid -0.249642 0.249642)
							(end -0.1778 0.2794)
						)
						(arc
							(start 0.1778 0.2794)
							(mid 0.249642 0.249642)
							(end 0.2794 0.1778)
						)
						(arc
							(start 0.2794 -0.1778)
							(mid 0.249642 -0.249642)
							(end 0.1778 -0.2794)
						)
					)
					(width 0)
					(fill yes)
				)
			)
		)
	)
	(footprint ""
		(layer "F.Cu")
		(at 50.423572 -57.303924)
		(property "Reference" "SKT6"
			(at 0 0 0)
			(layer "F.SilkS")
			(hide yes)
			(effects
				(font
					(size 1.27 1.27)
				)
			)
		)
		(property "Value" "SKT-SPI8P-9-GP"
			(at 6.989318 7.128764 0)
			(unlocked yes)
			(layer "F.Fab")
			(hide yes)
			(effects
				(font
					(size 1.016 1.016)
					(thickness 0.1524)
				)
			)
		)
		(property "Device Type" "SKT-SOIC8-104117H235"
			(at 6.989318 5.604764 0)
			(unlocked yes)
			(layer "F.Fab")
			(hide yes)
			(effects
				(font
					(size 1.016 1.016)
					(thickness 0.1524)
				)
			)
		)
		(duplicate_pad_numbers_are_jumpers no)
		(fp_line
			(start -5.4483 -1.416304)
			(end -4.0513 -3.334004)
			(stroke
				(width 0.1524)
				(type default)
			)
			(layer "F.SilkS")
		)
		(fp_line
			(start -5.4483 1.416304)
			(end -5.4483 -1.416304)
			(stroke
				(width 0.1524)
				(type default)
			)
			(layer "F.SilkS")
		)
		(fp_line
			(start -4.0513 -5.8293)
			(end 4.0513 -5.8293)
			(stroke
				(width 0.1524)
				(type default)
			)
			(layer "F.SilkS")
		)
		(fp_line
			(start -4.0513 -3.334004)
			(end -4.0513 -5.8293)
			(stroke
				(width 0.1524)
				(type default)
			)
			(layer "F.SilkS")
		)
		(fp_line
			(start -4.0513 3.334004)
			(end -5.4483 1.416304)
			(stroke
				(width 0.1524)
				(type default)
			)
			(layer "F.SilkS")
		)
		(fp_line
			(start -4.0513 5.8293)
			(end -4.0513 3.334004)
			(stroke
				(width 0.1524)
				(type default)
			)
			(layer "F.SilkS")
		)
		(fp_line
			(start 3.8735 -5.6515)
			(end 3.8735 -3.6449)
			(stroke
				(width 0.508)
				(type default)
			)
			(layer "F.SilkS")
		)
		(fp_line
			(start 4.0513 -5.8293)
			(end 4.0513 -3.334004)
			(stroke
				(width 0.1524)
				(type default)
			)
			(layer "F.SilkS")
		)
		(fp_line
			(start 4.0513 -3.334004)
			(end 5.4483 -1.416304)
			(stroke
				(width 0.1524)
				(type default)
			)
			(layer "F.SilkS")
		)
		(fp_line
			(start 4.0513 3.334004)
			(end 4.0513 5.8293)
			(stroke
				(width 0.1524)
				(type default)
			)
			(layer "F.SilkS")
		)
		(fp_line
			(start 4.0513 5.8293)
			(end -4.0513 5.8293)
			(stroke
				(width 0.1524)
				(type default)
			)
			(layer "F.SilkS")
		)
		(fp_line
			(start 4.6736 0)
			(end 5.4356 -0.762)
			(stroke
				(width 0.1524)
				(type default)
			)
			(layer "F.SilkS")
		)
		(fp_line
			(start 5.4356 0.762)
			(end 4.6736 0)
			(stroke
				(width 0.1524)
				(type default)
			)
			(layer "F.SilkS")
		)
		(fp_line
			(start 5.4483 -1.416304)
			(end 5.4483 1.416304)
			(stroke
				(width 0.1524)
				(type default)
			)
			(layer "F.SilkS")
		)
		(fp_line
			(start 5.4483 1.416304)
			(end 4.0513 3.334004)
			(stroke
				(width 0.1524)
				(type default)
			)
			(layer "F.SilkS")
		)
		(fp_poly
			(pts
				(xy -2.159 3.047492) (xy 2.159 3.047492) (xy 2.159 -3.047492) (xy -2.159 -3.047492)
			)
			(stroke
				(width 0)
				(type default)
			)
			(fill yes)
			(layer "F.SilkS")
		)
		(fp_rect
			(start -5.7023 -5.8293)
			(end 5.7023 -10.5156)
			(stroke
				(width 0)
				(type default)
			)
			(fill no)
			(layer "F.CrtYd")
		)
		(fp_rect
			(start -5.7023 9.7282)
			(end 5.7023 5.8293)
			(stroke
				(width 0)
				(type default)
			)
			(fill no)
			(layer "F.CrtYd")
		)
		(fp_poly
			(pts
				(xy -5.7023 5.8293) (xy -5.7023 -5.8293) (xy -3.7973 -5.8293) (xy -3.7973 -3.2512) (xy -5.1943 -1.3335)
				(xy -5.1943 1.3335) (xy -3.7973 3.2512) (xy -3.7973 5.8293)
			)
			(stroke
				(width 0)
				(type default)
			)
			(fill no)
			(layer "F.CrtYd")
		)
		(fp_poly
			(pts
				(xy 3.7973 5.8293) (xy 3.7973 3.2512) (xy 5.1943 1.3335) (xy 5.1943 -1.3335) (xy 3.7973 -3.2512)
				(xy 3.7973 -5.8293) (xy 5.7023 -5.8293) (xy 5.7023 5.8293)
			)
			(stroke
				(width 0)
				(type default)
			)
			(fill no)
			(layer "F.CrtYd")
		)
		(fp_poly
			(pts
				(xy -3.7973 5.8293) (xy -3.7973 3.2512) (xy -5.1943 1.3335) (xy -5.1943 -1.3335) (xy -3.7973 -3.2512)
				(xy -3.7973 -5.8293) (xy 3.7973 -5.8293) (xy 3.7973 -3.2512) (xy 5.1943 -1.3335) (xy 5.1943 1.3335)
				(xy 3.7973 3.2512) (xy 3.7973 5.8293)
			)
			(stroke
				(width 0)
				(type default)
			)
			(fill no)
			(layer "F.CrtYd")
		)
		(fp_rect
			(start -5.7023 9.7282)
			(end 5.7023 -10.5156)
			(stroke
				(width 0)
				(type default)
			)
			(fill no)
			(layer "F.Fab")
		)
		(pad "1" smd rect
			(at 1.905 -3.999992)
			(size 0.508 1.4986)
			(layers "F.Cu" "F.Mask" "F.Paste")
			(net "NVM_CS_N_R")
		)
		(pad "2" smd rect
			(at 0.635 -3.999992)
			(size 0.508 1.4986)
			(layers "F.Cu" "F.Mask" "F.Paste")
			(net "NVM_SO_R")
		)
		(pad "3" smd rect
			(at -0.635 -3.999992)
			(size 0.508 1.4986)
			(layers "F.Cu" "F.Mask" "F.Paste")
			(net "U44_WP_N")
		)
		(pad "4" smd rect
			(at -1.905 -3.999992)
			(size 0.508 1.4986)
			(layers "F.Cu" "F.Mask" "F.Paste")
			(net "GND")
		)
		(pad "5" smd rect
			(at -1.905 3.999992)
			(size 0.508 1.4986)
			(layers "F.Cu" "F.Mask" "F.Paste")
			(net "NVM_SI_R")
		)
		(pad "6" smd rect
			(at -0.635 3.999992)
			(size 0.508 1.4986)
			(layers "F.Cu" "F.Mask" "F.Paste")
			(net "NVM_SK_R")
		)
		(pad "7" smd rect
			(at 0.635 3.999992)
			(size 0.508 1.4986)
			(layers "F.Cu" "F.Mask" "F.Paste")
			(net "U44_HOLD_N")
		)
		(pad "8" smd rect
			(at 1.905 3.999992)
			(size 0.508 1.4986)
			(layers "F.Cu" "F.Mask" "F.Paste")
			(net "P3V3_STBY")
		)
		(zone
			(layer "F.Cu")
			(hatch none 0.5)
			(connect_pads
				(clearance 0)
			)
			(min_thickness 0.25)
			(keepout
				(tracks allowed)
				(vias not_allowed)
				(pads allowed)
				(copperpour not_allowed)
				(footprints allowed)
			)
			(placement
				(enabled no)
				(sheetname "")
			)
			(fill
				(thermal_gap 0.5)
				(thermal_bridge_width 0.5)
				(island_removal_mode 0)
			)
			(polygon
				(pts
					(xy 48.264572 -60.046616) (xy 52.582572 -60.046616) (xy 52.582572 -60.554616) (xy 48.264572 -60.554616)
				)
			)
		)
		(zone
			(layer "F.Cu")
			(hatch none 0.5)
			(connect_pads
				(clearance 0)
			)
			(min_thickness 0.25)
			(keepout
				(tracks allowed)
				(vias not_allowed)
				(pads allowed)
				(copperpour not_allowed)
				(footprints allowed)
			)
			(placement
				(enabled no)
				(sheetname "")
			)
			(fill
				(thermal_gap 0.5)
				(thermal_bridge_width 0.5)
				(island_removal_mode 0)
			)
			(polygon
				(pts
					(xy 48.264572 -54.053232) (xy 52.582572 -54.053232) (xy 52.582572 -60.554616) (xy 48.264572 -60.554616)
				)
			)
		)
		(zone
			(layer "F.Cu")
			(hatch none 0.5)
			(connect_pads
				(clearance 0)
			)
			(min_thickness 0.25)
			(keepout
				(tracks not_allowed)
				(vias allowed)
				(pads allowed)
				(copperpour not_allowed)
				(footprints allowed)
			)
			(placement
				(enabled no)
				(sheetname "")
			)
			(fill
				(thermal_gap 0.5)
				(thermal_bridge_width 0.5)
				(island_removal_mode 0)
			)
			(polygon
				(pts
					(xy 48.264572 -54.053232) (xy 52.582572 -54.053232) (xy 52.582572 -60.554616) (xy 48.264572 -60.554616)
				)
			)
		)
		(zone
			(layer "F.Cu")
			(hatch none 0.5)
			(connect_pads
				(clearance 0)
			)
			(min_thickness 0.25)
			(keepout
				(tracks allowed)
				(vias not_allowed)
				(pads allowed)
				(copperpour not_allowed)
				(footprints allowed)
			)
			(placement
				(enabled no)
				(sheetname "")
			)
			(fill
				(thermal_gap 0.5)
				(thermal_bridge_width 0.5)
				(island_removal_mode 0)
			)
			(polygon
				(pts
					(xy 48.264572 -54.053232) (xy 52.582572 -54.053232) (xy 52.582572 -54.561232) (xy 48.264572 -54.561232)
				)
			)
		)
	)
	(footprint ""
		(layer "F.Cu")
		(at 345.059 -70.739 -90)
		(property "Reference" "PR160"
			(at 0 0 270)
			(layer "F.SilkS")
			(hide yes)
			(effects
				(font
					(size 1.27 1.27)
				)
			)
		)
		(property "Value" "475KR2F-GP"
			(at 0.064008 -3.993896 270)
			(unlocked yes)
			(layer "F.Fab")
			(hide yes)
			(effects
				(font
					(size 1.016 1.016)
					(thickness 0.1524)
				)
			)
		)
		(property "Device Type" "R402H16"
			(at 0.064008 -5.517896 270)
			(unlocked yes)
			(layer "F.Fab")
			(hide yes)
			(effects
				(font
					(size 1.016 1.016)
					(thickness 0.1524)
				)
			)
		)
		(duplicate_pad_numbers_are_jumpers no)
		(fp_line
			(start -0.508 -0.9398)
			(end -0.508 0.9398)
			(stroke
				(width 0.1524)
				(type default)
			)
			(layer "F.SilkS")
		)
		(fp_line
			(start 0.508 -0.9398)
			(end -0.508 -0.9398)
			(stroke
				(width 0.1524)
				(type default)
			)
			(layer "F.SilkS")
		)
		(fp_rect
			(start -0.508 0.9398)
			(end 0.508 -0.9398)
			(stroke
				(width 0)
				(type default)
			)
			(fill no)
			(layer "F.CrtYd")
		)
		(fp_rect
			(start -0.508 0.9398)
			(end 0.508 -0.9398)
			(stroke
				(width 0)
				(type default)
			)
			(fill no)
			(layer "F.Fab")
		)
		(pad "1" smd custom
			(at 0 -0.4445 270)
			(size 0.1397 0.1397)
			(layers "F.Cu" "F.Mask" "F.Paste")
			(net "P0V9_E_PG")
			(options
				(clearance outline)
				(anchor circle)
			)
			(primitives
				(gr_poly
					(pts
						(arc
							(start -0.1778 -0.2794)
							(mid -0.249642 -0.249642)
							(end -0.2794 -0.1778)
						)
						(arc
							(start -0.2794 0.1778)
							(mid -0.249642 0.249642)
							(end -0.1778 0.2794)
						)
						(arc
							(start 0.1778 0.2794)
							(mid 0.249642 0.249642)
							(end 0.2794 0.1778)
						)
						(arc
							(start 0.2794 -0.1778)
							(mid 0.249642 -0.249642)
							(end 0.1778 -0.2794)
						)
					)
					(width 0)
					(fill yes)
				)
			)
		)
		(pad "2" smd custom
			(at 0 0.4445 270)
			(size 0.1397 0.1397)
			(layers "F.Cu" "F.Mask" "F.Paste")
			(net "P0V9_E_MODE")
			(options
				(clearance outline)
				(anchor circle)
			)
			(primitives
				(gr_poly
					(pts
						(arc
							(start -0.1778 -0.2794)
							(mid -0.249642 -0.249642)
							(end -0.2794 -0.1778)
						)
						(arc
							(start -0.2794 0.1778)
							(mid -0.249642 0.249642)
							(end -0.1778 0.2794)
						)
						(arc
							(start 0.1778 0.2794)
							(mid 0.249642 0.249642)
							(end 0.2794 0.1778)
						)
						(arc
							(start 0.2794 -0.1778)
							(mid 0.249642 -0.249642)
							(end 0.1778 -0.2794)
						)
					)
					(width 0)
					(fill yes)
				)
			)
		)
	)
	(footprint ""
		(layer "F.Cu")
		(at 61.595 -131.953 180)
		(property "Reference" "R315"
			(at 0 0 180)
			(layer "F.SilkS")
			(hide yes)
			(effects
				(font
					(size 1.27 1.27)
				)
			)
		)
		(property "Value" "0R2J-2-GP"
			(at 0.064008 -3.993896 180)
			(unlocked yes)
			(layer "F.Fab")
			(hide yes)
			(effects
				(font
					(size 1.016 1.016)
					(thickness 0.1524)
				)
			)
		)
		(property "Device Type" "R402H16"
			(at 0.064008 -5.517896 180)
			(unlocked yes)
			(layer "F.Fab")
			(hide yes)
			(effects
				(font
					(size 1.016 1.016)
					(thickness 0.1524)
				)
			)
		)
		(duplicate_pad_numbers_are_jumpers no)
		(fp_line
			(start 0.508 -0.9398)
			(end -0.508 -0.9398)
			(stroke
				(width 0.1524)
				(type default)
			)
			(layer "F.SilkS")
		)
		(fp_line
			(start -0.508 -0.9398)
			(end -0.508 0.9398)
			(stroke
				(width 0.1524)
				(type default)
			)
			(layer "F.SilkS")
		)
		(fp_rect
			(start -0.508 0.9398)
			(end 0.508 -0.9398)
			(stroke
				(width 0)
				(type default)
			)
			(fill no)
			(layer "F.CrtYd")
		)
		(fp_rect
			(start -0.508 0.9398)
			(end 0.508 -0.9398)
			(stroke
				(width 0)
				(type default)
			)
			(fill no)
			(layer "F.Fab")
		)
		(pad "1" smd custom
			(at 0 -0.4445 180)
			(size 0.1397 0.1397)
			(layers "F.Cu" "F.Mask" "F.Paste")
			(net "ADC_12V")
			(options
				(clearance outline)
				(anchor circle)
			)
			(primitives
				(gr_poly
					(pts
						(arc
							(start -0.1778 -0.2794)
							(mid -0.249642 -0.249642)
							(end -0.2794 -0.1778)
						)
						(arc
							(start -0.2794 0.1778)
							(mid -0.249642 0.249642)
							(end -0.1778 0.2794)
						)
						(arc
							(start 0.1778 0.2794)
							(mid 0.249642 0.249642)
							(end 0.2794 0.1778)
						)
						(arc
							(start 0.2794 -0.1778)
							(mid 0.249642 -0.249642)
							(end 0.1778 -0.2794)
						)
					)
					(width 0)
					(fill yes)
				)
			)
		)
		(pad "2" smd custom
			(at 0 0.4445 180)
			(size 0.1397 0.1397)
			(layers "F.Cu" "F.Mask" "F.Paste")
			(net "ADC0_12V_BMC")
			(options
				(clearance outline)
				(anchor circle)
			)
			(primitives
				(gr_poly
					(pts
						(arc
							(start -0.1778 -0.2794)
							(mid -0.249642 -0.249642)
							(end -0.2794 -0.1778)
						)
						(arc
							(start -0.2794 0.1778)
							(mid -0.249642 0.249642)
							(end -0.1778 0.2794)
						)
						(arc
							(start 0.1778 0.2794)
							(mid 0.249642 0.249642)
							(end 0.2794 0.1778)
						)
						(arc
							(start 0.2794 -0.1778)
							(mid 0.249642 -0.249642)
							(end 0.1778 -0.2794)
						)
					)
					(width 0)
					(fill yes)
				)
			)
		)
	)
	(footprint ""
		(layer "F.Cu")
		(at 67.808094 -212.420454 180)
		(property "Reference" "C356"
			(at 0 0 180)
			(layer "F.SilkS")
			(hide yes)
			(effects
				(font
					(size 1.27 1.27)
				)
			)
		)
		(property "Value" "SCD22U10V2KX-1GP"
			(at 1.1811 -2.7051 180)
			(unlocked yes)
			(layer "F.Fab")
			(hide yes)
			(effects
				(font
					(size 1.016 1.016)
					(thickness 0.1524)
				)
			)
		)
		(property "Device Type" "C402H22"
			(at 1.1811 -4.2291 180)
			(unlocked yes)
			(layer "F.Fab")
			(hide yes)
			(effects
				(font
					(size 1.016 1.016)
					(thickness 0.1524)
				)
			)
		)
		(duplicate_pad_numbers_are_jumpers no)
		(fp_rect
			(start -0.4318 0.9525)
			(end 0.4318 -0.9525)
			(stroke
				(width 0)
				(type default)
			)
			(fill no)
			(layer "F.CrtYd")
		)
		(fp_rect
			(start -0.4318 0.9525)
			(end 0.4318 -0.9525)
			(stroke
				(width 0)
				(type default)
			)
			(fill no)
			(layer "F.Fab")
		)
		(pad "1" smd custom
			(at 0 -0.4445 180)
			(size 0.1524 0.1524)
			(layers "F.Cu" "F.Mask" "F.Paste")
			(net "PCIE_TX_CAP_N70")
			(options
				(clearance outline)
				(anchor circle)
			)
			(primitives
				(gr_poly
					(pts
						(arc
							(start 0.3048 -0.2032)
							(mid 0.275042 -0.275042)
							(end 0.2032 -0.3048)
						)
						(arc
							(start -0.2032 -0.3048)
							(mid -0.275042 -0.275042)
							(end -0.3048 -0.2032)
						)
						(arc
							(start -0.3048 0.2032)
							(mid -0.275042 0.275042)
							(end -0.2032 0.3048)
						)
						(arc
							(start 0.2032 0.3048)
							(mid 0.275042 0.275042)
							(end 0.3048 0.2032)
						)
					)
					(width 0)
					(fill yes)
				)
			)
		)
		(pad "2" smd custom
			(at 0 0.4445 180)
			(size 0.1524 0.1524)
			(layers "F.Cu" "F.Mask" "F.Paste")
			(net "PCIE_TX_N70")
			(options
				(clearance outline)
				(anchor circle)
			)
			(primitives
				(gr_poly
					(pts
						(arc
							(start 0.3048 -0.2032)
							(mid 0.275042 -0.275042)
							(end 0.2032 -0.3048)
						)
						(arc
							(start -0.2032 -0.3048)
							(mid -0.275042 -0.275042)
							(end -0.3048 -0.2032)
						)
						(arc
							(start -0.3048 0.2032)
							(mid -0.275042 0.275042)
							(end -0.2032 0.3048)
						)
						(arc
							(start 0.2032 0.3048)
							(mid 0.275042 0.275042)
							(end 0.3048 0.2032)
						)
					)
					(width 0)
					(fill yes)
				)
			)
		)
	)
	(footprint ""
		(layer "F.Cu")
		(at 60.028074 -58.94832)
		(property "Reference" "R267"
			(at 0 0 0)
			(layer "F.SilkS")
			(hide yes)
			(effects
				(font
					(size 1.27 1.27)
				)
			)
		)
		(property "Value" "2K2R2J-2-GP"
			(at 0.064008 -3.993896 0)
			(unlocked yes)
			(layer "F.Fab")
			(hide yes)
			(effects
				(font
					(size 1.016 1.016)
					(thickness 0.1524)
				)
			)
		)
		(property "Device Type" "R402H16"
			(at 0.064008 -5.517896 0)
			(unlocked yes)
			(layer "F.Fab")
			(hide yes)
			(effects
				(font
					(size 1.016 1.016)
					(thickness 0.1524)
				)
			)
		)
		(duplicate_pad_numbers_are_jumpers no)
		(fp_line
			(start -0.508 -0.9398)
			(end -0.508 0.9398)
			(stroke
				(width 0.1524)
				(type default)
			)
			(layer "F.SilkS")
		)
		(fp_line
			(start 0.508 -0.9398)
			(end -0.508 -0.9398)
			(stroke
				(width 0.1524)
				(type default)
			)
			(layer "F.SilkS")
		)
		(fp_rect
			(start -0.508 0.9398)
			(end 0.508 -0.9398)
			(stroke
				(width 0)
				(type default)
			)
			(fill no)
			(layer "F.CrtYd")
		)
		(fp_rect
			(start -0.508 0.9398)
			(end 0.508 -0.9398)
			(stroke
				(width 0)
				(type default)
			)
			(fill no)
			(layer "F.Fab")
		)
		(pad "1" smd custom
			(at 0 -0.4445)
			(size 0.1397 0.1397)
			(layers "F.Cu" "F.Mask" "F.Paste")
			(net "FLA_WPN")
			(options
				(clearance outline)
				(anchor circle)
			)
			(primitives
				(gr_poly
					(pts
						(arc
							(start -0.1778 -0.2794)
							(mid -0.249642 -0.249642)
							(end -0.2794 -0.1778)
						)
						(arc
							(start -0.2794 0.1778)
							(mid -0.249642 0.249642)
							(end -0.1778 0.2794)
						)
						(arc
							(start 0.1778 0.2794)
							(mid 0.249642 0.249642)
							(end 0.2794 0.1778)
						)
						(arc
							(start 0.2794 -0.1778)
							(mid 0.249642 -0.249642)
							(end 0.1778 -0.2794)
						)
					)
					(width 0)
					(fill yes)
				)
			)
		)
		(pad "2" smd custom
			(at 0 0.4445)
			(size 0.1397 0.1397)
			(layers "F.Cu" "F.Mask" "F.Paste")
			(net "GND")
			(options
				(clearance outline)
				(anchor circle)
			)
			(primitives
				(gr_poly
					(pts
						(arc
							(start -0.1778 -0.2794)
							(mid -0.249642 -0.249642)
							(end -0.2794 -0.1778)
						)
						(arc
							(start -0.2794 0.1778)
							(mid -0.249642 0.249642)
							(end -0.1778 0.2794)
						)
						(arc
							(start 0.1778 0.2794)
							(mid 0.249642 0.249642)
							(end 0.2794 0.1778)
						)
						(arc
							(start 0.2794 -0.1778)
							(mid 0.249642 -0.249642)
							(end 0.1778 -0.2794)
						)
					)
					(width 0)
					(fill yes)
				)
			)
		)
	)
	(footprint ""
		(layer "F.Cu")
		(at 215.629236 0.46101 -90)
		(property "Reference" "SLED29"
			(at 0 0 270)
			(layer "F.SilkS")
			(hide yes)
			(effects
				(font
					(size 1.27 1.27)
				)
			)
		)
		(property "Value" "LED-YG-51-GP"
			(at -2.6924 -1.4224 270)
			(unlocked yes)
			(layer "F.Fab")
			(hide yes)
			(effects
				(font
					(size 1.016 1.016)
					(thickness 0.1524)
				)
			)
		)
		(property "Device Type" "LED1608AKH40"
			(at -2.6924 -2.9464 270)
			(unlocked yes)
			(layer "F.Fab")
			(hide yes)
			(effects
				(font
					(size 1.016 1.016)
					(thickness 0.1524)
				)
			)
		)
		(duplicate_pad_numbers_are_jumpers no)
		(fp_line
			(start -0.7493 1.651)
			(end -0.7493 1.1811)
			(stroke
				(width 0.3302)
				(type default)
			)
			(layer "F.SilkS")
		)
		(fp_line
			(start 0.7493 1.651)
			(end 0.7493 1.1811)
			(stroke
				(width 0.3302)
				(type default)
			)
			(layer "F.SilkS")
		)
		(fp_line
			(start -0.5969 1.5494)
			(end 0.5842 1.5494)
			(stroke
				(width 0.508)
				(type default)
			)
			(layer "F.SilkS")
		)
		(fp_line
			(start -0.6604 1.3716)
			(end -0.6604 -1.3716)
			(stroke
				(width 0.1524)
				(type default)
			)
			(layer "F.SilkS")
		)
		(fp_line
			(start 0.6604 1.3716)
			(end -0.6604 1.3716)
			(stroke
				(width 0.1524)
				(type default)
			)
			(layer "F.SilkS")
		)
		(fp_line
			(start -0.6604 -1.3716)
			(end 0.6604 -1.3716)
			(stroke
				(width 0.1524)
				(type default)
			)
			(layer "F.SilkS")
		)
		(fp_line
			(start 0.6604 -1.3716)
			(end 0.6604 1.3716)
			(stroke
				(width 0.1524)
				(type default)
			)
			(layer "F.SilkS")
		)
		(fp_rect
			(start -0.6223 1.3335)
			(end 0.6223 -1.3335)
			(stroke
				(width 0)
				(type default)
			)
			(fill no)
			(layer "F.CrtYd")
		)
		(fp_rect
			(start -0.6223 1.3335)
			(end 0.6223 -1.3335)
			(stroke
				(width 0)
				(type default)
			)
			(fill no)
			(layer "F.Fab")
		)
		(pad "A" smd custom
			(at 0 -0.762 270)
			(size 0.2159 0.2159)
			(layers "F.Cu" "F.Mask" "F.Paste")
			(net "SLED29_A")
			(options
				(clearance outline)
				(anchor circle)
			)
			(primitives
				(gr_poly
					(pts
						(arc
							(start -0.3302 -0.4318)
							(mid -0.402042 -0.402042)
							(end -0.4318 -0.3302)
						)
						(arc
							(start -0.4318 0.3302)
							(mid -0.402042 0.402042)
							(end -0.3302 0.4318)
						)
						(arc
							(start 0.3302 0.4318)
							(mid 0.402042 0.402042)
							(end 0.4318 0.3302)
						)
						(arc
							(start 0.4318 -0.3302)
							(mid 0.402042 -0.402042)
							(end 0.3302 -0.4318)
						)
					)
					(width 0)
					(fill yes)
				)
			)
		)
		(pad "K" smd custom
			(at 0 0.762 270)
			(size 0.2159 0.2159)
			(layers "F.Cu" "F.Mask" "F.Paste")
			(net "Q22_D")
			(options
				(clearance outline)
				(anchor circle)
			)
			(primitives
				(gr_poly
					(pts
						(arc
							(start -0.3302 -0.4318)
							(mid -0.402042 -0.402042)
							(end -0.4318 -0.3302)
						)
						(arc
							(start -0.4318 0.3302)
							(mid -0.402042 0.402042)
							(end -0.3302 0.4318)
						)
						(arc
							(start 0.3302 0.4318)
							(mid 0.402042 0.402042)
							(end 0.4318 0.3302)
						)
						(arc
							(start 0.4318 -0.3302)
							(mid 0.402042 -0.402042)
							(end 0.3302 -0.4318)
						)
					)
					(width 0)
					(fill yes)
				)
			)
		)
	)
	(footprint ""
		(layer "F.Cu")
		(at 20.701 -161.544)
		(property "Reference" "C275"
			(at 0 0 0)
			(layer "F.SilkS")
			(hide yes)
			(effects
				(font
					(size 1.27 1.27)
				)
			)
		)
		(property "Value" "SCD1U16V2KX-3GP"
			(at 1.1811 -2.7051 0)
			(unlocked yes)
			(layer "F.Fab")
			(hide yes)
			(effects
				(font
					(size 1.016 1.016)
					(thickness 0.1524)
				)
			)
		)
		(property "Device Type" "C402H22"
			(at 1.1811 -4.2291 0)
			(unlocked yes)
			(layer "F.Fab")
			(hide yes)
			(effects
				(font
					(size 1.016 1.016)
					(thickness 0.1524)
				)
			)
		)
		(duplicate_pad_numbers_are_jumpers no)
		(fp_rect
			(start -0.4318 0.9525)
			(end 0.4318 -0.9525)
			(stroke
				(width 0)
				(type default)
			)
			(fill no)
			(layer "F.CrtYd")
		)
		(fp_rect
			(start -0.4318 0.9525)
			(end 0.4318 -0.9525)
			(stroke
				(width 0)
				(type default)
			)
			(fill no)
			(layer "F.Fab")
		)
		(pad "1" smd custom
			(at 0 -0.4445)
			(size 0.1524 0.1524)
			(layers "F.Cu" "F.Mask" "F.Paste")
			(net "P3V3_STBY")
			(options
				(clearance outline)
				(anchor circle)
			)
			(primitives
				(gr_poly
					(pts
						(arc
							(start 0.3048 -0.2032)
							(mid 0.275042 -0.275042)
							(end 0.2032 -0.3048)
						)
						(arc
							(start -0.2032 -0.3048)
							(mid -0.275042 -0.275042)
							(end -0.3048 -0.2032)
						)
						(arc
							(start -0.3048 0.2032)
							(mid -0.275042 0.275042)
							(end -0.2032 0.3048)
						)
						(arc
							(start 0.2032 0.3048)
							(mid 0.275042 0.275042)
							(end 0.3048 0.2032)
						)
					)
					(width 0)
					(fill yes)
				)
			)
		)
		(pad "2" smd custom
			(at 0 0.4445)
			(size 0.1524 0.1524)
			(layers "F.Cu" "F.Mask" "F.Paste")
			(net "GND")
			(options
				(clearance outline)
				(anchor circle)
			)
			(primitives
				(gr_poly
					(pts
						(arc
							(start 0.3048 -0.2032)
							(mid 0.275042 -0.275042)
							(end 0.2032 -0.3048)
						)
						(arc
							(start -0.2032 -0.3048)
							(mid -0.275042 -0.275042)
							(end -0.3048 -0.2032)
						)
						(arc
							(start -0.3048 0.2032)
							(mid -0.275042 0.275042)
							(end -0.2032 0.3048)
						)
						(arc
							(start 0.2032 0.3048)
							(mid 0.275042 0.275042)
							(end 0.3048 0.2032)
						)
					)
					(width 0)
					(fill yes)
				)
			)
		)
	)
	(footprint ""
		(layer "F.Cu")
		(at 339.808058 -212.420454 180)
		(property "Reference" "C57"
			(at 0 0 180)
			(layer "F.SilkS")
			(hide yes)
			(effects
				(font
					(size 1.27 1.27)
				)
			)
		)
		(property "Value" "SCD22U10V2KX-1GP"
			(at 1.1811 -2.7051 180)
			(unlocked yes)
			(layer "F.Fab")
			(hide yes)
			(effects
				(font
					(size 1.016 1.016)
					(thickness 0.1524)
				)
			)
		)
		(property "Device Type" "C402H22"
			(at 1.1811 -4.2291 180)
			(unlocked yes)
			(layer "F.Fab")
			(hide yes)
			(effects
				(font
					(size 1.016 1.016)
					(thickness 0.1524)
				)
			)
		)
		(duplicate_pad_numbers_are_jumpers no)
		(fp_rect
			(start -0.4318 0.9525)
			(end 0.4318 -0.9525)
			(stroke
				(width 0)
				(type default)
			)
			(fill no)
			(layer "F.CrtYd")
		)
		(fp_rect
			(start -0.4318 0.9525)
			(end 0.4318 -0.9525)
			(stroke
				(width 0)
				(type default)
			)
			(fill no)
			(layer "F.Fab")
		)
		(pad "1" smd custom
			(at 0 -0.4445 180)
			(size 0.1524 0.1524)
			(layers "F.Cu" "F.Mask" "F.Paste")
			(net "PCIE_TX_CAP_N17")
			(options
				(clearance outline)
				(anchor circle)
			)
			(primitives
				(gr_poly
					(pts
						(arc
							(start 0.3048 -0.2032)
							(mid 0.275042 -0.275042)
							(end 0.2032 -0.3048)
						)
						(arc
							(start -0.2032 -0.3048)
							(mid -0.275042 -0.275042)
							(end -0.3048 -0.2032)
						)
						(arc
							(start -0.3048 0.2032)
							(mid -0.275042 0.275042)
							(end -0.2032 0.3048)
						)
						(arc
							(start 0.2032 0.3048)
							(mid 0.275042 0.275042)
							(end 0.3048 0.2032)
						)
					)
					(width 0)
					(fill yes)
				)
			)
		)
		(pad "2" smd custom
			(at 0 0.4445 180)
			(size 0.1524 0.1524)
			(layers "F.Cu" "F.Mask" "F.Paste")
			(net "PCIE_TX_N17")
			(options
				(clearance outline)
				(anchor circle)
			)
			(primitives
				(gr_poly
					(pts
						(arc
							(start 0.3048 -0.2032)
							(mid 0.275042 -0.275042)
							(end 0.2032 -0.3048)
						)
						(arc
							(start -0.2032 -0.3048)
							(mid -0.275042 -0.275042)
							(end -0.3048 -0.2032)
						)
						(arc
							(start -0.3048 0.2032)
							(mid -0.275042 0.275042)
							(end -0.2032 0.3048)
						)
						(arc
							(start 0.2032 0.3048)
							(mid 0.275042 0.275042)
							(end 0.3048 0.2032)
						)
					)
					(width 0)
					(fill yes)
				)
			)
		)
	)
	(footprint ""
		(layer "F.Cu")
		(at 17.1704 -83.5914 180)
		(property "Reference" "C628"
			(at 0 0 180)
			(layer "F.SilkS")
			(hide yes)
			(effects
				(font
					(size 1.27 1.27)
				)
			)
		)
		(property "Value" "SCD1U16V2KX-3GP"
			(at 1.1811 -2.7051 180)
			(unlocked yes)
			(layer "F.Fab")
			(hide yes)
			(effects
				(font
					(size 1.016 1.016)
					(thickness 0.1524)
				)
			)
		)
		(property "Device Type" "C402H22"
			(at 1.1811 -4.2291 180)
			(unlocked yes)
			(layer "F.Fab")
			(hide yes)
			(effects
				(font
					(size 1.016 1.016)
					(thickness 0.1524)
				)
			)
		)
		(duplicate_pad_numbers_are_jumpers no)
		(fp_rect
			(start -0.4318 0.9525)
			(end 0.4318 -0.9525)
			(stroke
				(width 0)
				(type default)
			)
			(fill no)
			(layer "F.CrtYd")
		)
		(fp_rect
			(start -0.4318 0.9525)
			(end 0.4318 -0.9525)
			(stroke
				(width 0)
				(type default)
			)
			(fill no)
			(layer "F.Fab")
		)
		(pad "1" smd custom
			(at 0 -0.4445 180)
			(size 0.1524 0.1524)
			(layers "F.Cu" "F.Mask" "F.Paste")
			(net "P3V3_STBY")
			(options
				(clearance outline)
				(anchor circle)
			)
			(primitives
				(gr_poly
					(pts
						(arc
							(start 0.3048 -0.2032)
							(mid 0.275042 -0.275042)
							(end 0.2032 -0.3048)
						)
						(arc
							(start -0.2032 -0.3048)
							(mid -0.275042 -0.275042)
							(end -0.3048 -0.2032)
						)
						(arc
							(start -0.3048 0.2032)
							(mid -0.275042 0.275042)
							(end -0.2032 0.3048)
						)
						(arc
							(start 0.2032 0.3048)
							(mid 0.275042 0.275042)
							(end 0.3048 0.2032)
						)
					)
					(width 0)
					(fill yes)
				)
			)
		)
		(pad "2" smd custom
			(at 0 0.4445 180)
			(size 0.1524 0.1524)
			(layers "F.Cu" "F.Mask" "F.Paste")
			(net "GND")
			(options
				(clearance outline)
				(anchor circle)
			)
			(primitives
				(gr_poly
					(pts
						(arc
							(start 0.3048 -0.2032)
							(mid 0.275042 -0.275042)
							(end 0.2032 -0.3048)
						)
						(arc
							(start -0.2032 -0.3048)
							(mid -0.275042 -0.275042)
							(end -0.3048 -0.2032)
						)
						(arc
							(start -0.3048 0.2032)
							(mid -0.275042 0.275042)
							(end -0.2032 0.3048)
						)
						(arc
							(start 0.2032 0.3048)
							(mid 0.275042 0.275042)
							(end 0.3048 0.2032)
						)
					)
					(width 0)
					(fill yes)
				)
			)
		)
	)
	(footprint ""
		(layer "F.Cu")
		(at 31.877 -118.364)
		(property "Reference" "TP243"
			(at 0 0 0)
			(layer "F.SilkS")
			(hide yes)
			(effects
				(font
					(size 1.27 1.27)
				)
			)
		)
		(property "Value" "TPAD28-2-GP"
			(at -0.0127 -1.6637 0)
			(unlocked yes)
			(layer "F.Fab")
			(hide yes)
			(effects
				(font
					(size 1.016 1.016)
					(thickness 0.1524)
				)
			)
		)
		(property "Device Type" "TPAD28"
			(at -0.0127 -3.1877 0)
			(unlocked yes)
			(layer "F.Fab")
			(hide yes)
			(effects
				(font
					(size 1.016 1.016)
					(thickness 0.1524)
				)
			)
		)
		(duplicate_pad_numbers_are_jumpers no)
		(fp_poly
			(pts
				(arc
					(start 0.3556 0)
					(mid -0.3556 0)
					(end 0.3556 0)
				)
			)
			(stroke
				(width 0)
				(type default)
			)
			(fill no)
			(layer "F.CrtYd")
		)
		(fp_poly
			(pts
				(arc
					(start 0.6096 0)
					(mid -0.6096 0)
					(end 0.6096 0)
				)
			)
			(stroke
				(width 0)
				(type default)
			)
			(fill no)
			(layer "F.Fab")
		)
		(pad "1" smd circle
			(at 0 0)
			(size 0.7112 0.7112)
			(layers "F.Cu" "F.Mask" "F.Paste")
			(net "TP_GPIOD3")
		)
	)
	(footprint ""
		(layer "F.Cu")
		(at 136.30275 -41.519602 90)
		(property "Reference" "R730"
			(at 0 0 90)
			(layer "F.SilkS")
			(hide yes)
			(effects
				(font
					(size 1.27 1.27)
				)
			)
		)
		(property "Value" "15KR2F-GP"
			(at 0.064008 -3.993896 90)
			(unlocked yes)
			(layer "F.Fab")
			(hide yes)
			(effects
				(font
					(size 1.016 1.016)
					(thickness 0.1524)
				)
			)
		)
		(property "Device Type" "R402H16"
			(at 0.064008 -5.517896 90)
			(unlocked yes)
			(layer "F.Fab")
			(hide yes)
			(effects
				(font
					(size 1.016 1.016)
					(thickness 0.1524)
				)
			)
		)
		(duplicate_pad_numbers_are_jumpers no)
		(fp_line
			(start 0.508 -0.9398)
			(end -0.508 -0.9398)
			(stroke
				(width 0.1524)
				(type default)
			)
			(layer "F.SilkS")
		)
		(fp_line
			(start -0.508 -0.9398)
			(end -0.508 0.9398)
			(stroke
				(width 0.1524)
				(type default)
			)
			(layer "F.SilkS")
		)
		(fp_rect
			(start -0.508 0.9398)
			(end 0.508 -0.9398)
			(stroke
				(width 0)
				(type default)
			)
			(fill no)
			(layer "F.CrtYd")
		)
		(fp_rect
			(start -0.508 0.9398)
			(end 0.508 -0.9398)
			(stroke
				(width 0)
				(type default)
			)
			(fill no)
			(layer "F.Fab")
		)
		(pad "1" smd custom
			(at 0 -0.4445 90)
			(size 0.1397 0.1397)
			(layers "F.Cu" "F.Mask" "F.Paste")
			(net "DUT_VDDO")
			(options
				(clearance outline)
				(anchor circle)
			)
			(primitives
				(gr_poly
					(pts
						(arc
							(start -0.1778 -0.2794)
							(mid -0.249642 -0.249642)
							(end -0.2794 -0.1778)
						)
						(arc
							(start -0.2794 0.1778)
							(mid -0.249642 0.249642)
							(end -0.1778 0.2794)
						)
						(arc
							(start 0.1778 0.2794)
							(mid 0.249642 0.249642)
							(end 0.2794 0.1778)
						)
						(arc
							(start 0.2794 -0.1778)
							(mid 0.249642 -0.249642)
							(end 0.1778 -0.2794)
						)
					)
					(width 0)
					(fill yes)
				)
			)
		)
		(pad "2" smd custom
			(at 0 0.4445 90)
			(size 0.1397 0.1397)
			(layers "F.Cu" "F.Mask" "F.Paste")
			(net "DUT_TDO")
			(options
				(clearance outline)
				(anchor circle)
			)
			(primitives
				(gr_poly
					(pts
						(arc
							(start -0.1778 -0.2794)
							(mid -0.249642 -0.249642)
							(end -0.2794 -0.1778)
						)
						(arc
							(start -0.2794 0.1778)
							(mid -0.249642 0.249642)
							(end -0.1778 0.2794)
						)
						(arc
							(start 0.1778 0.2794)
							(mid 0.249642 0.249642)
							(end 0.2794 0.1778)
						)
						(arc
							(start 0.2794 -0.1778)
							(mid 0.249642 -0.249642)
							(end 0.1778 -0.2794)
						)
					)
					(width 0)
					(fill yes)
				)
			)
		)
	)
	(footprint ""
		(layer "F.Cu")
		(at 38.5064 -103.632)
		(property "Reference" "R656"
			(at 0 0 0)
			(layer "F.SilkS")
			(hide yes)
			(effects
				(font
					(size 1.27 1.27)
				)
			)
		)
		(property "Value" "4K7R2F-GP"
			(at 0.064008 -3.993896 0)
			(unlocked yes)
			(layer "F.Fab")
			(hide yes)
			(effects
				(font
					(size 1.016 1.016)
					(thickness 0.1524)
				)
			)
		)
		(property "Device Type" "R402H16"
			(at 0.064008 -5.517896 0)
			(unlocked yes)
			(layer "F.Fab")
			(hide yes)
			(effects
				(font
					(size 1.016 1.016)
					(thickness 0.1524)
				)
			)
		)
		(duplicate_pad_numbers_are_jumpers no)
		(fp_line
			(start -0.508 -0.9398)
			(end -0.508 0.9398)
			(stroke
				(width 0.1524)
				(type default)
			)
			(layer "F.SilkS")
		)
		(fp_line
			(start 0.508 -0.9398)
			(end -0.508 -0.9398)
			(stroke
				(width 0.1524)
				(type default)
			)
			(layer "F.SilkS")
		)
		(fp_rect
			(start -0.508 0.9398)
			(end 0.508 -0.9398)
			(stroke
				(width 0)
				(type default)
			)
			(fill no)
			(layer "F.CrtYd")
		)
		(fp_rect
			(start -0.508 0.9398)
			(end 0.508 -0.9398)
			(stroke
				(width 0)
				(type default)
			)
			(fill no)
			(layer "F.Fab")
		)
		(pad "1" smd custom
			(at 0 -0.4445)
			(size 0.1397 0.1397)
			(layers "F.Cu" "F.Mask" "F.Paste")
			(net "SPI_FLASH_SELECT")
			(options
				(clearance outline)
				(anchor circle)
			)
			(primitives
				(gr_poly
					(pts
						(arc
							(start -0.1778 -0.2794)
							(mid -0.249642 -0.249642)
							(end -0.2794 -0.1778)
						)
						(arc
							(start -0.2794 0.1778)
							(mid -0.249642 0.249642)
							(end -0.1778 0.2794)
						)
						(arc
							(start 0.1778 0.2794)
							(mid 0.249642 0.249642)
							(end 0.2794 0.1778)
						)
						(arc
							(start 0.2794 -0.1778)
							(mid 0.249642 -0.249642)
							(end 0.1778 -0.2794)
						)
					)
					(width 0)
					(fill yes)
				)
			)
		)
		(pad "2" smd custom
			(at 0 0.4445)
			(size 0.1397 0.1397)
			(layers "F.Cu" "F.Mask" "F.Paste")
			(net "P3V3_STBY")
			(options
				(clearance outline)
				(anchor circle)
			)
			(primitives
				(gr_poly
					(pts
						(arc
							(start -0.1778 -0.2794)
							(mid -0.249642 -0.249642)
							(end -0.2794 -0.1778)
						)
						(arc
							(start -0.2794 0.1778)
							(mid -0.249642 0.249642)
							(end -0.1778 0.2794)
						)
						(arc
							(start 0.1778 0.2794)
							(mid 0.249642 0.249642)
							(end 0.2794 0.1778)
						)
						(arc
							(start 0.2794 -0.1778)
							(mid 0.249642 -0.249642)
							(end 0.1778 -0.2794)
						)
					)
					(width 0)
					(fill yes)
				)
			)
		)
	)
	(footprint ""
		(layer "F.Cu")
		(at 264.541 -26.289 180)
		(property "Reference" "R777"
			(at 0 0 180)
			(layer "F.SilkS")
			(hide yes)
			(effects
				(font
					(size 1.27 1.27)
				)
			)
		)
		(property "Value" "2KR2F-3-GP"
			(at 0.064008 -3.993896 180)
			(unlocked yes)
			(layer "F.Fab")
			(hide yes)
			(effects
				(font
					(size 1.016 1.016)
					(thickness 0.1524)
				)
			)
		)
		(property "Device Type" "R402H16"
			(at 0.064008 -5.517896 180)
			(unlocked yes)
			(layer "F.Fab")
			(hide yes)
			(effects
				(font
					(size 1.016 1.016)
					(thickness 0.1524)
				)
			)
		)
		(duplicate_pad_numbers_are_jumpers no)
		(fp_line
			(start 0.508 -0.9398)
			(end -0.508 -0.9398)
			(stroke
				(width 0.1524)
				(type default)
			)
			(layer "F.SilkS")
		)
		(fp_line
			(start -0.508 -0.9398)
			(end -0.508 0.9398)
			(stroke
				(width 0.1524)
				(type default)
			)
			(layer "F.SilkS")
		)
		(fp_rect
			(start -0.508 0.9398)
			(end 0.508 -0.9398)
			(stroke
				(width 0)
				(type default)
			)
			(fill no)
			(layer "F.CrtYd")
		)
		(fp_rect
			(start -0.508 0.9398)
			(end 0.508 -0.9398)
			(stroke
				(width 0)
				(type default)
			)
			(fill no)
			(layer "F.Fab")
		)
		(pad "1" smd custom
			(at 0 -0.4445 180)
			(size 0.1397 0.1397)
			(layers "F.Cu" "F.Mask" "F.Paste")
			(net "P3V3_GPIO")
			(options
				(clearance outline)
				(anchor circle)
			)
			(primitives
				(gr_poly
					(pts
						(arc
							(start -0.1778 -0.2794)
							(mid -0.249642 -0.249642)
							(end -0.2794 -0.1778)
						)
						(arc
							(start -0.2794 0.1778)
							(mid -0.249642 0.249642)
							(end -0.1778 0.2794)
						)
						(arc
							(start 0.1778 0.2794)
							(mid 0.249642 0.249642)
							(end 0.2794 0.1778)
						)
						(arc
							(start 0.2794 -0.1778)
							(mid 0.249642 -0.249642)
							(end 0.1778 -0.2794)
						)
					)
					(width 0)
					(fill yes)
				)
			)
		)
		(pad "2" smd custom
			(at 0 0.4445 180)
			(size 0.1397 0.1397)
			(layers "F.Cu" "F.Mask" "F.Paste")
			(net "TWI_SDA3")
			(options
				(clearance outline)
				(anchor circle)
			)
			(primitives
				(gr_poly
					(pts
						(arc
							(start -0.1778 -0.2794)
							(mid -0.249642 -0.249642)
							(end -0.2794 -0.1778)
						)
						(arc
							(start -0.2794 0.1778)
							(mid -0.249642 0.249642)
							(end -0.1778 0.2794)
						)
						(arc
							(start 0.1778 0.2794)
							(mid 0.249642 0.249642)
							(end 0.2794 0.1778)
						)
						(arc
							(start 0.2794 -0.1778)
							(mid 0.249642 -0.249642)
							(end 0.1778 -0.2794)
						)
					)
					(width 0)
					(fill yes)
				)
			)
		)
	)
	(footprint ""
		(layer "F.Cu")
		(at 10.760964 -95.073978)
		(property "Reference" "U21"
			(at 0 0 0)
			(layer "F.SilkS")
			(hide yes)
			(effects
				(font
					(size 1.27 1.27)
				)
			)
		)
		(property "Value" "ICS551MLFT-GP"
			(at -3.707384 -1.5367 0)
			(unlocked yes)
			(layer "F.Fab")
			(hide yes)
			(effects
				(font
					(size 1.016 1.016)
					(thickness 0.1524)
				)
			)
		)
		(property "Device Type" "SOIC8H69"
			(at -3.707384 -3.0607 0)
			(unlocked yes)
			(layer "F.Fab")
			(hide yes)
			(effects
				(font
					(size 1.016 1.016)
					(thickness 0.1524)
				)
			)
		)
		(duplicate_pad_numbers_are_jumpers no)
		(fp_line
			(start -2.7432 -1.4224)
			(end -2.7432 1.4224)
			(stroke
				(width 0.1524)
				(type default)
			)
			(layer "F.SilkS")
		)
		(fp_line
			(start -2.7432 1.4224)
			(end -2.6416 1.4224)
			(stroke
				(width 0.1524)
				(type default)
			)
			(layer "F.SilkS")
		)
		(fp_line
			(start -2.7432 1.4224)
			(end 2.1336 1.4224)
			(stroke
				(width 0.1524)
				(type default)
			)
			(layer "F.SilkS")
		)
		(fp_line
			(start -2.7178 -0.508)
			(end -2.1844 -0.0508)
			(stroke
				(width 0.1524)
				(type default)
			)
			(layer "F.SilkS")
		)
		(fp_line
			(start -2.6289 3.4417)
			(end -2.6289 1.4732)
			(stroke
				(width 0.381)
				(type default)
			)
			(layer "F.SilkS")
		)
		(fp_line
			(start -2.1844 -0.0508)
			(end -2.7178 0.508)
			(stroke
				(width 0.1524)
				(type default)
			)
			(layer "F.SilkS")
		)
		(fp_line
			(start 2.1336 -1.4224)
			(end -2.7432 -1.4224)
			(stroke
				(width 0.1524)
				(type default)
			)
			(layer "F.SilkS")
		)
		(fp_line
			(start 2.1336 1.4224)
			(end 2.1336 -1.4224)
			(stroke
				(width 0.1524)
				(type default)
			)
			(layer "F.SilkS")
		)
		(fp_poly
			(pts
				(xy -2.2098 -1.4224) (xy -2.2098 1.4224) (xy 2.2098 1.4224) (xy 2.2098 -1.4224)
			)
			(stroke
				(width 0)
				(type default)
			)
			(fill yes)
			(layer "F.SilkS")
		)
		(fp_rect
			(start -2.450084 2.999994)
			(end 2.450084 -2.999994)
			(stroke
				(width 0)
				(type default)
			)
			(fill no)
			(layer "F.CrtYd")
		)
		(fp_poly
			(pts
				(xy -2.8194 3.6322) (xy -2.8194 -3.6322) (xy 2.8194 -3.6322) (xy 2.8194 1.18364) (xy 2.450084 1.18364)
				(xy 2.450084 -2.999994) (xy -2.450084 -2.999994) (xy -2.450084 2.999994) (xy 2.450084 2.999994)
				(xy 2.450084 1.18618) (xy 2.8194 1.18618) (xy 2.8194 3.6322)
			)
			(stroke
				(width 0)
				(type default)
			)
			(fill no)
			(layer "F.CrtYd")
		)
		(fp_rect
			(start -2.8194 3.6322)
			(end 2.8194 -3.6322)
			(stroke
				(width 0)
				(type default)
			)
			(fill no)
			(layer "F.Fab")
		)
		(pad "1" smd rect
			(at -1.905 2.54)
			(size 0.635 1.651)
			(layers "F.Cu" "F.Mask" "F.Paste")
			(net "50M_CLK_OUT_R")
		)
		(pad "2" smd rect
			(at -0.635 2.54)
			(size 0.635 1.651)
			(layers "F.Cu" "F.Mask" "F.Paste")
			(net "CLK_50M_BMC_NCSI")
		)
		(pad "3" smd rect
			(at 0.635 2.54)
			(size 0.635 1.651)
			(layers "F.Cu" "F.Mask" "F.Paste")
			(net "CLK_50M_RMII_PHY")
		)
		(pad "4" smd rect
			(at 1.905 2.54)
			(size 0.635 1.651)
			(layers "F.Cu" "F.Mask" "F.Paste")
			(net "NCSI_10G_RCLK")
		)
		(pad "5" smd rect
			(at 1.905 -2.54)
			(size 0.635 1.651)
			(layers "F.Cu" "F.Mask" "F.Paste")
			(net "CLK_50M_BMC0")
		)
		(pad "6" smd rect
			(at 0.635 -2.54)
			(size 0.635 1.651)
			(layers "F.Cu" "F.Mask" "F.Paste")
			(net "GND")
		)
		(pad "7" smd rect
			(at -0.635 -2.54)
			(size 0.635 1.651)
			(layers "F.Cu" "F.Mask" "F.Paste")
			(net "P3V3_STBY")
		)
		(pad "8" smd rect
			(at -1.905 -2.54)
			(size 0.635 1.651)
			(layers "F.Cu" "F.Mask" "F.Paste")
			(net "50M_CLK_OE")
		)
	)
	(footprint ""
		(layer "F.Cu")
		(at 172.792136 -212.420454 180)
		(property "Reference" "C138"
			(at 0 0 180)
			(layer "F.SilkS")
			(hide yes)
			(effects
				(font
					(size 1.27 1.27)
				)
			)
		)
		(property "Value" "SCD22U10V2KX-1GP"
			(at 1.1811 -2.7051 180)
			(unlocked yes)
			(layer "F.Fab")
			(hide yes)
			(effects
				(font
					(size 1.016 1.016)
					(thickness 0.1524)
				)
			)
		)
		(property "Device Type" "C402H22"
			(at 1.1811 -4.2291 180)
			(unlocked yes)
			(layer "F.Fab")
			(hide yes)
			(effects
				(font
					(size 1.016 1.016)
					(thickness 0.1524)
				)
			)
		)
		(duplicate_pad_numbers_are_jumpers no)
		(fp_rect
			(start -0.4318 0.9525)
			(end 0.4318 -0.9525)
			(stroke
				(width 0)
				(type default)
			)
			(fill no)
			(layer "F.CrtYd")
		)
		(fp_rect
			(start -0.4318 0.9525)
			(end 0.4318 -0.9525)
			(stroke
				(width 0)
				(type default)
			)
			(fill no)
			(layer "F.Fab")
		)
		(pad "1" smd custom
			(at 0 -0.4445 180)
			(size 0.1524 0.1524)
			(layers "F.Cu" "F.Mask" "F.Paste")
			(net "PCIE_TX_CAP_P49")
			(options
				(clearance outline)
				(anchor circle)
			)
			(primitives
				(gr_poly
					(pts
						(arc
							(start 0.3048 -0.2032)
							(mid 0.275042 -0.275042)
							(end 0.2032 -0.3048)
						)
						(arc
							(start -0.2032 -0.3048)
							(mid -0.275042 -0.275042)
							(end -0.3048 -0.2032)
						)
						(arc
							(start -0.3048 0.2032)
							(mid -0.275042 0.275042)
							(end -0.2032 0.3048)
						)
						(arc
							(start 0.2032 0.3048)
							(mid 0.275042 0.275042)
							(end 0.3048 0.2032)
						)
					)
					(width 0)
					(fill yes)
				)
			)
		)
		(pad "2" smd custom
			(at 0 0.4445 180)
			(size 0.1524 0.1524)
			(layers "F.Cu" "F.Mask" "F.Paste")
			(net "PCIE_TX_P49")
			(options
				(clearance outline)
				(anchor circle)
			)
			(primitives
				(gr_poly
					(pts
						(arc
							(start 0.3048 -0.2032)
							(mid 0.275042 -0.275042)
							(end 0.2032 -0.3048)
						)
						(arc
							(start -0.2032 -0.3048)
							(mid -0.275042 -0.275042)
							(end -0.3048 -0.2032)
						)
						(arc
							(start -0.3048 0.2032)
							(mid -0.275042 0.275042)
							(end -0.2032 0.3048)
						)
						(arc
							(start 0.2032 0.3048)
							(mid 0.275042 0.275042)
							(end 0.3048 0.2032)
						)
					)
					(width 0)
					(fill yes)
				)
			)
		)
	)
	(footprint ""
		(layer "F.Cu")
		(at 160.366202 -58.447432)
		(property "Reference" "PR167"
			(at 0 0 0)
			(layer "F.SilkS")
			(hide yes)
			(effects
				(font
					(size 1.27 1.27)
				)
			)
		)
		(property "Value" "0R2J-2-GP"
			(at 0.064008 -3.993896 0)
			(unlocked yes)
			(layer "F.Fab")
			(hide yes)
			(effects
				(font
					(size 1.016 1.016)
					(thickness 0.1524)
				)
			)
		)
		(property "Device Type" "R402H16"
			(at 0.064008 -5.517896 0)
			(unlocked yes)
			(layer "F.Fab")
			(hide yes)
			(effects
				(font
					(size 1.016 1.016)
					(thickness 0.1524)
				)
			)
		)
		(duplicate_pad_numbers_are_jumpers no)
		(fp_line
			(start -0.508 -0.9398)
			(end -0.508 0.9398)
			(stroke
				(width 0.1524)
				(type default)
			)
			(layer "F.SilkS")
		)
		(fp_line
			(start 0.508 -0.9398)
			(end -0.508 -0.9398)
			(stroke
				(width 0.1524)
				(type default)
			)
			(layer "F.SilkS")
		)
		(fp_rect
			(start -0.508 0.9398)
			(end 0.508 -0.9398)
			(stroke
				(width 0)
				(type default)
			)
			(fill no)
			(layer "F.CrtYd")
		)
		(fp_rect
			(start -0.508 0.9398)
			(end 0.508 -0.9398)
			(stroke
				(width 0)
				(type default)
			)
			(fill no)
			(layer "F.Fab")
		)
		(pad "1" smd custom
			(at 0 -0.4445)
			(size 0.1397 0.1397)
			(layers "F.Cu" "F.Mask" "F.Paste")
			(net "P0V9_EN")
			(options
				(clearance outline)
				(anchor circle)
			)
			(primitives
				(gr_poly
					(pts
						(arc
							(start -0.1778 -0.2794)
							(mid -0.249642 -0.249642)
							(end -0.2794 -0.1778)
						)
						(arc
							(start -0.2794 0.1778)
							(mid -0.249642 0.249642)
							(end -0.1778 0.2794)
						)
						(arc
							(start 0.1778 0.2794)
							(mid 0.249642 0.249642)
							(end 0.2794 0.1778)
						)
						(arc
							(start 0.2794 -0.1778)
							(mid 0.249642 -0.249642)
							(end 0.1778 -0.2794)
						)
					)
					(width 0)
					(fill yes)
				)
			)
		)
		(pad "2" smd custom
			(at 0 0.4445)
			(size 0.1397 0.1397)
			(layers "F.Cu" "F.Mask" "F.Paste")
			(net "PWRGD_P1V26_STBY")
			(options
				(clearance outline)
				(anchor circle)
			)
			(primitives
				(gr_poly
					(pts
						(arc
							(start -0.1778 -0.2794)
							(mid -0.249642 -0.249642)
							(end -0.2794 -0.1778)
						)
						(arc
							(start -0.2794 0.1778)
							(mid -0.249642 0.249642)
							(end -0.1778 0.2794)
						)
						(arc
							(start 0.1778 0.2794)
							(mid 0.249642 0.249642)
							(end 0.2794 0.1778)
						)
						(arc
							(start 0.2794 -0.1778)
							(mid 0.249642 -0.249642)
							(end 0.1778 -0.2794)
						)
					)
					(width 0)
					(fill yes)
				)
			)
		)
	)
	(footprint ""
		(layer "F.Cu")
		(at 14.478 -52.3748 180)
		(property "Reference" "R594"
			(at 0 0 180)
			(layer "F.SilkS")
			(hide yes)
			(effects
				(font
					(size 1.27 1.27)
				)
			)
		)
		(property "Value" "0R2J-2-GP"
			(at 0.064008 -3.993896 180)
			(unlocked yes)
			(layer "F.Fab")
			(hide yes)
			(effects
				(font
					(size 1.016 1.016)
					(thickness 0.1524)
				)
			)
		)
		(property "Device Type" "R402H16"
			(at 0.064008 -5.517896 180)
			(unlocked yes)
			(layer "F.Fab")
			(hide yes)
			(effects
				(font
					(size 1.016 1.016)
					(thickness 0.1524)
				)
			)
		)
		(duplicate_pad_numbers_are_jumpers no)
		(fp_line
			(start 0.508 -0.9398)
			(end -0.508 -0.9398)
			(stroke
				(width 0.1524)
				(type default)
			)
			(layer "F.SilkS")
		)
		(fp_line
			(start -0.508 -0.9398)
			(end -0.508 0.9398)
			(stroke
				(width 0.1524)
				(type default)
			)
			(layer "F.SilkS")
		)
		(fp_rect
			(start -0.508 0.9398)
			(end 0.508 -0.9398)
			(stroke
				(width 0)
				(type default)
			)
			(fill no)
			(layer "F.CrtYd")
		)
		(fp_rect
			(start -0.508 0.9398)
			(end 0.508 -0.9398)
			(stroke
				(width 0)
				(type default)
			)
			(fill no)
			(layer "F.Fab")
		)
		(pad "1" smd custom
			(at 0 -0.4445 180)
			(size 0.1397 0.1397)
			(layers "F.Cu" "F.Mask" "F.Paste")
			(net "NIC0_MDI0_P1_R")
			(options
				(clearance outline)
				(anchor circle)
			)
			(primitives
				(gr_poly
					(pts
						(arc
							(start -0.1778 -0.2794)
							(mid -0.249642 -0.249642)
							(end -0.2794 -0.1778)
						)
						(arc
							(start -0.2794 0.1778)
							(mid -0.249642 0.249642)
							(end -0.1778 0.2794)
						)
						(arc
							(start 0.1778 0.2794)
							(mid 0.249642 0.249642)
							(end 0.2794 0.1778)
						)
						(arc
							(start 0.2794 -0.1778)
							(mid 0.249642 -0.249642)
							(end 0.1778 -0.2794)
						)
					)
					(width 0)
					(fill yes)
				)
			)
		)
		(pad "2" smd custom
			(at 0 0.4445 180)
			(size 0.1397 0.1397)
			(layers "F.Cu" "F.Mask" "F.Paste")
			(net "NIC0_MDI0_P1")
			(options
				(clearance outline)
				(anchor circle)
			)
			(primitives
				(gr_poly
					(pts
						(arc
							(start -0.1778 -0.2794)
							(mid -0.249642 -0.249642)
							(end -0.2794 -0.1778)
						)
						(arc
							(start -0.2794 0.1778)
							(mid -0.249642 0.249642)
							(end -0.1778 0.2794)
						)
						(arc
							(start 0.1778 0.2794)
							(mid 0.249642 0.249642)
							(end 0.2794 0.1778)
						)
						(arc
							(start 0.2794 -0.1778)
							(mid 0.249642 -0.249642)
							(end 0.1778 -0.2794)
						)
					)
					(width 0)
					(fill yes)
				)
			)
		)
	)
	(footprint ""
		(layer "F.Cu")
		(at 45.085 -200.533 180)
		(property "Reference" "R875"
			(at 0 0 180)
			(layer "F.SilkS")
			(hide yes)
			(effects
				(font
					(size 1.27 1.27)
				)
			)
		)
		(property "Value" "10KR2F-2-GP"
			(at 0.064008 -3.993896 180)
			(unlocked yes)
			(layer "F.Fab")
			(hide yes)
			(effects
				(font
					(size 1.016 1.016)
					(thickness 0.1524)
				)
			)
		)
		(property "Device Type" "R402H16"
			(at 0.064008 -5.517896 180)
			(unlocked yes)
			(layer "F.Fab")
			(hide yes)
			(effects
				(font
					(size 1.016 1.016)
					(thickness 0.1524)
				)
			)
		)
		(duplicate_pad_numbers_are_jumpers no)
		(fp_line
			(start 0.508 -0.9398)
			(end -0.508 -0.9398)
			(stroke
				(width 0.1524)
				(type default)
			)
			(layer "F.SilkS")
		)
		(fp_line
			(start -0.508 -0.9398)
			(end -0.508 0.9398)
			(stroke
				(width 0.1524)
				(type default)
			)
			(layer "F.SilkS")
		)
		(fp_rect
			(start -0.508 0.9398)
			(end 0.508 -0.9398)
			(stroke
				(width 0)
				(type default)
			)
			(fill no)
			(layer "F.CrtYd")
		)
		(fp_rect
			(start -0.508 0.9398)
			(end 0.508 -0.9398)
			(stroke
				(width 0)
				(type default)
			)
			(fill no)
			(layer "F.Fab")
		)
		(pad "1" smd custom
			(at 0 -0.4445 180)
			(size 0.1397 0.1397)
			(layers "F.Cu" "F.Mask" "F.Paste")
			(net "P3V3_STBY")
			(options
				(clearance outline)
				(anchor circle)
			)
			(primitives
				(gr_poly
					(pts
						(arc
							(start -0.1778 -0.2794)
							(mid -0.249642 -0.249642)
							(end -0.2794 -0.1778)
						)
						(arc
							(start -0.2794 0.1778)
							(mid -0.249642 0.249642)
							(end -0.1778 0.2794)
						)
						(arc
							(start 0.1778 0.2794)
							(mid 0.249642 0.249642)
							(end 0.2794 0.1778)
						)
						(arc
							(start 0.2794 -0.1778)
							(mid 0.249642 -0.249642)
							(end 0.1778 -0.2794)
						)
					)
					(width 0)
					(fill yes)
				)
			)
		)
		(pad "2" smd custom
			(at 0 0.4445 180)
			(size 0.1397 0.1397)
			(layers "F.Cu" "F.Mask" "F.Paste")
			(net "I2C6_BUFF_EN")
			(options
				(clearance outline)
				(anchor circle)
			)
			(primitives
				(gr_poly
					(pts
						(arc
							(start -0.1778 -0.2794)
							(mid -0.249642 -0.249642)
							(end -0.2794 -0.1778)
						)
						(arc
							(start -0.2794 0.1778)
							(mid -0.249642 0.249642)
							(end -0.1778 0.2794)
						)
						(arc
							(start 0.1778 0.2794)
							(mid 0.249642 0.249642)
							(end 0.2794 0.1778)
						)
						(arc
							(start 0.2794 -0.1778)
							(mid 0.249642 -0.249642)
							(end 0.1778 -0.2794)
						)
					)
					(width 0)
					(fill yes)
				)
			)
		)
	)
	(footprint ""
		(layer "F.Cu")
		(at 20.32 -102.9208)
		(property "Reference" "R2945"
			(at 0 0 0)
			(layer "F.SilkS")
			(hide yes)
			(effects
				(font
					(size 1.27 1.27)
				)
			)
		)
		(property "Value" "4K75R2F-1-GP"
			(at 0.064008 -3.993896 0)
			(unlocked yes)
			(layer "F.Fab")
			(hide yes)
			(effects
				(font
					(size 1.016 1.016)
					(thickness 0.1524)
				)
			)
		)
		(property "Device Type" "R402H16"
			(at 0.064008 -5.517896 0)
			(unlocked yes)
			(layer "F.Fab")
			(hide yes)
			(effects
				(font
					(size 1.016 1.016)
					(thickness 0.1524)
				)
			)
		)
		(duplicate_pad_numbers_are_jumpers no)
		(fp_line
			(start -0.508 -0.9398)
			(end -0.508 0.9398)
			(stroke
				(width 0.1524)
				(type default)
			)
			(layer "F.SilkS")
		)
		(fp_line
			(start 0.508 -0.9398)
			(end -0.508 -0.9398)
			(stroke
				(width 0.1524)
				(type default)
			)
			(layer "F.SilkS")
		)
		(fp_rect
			(start -0.508 0.9398)
			(end 0.508 -0.9398)
			(stroke
				(width 0)
				(type default)
			)
			(fill no)
			(layer "F.CrtYd")
		)
		(fp_rect
			(start -0.508 0.9398)
			(end 0.508 -0.9398)
			(stroke
				(width 0)
				(type default)
			)
			(fill no)
			(layer "F.Fab")
		)
		(pad "1" smd custom
			(at 0 -0.4445)
			(size 0.1397 0.1397)
			(layers "F.Cu" "F.Mask" "F.Paste")
			(net "P3V3_STBY")
			(options
				(clearance outline)
				(anchor circle)
			)
			(primitives
				(gr_poly
					(pts
						(arc
							(start -0.1778 -0.2794)
							(mid -0.249642 -0.249642)
							(end -0.2794 -0.1778)
						)
						(arc
							(start -0.2794 0.1778)
							(mid -0.249642 0.249642)
							(end -0.1778 0.2794)
						)
						(arc
							(start 0.1778 0.2794)
							(mid 0.249642 0.249642)
							(end 0.2794 0.1778)
						)
						(arc
							(start 0.2794 -0.1778)
							(mid 0.249642 -0.249642)
							(end 0.1778 -0.2794)
						)
					)
					(width 0)
					(fill yes)
				)
			)
		)
		(pad "2" smd custom
			(at 0 0.4445)
			(size 0.1397 0.1397)
			(layers "F.Cu" "F.Mask" "F.Paste")
			(net "VREF_2V2")
			(options
				(clearance outline)
				(anchor circle)
			)
			(primitives
				(gr_poly
					(pts
						(arc
							(start -0.1778 -0.2794)
							(mid -0.249642 -0.249642)
							(end -0.2794 -0.1778)
						)
						(arc
							(start -0.2794 0.1778)
							(mid -0.249642 0.249642)
							(end -0.1778 0.2794)
						)
						(arc
							(start 0.1778 0.2794)
							(mid 0.249642 0.249642)
							(end 0.2794 0.1778)
						)
						(arc
							(start 0.2794 -0.1778)
							(mid 0.249642 -0.249642)
							(end 0.1778 -0.2794)
						)
					)
					(width 0)
					(fill yes)
				)
			)
		)
	)
	(footprint ""
		(layer "F.Cu")
		(at 50.756566 -123.430538)
		(property "Reference" "TP173"
			(at 0 0 0)
			(layer "F.SilkS")
			(hide yes)
			(effects
				(font
					(size 1.27 1.27)
				)
			)
		)
		(property "Value" "TPAD28-2-GP"
			(at -0.0127 -1.6637 0)
			(unlocked yes)
			(layer "F.Fab")
			(hide yes)
			(effects
				(font
					(size 1.016 1.016)
					(thickness 0.1524)
				)
			)
		)
		(property "Device Type" "TPAD28"
			(at -0.0127 -3.1877 0)
			(unlocked yes)
			(layer "F.Fab")
			(hide yes)
			(effects
				(font
					(size 1.016 1.016)
					(thickness 0.1524)
				)
			)
		)
		(duplicate_pad_numbers_are_jumpers no)
		(fp_poly
			(pts
				(arc
					(start 0.3556 0)
					(mid -0.3556 0)
					(end 0.3556 0)
				)
			)
			(stroke
				(width 0)
				(type default)
			)
			(fill no)
			(layer "F.CrtYd")
		)
		(fp_poly
			(pts
				(arc
					(start 0.6096 0)
					(mid -0.6096 0)
					(end 0.6096 0)
				)
			)
			(stroke
				(width 0)
				(type default)
			)
			(fill no)
			(layer "F.Fab")
		)
		(pad "1" smd circle
			(at 0 0)
			(size 0.7112 0.7112)
			(layers "F.Cu" "F.Mask" "F.Paste")
			(net "JTAG_BMC_TDI")
		)
	)
	(footprint ""
		(layer "F.Cu")
		(at 239.395 -23.241 180)
		(property "Reference" "R781"
			(at 0 0 180)
			(layer "F.SilkS")
			(hide yes)
			(effects
				(font
					(size 1.27 1.27)
				)
			)
		)
		(property "Value" "4K7R2F-GP"
			(at 0.064008 -3.993896 180)
			(unlocked yes)
			(layer "F.Fab")
			(hide yes)
			(effects
				(font
					(size 1.016 1.016)
					(thickness 0.1524)
				)
			)
		)
		(property "Device Type" "R402H16"
			(at 0.064008 -5.517896 180)
			(unlocked yes)
			(layer "F.Fab")
			(hide yes)
			(effects
				(font
					(size 1.016 1.016)
					(thickness 0.1524)
				)
			)
		)
		(duplicate_pad_numbers_are_jumpers no)
		(fp_line
			(start 0.508 -0.9398)
			(end -0.508 -0.9398)
			(stroke
				(width 0.1524)
				(type default)
			)
			(layer "F.SilkS")
		)
		(fp_line
			(start -0.508 -0.9398)
			(end -0.508 0.9398)
			(stroke
				(width 0.1524)
				(type default)
			)
			(layer "F.SilkS")
		)
		(fp_rect
			(start -0.508 0.9398)
			(end 0.508 -0.9398)
			(stroke
				(width 0)
				(type default)
			)
			(fill no)
			(layer "F.CrtYd")
		)
		(fp_rect
			(start -0.508 0.9398)
			(end 0.508 -0.9398)
			(stroke
				(width 0)
				(type default)
			)
			(fill no)
			(layer "F.Fab")
		)
		(pad "1" smd custom
			(at 0 -0.4445 180)
			(size 0.1397 0.1397)
			(layers "F.Cu" "F.Mask" "F.Paste")
			(net "BOOTSTRAP1")
			(options
				(clearance outline)
				(anchor circle)
			)
			(primitives
				(gr_poly
					(pts
						(arc
							(start -0.1778 -0.2794)
							(mid -0.249642 -0.249642)
							(end -0.2794 -0.1778)
						)
						(arc
							(start -0.2794 0.1778)
							(mid -0.249642 0.249642)
							(end -0.1778 0.2794)
						)
						(arc
							(start 0.1778 0.2794)
							(mid 0.249642 0.249642)
							(end 0.2794 0.1778)
						)
						(arc
							(start 0.2794 -0.1778)
							(mid 0.249642 -0.249642)
							(end 0.1778 -0.2794)
						)
					)
					(width 0)
					(fill yes)
				)
			)
		)
		(pad "2" smd custom
			(at 0 0.4445 180)
			(size 0.1397 0.1397)
			(layers "F.Cu" "F.Mask" "F.Paste")
			(net "BOOTSTRAP_R_1")
			(options
				(clearance outline)
				(anchor circle)
			)
			(primitives
				(gr_poly
					(pts
						(arc
							(start -0.1778 -0.2794)
							(mid -0.249642 -0.249642)
							(end -0.2794 -0.1778)
						)
						(arc
							(start -0.2794 0.1778)
							(mid -0.249642 0.249642)
							(end -0.1778 0.2794)
						)
						(arc
							(start 0.1778 0.2794)
							(mid 0.249642 0.249642)
							(end 0.2794 0.1778)
						)
						(arc
							(start 0.2794 -0.1778)
							(mid 0.249642 -0.249642)
							(end 0.1778 -0.2794)
						)
					)
					(width 0)
					(fill yes)
				)
			)
		)
	)
	(footprint ""
		(layer "F.Cu")
		(at 28.079954 -162.162744 90)
		(property "Reference" "C272"
			(at 0 0 90)
			(layer "F.SilkS")
			(hide yes)
			(effects
				(font
					(size 1.27 1.27)
				)
			)
		)
		(property "Value" "SCD1U16V2KX-3GP"
			(at 1.1811 -2.7051 90)
			(unlocked yes)
			(layer "F.Fab")
			(hide yes)
			(effects
				(font
					(size 1.016 1.016)
					(thickness 0.1524)
				)
			)
		)
		(property "Device Type" "C402H22"
			(at 1.1811 -4.2291 90)
			(unlocked yes)
			(layer "F.Fab")
			(hide yes)
			(effects
				(font
					(size 1.016 1.016)
					(thickness 0.1524)
				)
			)
		)
		(duplicate_pad_numbers_are_jumpers no)
		(fp_rect
			(start -0.4318 0.9525)
			(end 0.4318 -0.9525)
			(stroke
				(width 0)
				(type default)
			)
			(fill no)
			(layer "F.CrtYd")
		)
		(fp_rect
			(start -0.4318 0.9525)
			(end 0.4318 -0.9525)
			(stroke
				(width 0)
				(type default)
			)
			(fill no)
			(layer "F.Fab")
		)
		(pad "1" smd custom
			(at 0 -0.4445 90)
			(size 0.1524 0.1524)
			(layers "F.Cu" "F.Mask" "F.Paste")
			(net "P3V3_STBY")
			(options
				(clearance outline)
				(anchor circle)
			)
			(primitives
				(gr_poly
					(pts
						(arc
							(start 0.3048 -0.2032)
							(mid 0.275042 -0.275042)
							(end 0.2032 -0.3048)
						)
						(arc
							(start -0.2032 -0.3048)
							(mid -0.275042 -0.275042)
							(end -0.3048 -0.2032)
						)
						(arc
							(start -0.3048 0.2032)
							(mid -0.275042 0.275042)
							(end -0.2032 0.3048)
						)
						(arc
							(start 0.2032 0.3048)
							(mid 0.275042 0.275042)
							(end 0.3048 0.2032)
						)
					)
					(width 0)
					(fill yes)
				)
			)
		)
		(pad "2" smd custom
			(at 0 0.4445 90)
			(size 0.1524 0.1524)
			(layers "F.Cu" "F.Mask" "F.Paste")
			(net "GND")
			(options
				(clearance outline)
				(anchor circle)
			)
			(primitives
				(gr_poly
					(pts
						(arc
							(start 0.3048 -0.2032)
							(mid 0.275042 -0.275042)
							(end 0.2032 -0.3048)
						)
						(arc
							(start -0.2032 -0.3048)
							(mid -0.275042 -0.275042)
							(end -0.3048 -0.2032)
						)
						(arc
							(start -0.3048 0.2032)
							(mid -0.275042 0.275042)
							(end -0.2032 0.3048)
						)
						(arc
							(start 0.2032 0.3048)
							(mid 0.275042 0.275042)
							(end 0.3048 0.2032)
						)
					)
					(width 0)
					(fill yes)
				)
			)
		)
	)
	(footprint ""
		(layer "F.Cu")
		(at 75.983592 -195.73367 180)
		(property "Reference" "R7931"
			(at 0 0 180)
			(layer "F.SilkS")
			(hide yes)
			(effects
				(font
					(size 1.27 1.27)
				)
			)
		)
		(property "Value" "0R2J-2-GP"
			(at 0.064008 -3.993896 180)
			(unlocked yes)
			(layer "F.Fab")
			(hide yes)
			(effects
				(font
					(size 1.016 1.016)
					(thickness 0.1524)
				)
			)
		)
		(property "Device Type" "R402H16"
			(at 0.064008 -5.517896 180)
			(unlocked yes)
			(layer "F.Fab")
			(hide yes)
			(effects
				(font
					(size 1.016 1.016)
					(thickness 0.1524)
				)
			)
		)
		(duplicate_pad_numbers_are_jumpers no)
		(fp_line
			(start 0.508 -0.9398)
			(end -0.508 -0.9398)
			(stroke
				(width 0.1524)
				(type default)
			)
			(layer "F.SilkS")
		)
		(fp_line
			(start -0.508 -0.9398)
			(end -0.508 0.9398)
			(stroke
				(width 0.1524)
				(type default)
			)
			(layer "F.SilkS")
		)
		(fp_rect
			(start -0.508 0.9398)
			(end 0.508 -0.9398)
			(stroke
				(width 0)
				(type default)
			)
			(fill no)
			(layer "F.CrtYd")
		)
		(fp_rect
			(start -0.508 0.9398)
			(end 0.508 -0.9398)
			(stroke
				(width 0)
				(type default)
			)
			(fill no)
			(layer "F.Fab")
		)
		(pad "1" smd custom
			(at 0 -0.4445 180)
			(size 0.1397 0.1397)
			(layers "F.Cu" "F.Mask" "F.Paste")
			(net "SSD_PRSNT#11")
			(options
				(clearance outline)
				(anchor circle)
			)
			(primitives
				(gr_poly
					(pts
						(arc
							(start -0.1778 -0.2794)
							(mid -0.249642 -0.249642)
							(end -0.2794 -0.1778)
						)
						(arc
							(start -0.2794 0.1778)
							(mid -0.249642 0.249642)
							(end -0.1778 0.2794)
						)
						(arc
							(start 0.1778 0.2794)
							(mid 0.249642 0.249642)
							(end 0.2794 0.1778)
						)
						(arc
							(start 0.2794 -0.1778)
							(mid 0.249642 -0.249642)
							(end 0.1778 -0.2794)
						)
					)
					(width 0)
					(fill yes)
				)
			)
		)
		(pad "2" smd custom
			(at 0 0.4445 180)
			(size 0.1397 0.1397)
			(layers "F.Cu" "F.Mask" "F.Paste")
			(net "SSD_PRSNT#11_R")
			(options
				(clearance outline)
				(anchor circle)
			)
			(primitives
				(gr_poly
					(pts
						(arc
							(start -0.1778 -0.2794)
							(mid -0.249642 -0.249642)
							(end -0.2794 -0.1778)
						)
						(arc
							(start -0.2794 0.1778)
							(mid -0.249642 0.249642)
							(end -0.1778 0.2794)
						)
						(arc
							(start 0.1778 0.2794)
							(mid 0.249642 0.249642)
							(end 0.2794 0.1778)
						)
						(arc
							(start 0.2794 -0.1778)
							(mid 0.249642 -0.249642)
							(end 0.1778 -0.2794)
						)
					)
					(width 0)
					(fill yes)
				)
			)
		)
	)
	(footprint ""
		(layer "F.Cu")
		(at 52.197 -185.293 -90)
		(property "Reference" "R898"
			(at 0 0 270)
			(layer "F.SilkS")
			(hide yes)
			(effects
				(font
					(size 1.27 1.27)
				)
			)
		)
		(property "Value" "4K7R2J-2-GP"
			(at 0.064008 -3.993896 270)
			(unlocked yes)
			(layer "F.Fab")
			(hide yes)
			(effects
				(font
					(size 1.016 1.016)
					(thickness 0.1524)
				)
			)
		)
		(property "Device Type" "R402H16"
			(at 0.064008 -5.517896 270)
			(unlocked yes)
			(layer "F.Fab")
			(hide yes)
			(effects
				(font
					(size 1.016 1.016)
					(thickness 0.1524)
				)
			)
		)
		(duplicate_pad_numbers_are_jumpers no)
		(fp_line
			(start -0.508 -0.9398)
			(end -0.508 0.9398)
			(stroke
				(width 0.1524)
				(type default)
			)
			(layer "F.SilkS")
		)
		(fp_line
			(start 0.508 -0.9398)
			(end -0.508 -0.9398)
			(stroke
				(width 0.1524)
				(type default)
			)
			(layer "F.SilkS")
		)
		(fp_rect
			(start -0.508 0.9398)
			(end 0.508 -0.9398)
			(stroke
				(width 0)
				(type default)
			)
			(fill no)
			(layer "F.CrtYd")
		)
		(fp_rect
			(start -0.508 0.9398)
			(end 0.508 -0.9398)
			(stroke
				(width 0)
				(type default)
			)
			(fill no)
			(layer "F.Fab")
		)
		(pad "1" smd custom
			(at 0 -0.4445 270)
			(size 0.1397 0.1397)
			(layers "F.Cu" "F.Mask" "F.Paste")
			(net "P3V3_STBY")
			(options
				(clearance outline)
				(anchor circle)
			)
			(primitives
				(gr_poly
					(pts
						(arc
							(start -0.1778 -0.2794)
							(mid -0.249642 -0.249642)
							(end -0.2794 -0.1778)
						)
						(arc
							(start -0.2794 0.1778)
							(mid -0.249642 0.249642)
							(end -0.1778 0.2794)
						)
						(arc
							(start 0.1778 0.2794)
							(mid 0.249642 0.249642)
							(end 0.2794 0.1778)
						)
						(arc
							(start 0.2794 -0.1778)
							(mid 0.249642 -0.249642)
							(end 0.1778 -0.2794)
						)
					)
					(width 0)
					(fill yes)
				)
			)
		)
		(pad "2" smd custom
			(at 0 0.4445 270)
			(size 0.1397 0.1397)
			(layers "F.Cu" "F.Mask" "F.Paste")
			(net "BUF_I2C8_CLKBUF1_SCL_R")
			(options
				(clearance outline)
				(anchor circle)
			)
			(primitives
				(gr_poly
					(pts
						(arc
							(start -0.1778 -0.2794)
							(mid -0.249642 -0.249642)
							(end -0.2794 -0.1778)
						)
						(arc
							(start -0.2794 0.1778)
							(mid -0.249642 0.249642)
							(end -0.1778 0.2794)
						)
						(arc
							(start 0.1778 0.2794)
							(mid 0.249642 0.249642)
							(end 0.2794 0.1778)
						)
						(arc
							(start 0.2794 -0.1778)
							(mid 0.249642 -0.249642)
							(end 0.1778 -0.2794)
						)
					)
					(width 0)
					(fill yes)
				)
			)
		)
	)
	(footprint ""
		(layer "F.Cu")
		(at 301.244 -57.0992)
		(property "Reference" "C426"
			(at 0 0 0)
			(layer "F.SilkS")
			(hide yes)
			(effects
				(font
					(size 1.27 1.27)
				)
			)
		)
		(property "Value" "SC10U16V5KX-1-GP"
			(at -0.0762 -6.1214 0)
			(unlocked yes)
			(layer "F.Fab")
			(hide yes)
			(effects
				(font
					(size 1.016 1.016)
					(thickness 0.1524)
				)
			)
		)
		(property "Device Type" "C805H54"
			(at -0.0762 -8.1534 0)
			(unlocked yes)
			(layer "F.Fab")
			(hide yes)
			(effects
				(font
					(size 1.016 1.016)
					(thickness 0.1524)
				)
			)
		)
		(duplicate_pad_numbers_are_jumpers no)
		(fp_line
			(start 0.635 0)
			(end -0.635 0)
			(stroke
				(width 0.508)
				(type default)
			)
			(layer "F.SilkS")
		)
		(fp_rect
			(start -0.9652 1.778)
			(end 0.9652 -1.778)
			(stroke
				(width 0)
				(type default)
			)
			(fill no)
			(layer "F.CrtYd")
		)
		(fp_poly
			(pts
				(xy -0.9652 -1.778) (xy 0.9652 -1.778) (xy 0.9652 1.778) (xy -0.9652 1.778)
			)
			(stroke
				(width 0)
				(type default)
			)
			(fill no)
			(layer "F.Fab")
		)
		(pad "1" smd rect
			(at 0 -0.9652)
			(size 1.397 1.143)
			(layers "F.Cu" "F.Mask" "F.Paste")
			(net "DUT_VDD")
		)
		(pad "2" smd rect
			(at 0 0.9652)
			(size 1.397 1.143)
			(layers "F.Cu" "F.Mask" "F.Paste")
			(net "GND")
		)
	)
	(footprint ""
		(layer "F.Cu")
		(at 63.5254 -86.2838 90)
		(property "Reference" "R480"
			(at 0 0 90)
			(layer "F.SilkS")
			(hide yes)
			(effects
				(font
					(size 1.27 1.27)
				)
			)
		)
		(property "Value" "10KR2F-2-GP"
			(at 0.064008 -3.993896 90)
			(unlocked yes)
			(layer "F.Fab")
			(hide yes)
			(effects
				(font
					(size 1.016 1.016)
					(thickness 0.1524)
				)
			)
		)
		(property "Device Type" "R402H16"
			(at 0.064008 -5.517896 90)
			(unlocked yes)
			(layer "F.Fab")
			(hide yes)
			(effects
				(font
					(size 1.016 1.016)
					(thickness 0.1524)
				)
			)
		)
		(duplicate_pad_numbers_are_jumpers no)
		(fp_line
			(start 0.508 -0.9398)
			(end -0.508 -0.9398)
			(stroke
				(width 0.1524)
				(type default)
			)
			(layer "F.SilkS")
		)
		(fp_line
			(start -0.508 -0.9398)
			(end -0.508 0.9398)
			(stroke
				(width 0.1524)
				(type default)
			)
			(layer "F.SilkS")
		)
		(fp_rect
			(start -0.508 0.9398)
			(end 0.508 -0.9398)
			(stroke
				(width 0)
				(type default)
			)
			(fill no)
			(layer "F.CrtYd")
		)
		(fp_rect
			(start -0.508 0.9398)
			(end 0.508 -0.9398)
			(stroke
				(width 0)
				(type default)
			)
			(fill no)
			(layer "F.Fab")
		)
		(pad "1" smd custom
			(at 0 -0.4445 90)
			(size 0.1397 0.1397)
			(layers "F.Cu" "F.Mask" "F.Paste")
			(net "P3V3_STBY")
			(options
				(clearance outline)
				(anchor circle)
			)
			(primitives
				(gr_poly
					(pts
						(arc
							(start -0.1778 -0.2794)
							(mid -0.249642 -0.249642)
							(end -0.2794 -0.1778)
						)
						(arc
							(start -0.2794 0.1778)
							(mid -0.249642 0.249642)
							(end -0.1778 0.2794)
						)
						(arc
							(start 0.1778 0.2794)
							(mid 0.249642 0.249642)
							(end 0.2794 0.1778)
						)
						(arc
							(start 0.2794 -0.1778)
							(mid 0.249642 -0.249642)
							(end 0.1778 -0.2794)
						)
					)
					(width 0)
					(fill yes)
				)
			)
		)
		(pad "2" smd custom
			(at 0 0.4445 90)
			(size 0.1397 0.1397)
			(layers "F.Cu" "F.Mask" "F.Paste")
			(net "INVERTER_G2")
			(options
				(clearance outline)
				(anchor circle)
			)
			(primitives
				(gr_poly
					(pts
						(arc
							(start -0.1778 -0.2794)
							(mid -0.249642 -0.249642)
							(end -0.2794 -0.1778)
						)
						(arc
							(start -0.2794 0.1778)
							(mid -0.249642 0.249642)
							(end -0.1778 0.2794)
						)
						(arc
							(start 0.1778 0.2794)
							(mid 0.249642 0.249642)
							(end 0.2794 0.1778)
						)
						(arc
							(start 0.2794 -0.1778)
							(mid 0.249642 -0.249642)
							(end 0.1778 -0.2794)
						)
					)
					(width 0)
					(fill yes)
				)
			)
		)
	)
	(footprint ""
		(layer "F.Cu")
		(at 195.3768 -18.796 90)
		(property "Reference" "R566"
			(at 0 0 90)
			(layer "F.SilkS")
			(hide yes)
			(effects
				(font
					(size 1.27 1.27)
				)
			)
		)
		(property "Value" "4K7R2F-GP"
			(at 0.064008 -3.993896 90)
			(unlocked yes)
			(layer "F.Fab")
			(hide yes)
			(effects
				(font
					(size 1.016 1.016)
					(thickness 0.1524)
				)
			)
		)
		(property "Device Type" "R402H16"
			(at 0.064008 -5.517896 90)
			(unlocked yes)
			(layer "F.Fab")
			(hide yes)
			(effects
				(font
					(size 1.016 1.016)
					(thickness 0.1524)
				)
			)
		)
		(duplicate_pad_numbers_are_jumpers no)
		(fp_line
			(start 0.508 -0.9398)
			(end -0.508 -0.9398)
			(stroke
				(width 0.1524)
				(type default)
			)
			(layer "F.SilkS")
		)
		(fp_line
			(start -0.508 -0.9398)
			(end -0.508 0.9398)
			(stroke
				(width 0.1524)
				(type default)
			)
			(layer "F.SilkS")
		)
		(fp_rect
			(start -0.508 0.9398)
			(end 0.508 -0.9398)
			(stroke
				(width 0)
				(type default)
			)
			(fill no)
			(layer "F.CrtYd")
		)
		(fp_rect
			(start -0.508 0.9398)
			(end 0.508 -0.9398)
			(stroke
				(width 0)
				(type default)
			)
			(fill no)
			(layer "F.Fab")
		)
		(pad "1" smd custom
			(at 0 -0.4445 90)
			(size 0.1397 0.1397)
			(layers "F.Cu" "F.Mask" "F.Paste")
			(net "MINISAS_CN15_D_I2C_INT#")
			(options
				(clearance outline)
				(anchor circle)
			)
			(primitives
				(gr_poly
					(pts
						(arc
							(start -0.1778 -0.2794)
							(mid -0.249642 -0.249642)
							(end -0.2794 -0.1778)
						)
						(arc
							(start -0.2794 0.1778)
							(mid -0.249642 0.249642)
							(end -0.1778 0.2794)
						)
						(arc
							(start 0.1778 0.2794)
							(mid 0.249642 0.249642)
							(end 0.2794 0.1778)
						)
						(arc
							(start 0.2794 -0.1778)
							(mid 0.249642 -0.249642)
							(end 0.1778 -0.2794)
						)
					)
					(width 0)
					(fill yes)
				)
			)
		)
		(pad "2" smd custom
			(at 0 0.4445 90)
			(size 0.1397 0.1397)
			(layers "F.Cu" "F.Mask" "F.Paste")
			(net "P3V3_STBY")
			(options
				(clearance outline)
				(anchor circle)
			)
			(primitives
				(gr_poly
					(pts
						(arc
							(start -0.1778 -0.2794)
							(mid -0.249642 -0.249642)
							(end -0.2794 -0.1778)
						)
						(arc
							(start -0.2794 0.1778)
							(mid -0.249642 0.249642)
							(end -0.1778 0.2794)
						)
						(arc
							(start 0.1778 0.2794)
							(mid 0.249642 0.249642)
							(end 0.2794 0.1778)
						)
						(arc
							(start 0.2794 -0.1778)
							(mid 0.249642 -0.249642)
							(end 0.1778 -0.2794)
						)
					)
					(width 0)
					(fill yes)
				)
			)
		)
	)
	(footprint ""
		(layer "F.Cu")
		(at 134.1374 -196.4182)
		(property "Reference" "R9031"
			(at 0 0 0)
			(layer "F.SilkS")
			(hide yes)
			(effects
				(font
					(size 1.27 1.27)
				)
			)
		)
		(property "Value" "4K7R2F-GP"
			(at 0.064008 -3.993896 0)
			(unlocked yes)
			(layer "F.Fab")
			(hide yes)
			(effects
				(font
					(size 1.016 1.016)
					(thickness 0.1524)
				)
			)
		)
		(property "Device Type" "R402H16"
			(at 0.064008 -5.517896 0)
			(unlocked yes)
			(layer "F.Fab")
			(hide yes)
			(effects
				(font
					(size 1.016 1.016)
					(thickness 0.1524)
				)
			)
		)
		(duplicate_pad_numbers_are_jumpers no)
		(fp_line
			(start -0.508 -0.9398)
			(end -0.508 0.9398)
			(stroke
				(width 0.1524)
				(type default)
			)
			(layer "F.SilkS")
		)
		(fp_line
			(start 0.508 -0.9398)
			(end -0.508 -0.9398)
			(stroke
				(width 0.1524)
				(type default)
			)
			(layer "F.SilkS")
		)
		(fp_rect
			(start -0.508 0.9398)
			(end 0.508 -0.9398)
			(stroke
				(width 0)
				(type default)
			)
			(fill no)
			(layer "F.CrtYd")
		)
		(fp_rect
			(start -0.508 0.9398)
			(end 0.508 -0.9398)
			(stroke
				(width 0)
				(type default)
			)
			(fill no)
			(layer "F.Fab")
		)
		(pad "1" smd custom
			(at 0 -0.4445)
			(size 0.1397 0.1397)
			(layers "F.Cu" "F.Mask" "F.Paste")
			(net "SSD_PERST#2")
			(options
				(clearance outline)
				(anchor circle)
			)
			(primitives
				(gr_poly
					(pts
						(arc
							(start -0.1778 -0.2794)
							(mid -0.249642 -0.249642)
							(end -0.2794 -0.1778)
						)
						(arc
							(start -0.2794 0.1778)
							(mid -0.249642 0.249642)
							(end -0.1778 0.2794)
						)
						(arc
							(start 0.1778 0.2794)
							(mid 0.249642 0.249642)
							(end 0.2794 0.1778)
						)
						(arc
							(start 0.2794 -0.1778)
							(mid 0.249642 -0.249642)
							(end 0.1778 -0.2794)
						)
					)
					(width 0)
					(fill yes)
				)
			)
		)
		(pad "2" smd custom
			(at 0 0.4445)
			(size 0.1397 0.1397)
			(layers "F.Cu" "F.Mask" "F.Paste")
			(net "GND")
			(options
				(clearance outline)
				(anchor circle)
			)
			(primitives
				(gr_poly
					(pts
						(arc
							(start -0.1778 -0.2794)
							(mid -0.249642 -0.249642)
							(end -0.2794 -0.1778)
						)
						(arc
							(start -0.2794 0.1778)
							(mid -0.249642 0.249642)
							(end -0.1778 0.2794)
						)
						(arc
							(start 0.1778 0.2794)
							(mid 0.249642 0.249642)
							(end 0.2794 0.1778)
						)
						(arc
							(start 0.2794 -0.1778)
							(mid 0.249642 -0.249642)
							(end 0.1778 -0.2794)
						)
					)
					(width 0)
					(fill yes)
				)
			)
		)
	)
	(footprint ""
		(layer "F.Cu")
		(at 218.797124 -190.601092 180)
		(property "Reference" "R550"
			(at 0 0 180)
			(layer "F.SilkS")
			(hide yes)
			(effects
				(font
					(size 1.27 1.27)
				)
			)
		)
		(property "Value" "10KR2F-2-GP"
			(at 0.064008 -3.993896 180)
			(unlocked yes)
			(layer "F.Fab")
			(hide yes)
			(effects
				(font
					(size 1.016 1.016)
					(thickness 0.1524)
				)
			)
		)
		(property "Device Type" "R402H16"
			(at 0.064008 -5.517896 180)
			(unlocked yes)
			(layer "F.Fab")
			(hide yes)
			(effects
				(font
					(size 1.016 1.016)
					(thickness 0.1524)
				)
			)
		)
		(duplicate_pad_numbers_are_jumpers no)
		(fp_line
			(start 0.508 -0.9398)
			(end -0.508 -0.9398)
			(stroke
				(width 0.1524)
				(type default)
			)
			(layer "F.SilkS")
		)
		(fp_line
			(start -0.508 -0.9398)
			(end -0.508 0.9398)
			(stroke
				(width 0.1524)
				(type default)
			)
			(layer "F.SilkS")
		)
		(fp_rect
			(start -0.508 0.9398)
			(end 0.508 -0.9398)
			(stroke
				(width 0)
				(type default)
			)
			(fill no)
			(layer "F.CrtYd")
		)
		(fp_rect
			(start -0.508 0.9398)
			(end 0.508 -0.9398)
			(stroke
				(width 0)
				(type default)
			)
			(fill no)
			(layer "F.Fab")
		)
		(pad "1" smd custom
			(at 0 -0.4445 180)
			(size 0.1397 0.1397)
			(layers "F.Cu" "F.Mask" "F.Paste")
			(net "GND")
			(options
				(clearance outline)
				(anchor circle)
			)
			(primitives
				(gr_poly
					(pts
						(arc
							(start -0.1778 -0.2794)
							(mid -0.249642 -0.249642)
							(end -0.2794 -0.1778)
						)
						(arc
							(start -0.2794 0.1778)
							(mid -0.249642 0.249642)
							(end -0.1778 0.2794)
						)
						(arc
							(start 0.1778 0.2794)
							(mid 0.249642 0.249642)
							(end 0.2794 0.1778)
						)
						(arc
							(start 0.2794 -0.1778)
							(mid 0.249642 -0.249642)
							(end 0.1778 -0.2794)
						)
					)
					(width 0)
					(fill yes)
				)
			)
		)
		(pad "2" smd custom
			(at 0 0.4445 180)
			(size 0.1397 0.1397)
			(layers "F.Cu" "F.Mask" "F.Paste")
			(net "IOEXP3_AD2")
			(options
				(clearance outline)
				(anchor circle)
			)
			(primitives
				(gr_poly
					(pts
						(arc
							(start -0.1778 -0.2794)
							(mid -0.249642 -0.249642)
							(end -0.2794 -0.1778)
						)
						(arc
							(start -0.2794 0.1778)
							(mid -0.249642 0.249642)
							(end -0.1778 0.2794)
						)
						(arc
							(start 0.1778 0.2794)
							(mid 0.249642 0.249642)
							(end 0.2794 0.1778)
						)
						(arc
							(start 0.2794 -0.1778)
							(mid 0.249642 -0.249642)
							(end 0.1778 -0.2794)
						)
					)
					(width 0)
					(fill yes)
				)
			)
		)
	)
	(footprint ""
		(layer "F.Cu")
		(at 183.0578 -4.23418)
		(property "Reference" "R2951"
			(at 0 0 0)
			(layer "F.SilkS")
			(hide yes)
			(effects
				(font
					(size 1.27 1.27)
				)
			)
		)
		(property "Value" "0R2J-2-GP"
			(at 0.064008 -3.993896 0)
			(unlocked yes)
			(layer "F.Fab")
			(hide yes)
			(effects
				(font
					(size 1.016 1.016)
					(thickness 0.1524)
				)
			)
		)
		(property "Device Type" "R402H16"
			(at 0.064008 -5.517896 0)
			(unlocked yes)
			(layer "F.Fab")
			(hide yes)
			(effects
				(font
					(size 1.016 1.016)
					(thickness 0.1524)
				)
			)
		)
		(duplicate_pad_numbers_are_jumpers no)
		(fp_line
			(start -0.508 -0.9398)
			(end -0.508 0.9398)
			(stroke
				(width 0.1524)
				(type default)
			)
			(layer "F.SilkS")
		)
		(fp_line
			(start 0.508 -0.9398)
			(end -0.508 -0.9398)
			(stroke
				(width 0.1524)
				(type default)
			)
			(layer "F.SilkS")
		)
		(fp_rect
			(start -0.508 0.9398)
			(end 0.508 -0.9398)
			(stroke
				(width 0)
				(type default)
			)
			(fill no)
			(layer "F.CrtYd")
		)
		(fp_rect
			(start -0.508 0.9398)
			(end 0.508 -0.9398)
			(stroke
				(width 0)
				(type default)
			)
			(fill no)
			(layer "F.Fab")
		)
		(pad "1" smd custom
			(at 0 -0.4445)
			(size 0.1397 0.1397)
			(layers "F.Cu" "F.Mask" "F.Paste")
			(net "HOST3_RST_N")
			(options
				(clearance outline)
				(anchor circle)
			)
			(primitives
				(gr_poly
					(pts
						(arc
							(start -0.1778 -0.2794)
							(mid -0.249642 -0.249642)
							(end -0.2794 -0.1778)
						)
						(arc
							(start -0.2794 0.1778)
							(mid -0.249642 0.249642)
							(end -0.1778 0.2794)
						)
						(arc
							(start 0.1778 0.2794)
							(mid 0.249642 0.249642)
							(end 0.2794 0.1778)
						)
						(arc
							(start 0.2794 -0.1778)
							(mid 0.249642 -0.249642)
							(end 0.1778 -0.2794)
						)
					)
					(width 0)
					(fill yes)
				)
			)
		)
		(pad "2" smd custom
			(at 0 0.4445)
			(size 0.1397 0.1397)
			(layers "F.Cu" "F.Mask" "F.Paste")
			(net "HOST3_RST_N_C")
			(options
				(clearance outline)
				(anchor circle)
			)
			(primitives
				(gr_poly
					(pts
						(arc
							(start -0.1778 -0.2794)
							(mid -0.249642 -0.249642)
							(end -0.2794 -0.1778)
						)
						(arc
							(start -0.2794 0.1778)
							(mid -0.249642 0.249642)
							(end -0.1778 0.2794)
						)
						(arc
							(start 0.1778 0.2794)
							(mid 0.249642 0.249642)
							(end 0.2794 0.1778)
						)
						(arc
							(start 0.2794 -0.1778)
							(mid 0.249642 -0.249642)
							(end 0.1778 -0.2794)
						)
					)
					(width 0)
					(fill yes)
				)
			)
		)
	)
	(footprint ""
		(layer "F.Cu")
		(at 23.876 -133.731 90)
		(property "Reference" "R343"
			(at 0 0 90)
			(layer "F.SilkS")
			(hide yes)
			(effects
				(font
					(size 1.27 1.27)
				)
			)
		)
		(property "Value" "3K3R2F-2-GP"
			(at 0.064008 -3.993896 90)
			(unlocked yes)
			(layer "F.Fab")
			(hide yes)
			(effects
				(font
					(size 1.016 1.016)
					(thickness 0.1524)
				)
			)
		)
		(property "Device Type" "R402H16"
			(at 0.064008 -5.517896 90)
			(unlocked yes)
			(layer "F.Fab")
			(hide yes)
			(effects
				(font
					(size 1.016 1.016)
					(thickness 0.1524)
				)
			)
		)
		(duplicate_pad_numbers_are_jumpers no)
		(fp_line
			(start 0.508 -0.9398)
			(end -0.508 -0.9398)
			(stroke
				(width 0.1524)
				(type default)
			)
			(layer "F.SilkS")
		)
		(fp_line
			(start -0.508 -0.9398)
			(end -0.508 0.9398)
			(stroke
				(width 0.1524)
				(type default)
			)
			(layer "F.SilkS")
		)
		(fp_rect
			(start -0.508 0.9398)
			(end 0.508 -0.9398)
			(stroke
				(width 0)
				(type default)
			)
			(fill no)
			(layer "F.CrtYd")
		)
		(fp_rect
			(start -0.508 0.9398)
			(end 0.508 -0.9398)
			(stroke
				(width 0)
				(type default)
			)
			(fill no)
			(layer "F.Fab")
		)
		(pad "1" smd custom
			(at 0 -0.4445 90)
			(size 0.1397 0.1397)
			(layers "F.Cu" "F.Mask" "F.Paste")
			(net "P3V3_STBY")
			(options
				(clearance outline)
				(anchor circle)
			)
			(primitives
				(gr_poly
					(pts
						(arc
							(start -0.1778 -0.2794)
							(mid -0.249642 -0.249642)
							(end -0.2794 -0.1778)
						)
						(arc
							(start -0.2794 0.1778)
							(mid -0.249642 0.249642)
							(end -0.1778 0.2794)
						)
						(arc
							(start 0.1778 0.2794)
							(mid 0.249642 0.249642)
							(end 0.2794 0.1778)
						)
						(arc
							(start 0.2794 -0.1778)
							(mid 0.249642 -0.249642)
							(end 0.1778 -0.2794)
						)
					)
					(width 0)
					(fill yes)
				)
			)
		)
		(pad "2" smd custom
			(at 0 0.4445 90)
			(size 0.1397 0.1397)
			(layers "F.Cu" "F.Mask" "F.Paste")
			(net "ROMA1")
			(options
				(clearance outline)
				(anchor circle)
			)
			(primitives
				(gr_poly
					(pts
						(arc
							(start -0.1778 -0.2794)
							(mid -0.249642 -0.249642)
							(end -0.2794 -0.1778)
						)
						(arc
							(start -0.2794 0.1778)
							(mid -0.249642 0.249642)
							(end -0.1778 0.2794)
						)
						(arc
							(start 0.1778 0.2794)
							(mid 0.249642 0.249642)
							(end 0.2794 0.1778)
						)
						(arc
							(start 0.2794 -0.1778)
							(mid 0.249642 -0.249642)
							(end 0.1778 -0.2794)
						)
					)
					(width 0)
					(fill yes)
				)
			)
		)
	)
	(footprint ""
		(layer "F.Cu")
		(at 11.654028 -72.933814 -90)
		(property "Reference" "TP157"
			(at 0 0 270)
			(layer "F.SilkS")
			(hide yes)
			(effects
				(font
					(size 1.27 1.27)
				)
			)
		)
		(property "Value" "TPAD28-2-GP"
			(at -0.0127 -1.6637 270)
			(unlocked yes)
			(layer "F.Fab")
			(hide yes)
			(effects
				(font
					(size 1.016 1.016)
					(thickness 0.1524)
				)
			)
		)
		(property "Device Type" "TPAD28"
			(at -0.0127 -3.1877 270)
			(unlocked yes)
			(layer "F.Fab")
			(hide yes)
			(effects
				(font
					(size 1.016 1.016)
					(thickness 0.1524)
				)
			)
		)
		(duplicate_pad_numbers_are_jumpers no)
		(fp_poly
			(pts
				(arc
					(start 0 -0.3556)
					(mid 0 0.3556)
					(end 0 -0.3556)
				)
			)
			(stroke
				(width 0)
				(type default)
			)
			(fill no)
			(layer "F.CrtYd")
		)
		(fp_poly
			(pts
				(arc
					(start 0 -0.6096)
					(mid 0 0.6096)
					(end 0 -0.6096)
				)
			)
			(stroke
				(width 0)
				(type default)
			)
			(fill no)
			(layer "F.Fab")
		)
		(pad "1" smd circle
			(at 0 0 270)
			(size 0.7112 0.7112)
			(layers "F.Cu" "F.Mask" "F.Paste")
			(net "NCSI_ARB_OUT")
		)
	)
	(footprint ""
		(layer "F.Cu")
		(at 330.835 -86.487)
		(property "Reference" "R4174"
			(at 0 0 0)
			(layer "F.SilkS")
			(hide yes)
			(effects
				(font
					(size 1.27 1.27)
				)
			)
		)
		(property "Value" "4K7R2F-GP"
			(at 0.064008 -3.993896 0)
			(unlocked yes)
			(layer "F.Fab")
			(hide yes)
			(effects
				(font
					(size 1.016 1.016)
					(thickness 0.1524)
				)
			)
		)
		(property "Device Type" "R402H16"
			(at 0.064008 -5.517896 0)
			(unlocked yes)
			(layer "F.Fab")
			(hide yes)
			(effects
				(font
					(size 1.016 1.016)
					(thickness 0.1524)
				)
			)
		)
		(duplicate_pad_numbers_are_jumpers no)
		(fp_line
			(start -0.508 -0.9398)
			(end -0.508 0.9398)
			(stroke
				(width 0.1524)
				(type default)
			)
			(layer "F.SilkS")
		)
		(fp_line
			(start 0.508 -0.9398)
			(end -0.508 -0.9398)
			(stroke
				(width 0.1524)
				(type default)
			)
			(layer "F.SilkS")
		)
		(fp_rect
			(start -0.508 0.9398)
			(end 0.508 -0.9398)
			(stroke
				(width 0)
				(type default)
			)
			(fill no)
			(layer "F.CrtYd")
		)
		(fp_rect
			(start -0.508 0.9398)
			(end 0.508 -0.9398)
			(stroke
				(width 0)
				(type default)
			)
			(fill no)
			(layer "F.Fab")
		)
		(pad "1" smd custom
			(at 0 -0.4445)
			(size 0.1397 0.1397)
			(layers "F.Cu" "F.Mask" "F.Paste")
			(net "UPLINK8")
			(options
				(clearance outline)
				(anchor circle)
			)
			(primitives
				(gr_poly
					(pts
						(arc
							(start -0.1778 -0.2794)
							(mid -0.249642 -0.249642)
							(end -0.2794 -0.1778)
						)
						(arc
							(start -0.2794 0.1778)
							(mid -0.249642 0.249642)
							(end -0.1778 0.2794)
						)
						(arc
							(start 0.1778 0.2794)
							(mid 0.249642 0.249642)
							(end 0.2794 0.1778)
						)
						(arc
							(start 0.2794 -0.1778)
							(mid 0.249642 -0.249642)
							(end 0.1778 -0.2794)
						)
					)
					(width 0)
					(fill yes)
				)
			)
		)
		(pad "2" smd custom
			(at 0 0.4445)
			(size 0.1397 0.1397)
			(layers "F.Cu" "F.Mask" "F.Paste")
			(net "P3V3_STBY")
			(options
				(clearance outline)
				(anchor circle)
			)
			(primitives
				(gr_poly
					(pts
						(arc
							(start -0.1778 -0.2794)
							(mid -0.249642 -0.249642)
							(end -0.2794 -0.1778)
						)
						(arc
							(start -0.2794 0.1778)
							(mid -0.249642 0.249642)
							(end -0.1778 0.2794)
						)
						(arc
							(start 0.1778 0.2794)
							(mid 0.249642 0.249642)
							(end 0.2794 0.1778)
						)
						(arc
							(start 0.2794 -0.1778)
							(mid 0.249642 -0.249642)
							(end 0.1778 -0.2794)
						)
					)
					(width 0)
					(fill yes)
				)
			)
		)
	)
	(footprint ""
		(layer "F.Cu")
		(at 17.653 -111.379 90)
		(property "Reference" "PC79"
			(at 0 0 90)
			(layer "F.SilkS")
			(hide yes)
			(effects
				(font
					(size 1.27 1.27)
				)
			)
		)
		(property "Value" "SC22U6D3V5MX-5-GP"
			(at -0.0762 -6.1214 90)
			(unlocked yes)
			(layer "F.Fab")
			(hide yes)
			(effects
				(font
					(size 1.016 1.016)
					(thickness 0.1524)
				)
			)
		)
		(property "Device Type" "C805H56"
			(at -0.0762 -8.1534 90)
			(unlocked yes)
			(layer "F.Fab")
			(hide yes)
			(effects
				(font
					(size 1.016 1.016)
					(thickness 0.1524)
				)
			)
		)
		(duplicate_pad_numbers_are_jumpers no)
		(fp_line
			(start 0.635 0)
			(end -0.635 0)
			(stroke
				(width 0.508)
				(type default)
			)
			(layer "F.SilkS")
		)
		(fp_rect
			(start -0.9652 1.778)
			(end 0.9652 -1.778)
			(stroke
				(width 0)
				(type default)
			)
			(fill no)
			(layer "F.CrtYd")
		)
		(fp_poly
			(pts
				(xy -0.9652 -1.778) (xy 0.9652 -1.778) (xy 0.9652 1.778) (xy -0.9652 1.778)
			)
			(stroke
				(width 0)
				(type default)
			)
			(fill no)
			(layer "F.Fab")
		)
		(pad "1" smd rect
			(at 0 -0.9652 90)
			(size 1.397 1.143)
			(layers "F.Cu" "F.Mask" "F.Paste")
			(net "P1V26_PWR")
		)
		(pad "2" smd rect
			(at 0 0.9652 90)
			(size 1.397 1.143)
			(layers "F.Cu" "F.Mask" "F.Paste")
			(net "GND")
		)
	)
	(footprint ""
		(layer "F.Cu")
		(at 26.415492 -87.0077)
		(property "Reference" "R372"
			(at 0 0 0)
			(layer "F.SilkS")
			(hide yes)
			(effects
				(font
					(size 1.27 1.27)
				)
			)
		)
		(property "Value" "0R2J-2-GP"
			(at 0.064008 -3.993896 0)
			(unlocked yes)
			(layer "F.Fab")
			(hide yes)
			(effects
				(font
					(size 1.016 1.016)
					(thickness 0.1524)
				)
			)
		)
		(property "Device Type" "R402H16"
			(at 0.064008 -5.517896 0)
			(unlocked yes)
			(layer "F.Fab")
			(hide yes)
			(effects
				(font
					(size 1.016 1.016)
					(thickness 0.1524)
				)
			)
		)
		(duplicate_pad_numbers_are_jumpers no)
		(fp_line
			(start -0.508 -0.9398)
			(end -0.508 0.9398)
			(stroke
				(width 0.1524)
				(type default)
			)
			(layer "F.SilkS")
		)
		(fp_line
			(start 0.508 -0.9398)
			(end -0.508 -0.9398)
			(stroke
				(width 0.1524)
				(type default)
			)
			(layer "F.SilkS")
		)
		(fp_rect
			(start -0.508 0.9398)
			(end 0.508 -0.9398)
			(stroke
				(width 0)
				(type default)
			)
			(fill no)
			(layer "F.CrtYd")
		)
		(fp_rect
			(start -0.508 0.9398)
			(end 0.508 -0.9398)
			(stroke
				(width 0)
				(type default)
			)
			(fill no)
			(layer "F.Fab")
		)
		(pad "1" smd custom
			(at 0 -0.4445)
			(size 0.1397 0.1397)
			(layers "F.Cu" "F.Mask" "F.Paste")
			(net "I210_PERST_N")
			(options
				(clearance outline)
				(anchor circle)
			)
			(primitives
				(gr_poly
					(pts
						(arc
							(start -0.1778 -0.2794)
							(mid -0.249642 -0.249642)
							(end -0.2794 -0.1778)
						)
						(arc
							(start -0.2794 0.1778)
							(mid -0.249642 0.249642)
							(end -0.1778 0.2794)
						)
						(arc
							(start 0.1778 0.2794)
							(mid 0.249642 0.249642)
							(end 0.2794 0.1778)
						)
						(arc
							(start 0.2794 -0.1778)
							(mid 0.249642 -0.249642)
							(end 0.1778 -0.2794)
						)
					)
					(width 0)
					(fill yes)
				)
			)
		)
		(pad "2" smd custom
			(at 0 0.4445)
			(size 0.1397 0.1397)
			(layers "F.Cu" "F.Mask" "F.Paste")
			(net "PHY_RESET_N")
			(options
				(clearance outline)
				(anchor circle)
			)
			(primitives
				(gr_poly
					(pts
						(arc
							(start -0.1778 -0.2794)
							(mid -0.249642 -0.249642)
							(end -0.2794 -0.1778)
						)
						(arc
							(start -0.2794 0.1778)
							(mid -0.249642 0.249642)
							(end -0.1778 0.2794)
						)
						(arc
							(start 0.1778 0.2794)
							(mid 0.249642 0.249642)
							(end 0.2794 0.1778)
						)
						(arc
							(start 0.2794 -0.1778)
							(mid 0.249642 -0.249642)
							(end 0.1778 -0.2794)
						)
					)
					(width 0)
					(fill yes)
				)
			)
		)
	)
	(footprint ""
		(layer "F.Cu")
		(at 331.216 -3.683)
		(property "Reference" "SR713"
			(at 0 0 0)
			(layer "F.SilkS")
			(hide yes)
			(effects
				(font
					(size 1.27 1.27)
				)
			)
		)
		(property "Value" "150R2F-1-GP"
			(at 0.064008 -3.993896 0)
			(unlocked yes)
			(layer "F.Fab")
			(hide yes)
			(effects
				(font
					(size 1.016 1.016)
					(thickness 0.1524)
				)
			)
		)
		(property "Device Type" "R402H16"
			(at 0.064008 -5.517896 0)
			(unlocked yes)
			(layer "F.Fab")
			(hide yes)
			(effects
				(font
					(size 1.016 1.016)
					(thickness 0.1524)
				)
			)
		)
		(duplicate_pad_numbers_are_jumpers no)
		(fp_line
			(start -0.508 -0.9398)
			(end -0.508 0.9398)
			(stroke
				(width 0.1524)
				(type default)
			)
			(layer "F.SilkS")
		)
		(fp_line
			(start 0.508 -0.9398)
			(end -0.508 -0.9398)
			(stroke
				(width 0.1524)
				(type default)
			)
			(layer "F.SilkS")
		)
		(fp_rect
			(start -0.508 0.9398)
			(end 0.508 -0.9398)
			(stroke
				(width 0)
				(type default)
			)
			(fill no)
			(layer "F.CrtYd")
		)
		(fp_rect
			(start -0.508 0.9398)
			(end 0.508 -0.9398)
			(stroke
				(width 0)
				(type default)
			)
			(fill no)
			(layer "F.Fab")
		)
		(pad "1" smd custom
			(at 0 -0.4445)
			(size 0.1397 0.1397)
			(layers "F.Cu" "F.Mask" "F.Paste")
			(net "P3V3_STBY")
			(options
				(clearance outline)
				(anchor circle)
			)
			(primitives
				(gr_poly
					(pts
						(arc
							(start -0.1778 -0.2794)
							(mid -0.249642 -0.249642)
							(end -0.2794 -0.1778)
						)
						(arc
							(start -0.2794 0.1778)
							(mid -0.249642 0.249642)
							(end -0.1778 0.2794)
						)
						(arc
							(start 0.1778 0.2794)
							(mid 0.249642 0.249642)
							(end 0.2794 0.1778)
						)
						(arc
							(start 0.2794 -0.1778)
							(mid 0.249642 -0.249642)
							(end 0.1778 -0.2794)
						)
					)
					(width 0)
					(fill yes)
				)
			)
		)
		(pad "2" smd custom
			(at 0 0.4445)
			(size 0.1397 0.1397)
			(layers "F.Cu" "F.Mask" "F.Paste")
			(net "LED_R_8")
			(options
				(clearance outline)
				(anchor circle)
			)
			(primitives
				(gr_poly
					(pts
						(arc
							(start -0.1778 -0.2794)
							(mid -0.249642 -0.249642)
							(end -0.2794 -0.1778)
						)
						(arc
							(start -0.2794 0.1778)
							(mid -0.249642 0.249642)
							(end -0.1778 0.2794)
						)
						(arc
							(start 0.1778 0.2794)
							(mid 0.249642 0.249642)
							(end 0.2794 0.1778)
						)
						(arc
							(start 0.2794 -0.1778)
							(mid 0.249642 -0.249642)
							(end 0.1778 -0.2794)
						)
					)
					(width 0)
					(fill yes)
				)
			)
		)
	)
	(footprint ""
		(layer "F.Cu")
		(at 336.8294 -186.9186 180)
		(property "Reference" "R9043"
			(at 0 0 180)
			(layer "F.SilkS")
			(hide yes)
			(effects
				(font
					(size 1.27 1.27)
				)
			)
		)
		(property "Value" "4K7R2F-GP"
			(at 0.064008 -3.993896 180)
			(unlocked yes)
			(layer "F.Fab")
			(hide yes)
			(effects
				(font
					(size 1.016 1.016)
					(thickness 0.1524)
				)
			)
		)
		(property "Device Type" "R402H16"
			(at 0.064008 -5.517896 180)
			(unlocked yes)
			(layer "F.Fab")
			(hide yes)
			(effects
				(font
					(size 1.016 1.016)
					(thickness 0.1524)
				)
			)
		)
		(duplicate_pad_numbers_are_jumpers no)
		(fp_line
			(start 0.508 -0.9398)
			(end -0.508 -0.9398)
			(stroke
				(width 0.1524)
				(type default)
			)
			(layer "F.SilkS")
		)
		(fp_line
			(start -0.508 -0.9398)
			(end -0.508 0.9398)
			(stroke
				(width 0.1524)
				(type default)
			)
			(layer "F.SilkS")
		)
		(fp_rect
			(start -0.508 0.9398)
			(end 0.508 -0.9398)
			(stroke
				(width 0)
				(type default)
			)
			(fill no)
			(layer "F.CrtYd")
		)
		(fp_rect
			(start -0.508 0.9398)
			(end 0.508 -0.9398)
			(stroke
				(width 0)
				(type default)
			)
			(fill no)
			(layer "F.Fab")
		)
		(pad "1" smd custom
			(at 0 -0.4445 180)
			(size 0.1397 0.1397)
			(layers "F.Cu" "F.Mask" "F.Paste")
			(net "SSD_PERST#14")
			(options
				(clearance outline)
				(anchor circle)
			)
			(primitives
				(gr_poly
					(pts
						(arc
							(start -0.1778 -0.2794)
							(mid -0.249642 -0.249642)
							(end -0.2794 -0.1778)
						)
						(arc
							(start -0.2794 0.1778)
							(mid -0.249642 0.249642)
							(end -0.1778 0.2794)
						)
						(arc
							(start 0.1778 0.2794)
							(mid 0.249642 0.249642)
							(end 0.2794 0.1778)
						)
						(arc
							(start 0.2794 -0.1778)
							(mid 0.249642 -0.249642)
							(end 0.1778 -0.2794)
						)
					)
					(width 0)
					(fill yes)
				)
			)
		)
		(pad "2" smd custom
			(at 0 0.4445 180)
			(size 0.1397 0.1397)
			(layers "F.Cu" "F.Mask" "F.Paste")
			(net "GND")
			(options
				(clearance outline)
				(anchor circle)
			)
			(primitives
				(gr_poly
					(pts
						(arc
							(start -0.1778 -0.2794)
							(mid -0.249642 -0.249642)
							(end -0.2794 -0.1778)
						)
						(arc
							(start -0.2794 0.1778)
							(mid -0.249642 0.249642)
							(end -0.1778 0.2794)
						)
						(arc
							(start 0.1778 0.2794)
							(mid 0.249642 0.249642)
							(end 0.2794 0.1778)
						)
						(arc
							(start 0.2794 -0.1778)
							(mid 0.249642 -0.249642)
							(end 0.1778 -0.2794)
						)
					)
					(width 0)
					(fill yes)
				)
			)
		)
	)
	(footprint ""
		(layer "F.Cu")
		(at 12.1412 -194.6656 180)
		(property "Reference" "C7317"
			(at 0 0 180)
			(layer "F.SilkS")
			(hide yes)
			(effects
				(font
					(size 1.27 1.27)
				)
			)
		)
		(property "Value" "SCD1U25V3JX-GP"
			(at 0 -2.8194 180)
			(unlocked yes)
			(layer "F.Fab")
			(hide yes)
			(effects
				(font
					(size 1.016 1.016)
					(thickness 0.1524)
				)
			)
		)
		(property "Device Type" "C603H36"
			(at 0 -4.3434 180)
			(unlocked yes)
			(layer "F.Fab")
			(hide yes)
			(effects
				(font
					(size 1.016 1.016)
					(thickness 0.1524)
				)
			)
		)
		(duplicate_pad_numbers_are_jumpers no)
		(fp_line
			(start 0.508 0)
			(end -0.508 0)
			(stroke
				(width 0.2032)
				(type default)
			)
			(layer "F.SilkS")
		)
		(fp_rect
			(start -0.5842 1.3335)
			(end 0.5842 -1.3335)
			(stroke
				(width 0)
				(type default)
			)
			(fill no)
			(layer "F.CrtYd")
		)
		(fp_rect
			(start -0.5842 1.3335)
			(end 0.5842 -1.3335)
			(stroke
				(width 0)
				(type default)
			)
			(fill no)
			(layer "F.Fab")
		)
		(pad "1" smd custom
			(at 0 -0.762 180)
			(size 0.2159 0.2159)
			(layers "F.Cu" "F.Mask" "F.Paste")
			(net "MB0_ISTART_R")
			(options
				(clearance outline)
				(anchor circle)
			)
			(primitives
				(gr_poly
					(pts
						(arc
							(start -0.3302 -0.4318)
							(mid -0.402042 -0.402042)
							(end -0.4318 -0.3302)
						)
						(arc
							(start -0.4318 0.3302)
							(mid -0.402042 0.402042)
							(end -0.3302 0.4318)
						)
						(arc
							(start 0.3302 0.4318)
							(mid 0.402042 0.402042)
							(end 0.4318 0.3302)
						)
						(arc
							(start 0.4318 -0.3302)
							(mid 0.402042 -0.402042)
							(end 0.3302 -0.4318)
						)
					)
					(width 0)
					(fill yes)
				)
			)
		)
		(pad "2" smd custom
			(at 0 0.762 180)
			(size 0.2159 0.2159)
			(layers "F.Cu" "F.Mask" "F.Paste")
			(net "AGND_CURRENT_MON")
			(options
				(clearance outline)
				(anchor circle)
			)
			(primitives
				(gr_poly
					(pts
						(arc
							(start -0.3302 -0.4318)
							(mid -0.402042 -0.402042)
							(end -0.4318 -0.3302)
						)
						(arc
							(start -0.4318 0.3302)
							(mid -0.402042 0.402042)
							(end -0.3302 0.4318)
						)
						(arc
							(start 0.3302 0.4318)
							(mid 0.402042 0.402042)
							(end 0.4318 0.3302)
						)
						(arc
							(start 0.4318 -0.3302)
							(mid 0.402042 -0.402042)
							(end 0.3302 -0.4318)
						)
					)
					(width 0)
					(fill yes)
				)
			)
		)
	)
	(footprint ""
		(layer "F.Cu")
		(at 289.179 -33.528)
		(property "Reference" "C10"
			(at 0 0 0)
			(layer "F.SilkS")
			(hide yes)
			(effects
				(font
					(size 1.27 1.27)
				)
			)
		)
		(property "Value" "SCD22U10V2KX-1GP"
			(at 1.1811 -2.7051 0)
			(unlocked yes)
			(layer "F.Fab")
			(hide yes)
			(effects
				(font
					(size 1.016 1.016)
					(thickness 0.1524)
				)
			)
		)
		(property "Device Type" "C402H22"
			(at 1.1811 -4.2291 0)
			(unlocked yes)
			(layer "F.Fab")
			(hide yes)
			(effects
				(font
					(size 1.016 1.016)
					(thickness 0.1524)
				)
			)
		)
		(duplicate_pad_numbers_are_jumpers no)
		(fp_rect
			(start -0.4318 0.9525)
			(end 0.4318 -0.9525)
			(stroke
				(width 0)
				(type default)
			)
			(fill no)
			(layer "F.CrtYd")
		)
		(fp_rect
			(start -0.4318 0.9525)
			(end 0.4318 -0.9525)
			(stroke
				(width 0)
				(type default)
			)
			(fill no)
			(layer "F.Fab")
		)
		(pad "1" smd custom
			(at 0 -0.4445)
			(size 0.1524 0.1524)
			(layers "F.Cu" "F.Mask" "F.Paste")
			(net "PCIE_TX_CAP_P3")
			(options
				(clearance outline)
				(anchor circle)
			)
			(primitives
				(gr_poly
					(pts
						(arc
							(start 0.3048 -0.2032)
							(mid 0.275042 -0.275042)
							(end 0.2032 -0.3048)
						)
						(arc
							(start -0.2032 -0.3048)
							(mid -0.275042 -0.275042)
							(end -0.3048 -0.2032)
						)
						(arc
							(start -0.3048 0.2032)
							(mid -0.275042 0.275042)
							(end -0.2032 0.3048)
						)
						(arc
							(start 0.2032 0.3048)
							(mid 0.275042 0.275042)
							(end 0.3048 0.2032)
						)
					)
					(width 0)
					(fill yes)
				)
			)
		)
		(pad "2" smd custom
			(at 0 0.4445)
			(size 0.1524 0.1524)
			(layers "F.Cu" "F.Mask" "F.Paste")
			(net "PCIE_TX_P3")
			(options
				(clearance outline)
				(anchor circle)
			)
			(primitives
				(gr_poly
					(pts
						(arc
							(start 0.3048 -0.2032)
							(mid 0.275042 -0.275042)
							(end 0.2032 -0.3048)
						)
						(arc
							(start -0.2032 -0.3048)
							(mid -0.275042 -0.275042)
							(end -0.3048 -0.2032)
						)
						(arc
							(start -0.3048 0.2032)
							(mid -0.275042 0.275042)
							(end -0.2032 0.3048)
						)
						(arc
							(start 0.2032 0.3048)
							(mid 0.275042 0.275042)
							(end 0.3048 0.2032)
						)
					)
					(width 0)
					(fill yes)
				)
			)
		)
	)
	(footprint ""
		(layer "F.Cu")
		(at 178.1048 -69.215 180)
		(property "Reference" "PG19"
			(at 0 0 180)
			(layer "F.SilkS")
			(hide yes)
			(effects
				(font
					(size 1.27 1.27)
				)
			)
		)
		(property "Value" "GAP-CLOSE-PWR-3-GP"
			(at 0.0254 -6.5786 180)
			(unlocked yes)
			(layer "F.Fab")
			(hide yes)
			(effects
				(font
					(size 1.016 1.016)
					(thickness 0.1524)
				)
			)
		)
		(property "Device Type" "GAP-CLOSE-PWR-3"
			(at 0.0254 -8.255 180)
			(unlocked yes)
			(layer "F.Fab")
			(hide yes)
			(effects
				(font
					(size 1.016 1.016)
					(thickness 0.1524)
				)
			)
		)
		(duplicate_pad_numbers_are_jumpers no)
		(fp_rect
			(start -0.7112 0.4572)
			(end 0.7112 -0.4572)
			(stroke
				(width 0)
				(type default)
			)
			(fill no)
			(layer "F.CrtYd")
		)
		(fp_poly
			(pts
				(xy -0.7112 -0.4572) (xy 0.7112 -0.4572) (xy 0.7112 0.4572) (xy -0.7112 0.4572)
			)
			(stroke
				(width 0)
				(type default)
			)
			(fill no)
			(layer "F.Fab")
		)
		(pad "1" smd rect
			(at -0.3048 0 180)
			(size 0.6604 0.762)
			(layers "F.Cu" "F.Mask" "F.Paste")
			(net "DUT_AVD_PCIE")
		)
		(pad "2" smd rect
			(at 0.3048 0 180)
			(size 0.6604 0.762)
			(layers "F.Cu" "F.Mask" "F.Paste")
			(net "P0V9")
		)
	)
	(footprint ""
		(layer "F.Cu")
		(at 142.608046 -212.420454 180)
		(property "Reference" "C341"
			(at 0 0 180)
			(layer "F.SilkS")
			(hide yes)
			(effects
				(font
					(size 1.27 1.27)
				)
			)
		)
		(property "Value" "SCD22U10V2KX-1GP"
			(at 1.1811 -2.7051 180)
			(unlocked yes)
			(layer "F.Fab")
			(hide yes)
			(effects
				(font
					(size 1.016 1.016)
					(thickness 0.1524)
				)
			)
		)
		(property "Device Type" "C402H22"
			(at 1.1811 -4.2291 180)
			(unlocked yes)
			(layer "F.Fab")
			(hide yes)
			(effects
				(font
					(size 1.016 1.016)
					(thickness 0.1524)
				)
			)
		)
		(duplicate_pad_numbers_are_jumpers no)
		(fp_rect
			(start -0.4318 0.9525)
			(end 0.4318 -0.9525)
			(stroke
				(width 0)
				(type default)
			)
			(fill no)
			(layer "F.CrtYd")
		)
		(fp_rect
			(start -0.4318 0.9525)
			(end 0.4318 -0.9525)
			(stroke
				(width 0)
				(type default)
			)
			(fill no)
			(layer "F.Fab")
		)
		(pad "1" smd custom
			(at 0 -0.4445 180)
			(size 0.1524 0.1524)
			(layers "F.Cu" "F.Mask" "F.Paste")
			(net "PCIE_TX_CAP_N58")
			(options
				(clearance outline)
				(anchor circle)
			)
			(primitives
				(gr_poly
					(pts
						(arc
							(start 0.3048 -0.2032)
							(mid 0.275042 -0.275042)
							(end 0.2032 -0.3048)
						)
						(arc
							(start -0.2032 -0.3048)
							(mid -0.275042 -0.275042)
							(end -0.3048 -0.2032)
						)
						(arc
							(start -0.3048 0.2032)
							(mid -0.275042 0.275042)
							(end -0.2032 0.3048)
						)
						(arc
							(start 0.2032 0.3048)
							(mid 0.275042 0.275042)
							(end 0.3048 0.2032)
						)
					)
					(width 0)
					(fill yes)
				)
			)
		)
		(pad "2" smd custom
			(at 0 0.4445 180)
			(size 0.1524 0.1524)
			(layers "F.Cu" "F.Mask" "F.Paste")
			(net "PCIE_TX_N58")
			(options
				(clearance outline)
				(anchor circle)
			)
			(primitives
				(gr_poly
					(pts
						(arc
							(start 0.3048 -0.2032)
							(mid 0.275042 -0.275042)
							(end 0.2032 -0.3048)
						)
						(arc
							(start -0.2032 -0.3048)
							(mid -0.275042 -0.275042)
							(end -0.3048 -0.2032)
						)
						(arc
							(start -0.3048 0.2032)
							(mid -0.275042 0.275042)
							(end -0.2032 0.3048)
						)
						(arc
							(start 0.2032 0.3048)
							(mid 0.275042 0.275042)
							(end 0.3048 0.2032)
						)
					)
					(width 0)
					(fill yes)
				)
			)
		)
	)
	(footprint ""
		(layer "F.Cu")
		(at 25.908 -126.4158)
		(property "Reference" "TP236"
			(at 0 0 0)
			(layer "F.SilkS")
			(hide yes)
			(effects
				(font
					(size 1.27 1.27)
				)
			)
		)
		(property "Value" "TPAD28-2-GP"
			(at -0.0127 -1.6637 0)
			(unlocked yes)
			(layer "F.Fab")
			(hide yes)
			(effects
				(font
					(size 1.016 1.016)
					(thickness 0.1524)
				)
			)
		)
		(property "Device Type" "TPAD28"
			(at -0.0127 -3.1877 0)
			(unlocked yes)
			(layer "F.Fab")
			(hide yes)
			(effects
				(font
					(size 1.016 1.016)
					(thickness 0.1524)
				)
			)
		)
		(duplicate_pad_numbers_are_jumpers no)
		(fp_poly
			(pts
				(arc
					(start 0.3556 0)
					(mid -0.3556 0)
					(end 0.3556 0)
				)
			)
			(stroke
				(width 0)
				(type default)
			)
			(fill no)
			(layer "F.CrtYd")
		)
		(fp_poly
			(pts
				(arc
					(start 0.6096 0)
					(mid -0.6096 0)
					(end 0.6096 0)
				)
			)
			(stroke
				(width 0)
				(type default)
			)
			(fill no)
			(layer "F.Fab")
		)
		(pad "1" smd circle
			(at 0 0)
			(size 0.7112 0.7112)
			(layers "F.Cu" "F.Mask" "F.Paste")
			(net "TP_GPIOY3")
		)
	)
	(footprint ""
		(layer "F.Cu")
		(at 75.623166 -90.58656 180)
		(property "Reference" "C263"
			(at 0 0 180)
			(layer "F.SilkS")
			(hide yes)
			(effects
				(font
					(size 1.27 1.27)
				)
			)
		)
		(property "Value" "SCD1U16V2KX-3GP"
			(at 1.1811 -2.7051 180)
			(unlocked yes)
			(layer "F.Fab")
			(hide yes)
			(effects
				(font
					(size 1.016 1.016)
					(thickness 0.1524)
				)
			)
		)
		(property "Device Type" "C402H22"
			(at 1.1811 -4.2291 180)
			(unlocked yes)
			(layer "F.Fab")
			(hide yes)
			(effects
				(font
					(size 1.016 1.016)
					(thickness 0.1524)
				)
			)
		)
		(duplicate_pad_numbers_are_jumpers no)
		(fp_rect
			(start -0.4318 0.9525)
			(end 0.4318 -0.9525)
			(stroke
				(width 0)
				(type default)
			)
			(fill no)
			(layer "F.CrtYd")
		)
		(fp_rect
			(start -0.4318 0.9525)
			(end 0.4318 -0.9525)
			(stroke
				(width 0)
				(type default)
			)
			(fill no)
			(layer "F.Fab")
		)
		(pad "1" smd custom
			(at 0 -0.4445 180)
			(size 0.1524 0.1524)
			(layers "F.Cu" "F.Mask" "F.Paste")
			(net "P3V3_STBY")
			(options
				(clearance outline)
				(anchor circle)
			)
			(primitives
				(gr_poly
					(pts
						(arc
							(start 0.3048 -0.2032)
							(mid 0.275042 -0.275042)
							(end 0.2032 -0.3048)
						)
						(arc
							(start -0.2032 -0.3048)
							(mid -0.275042 -0.275042)
							(end -0.3048 -0.2032)
						)
						(arc
							(start -0.3048 0.2032)
							(mid -0.275042 0.275042)
							(end -0.2032 0.3048)
						)
						(arc
							(start 0.2032 0.3048)
							(mid 0.275042 0.275042)
							(end 0.3048 0.2032)
						)
					)
					(width 0)
					(fill yes)
				)
			)
		)
		(pad "2" smd custom
			(at 0 0.4445 180)
			(size 0.1524 0.1524)
			(layers "F.Cu" "F.Mask" "F.Paste")
			(net "GND")
			(options
				(clearance outline)
				(anchor circle)
			)
			(primitives
				(gr_poly
					(pts
						(arc
							(start 0.3048 -0.2032)
							(mid 0.275042 -0.275042)
							(end 0.2032 -0.3048)
						)
						(arc
							(start -0.2032 -0.3048)
							(mid -0.275042 -0.275042)
							(end -0.3048 -0.2032)
						)
						(arc
							(start -0.3048 0.2032)
							(mid -0.275042 0.275042)
							(end -0.2032 0.3048)
						)
						(arc
							(start 0.2032 0.3048)
							(mid 0.275042 0.275042)
							(end 0.3048 0.2032)
						)
					)
					(width 0)
					(fill yes)
				)
			)
		)
	)
	(footprint ""
		(layer "F.Cu")
		(at 270.792194 -212.420454 180)
		(property "Reference" "C103"
			(at 0 0 180)
			(layer "F.SilkS")
			(hide yes)
			(effects
				(font
					(size 1.27 1.27)
				)
			)
		)
		(property "Value" "SCD22U10V2KX-1GP"
			(at 1.1811 -2.7051 180)
			(unlocked yes)
			(layer "F.Fab")
			(hide yes)
			(effects
				(font
					(size 1.016 1.016)
					(thickness 0.1524)
				)
			)
		)
		(property "Device Type" "C402H22"
			(at 1.1811 -4.2291 180)
			(unlocked yes)
			(layer "F.Fab")
			(hide yes)
			(effects
				(font
					(size 1.016 1.016)
					(thickness 0.1524)
				)
			)
		)
		(duplicate_pad_numbers_are_jumpers no)
		(fp_rect
			(start -0.4318 0.9525)
			(end 0.4318 -0.9525)
			(stroke
				(width 0)
				(type default)
			)
			(fill no)
			(layer "F.CrtYd")
		)
		(fp_rect
			(start -0.4318 0.9525)
			(end 0.4318 -0.9525)
			(stroke
				(width 0)
				(type default)
			)
			(fill no)
			(layer "F.Fab")
		)
		(pad "1" smd custom
			(at 0 -0.4445 180)
			(size 0.1524 0.1524)
			(layers "F.Cu" "F.Mask" "F.Paste")
			(net "PCIE_TX_CAP_P35")
			(options
				(clearance outline)
				(anchor circle)
			)
			(primitives
				(gr_poly
					(pts
						(arc
							(start 0.3048 -0.2032)
							(mid 0.275042 -0.275042)
							(end 0.2032 -0.3048)
						)
						(arc
							(start -0.2032 -0.3048)
							(mid -0.275042 -0.275042)
							(end -0.3048 -0.2032)
						)
						(arc
							(start -0.3048 0.2032)
							(mid -0.275042 0.275042)
							(end -0.2032 0.3048)
						)
						(arc
							(start 0.2032 0.3048)
							(mid 0.275042 0.275042)
							(end 0.3048 0.2032)
						)
					)
					(width 0)
					(fill yes)
				)
			)
		)
		(pad "2" smd custom
			(at 0 0.4445 180)
			(size 0.1524 0.1524)
			(layers "F.Cu" "F.Mask" "F.Paste")
			(net "PCIE_TX_P35")
			(options
				(clearance outline)
				(anchor circle)
			)
			(primitives
				(gr_poly
					(pts
						(arc
							(start 0.3048 -0.2032)
							(mid 0.275042 -0.275042)
							(end 0.2032 -0.3048)
						)
						(arc
							(start -0.2032 -0.3048)
							(mid -0.275042 -0.275042)
							(end -0.3048 -0.2032)
						)
						(arc
							(start -0.3048 0.2032)
							(mid -0.275042 0.275042)
							(end -0.2032 0.3048)
						)
						(arc
							(start 0.2032 0.3048)
							(mid 0.275042 0.275042)
							(end 0.3048 0.2032)
						)
					)
					(width 0)
					(fill yes)
				)
			)
		)
	)
	(footprint ""
		(layer "F.Cu")
		(at 152.6032 -33.5026)
		(property "Reference" "C394"
			(at 0 0 0)
			(layer "F.SilkS")
			(hide yes)
			(effects
				(font
					(size 1.27 1.27)
				)
			)
		)
		(property "Value" "SCD22U10V2KX-1GP"
			(at 1.1811 -2.7051 0)
			(unlocked yes)
			(layer "F.Fab")
			(hide yes)
			(effects
				(font
					(size 1.016 1.016)
					(thickness 0.1524)
				)
			)
		)
		(property "Device Type" "C402H22"
			(at 1.1811 -4.2291 0)
			(unlocked yes)
			(layer "F.Fab")
			(hide yes)
			(effects
				(font
					(size 1.016 1.016)
					(thickness 0.1524)
				)
			)
		)
		(duplicate_pad_numbers_are_jumpers no)
		(fp_rect
			(start -0.4318 0.9525)
			(end 0.4318 -0.9525)
			(stroke
				(width 0)
				(type default)
			)
			(fill no)
			(layer "F.CrtYd")
		)
		(fp_rect
			(start -0.4318 0.9525)
			(end 0.4318 -0.9525)
			(stroke
				(width 0)
				(type default)
			)
			(fill no)
			(layer "F.Fab")
		)
		(pad "1" smd custom
			(at 0 -0.4445)
			(size 0.1524 0.1524)
			(layers "F.Cu" "F.Mask" "F.Paste")
			(net "PCIE_TX_CAP_P87")
			(options
				(clearance outline)
				(anchor circle)
			)
			(primitives
				(gr_poly
					(pts
						(arc
							(start 0.3048 -0.2032)
							(mid 0.275042 -0.275042)
							(end 0.2032 -0.3048)
						)
						(arc
							(start -0.2032 -0.3048)
							(mid -0.275042 -0.275042)
							(end -0.3048 -0.2032)
						)
						(arc
							(start -0.3048 0.2032)
							(mid -0.275042 0.275042)
							(end -0.2032 0.3048)
						)
						(arc
							(start 0.2032 0.3048)
							(mid 0.275042 0.275042)
							(end 0.3048 0.2032)
						)
					)
					(width 0)
					(fill yes)
				)
			)
		)
		(pad "2" smd custom
			(at 0 0.4445)
			(size 0.1524 0.1524)
			(layers "F.Cu" "F.Mask" "F.Paste")
			(net "PCIE_TX_P87")
			(options
				(clearance outline)
				(anchor circle)
			)
			(primitives
				(gr_poly
					(pts
						(arc
							(start 0.3048 -0.2032)
							(mid 0.275042 -0.275042)
							(end 0.2032 -0.3048)
						)
						(arc
							(start -0.2032 -0.3048)
							(mid -0.275042 -0.275042)
							(end -0.3048 -0.2032)
						)
						(arc
							(start -0.3048 0.2032)
							(mid -0.275042 0.275042)
							(end -0.2032 0.3048)
						)
						(arc
							(start 0.2032 0.3048)
							(mid 0.275042 0.275042)
							(end 0.3048 0.2032)
						)
					)
					(width 0)
					(fill yes)
				)
			)
		)
	)
	(footprint ""
		(layer "F.Cu")
		(at 330.591922 -39.64559 180)
		(property "Reference" "Q30"
			(at 0 0 180)
			(layer "F.SilkS")
			(hide yes)
			(effects
				(font
					(size 1.27 1.27)
				)
			)
		)
		(property "Value" "2N7002K-1-GP"
			(at 0.127 -8.9662 180)
			(unlocked yes)
			(layer "F.Fab")
			(hide yes)
			(effects
				(font
					(size 1.016 1.016)
					(thickness 0.1524)
				)
			)
		)
		(property "Device Type" "SOT23DGS2D4H44"
			(at 0.127 -10.4902 180)
			(unlocked yes)
			(layer "F.Fab")
			(hide yes)
			(effects
				(font
					(size 1.016 1.016)
					(thickness 0.1524)
				)
			)
		)
		(duplicate_pad_numbers_are_jumpers no)
		(fp_line
			(start 1.651 1.778)
			(end 1.651 -1.778)
			(stroke
				(width 0.1524)
				(type default)
			)
			(layer "F.SilkS")
		)
		(fp_line
			(start 1.651 -1.778)
			(end -1.651 -1.778)
			(stroke
				(width 0.1524)
				(type default)
			)
			(layer "F.SilkS")
		)
		(fp_line
			(start -1.651 1.778)
			(end 1.651 1.778)
			(stroke
				(width 0.1524)
				(type default)
			)
			(layer "F.SilkS")
		)
		(fp_line
			(start -1.651 -1.778)
			(end -1.651 1.778)
			(stroke
				(width 0.1524)
				(type default)
			)
			(layer "F.SilkS")
		)
		(fp_poly
			(pts
				(xy -1.778 1.8796) (xy -1.778 -1.8796) (xy 1.778 -1.8796) (xy 1.778 1.8796)
			)
			(stroke
				(width 0)
				(type default)
			)
			(fill no)
			(layer "F.CrtYd")
		)
		(fp_poly
			(pts
				(xy -1.778 1.8796) (xy -1.778 -1.8796) (xy 1.778 -1.8796) (xy 1.778 1.8796)
			)
			(stroke
				(width 0)
				(type default)
			)
			(fill no)
			(layer "F.Fab")
		)
		(pad "D" smd custom
			(at 0 -0.9525 180)
			(size 0.1905 0.1905)
			(layers "F.Cu" "F.Mask" "F.Paste")
			(net "LED_Q_5")
			(options
				(clearance outline)
				(anchor circle)
			)
			(primitives
				(gr_poly
					(pts
						(arc
							(start -0.1778 0.5715)
							(mid -0.321484 0.511984)
							(end -0.381 0.3683)
						)
						(arc
							(start -0.381 -0.3683)
							(mid -0.321484 -0.511984)
							(end -0.1778 -0.5715)
						)
						(arc
							(start 0.1778 -0.5715)
							(mid 0.321484 -0.511984)
							(end 0.381 -0.3683)
						)
						(arc
							(start 0.381 0.3683)
							(mid 0.321484 0.511984)
							(end 0.1778 0.5715)
						)
					)
					(width 0)
					(fill yes)
				)
			)
		)
		(pad "G" smd custom
			(at -0.98425 0.9525 180)
			(size 0.1905 0.1905)
			(layers "F.Cu" "F.Mask" "F.Paste")
			(net "UPLINK5_R")
			(options
				(clearance outline)
				(anchor circle)
			)
			(primitives
				(gr_poly
					(pts
						(arc
							(start -0.1778 0.5715)
							(mid -0.321484 0.511984)
							(end -0.381 0.3683)
						)
						(arc
							(start -0.381 -0.3683)
							(mid -0.321484 -0.511984)
							(end -0.1778 -0.5715)
						)
						(arc
							(start 0.1778 -0.5715)
							(mid 0.321484 -0.511984)
							(end 0.381 -0.3683)
						)
						(arc
							(start 0.381 0.3683)
							(mid 0.321484 0.511984)
							(end 0.1778 0.5715)
						)
					)
					(width 0)
					(fill yes)
				)
			)
		)
		(pad "S" smd custom
			(at 0.98425 0.9525 180)
			(size 0.1905 0.1905)
			(layers "F.Cu" "F.Mask" "F.Paste")
			(net "GND")
			(options
				(clearance outline)
				(anchor circle)
			)
			(primitives
				(gr_poly
					(pts
						(arc
							(start -0.1778 0.5715)
							(mid -0.321484 0.511984)
							(end -0.381 0.3683)
						)
						(arc
							(start -0.381 -0.3683)
							(mid -0.321484 -0.511984)
							(end -0.1778 -0.5715)
						)
						(arc
							(start 0.1778 -0.5715)
							(mid 0.321484 -0.511984)
							(end 0.381 -0.3683)
						)
						(arc
							(start 0.381 0.3683)
							(mid 0.321484 0.511984)
							(end 0.1778 0.5715)
						)
					)
					(width 0)
					(fill yes)
				)
			)
		)
	)
	(footprint ""
		(layer "F.Cu")
		(at 229.108 -86.7664 90)
		(property "Reference" "R591"
			(at 0 0 90)
			(layer "F.SilkS")
			(hide yes)
			(effects
				(font
					(size 1.27 1.27)
				)
			)
		)
		(property "Value" "4K7R2F-GP"
			(at 0.064008 -3.993896 90)
			(unlocked yes)
			(layer "F.Fab")
			(hide yes)
			(effects
				(font
					(size 1.016 1.016)
					(thickness 0.1524)
				)
			)
		)
		(property "Device Type" "R402H16"
			(at 0.064008 -5.517896 90)
			(unlocked yes)
			(layer "F.Fab")
			(hide yes)
			(effects
				(font
					(size 1.016 1.016)
					(thickness 0.1524)
				)
			)
		)
		(duplicate_pad_numbers_are_jumpers no)
		(fp_line
			(start 0.508 -0.9398)
			(end -0.508 -0.9398)
			(stroke
				(width 0.1524)
				(type default)
			)
			(layer "F.SilkS")
		)
		(fp_line
			(start -0.508 -0.9398)
			(end -0.508 0.9398)
			(stroke
				(width 0.1524)
				(type default)
			)
			(layer "F.SilkS")
		)
		(fp_rect
			(start -0.508 0.9398)
			(end 0.508 -0.9398)
			(stroke
				(width 0)
				(type default)
			)
			(fill no)
			(layer "F.CrtYd")
		)
		(fp_rect
			(start -0.508 0.9398)
			(end 0.508 -0.9398)
			(stroke
				(width 0)
				(type default)
			)
			(fill no)
			(layer "F.Fab")
		)
		(pad "1" smd custom
			(at 0 -0.4445 90)
			(size 0.1397 0.1397)
			(layers "F.Cu" "F.Mask" "F.Paste")
			(net "TEMP_3_A2")
			(options
				(clearance outline)
				(anchor circle)
			)
			(primitives
				(gr_poly
					(pts
						(arc
							(start -0.1778 -0.2794)
							(mid -0.249642 -0.249642)
							(end -0.2794 -0.1778)
						)
						(arc
							(start -0.2794 0.1778)
							(mid -0.249642 0.249642)
							(end -0.1778 0.2794)
						)
						(arc
							(start 0.1778 0.2794)
							(mid 0.249642 0.249642)
							(end 0.2794 0.1778)
						)
						(arc
							(start 0.2794 -0.1778)
							(mid 0.249642 -0.249642)
							(end 0.1778 -0.2794)
						)
					)
					(width 0)
					(fill yes)
				)
			)
		)
		(pad "2" smd custom
			(at 0 0.4445 90)
			(size 0.1397 0.1397)
			(layers "F.Cu" "F.Mask" "F.Paste")
			(net "GND")
			(options
				(clearance outline)
				(anchor circle)
			)
			(primitives
				(gr_poly
					(pts
						(arc
							(start -0.1778 -0.2794)
							(mid -0.249642 -0.249642)
							(end -0.2794 -0.1778)
						)
						(arc
							(start -0.2794 0.1778)
							(mid -0.249642 0.249642)
							(end -0.1778 0.2794)
						)
						(arc
							(start 0.1778 0.2794)
							(mid 0.249642 0.249642)
							(end 0.2794 0.1778)
						)
						(arc
							(start 0.2794 -0.1778)
							(mid 0.249642 -0.249642)
							(end 0.1778 -0.2794)
						)
					)
					(width 0)
					(fill yes)
				)
			)
		)
	)
	(footprint ""
		(layer "F.Cu")
		(at 27.488896 -40.992298)
		(property "Reference" "R514"
			(at 0 0 0)
			(layer "F.SilkS")
			(hide yes)
			(effects
				(font
					(size 1.27 1.27)
				)
			)
		)
		(property "Value" "150R3J-L-GP"
			(at -0.0254 -2.5146 0)
			(unlocked yes)
			(layer "F.Fab")
			(hide yes)
			(effects
				(font
					(size 1.016 1.016)
					(thickness 0.1524)
				)
			)
		)
		(property "Device Type" "R603H22"
			(at -0.0254 -4.0386 0)
			(unlocked yes)
			(layer "F.Fab")
			(hide yes)
			(effects
				(font
					(size 1.016 1.016)
					(thickness 0.1524)
				)
			)
		)
		(duplicate_pad_numbers_are_jumpers no)
		(fp_line
			(start -0.4826 0)
			(end -0.2032 0)
			(stroke
				(width 0.2032)
				(type default)
			)
			(layer "F.SilkS")
		)
		(fp_line
			(start 0.2032 0)
			(end 0.4826 0)
			(stroke
				(width 0.2032)
				(type default)
			)
			(layer "F.SilkS")
		)
		(fp_rect
			(start -0.5842 1.3335)
			(end 0.5842 -1.3335)
			(stroke
				(width 0)
				(type default)
			)
			(fill no)
			(layer "F.CrtYd")
		)
		(fp_rect
			(start -0.5842 1.3335)
			(end 0.5842 -1.3335)
			(stroke
				(width 0)
				(type default)
			)
			(fill no)
			(layer "F.Fab")
		)
		(pad "1" smd custom
			(at 0 -0.762)
			(size 0.2159 0.2159)
			(layers "F.Cu" "F.Mask" "F.Paste")
			(net "P3V3_STBY")
			(options
				(clearance outline)
				(anchor circle)
			)
			(primitives
				(gr_poly
					(pts
						(arc
							(start -0.3302 -0.4318)
							(mid -0.402042 -0.402042)
							(end -0.4318 -0.3302)
						)
						(arc
							(start -0.4318 0.3302)
							(mid -0.402042 0.402042)
							(end -0.3302 0.4318)
						)
						(arc
							(start 0.3302 0.4318)
							(mid 0.402042 0.402042)
							(end 0.4318 0.3302)
						)
						(arc
							(start 0.4318 -0.3302)
							(mid 0.402042 -0.402042)
							(end 0.3302 -0.4318)
						)
					)
					(width 0)
					(fill yes)
				)
			)
		)
		(pad "2" smd custom
			(at 0 0.762)
			(size 0.2159 0.2159)
			(layers "F.Cu" "F.Mask" "F.Paste")
			(net "LED_MDI0_100M_1G_N")
			(options
				(clearance outline)
				(anchor circle)
			)
			(primitives
				(gr_poly
					(pts
						(arc
							(start -0.3302 -0.4318)
							(mid -0.402042 -0.402042)
							(end -0.4318 -0.3302)
						)
						(arc
							(start -0.4318 0.3302)
							(mid -0.402042 0.402042)
							(end -0.3302 0.4318)
						)
						(arc
							(start 0.3302 0.4318)
							(mid 0.402042 0.402042)
							(end 0.4318 0.3302)
						)
						(arc
							(start 0.4318 -0.3302)
							(mid 0.402042 -0.402042)
							(end 0.3302 -0.4318)
						)
					)
					(width 0)
					(fill yes)
				)
			)
		)
	)
	(footprint ""
		(layer "F.Cu")
		(at 340.233 -48.895 -90)
		(property "Reference" "PC215"
			(at 0 0 270)
			(layer "F.SilkS")
			(hide yes)
			(effects
				(font
					(size 1.27 1.27)
				)
			)
		)
		(property "Value" "SC22U25V6KX-GP-U"
			(at -2.860802 -5.279644 270)
			(unlocked yes)
			(layer "F.Fab")
			(hide yes)
			(effects
				(font
					(size 1.016 1.016)
					(thickness 0.1524)
				)
			)
		)
		(property "Device Type" "C1206-TO0D3H75"
			(at -2.860802 -6.803644 270)
			(unlocked yes)
			(layer "F.Fab")
			(hide yes)
			(effects
				(font
					(size 1.016 1.016)
					(thickness 0.1524)
				)
			)
		)
		(duplicate_pad_numbers_are_jumpers no)
		(fp_line
			(start -1.3081 2.3749)
			(end -1.3081 -2.3749)
			(stroke
				(width 0.1524)
				(type default)
			)
			(layer "F.SilkS")
		)
		(fp_line
			(start 1.3081 2.3749)
			(end -1.3081 2.3749)
			(stroke
				(width 0.1524)
				(type default)
			)
			(layer "F.SilkS")
		)
		(fp_line
			(start -1.3081 -2.3749)
			(end 1.3081 -2.3749)
			(stroke
				(width 0.1524)
				(type default)
			)
			(layer "F.SilkS")
		)
		(fp_line
			(start 1.3081 -2.3749)
			(end 1.3081 2.3749)
			(stroke
				(width 0.1524)
				(type default)
			)
			(layer "F.SilkS")
		)
		(fp_rect
			(start -0.8001 1.6002)
			(end 0.8001 -1.6002)
			(stroke
				(width 0)
				(type default)
			)
			(fill no)
			(layer "F.CrtYd")
		)
		(fp_poly
			(pts
				(xy -1.5621 2.4511) (xy -1.5621 1.6002) (xy 0.8001 1.6002) (xy 0.8001 -1.6002) (xy -0.8001 -1.6002)
				(xy -0.8001 1.5875) (xy -1.5621 1.5875) (xy -1.5621 -2.4511) (xy 1.5621 -2.4511) (xy 1.5621 2.4511)
			)
			(stroke
				(width 0)
				(type default)
			)
			(fill no)
			(layer "F.CrtYd")
		)
		(fp_rect
			(start -1.5621 2.4511)
			(end 1.5621 -2.4511)
			(stroke
				(width 0)
				(type default)
			)
			(fill no)
			(layer "F.Fab")
		)
		(pad "1" smd rect
			(at 0 -1.392936 270)
			(size 2.1082 1.4478)
			(layers "F.Cu" "F.Mask" "F.Paste")
			(net "P0V9_E_VIN")
		)
		(pad "2" smd rect
			(at 0 1.392936 270)
			(size 2.1082 1.4478)
			(layers "F.Cu" "F.Mask" "F.Paste")
			(net "GND")
		)
	)
	(footprint ""
		(layer "F.Cu")
		(at 45.933106 -114.489738 90)
		(property "Reference" "R546"
			(at 0 0 90)
			(layer "F.SilkS")
			(hide yes)
			(effects
				(font
					(size 1.27 1.27)
				)
			)
		)
		(property "Value" "10KR2F-2-GP"
			(at 0.064008 -3.993896 90)
			(unlocked yes)
			(layer "F.Fab")
			(hide yes)
			(effects
				(font
					(size 1.016 1.016)
					(thickness 0.1524)
				)
			)
		)
		(property "Device Type" "R402H16"
			(at 0.064008 -5.517896 90)
			(unlocked yes)
			(layer "F.Fab")
			(hide yes)
			(effects
				(font
					(size 1.016 1.016)
					(thickness 0.1524)
				)
			)
		)
		(duplicate_pad_numbers_are_jumpers no)
		(fp_line
			(start 0.508 -0.9398)
			(end -0.508 -0.9398)
			(stroke
				(width 0.1524)
				(type default)
			)
			(layer "F.SilkS")
		)
		(fp_line
			(start -0.508 -0.9398)
			(end -0.508 0.9398)
			(stroke
				(width 0.1524)
				(type default)
			)
			(layer "F.SilkS")
		)
		(fp_rect
			(start -0.508 0.9398)
			(end 0.508 -0.9398)
			(stroke
				(width 0)
				(type default)
			)
			(fill no)
			(layer "F.CrtYd")
		)
		(fp_rect
			(start -0.508 0.9398)
			(end 0.508 -0.9398)
			(stroke
				(width 0)
				(type default)
			)
			(fill no)
			(layer "F.Fab")
		)
		(pad "1" smd custom
			(at 0 -0.4445 90)
			(size 0.1397 0.1397)
			(layers "F.Cu" "F.Mask" "F.Paste")
			(net "P3V3_STBY")
			(options
				(clearance outline)
				(anchor circle)
			)
			(primitives
				(gr_poly
					(pts
						(arc
							(start -0.1778 -0.2794)
							(mid -0.249642 -0.249642)
							(end -0.2794 -0.1778)
						)
						(arc
							(start -0.2794 0.1778)
							(mid -0.249642 0.249642)
							(end -0.1778 0.2794)
						)
						(arc
							(start 0.1778 0.2794)
							(mid 0.249642 0.249642)
							(end 0.2794 0.1778)
						)
						(arc
							(start 0.2794 -0.1778)
							(mid 0.249642 -0.249642)
							(end 0.1778 -0.2794)
						)
					)
					(width 0)
					(fill yes)
				)
			)
		)
		(pad "2" smd custom
			(at 0 0.4445 90)
			(size 0.1397 0.1397)
			(layers "F.Cu" "F.Mask" "F.Paste")
			(net "BMC_JTAG_L_EN")
			(options
				(clearance outline)
				(anchor circle)
			)
			(primitives
				(gr_poly
					(pts
						(arc
							(start -0.1778 -0.2794)
							(mid -0.249642 -0.249642)
							(end -0.2794 -0.1778)
						)
						(arc
							(start -0.2794 0.1778)
							(mid -0.249642 0.249642)
							(end -0.1778 0.2794)
						)
						(arc
							(start 0.1778 0.2794)
							(mid 0.249642 0.249642)
							(end 0.2794 0.1778)
						)
						(arc
							(start 0.2794 -0.1778)
							(mid 0.249642 -0.249642)
							(end 0.1778 -0.2794)
						)
					)
					(width 0)
					(fill yes)
				)
			)
		)
	)
	(footprint ""
		(layer "F.Cu")
		(at 54.102 -149.987 90)
		(property "Reference" "U134"
			(at 0 0 90)
			(layer "F.SilkS")
			(hide yes)
			(effects
				(font
					(size 1.27 1.27)
				)
			)
		)
		(property "Value" "TMP75AIDGKR-GP"
			(at -0.1143 -9.1948 90)
			(unlocked yes)
			(layer "F.Fab")
			(hide yes)
			(effects
				(font
					(size 1.016 1.016)
					(thickness 0.1524)
				)
			)
		)
		(property "Device Type" "MSOP8-1H44"
			(at -0.1143 -10.795 90)
			(unlocked yes)
			(layer "F.Fab")
			(hide yes)
			(effects
				(font
					(size 1.016 1.016)
					(thickness 0.1524)
				)
			)
		)
		(duplicate_pad_numbers_are_jumpers no)
		(fp_line
			(start 1.0795 -1.016)
			(end -1.9558 -1.016)
			(stroke
				(width 0.1524)
				(type default)
			)
			(layer "F.SilkS")
		)
		(fp_line
			(start -1.9558 -1.016)
			(end -1.9558 1.016)
			(stroke
				(width 0.1524)
				(type default)
			)
			(layer "F.SilkS")
		)
		(fp_line
			(start -1.9558 -0.5461)
			(end -1.4478 -0.0381)
			(stroke
				(width 0.1524)
				(type default)
			)
			(layer "F.SilkS")
		)
		(fp_line
			(start -1.4478 -0.0381)
			(end -1.9558 0.4699)
			(stroke
				(width 0.1524)
				(type default)
			)
			(layer "F.SilkS")
		)
		(fp_line
			(start 1.0795 1.016)
			(end 1.0795 -1.016)
			(stroke
				(width 0.1524)
				(type default)
			)
			(layer "F.SilkS")
		)
		(fp_line
			(start -1.9558 1.016)
			(end 1.0795 1.016)
			(stroke
				(width 0.1524)
				(type default)
			)
			(layer "F.SilkS")
		)
		(fp_line
			(start -1.778 1.0922)
			(end -1.778 3.048)
			(stroke
				(width 0.508)
				(type default)
			)
			(layer "F.SilkS")
		)
		(fp_poly
			(pts
				(xy -1.1557 -1.016) (xy -1.1557 1.016) (xy 1.1557 1.016) (xy 1.1557 -1.016)
			)
			(stroke
				(width 0)
				(type default)
			)
			(fill yes)
			(layer "F.SilkS")
		)
		(fp_rect
			(start -1.4986 2.4511)
			(end 1.4986 -2.4511)
			(stroke
				(width 0)
				(type default)
			)
			(fill no)
			(layer "F.CrtYd")
		)
		(fp_poly
			(pts
				(xy -2.032 3.302) (xy -2.032 -3.302) (xy 2.032 -3.302) (xy 2.032 -2.1209) (xy 1.4986 -2.1209) (xy 1.4986 -2.4511)
				(xy -1.4986 -2.4511) (xy -1.4986 2.4511) (xy 1.4986 2.4511) (xy 1.4986 -2.1082) (xy 2.032 -2.1082)
				(xy 2.032 3.302)
			)
			(stroke
				(width 0)
				(type default)
			)
			(fill no)
			(layer "F.CrtYd")
		)
		(fp_rect
			(start -2.032 3.302)
			(end 2.032 -3.302)
			(stroke
				(width 0)
				(type default)
			)
			(fill no)
			(layer "F.Fab")
		)
		(pad "1" smd rect
			(at -0.97536 2.05486 90)
			(size 0.3556 1.524)
			(layers "F.Cu" "F.Mask" "F.Paste")
			(net "TEMP_2_SDA")
		)
		(pad "2" smd rect
			(at -0.32512 2.05486 90)
			(size 0.3556 1.524)
			(layers "F.Cu" "F.Mask" "F.Paste")
			(net "TEMP_2_SCL")
		)
		(pad "3" smd rect
			(at 0.32512 2.05486 90)
			(size 0.3556 1.524)
			(layers "F.Cu" "F.Mask" "F.Paste")
			(net "TEMP_2_ALERT")
		)
		(pad "4" smd rect
			(at 0.97536 2.05486 90)
			(size 0.3556 1.524)
			(layers "F.Cu" "F.Mask" "F.Paste")
			(net "GND")
		)
		(pad "5" smd rect
			(at 0.97536 -2.05486 90)
			(size 0.3556 1.524)
			(layers "F.Cu" "F.Mask" "F.Paste")
			(net "TEMP_2_A2")
		)
		(pad "6" smd rect
			(at 0.32512 -2.05486 90)
			(size 0.3556 1.524)
			(layers "F.Cu" "F.Mask" "F.Paste")
			(net "TEMP_2_A1")
		)
		(pad "7" smd rect
			(at -0.32512 -2.05486 90)
			(size 0.3556 1.524)
			(layers "F.Cu" "F.Mask" "F.Paste")
			(net "TEMP_2_A0")
		)
		(pad "8" smd rect
			(at -0.97536 -2.05486 90)
			(size 0.3556 1.524)
			(layers "F.Cu" "F.Mask" "F.Paste")
			(net "P3V3_STBY")
		)
	)
	(footprint ""
		(layer "F.Cu")
		(at 310.007 -59.4106)
		(property "Reference" "PG48"
			(at 0 0 0)
			(layer "F.SilkS")
			(hide yes)
			(effects
				(font
					(size 1.27 1.27)
				)
			)
		)
		(property "Value" "GAP-CLOSE-PWR-3-GP"
			(at 0.0254 -6.5786 0)
			(unlocked yes)
			(layer "F.Fab")
			(hide yes)
			(effects
				(font
					(size 1.016 1.016)
					(thickness 0.1524)
				)
			)
		)
		(property "Device Type" "GAP-CLOSE-PWR-3"
			(at 0.0254 -8.255 0)
			(unlocked yes)
			(layer "F.Fab")
			(hide yes)
			(effects
				(font
					(size 1.016 1.016)
					(thickness 0.1524)
				)
			)
		)
		(duplicate_pad_numbers_are_jumpers no)
		(fp_rect
			(start -0.7112 0.4572)
			(end 0.7112 -0.4572)
			(stroke
				(width 0)
				(type default)
			)
			(fill no)
			(layer "F.CrtYd")
		)
		(fp_poly
			(pts
				(xy -0.7112 -0.4572) (xy 0.7112 -0.4572) (xy 0.7112 0.4572) (xy -0.7112 0.4572)
			)
			(stroke
				(width 0)
				(type default)
			)
			(fill no)
			(layer "F.Fab")
		)
		(pad "1" smd rect
			(at -0.3048 0)
			(size 0.6604 0.762)
			(layers "F.Cu" "F.Mask" "F.Paste")
			(net "DUT_VDD")
		)
		(pad "2" smd rect
			(at 0.3048 0)
			(size 0.6604 0.762)
			(layers "F.Cu" "F.Mask" "F.Paste")
			(net "P0V9_E")
		)
	)
	(footprint ""
		(layer "F.Cu")
		(at 116.253768 -29.020516 -90)
		(property "Reference" "C133"
			(at 0 0 270)
			(layer "F.SilkS")
			(hide yes)
			(effects
				(font
					(size 1.27 1.27)
				)
			)
		)
		(property "Value" "SCD1U10V2KX-5GP"
			(at 1.1811 -2.7051 270)
			(unlocked yes)
			(layer "F.Fab")
			(hide yes)
			(effects
				(font
					(size 1.016 1.016)
					(thickness 0.1524)
				)
			)
		)
		(property "Device Type" "C402H22"
			(at 1.1811 -4.2291 270)
			(unlocked yes)
			(layer "F.Fab")
			(hide yes)
			(effects
				(font
					(size 1.016 1.016)
					(thickness 0.1524)
				)
			)
		)
		(duplicate_pad_numbers_are_jumpers no)
		(fp_rect
			(start -0.4318 0.9525)
			(end 0.4318 -0.9525)
			(stroke
				(width 0)
				(type default)
			)
			(fill no)
			(layer "F.CrtYd")
		)
		(fp_rect
			(start -0.4318 0.9525)
			(end 0.4318 -0.9525)
			(stroke
				(width 0)
				(type default)
			)
			(fill no)
			(layer "F.Fab")
		)
		(pad "1" smd custom
			(at 0 -0.4445 270)
			(size 0.1524 0.1524)
			(layers "F.Cu" "F.Mask" "F.Paste")
			(net "P3V3_STBY")
			(options
				(clearance outline)
				(anchor circle)
			)
			(primitives
				(gr_poly
					(pts
						(arc
							(start 0.3048 -0.2032)
							(mid 0.275042 -0.275042)
							(end 0.2032 -0.3048)
						)
						(arc
							(start -0.2032 -0.3048)
							(mid -0.275042 -0.275042)
							(end -0.3048 -0.2032)
						)
						(arc
							(start -0.3048 0.2032)
							(mid -0.275042 0.275042)
							(end -0.2032 0.3048)
						)
						(arc
							(start 0.2032 0.3048)
							(mid 0.275042 0.275042)
							(end 0.3048 0.2032)
						)
					)
					(width 0)
					(fill yes)
				)
			)
		)
		(pad "2" smd custom
			(at 0 0.4445 270)
			(size 0.1524 0.1524)
			(layers "F.Cu" "F.Mask" "F.Paste")
			(net "GND")
			(options
				(clearance outline)
				(anchor circle)
			)
			(primitives
				(gr_poly
					(pts
						(arc
							(start 0.3048 -0.2032)
							(mid 0.275042 -0.275042)
							(end 0.2032 -0.3048)
						)
						(arc
							(start -0.2032 -0.3048)
							(mid -0.275042 -0.275042)
							(end -0.3048 -0.2032)
						)
						(arc
							(start -0.3048 0.2032)
							(mid -0.275042 0.275042)
							(end -0.2032 0.3048)
						)
						(arc
							(start 0.2032 0.3048)
							(mid 0.275042 0.275042)
							(end 0.3048 0.2032)
						)
					)
					(width 0)
					(fill yes)
				)
			)
		)
	)
	(footprint ""
		(layer "F.Cu")
		(at 58.166 -133.985)
		(property "Reference" "R5765"
			(at 0 0 0)
			(layer "F.SilkS")
			(hide yes)
			(effects
				(font
					(size 1.27 1.27)
				)
			)
		)
		(property "Value" "1K8R2F-GP"
			(at 0.064008 -3.993896 0)
			(unlocked yes)
			(layer "F.Fab")
			(hide yes)
			(effects
				(font
					(size 1.016 1.016)
					(thickness 0.1524)
				)
			)
		)
		(property "Device Type" "R402H16"
			(at 0.064008 -5.517896 0)
			(unlocked yes)
			(layer "F.Fab")
			(hide yes)
			(effects
				(font
					(size 1.016 1.016)
					(thickness 0.1524)
				)
			)
		)
		(duplicate_pad_numbers_are_jumpers no)
		(fp_line
			(start -0.508 -0.9398)
			(end -0.508 0.9398)
			(stroke
				(width 0.1524)
				(type default)
			)
			(layer "F.SilkS")
		)
		(fp_line
			(start 0.508 -0.9398)
			(end -0.508 -0.9398)
			(stroke
				(width 0.1524)
				(type default)
			)
			(layer "F.SilkS")
		)
		(fp_rect
			(start -0.508 0.9398)
			(end 0.508 -0.9398)
			(stroke
				(width 0)
				(type default)
			)
			(fill no)
			(layer "F.CrtYd")
		)
		(fp_rect
			(start -0.508 0.9398)
			(end 0.508 -0.9398)
			(stroke
				(width 0)
				(type default)
			)
			(fill no)
			(layer "F.Fab")
		)
		(pad "1" smd custom
			(at 0 -0.4445)
			(size 0.1397 0.1397)
			(layers "F.Cu" "F.Mask" "F.Paste")
			(net "P1V8_STBY")
			(options
				(clearance outline)
				(anchor circle)
			)
			(primitives
				(gr_poly
					(pts
						(arc
							(start -0.1778 -0.2794)
							(mid -0.249642 -0.249642)
							(end -0.2794 -0.1778)
						)
						(arc
							(start -0.2794 0.1778)
							(mid -0.249642 0.249642)
							(end -0.1778 0.2794)
						)
						(arc
							(start 0.1778 0.2794)
							(mid 0.249642 0.249642)
							(end 0.2794 0.1778)
						)
						(arc
							(start 0.2794 -0.1778)
							(mid 0.249642 -0.249642)
							(end 0.1778 -0.2794)
						)
					)
					(width 0)
					(fill yes)
				)
			)
		)
		(pad "2" smd custom
			(at 0 0.4445)
			(size 0.1397 0.1397)
			(layers "F.Cu" "F.Mask" "F.Paste")
			(net "ADC_P1V8_STBY")
			(options
				(clearance outline)
				(anchor circle)
			)
			(primitives
				(gr_poly
					(pts
						(arc
							(start -0.1778 -0.2794)
							(mid -0.249642 -0.249642)
							(end -0.2794 -0.1778)
						)
						(arc
							(start -0.2794 0.1778)
							(mid -0.249642 0.249642)
							(end -0.1778 0.2794)
						)
						(arc
							(start 0.1778 0.2794)
							(mid 0.249642 0.249642)
							(end 0.2794 0.1778)
						)
						(arc
							(start 0.2794 -0.1778)
							(mid 0.249642 -0.249642)
							(end 0.1778 -0.2794)
						)
					)
					(width 0)
					(fill yes)
				)
			)
		)
	)
	(footprint ""
		(layer "F.Cu")
		(at 68.961 -32.004 -90)
		(property "Reference" "PR37"
			(at 0 0 270)
			(layer "F.SilkS")
			(hide yes)
			(effects
				(font
					(size 1.27 1.27)
				)
			)
		)
		(property "Value" "10KR2F-2-GP"
			(at 0.064008 -3.993896 270)
			(unlocked yes)
			(layer "F.Fab")
			(hide yes)
			(effects
				(font
					(size 1.016 1.016)
					(thickness 0.1524)
				)
			)
		)
		(property "Device Type" "R402H16"
			(at 0.064008 -5.517896 270)
			(unlocked yes)
			(layer "F.Fab")
			(hide yes)
			(effects
				(font
					(size 1.016 1.016)
					(thickness 0.1524)
				)
			)
		)
		(duplicate_pad_numbers_are_jumpers no)
		(fp_line
			(start -0.508 -0.9398)
			(end -0.508 0.9398)
			(stroke
				(width 0.1524)
				(type default)
			)
			(layer "F.SilkS")
		)
		(fp_line
			(start 0.508 -0.9398)
			(end -0.508 -0.9398)
			(stroke
				(width 0.1524)
				(type default)
			)
			(layer "F.SilkS")
		)
		(fp_rect
			(start -0.508 0.9398)
			(end 0.508 -0.9398)
			(stroke
				(width 0)
				(type default)
			)
			(fill no)
			(layer "F.CrtYd")
		)
		(fp_rect
			(start -0.508 0.9398)
			(end 0.508 -0.9398)
			(stroke
				(width 0)
				(type default)
			)
			(fill no)
			(layer "F.Fab")
		)
		(pad "1" smd custom
			(at 0 -0.4445 270)
			(size 0.1397 0.1397)
			(layers "F.Cu" "F.Mask" "F.Paste")
			(net "P3V3_STBY_VFB")
			(options
				(clearance outline)
				(anchor circle)
			)
			(primitives
				(gr_poly
					(pts
						(arc
							(start -0.1778 -0.2794)
							(mid -0.249642 -0.249642)
							(end -0.2794 -0.1778)
						)
						(arc
							(start -0.2794 0.1778)
							(mid -0.249642 0.249642)
							(end -0.1778 0.2794)
						)
						(arc
							(start 0.1778 0.2794)
							(mid 0.249642 0.249642)
							(end 0.2794 0.1778)
						)
						(arc
							(start 0.2794 -0.1778)
							(mid 0.249642 -0.249642)
							(end 0.1778 -0.2794)
						)
					)
					(width 0)
					(fill yes)
				)
			)
		)
		(pad "2" smd custom
			(at 0 0.4445 270)
			(size 0.1397 0.1397)
			(layers "F.Cu" "F.Mask" "F.Paste")
			(net "AGND_P3V3_STBY")
			(options
				(clearance outline)
				(anchor circle)
			)
			(primitives
				(gr_poly
					(pts
						(arc
							(start -0.1778 -0.2794)
							(mid -0.249642 -0.249642)
							(end -0.2794 -0.1778)
						)
						(arc
							(start -0.2794 0.1778)
							(mid -0.249642 0.249642)
							(end -0.1778 0.2794)
						)
						(arc
							(start 0.1778 0.2794)
							(mid 0.249642 0.249642)
							(end 0.2794 0.1778)
						)
						(arc
							(start 0.2794 -0.1778)
							(mid 0.249642 -0.249642)
							(end 0.1778 -0.2794)
						)
					)
					(width 0)
					(fill yes)
				)
			)
		)
	)
	(footprint ""
		(layer "F.Cu")
		(at 6.8072 -186.2836 -90)
		(property "Reference" "PR9006"
			(at 0 0 270)
			(layer "F.SilkS")
			(hide yes)
			(effects
				(font
					(size 1.27 1.27)
				)
			)
		)
		(property "Value" "0R2J-2-GP"
			(at 0.064008 -3.993896 270)
			(unlocked yes)
			(layer "F.Fab")
			(hide yes)
			(effects
				(font
					(size 1.016 1.016)
					(thickness 0.1524)
				)
			)
		)
		(property "Device Type" "R402H16"
			(at 0.064008 -5.517896 270)
			(unlocked yes)
			(layer "F.Fab")
			(hide yes)
			(effects
				(font
					(size 1.016 1.016)
					(thickness 0.1524)
				)
			)
		)
		(duplicate_pad_numbers_are_jumpers no)
		(fp_line
			(start -0.508 -0.9398)
			(end -0.508 0.9398)
			(stroke
				(width 0.1524)
				(type default)
			)
			(layer "F.SilkS")
		)
		(fp_line
			(start 0.508 -0.9398)
			(end -0.508 -0.9398)
			(stroke
				(width 0.1524)
				(type default)
			)
			(layer "F.SilkS")
		)
		(fp_rect
			(start -0.508 0.9398)
			(end 0.508 -0.9398)
			(stroke
				(width 0)
				(type default)
			)
			(fill no)
			(layer "F.CrtYd")
		)
		(fp_rect
			(start -0.508 0.9398)
			(end 0.508 -0.9398)
			(stroke
				(width 0)
				(type default)
			)
			(fill no)
			(layer "F.Fab")
		)
		(pad "1" smd custom
			(at 0 -0.4445 270)
			(size 0.1397 0.1397)
			(layers "F.Cu" "F.Mask" "F.Paste")
			(net "HSW_SDA_2")
			(options
				(clearance outline)
				(anchor circle)
			)
			(primitives
				(gr_poly
					(pts
						(arc
							(start -0.1778 -0.2794)
							(mid -0.249642 -0.249642)
							(end -0.2794 -0.1778)
						)
						(arc
							(start -0.2794 0.1778)
							(mid -0.249642 0.249642)
							(end -0.1778 0.2794)
						)
						(arc
							(start 0.1778 0.2794)
							(mid 0.249642 0.249642)
							(end 0.2794 0.1778)
						)
						(arc
							(start 0.2794 -0.1778)
							(mid 0.249642 -0.249642)
							(end 0.1778 -0.2794)
						)
					)
					(width 0)
					(fill yes)
				)
			)
		)
		(pad "2" smd custom
			(at 0 0.4445 270)
			(size 0.1397 0.1397)
			(layers "F.Cu" "F.Mask" "F.Paste")
			(net "BMC_I2C5_D_PEB_SDA")
			(options
				(clearance outline)
				(anchor circle)
			)
			(primitives
				(gr_poly
					(pts
						(arc
							(start -0.1778 -0.2794)
							(mid -0.249642 -0.249642)
							(end -0.2794 -0.1778)
						)
						(arc
							(start -0.2794 0.1778)
							(mid -0.249642 0.249642)
							(end -0.1778 0.2794)
						)
						(arc
							(start 0.1778 0.2794)
							(mid 0.249642 0.249642)
							(end 0.2794 0.1778)
						)
						(arc
							(start 0.2794 -0.1778)
							(mid 0.249642 -0.249642)
							(end 0.1778 -0.2794)
						)
					)
					(width 0)
					(fill yes)
				)
			)
		)
	)
	(footprint ""
		(layer "F.Cu")
		(at 227.457 -82.9564)
		(property "Reference" "U136"
			(at 0 0 0)
			(layer "F.SilkS")
			(hide yes)
			(effects
				(font
					(size 1.27 1.27)
				)
			)
		)
		(property "Value" "TMP75AIDGKR-GP"
			(at -0.1143 -9.1948 0)
			(unlocked yes)
			(layer "F.Fab")
			(hide yes)
			(effects
				(font
					(size 1.016 1.016)
					(thickness 0.1524)
				)
			)
		)
		(property "Device Type" "MSOP8-1H44"
			(at -0.1143 -10.795 0)
			(unlocked yes)
			(layer "F.Fab")
			(hide yes)
			(effects
				(font
					(size 1.016 1.016)
					(thickness 0.1524)
				)
			)
		)
		(duplicate_pad_numbers_are_jumpers no)
		(fp_line
			(start -1.9558 -1.016)
			(end -1.9558 1.016)
			(stroke
				(width 0.1524)
				(type default)
			)
			(layer "F.SilkS")
		)
		(fp_line
			(start -1.9558 -0.5461)
			(end -1.4478 -0.0381)
			(stroke
				(width 0.1524)
				(type default)
			)
			(layer "F.SilkS")
		)
		(fp_line
			(start -1.9558 1.016)
			(end 1.0795 1.016)
			(stroke
				(width 0.1524)
				(type default)
			)
			(layer "F.SilkS")
		)
		(fp_line
			(start -1.778 1.0922)
			(end -1.778 3.048)
			(stroke
				(width 0.508)
				(type default)
			)
			(layer "F.SilkS")
		)
		(fp_line
			(start -1.4478 -0.0381)
			(end -1.9558 0.4699)
			(stroke
				(width 0.1524)
				(type default)
			)
			(layer "F.SilkS")
		)
		(fp_line
			(start 1.0795 -1.016)
			(end -1.9558 -1.016)
			(stroke
				(width 0.1524)
				(type default)
			)
			(layer "F.SilkS")
		)
		(fp_line
			(start 1.0795 1.016)
			(end 1.0795 -1.016)
			(stroke
				(width 0.1524)
				(type default)
			)
			(layer "F.SilkS")
		)
		(fp_poly
			(pts
				(xy -1.1557 -1.016) (xy -1.1557 1.016) (xy 1.1557 1.016) (xy 1.1557 -1.016)
			)
			(stroke
				(width 0)
				(type default)
			)
			(fill yes)
			(layer "F.SilkS")
		)
		(fp_rect
			(start -1.4986 2.4511)
			(end 1.4986 -2.4511)
			(stroke
				(width 0)
				(type default)
			)
			(fill no)
			(layer "F.CrtYd")
		)
		(fp_poly
			(pts
				(xy -2.032 3.302) (xy -2.032 -3.302) (xy 2.032 -3.302) (xy 2.032 -2.1209) (xy 1.4986 -2.1209) (xy 1.4986 -2.4511)
				(xy -1.4986 -2.4511) (xy -1.4986 2.4511) (xy 1.4986 2.4511) (xy 1.4986 -2.1082) (xy 2.032 -2.1082)
				(xy 2.032 3.302)
			)
			(stroke
				(width 0)
				(type default)
			)
			(fill no)
			(layer "F.CrtYd")
		)
		(fp_rect
			(start -2.032 3.302)
			(end 2.032 -3.302)
			(stroke
				(width 0)
				(type default)
			)
			(fill no)
			(layer "F.Fab")
		)
		(pad "1" smd rect
			(at -0.97536 2.05486)
			(size 0.3556 1.524)
			(layers "F.Cu" "F.Mask" "F.Paste")
			(net "TEMP_3_SDA")
		)
		(pad "2" smd rect
			(at -0.32512 2.05486)
			(size 0.3556 1.524)
			(layers "F.Cu" "F.Mask" "F.Paste")
			(net "TEMP_3_SCL")
		)
		(pad "3" smd rect
			(at 0.32512 2.05486)
			(size 0.3556 1.524)
			(layers "F.Cu" "F.Mask" "F.Paste")
			(net "TEMP_3_ALERT")
		)
		(pad "4" smd rect
			(at 0.97536 2.05486)
			(size 0.3556 1.524)
			(layers "F.Cu" "F.Mask" "F.Paste")
			(net "GND")
		)
		(pad "5" smd rect
			(at 0.97536 -2.05486)
			(size 0.3556 1.524)
			(layers "F.Cu" "F.Mask" "F.Paste")
			(net "TEMP_3_A2")
		)
		(pad "6" smd rect
			(at 0.32512 -2.05486)
			(size 0.3556 1.524)
			(layers "F.Cu" "F.Mask" "F.Paste")
			(net "TEMP_3_A1")
		)
		(pad "7" smd rect
			(at -0.32512 -2.05486)
			(size 0.3556 1.524)
			(layers "F.Cu" "F.Mask" "F.Paste")
			(net "TEMP_3_A0")
		)
		(pad "8" smd rect
			(at -0.97536 -2.05486)
			(size 0.3556 1.524)
			(layers "F.Cu" "F.Mask" "F.Paste")
			(net "P3V3_STBY")
		)
	)
	(footprint ""
		(layer "F.Cu")
		(at 17.63268 -136.126474 90)
		(property "Reference" "R346"
			(at 0 0 90)
			(layer "F.SilkS")
			(hide yes)
			(effects
				(font
					(size 1.27 1.27)
				)
			)
		)
		(property "Value" "3K3R2F-2-GP"
			(at 0.064008 -3.993896 90)
			(unlocked yes)
			(layer "F.Fab")
			(hide yes)
			(effects
				(font
					(size 1.016 1.016)
					(thickness 0.1524)
				)
			)
		)
		(property "Device Type" "R402H16"
			(at 0.064008 -5.517896 90)
			(unlocked yes)
			(layer "F.Fab")
			(hide yes)
			(effects
				(font
					(size 1.016 1.016)
					(thickness 0.1524)
				)
			)
		)
		(duplicate_pad_numbers_are_jumpers no)
		(fp_line
			(start 0.508 -0.9398)
			(end -0.508 -0.9398)
			(stroke
				(width 0.1524)
				(type default)
			)
			(layer "F.SilkS")
		)
		(fp_line
			(start -0.508 -0.9398)
			(end -0.508 0.9398)
			(stroke
				(width 0.1524)
				(type default)
			)
			(layer "F.SilkS")
		)
		(fp_rect
			(start -0.508 0.9398)
			(end 0.508 -0.9398)
			(stroke
				(width 0)
				(type default)
			)
			(fill no)
			(layer "F.CrtYd")
		)
		(fp_rect
			(start -0.508 0.9398)
			(end 0.508 -0.9398)
			(stroke
				(width 0)
				(type default)
			)
			(fill no)
			(layer "F.Fab")
		)
		(pad "1" smd custom
			(at 0 -0.4445 90)
			(size 0.1397 0.1397)
			(layers "F.Cu" "F.Mask" "F.Paste")
			(net "P3V3_STBY")
			(options
				(clearance outline)
				(anchor circle)
			)
			(primitives
				(gr_poly
					(pts
						(arc
							(start -0.1778 -0.2794)
							(mid -0.249642 -0.249642)
							(end -0.2794 -0.1778)
						)
						(arc
							(start -0.2794 0.1778)
							(mid -0.249642 0.249642)
							(end -0.1778 0.2794)
						)
						(arc
							(start 0.1778 0.2794)
							(mid 0.249642 0.249642)
							(end 0.2794 0.1778)
						)
						(arc
							(start 0.2794 -0.1778)
							(mid 0.249642 -0.249642)
							(end 0.1778 -0.2794)
						)
					)
					(width 0)
					(fill yes)
				)
			)
		)
		(pad "2" smd custom
			(at 0 0.4445 90)
			(size 0.1397 0.1397)
			(layers "F.Cu" "F.Mask" "F.Paste")
			(net "ROMD1_R")
			(options
				(clearance outline)
				(anchor circle)
			)
			(primitives
				(gr_poly
					(pts
						(arc
							(start -0.1778 -0.2794)
							(mid -0.249642 -0.249642)
							(end -0.2794 -0.1778)
						)
						(arc
							(start -0.2794 0.1778)
							(mid -0.249642 0.249642)
							(end -0.1778 0.2794)
						)
						(arc
							(start 0.1778 0.2794)
							(mid 0.249642 0.249642)
							(end 0.2794 0.1778)
						)
						(arc
							(start 0.2794 -0.1778)
							(mid 0.249642 -0.249642)
							(end 0.1778 -0.2794)
						)
					)
					(width 0)
					(fill yes)
				)
			)
		)
	)
	(footprint ""
		(layer "F.Cu")
		(at 230.251 -8.382 90)
		(property "Reference" "R953"
			(at 0 0 90)
			(layer "F.SilkS")
			(hide yes)
			(effects
				(font
					(size 1.27 1.27)
				)
			)
		)
		(property "Value" "0R2J-2-GP"
			(at 0.064008 -3.993896 90)
			(unlocked yes)
			(layer "F.Fab")
			(hide yes)
			(effects
				(font
					(size 1.016 1.016)
					(thickness 0.1524)
				)
			)
		)
		(property "Device Type" "R402H16"
			(at 0.064008 -5.517896 90)
			(unlocked yes)
			(layer "F.Fab")
			(hide yes)
			(effects
				(font
					(size 1.016 1.016)
					(thickness 0.1524)
				)
			)
		)
		(duplicate_pad_numbers_are_jumpers no)
		(fp_line
			(start 0.508 -0.9398)
			(end -0.508 -0.9398)
			(stroke
				(width 0.1524)
				(type default)
			)
			(layer "F.SilkS")
		)
		(fp_line
			(start -0.508 -0.9398)
			(end -0.508 0.9398)
			(stroke
				(width 0.1524)
				(type default)
			)
			(layer "F.SilkS")
		)
		(fp_rect
			(start -0.508 0.9398)
			(end 0.508 -0.9398)
			(stroke
				(width 0)
				(type default)
			)
			(fill no)
			(layer "F.CrtYd")
		)
		(fp_rect
			(start -0.508 0.9398)
			(end 0.508 -0.9398)
			(stroke
				(width 0)
				(type default)
			)
			(fill no)
			(layer "F.Fab")
		)
		(pad "1" smd custom
			(at 0 -0.4445 90)
			(size 0.1397 0.1397)
			(layers "F.Cu" "F.Mask" "F.Paste")
			(net "TWI_SCL2_R")
			(options
				(clearance outline)
				(anchor circle)
			)
			(primitives
				(gr_poly
					(pts
						(arc
							(start -0.1778 -0.2794)
							(mid -0.249642 -0.249642)
							(end -0.2794 -0.1778)
						)
						(arc
							(start -0.2794 0.1778)
							(mid -0.249642 0.249642)
							(end -0.1778 0.2794)
						)
						(arc
							(start 0.1778 0.2794)
							(mid 0.249642 0.249642)
							(end 0.2794 0.1778)
						)
						(arc
							(start 0.2794 -0.1778)
							(mid 0.249642 -0.249642)
							(end 0.1778 -0.2794)
						)
					)
					(width 0)
					(fill yes)
				)
			)
		)
		(pad "2" smd custom
			(at 0 0.4445 90)
			(size 0.1397 0.1397)
			(layers "F.Cu" "F.Mask" "F.Paste")
			(net "TWI_SCL2")
			(options
				(clearance outline)
				(anchor circle)
			)
			(primitives
				(gr_poly
					(pts
						(arc
							(start -0.1778 -0.2794)
							(mid -0.249642 -0.249642)
							(end -0.2794 -0.1778)
						)
						(arc
							(start -0.2794 0.1778)
							(mid -0.249642 0.249642)
							(end -0.1778 0.2794)
						)
						(arc
							(start 0.1778 0.2794)
							(mid 0.249642 0.249642)
							(end 0.2794 0.1778)
						)
						(arc
							(start 0.2794 -0.1778)
							(mid 0.249642 -0.249642)
							(end 0.1778 -0.2794)
						)
					)
					(width 0)
					(fill yes)
				)
			)
		)
	)
	(footprint ""
		(layer "F.Cu")
		(at 69.3166 -74.93)
		(property "Reference" "R266"
			(at 0 0 0)
			(layer "F.SilkS")
			(hide yes)
			(effects
				(font
					(size 1.27 1.27)
				)
			)
		)
		(property "Value" "2K2R2J-2-GP"
			(at 0.064008 -3.993896 0)
			(unlocked yes)
			(layer "F.Fab")
			(hide yes)
			(effects
				(font
					(size 1.016 1.016)
					(thickness 0.1524)
				)
			)
		)
		(property "Device Type" "R402H16"
			(at 0.064008 -5.517896 0)
			(unlocked yes)
			(layer "F.Fab")
			(hide yes)
			(effects
				(font
					(size 1.016 1.016)
					(thickness 0.1524)
				)
			)
		)
		(duplicate_pad_numbers_are_jumpers no)
		(fp_line
			(start -0.508 -0.9398)
			(end -0.508 0.9398)
			(stroke
				(width 0.1524)
				(type default)
			)
			(layer "F.SilkS")
		)
		(fp_line
			(start 0.508 -0.9398)
			(end -0.508 -0.9398)
			(stroke
				(width 0.1524)
				(type default)
			)
			(layer "F.SilkS")
		)
		(fp_rect
			(start -0.508 0.9398)
			(end 0.508 -0.9398)
			(stroke
				(width 0)
				(type default)
			)
			(fill no)
			(layer "F.CrtYd")
		)
		(fp_rect
			(start -0.508 0.9398)
			(end 0.508 -0.9398)
			(stroke
				(width 0)
				(type default)
			)
			(fill no)
			(layer "F.Fab")
		)
		(pad "1" smd custom
			(at 0 -0.4445)
			(size 0.1397 0.1397)
			(layers "F.Cu" "F.Mask" "F.Paste")
			(net "P3V3_STBY")
			(options
				(clearance outline)
				(anchor circle)
			)
			(primitives
				(gr_poly
					(pts
						(arc
							(start -0.1778 -0.2794)
							(mid -0.249642 -0.249642)
							(end -0.2794 -0.1778)
						)
						(arc
							(start -0.2794 0.1778)
							(mid -0.249642 0.249642)
							(end -0.1778 0.2794)
						)
						(arc
							(start 0.1778 0.2794)
							(mid 0.249642 0.249642)
							(end 0.2794 0.1778)
						)
						(arc
							(start 0.2794 -0.1778)
							(mid 0.249642 -0.249642)
							(end 0.1778 -0.2794)
						)
					)
					(width 0)
					(fill yes)
				)
			)
		)
		(pad "2" smd custom
			(at 0 0.4445)
			(size 0.1397 0.1397)
			(layers "F.Cu" "F.Mask" "F.Paste")
			(net "PU_IBMC_BT_HOLD_N")
			(options
				(clearance outline)
				(anchor circle)
			)
			(primitives
				(gr_poly
					(pts
						(arc
							(start -0.1778 -0.2794)
							(mid -0.249642 -0.249642)
							(end -0.2794 -0.1778)
						)
						(arc
							(start -0.2794 0.1778)
							(mid -0.249642 0.249642)
							(end -0.1778 0.2794)
						)
						(arc
							(start 0.1778 0.2794)
							(mid 0.249642 0.249642)
							(end 0.2794 0.1778)
						)
						(arc
							(start 0.2794 -0.1778)
							(mid 0.249642 -0.249642)
							(end 0.1778 -0.2794)
						)
					)
					(width 0)
					(fill yes)
				)
			)
		)
	)
	(footprint ""
		(layer "F.Cu")
		(at 22.6568 -173.2026 90)
		(property "Reference" "R648"
			(at 0 0 90)
			(layer "F.SilkS")
			(hide yes)
			(effects
				(font
					(size 1.27 1.27)
				)
			)
		)
		(property "Value" "27KR2F-L-GP"
			(at 0.064008 -3.993896 90)
			(unlocked yes)
			(layer "F.Fab")
			(hide yes)
			(effects
				(font
					(size 1.016 1.016)
					(thickness 0.1524)
				)
			)
		)
		(property "Device Type" "R402H16"
			(at 0.064008 -5.517896 90)
			(unlocked yes)
			(layer "F.Fab")
			(hide yes)
			(effects
				(font
					(size 1.016 1.016)
					(thickness 0.1524)
				)
			)
		)
		(duplicate_pad_numbers_are_jumpers no)
		(fp_line
			(start 0.508 -0.9398)
			(end -0.508 -0.9398)
			(stroke
				(width 0.1524)
				(type default)
			)
			(layer "F.SilkS")
		)
		(fp_line
			(start -0.508 -0.9398)
			(end -0.508 0.9398)
			(stroke
				(width 0.1524)
				(type default)
			)
			(layer "F.SilkS")
		)
		(fp_rect
			(start -0.508 0.9398)
			(end 0.508 -0.9398)
			(stroke
				(width 0)
				(type default)
			)
			(fill no)
			(layer "F.CrtYd")
		)
		(fp_rect
			(start -0.508 0.9398)
			(end 0.508 -0.9398)
			(stroke
				(width 0)
				(type default)
			)
			(fill no)
			(layer "F.Fab")
		)
		(pad "1" smd custom
			(at 0 -0.4445 90)
			(size 0.1397 0.1397)
			(layers "F.Cu" "F.Mask" "F.Paste")
			(net "PCIE_MATED#_B")
			(options
				(clearance outline)
				(anchor circle)
			)
			(primitives
				(gr_poly
					(pts
						(arc
							(start -0.1778 -0.2794)
							(mid -0.249642 -0.249642)
							(end -0.2794 -0.1778)
						)
						(arc
							(start -0.2794 0.1778)
							(mid -0.249642 0.249642)
							(end -0.1778 0.2794)
						)
						(arc
							(start 0.1778 0.2794)
							(mid 0.249642 0.249642)
							(end 0.2794 0.1778)
						)
						(arc
							(start 0.2794 -0.1778)
							(mid 0.249642 -0.249642)
							(end 0.1778 -0.2794)
						)
					)
					(width 0)
					(fill yes)
				)
			)
		)
		(pad "2" smd custom
			(at 0 0.4445 90)
			(size 0.1397 0.1397)
			(layers "F.Cu" "F.Mask" "F.Paste")
			(net "P12V_PCIE")
			(options
				(clearance outline)
				(anchor circle)
			)
			(primitives
				(gr_poly
					(pts
						(arc
							(start -0.1778 -0.2794)
							(mid -0.249642 -0.249642)
							(end -0.2794 -0.1778)
						)
						(arc
							(start -0.2794 0.1778)
							(mid -0.249642 0.249642)
							(end -0.1778 0.2794)
						)
						(arc
							(start 0.1778 0.2794)
							(mid 0.249642 0.249642)
							(end 0.2794 0.1778)
						)
						(arc
							(start 0.2794 -0.1778)
							(mid 0.249642 -0.249642)
							(end 0.1778 -0.2794)
						)
					)
					(width 0)
					(fill yes)
				)
			)
		)
	)
	(footprint ""
		(layer "F.Cu")
		(at 45.936916 -113.454688 -90)
		(property "Reference" "R561"
			(at 0 0 270)
			(layer "F.SilkS")
			(hide yes)
			(effects
				(font
					(size 1.27 1.27)
				)
			)
		)
		(property "Value" "10KR2F-2-GP"
			(at 0.064008 -3.993896 270)
			(unlocked yes)
			(layer "F.Fab")
			(hide yes)
			(effects
				(font
					(size 1.016 1.016)
					(thickness 0.1524)
				)
			)
		)
		(property "Device Type" "R402H16"
			(at 0.064008 -5.517896 270)
			(unlocked yes)
			(layer "F.Fab")
			(hide yes)
			(effects
				(font
					(size 1.016 1.016)
					(thickness 0.1524)
				)
			)
		)
		(duplicate_pad_numbers_are_jumpers no)
		(fp_line
			(start -0.508 -0.9398)
			(end -0.508 0.9398)
			(stroke
				(width 0.1524)
				(type default)
			)
			(layer "F.SilkS")
		)
		(fp_line
			(start 0.508 -0.9398)
			(end -0.508 -0.9398)
			(stroke
				(width 0.1524)
				(type default)
			)
			(layer "F.SilkS")
		)
		(fp_rect
			(start -0.508 0.9398)
			(end 0.508 -0.9398)
			(stroke
				(width 0)
				(type default)
			)
			(fill no)
			(layer "F.CrtYd")
		)
		(fp_rect
			(start -0.508 0.9398)
			(end 0.508 -0.9398)
			(stroke
				(width 0)
				(type default)
			)
			(fill no)
			(layer "F.Fab")
		)
		(pad "1" smd custom
			(at 0 -0.4445 270)
			(size 0.1397 0.1397)
			(layers "F.Cu" "F.Mask" "F.Paste")
			(net "BMC_JTAG_L_EN")
			(options
				(clearance outline)
				(anchor circle)
			)
			(primitives
				(gr_poly
					(pts
						(arc
							(start -0.1778 -0.2794)
							(mid -0.249642 -0.249642)
							(end -0.2794 -0.1778)
						)
						(arc
							(start -0.2794 0.1778)
							(mid -0.249642 0.249642)
							(end -0.1778 0.2794)
						)
						(arc
							(start 0.1778 0.2794)
							(mid 0.249642 0.249642)
							(end 0.2794 0.1778)
						)
						(arc
							(start 0.2794 -0.1778)
							(mid 0.249642 -0.249642)
							(end 0.1778 -0.2794)
						)
					)
					(width 0)
					(fill yes)
				)
			)
		)
		(pad "2" smd custom
			(at 0 0.4445 270)
			(size 0.1397 0.1397)
			(layers "F.Cu" "F.Mask" "F.Paste")
			(net "GND")
			(options
				(clearance outline)
				(anchor circle)
			)
			(primitives
				(gr_poly
					(pts
						(arc
							(start -0.1778 -0.2794)
							(mid -0.249642 -0.249642)
							(end -0.2794 -0.1778)
						)
						(arc
							(start -0.2794 0.1778)
							(mid -0.249642 0.249642)
							(end -0.1778 0.2794)
						)
						(arc
							(start 0.1778 0.2794)
							(mid 0.249642 0.249642)
							(end 0.2794 0.1778)
						)
						(arc
							(start 0.2794 -0.1778)
							(mid 0.249642 -0.249642)
							(end 0.1778 -0.2794)
						)
					)
					(width 0)
					(fill yes)
				)
			)
		)
	)
	(footprint ""
		(layer "F.Cu")
		(at 50.362866 -126.04242)
		(property "Reference" "TP177"
			(at 0 0 0)
			(layer "F.SilkS")
			(hide yes)
			(effects
				(font
					(size 1.27 1.27)
				)
			)
		)
		(property "Value" "TPAD28-2-GP"
			(at -0.0127 -1.6637 0)
			(unlocked yes)
			(layer "F.Fab")
			(hide yes)
			(effects
				(font
					(size 1.016 1.016)
					(thickness 0.1524)
				)
			)
		)
		(property "Device Type" "TPAD28"
			(at -0.0127 -3.1877 0)
			(unlocked yes)
			(layer "F.Fab")
			(hide yes)
			(effects
				(font
					(size 1.016 1.016)
					(thickness 0.1524)
				)
			)
		)
		(duplicate_pad_numbers_are_jumpers no)
		(fp_poly
			(pts
				(arc
					(start 0.3556 0)
					(mid -0.3556 0)
					(end 0.3556 0)
				)
			)
			(stroke
				(width 0)
				(type default)
			)
			(fill no)
			(layer "F.CrtYd")
		)
		(fp_poly
			(pts
				(arc
					(start 0.6096 0)
					(mid -0.6096 0)
					(end 0.6096 0)
				)
			)
			(stroke
				(width 0)
				(type default)
			)
			(fill no)
			(layer "F.Fab")
		)
		(pad "1" smd circle
			(at 0 0)
			(size 0.7112 0.7112)
			(layers "F.Cu" "F.Mask" "F.Paste")
			(net "JTAG_BMC_TMS")
		)
	)
	(footprint ""
		(layer "F.Cu")
		(at 310.007 -65.5066)
		(property "Reference" "PG43"
			(at 0 0 0)
			(layer "F.SilkS")
			(hide yes)
			(effects
				(font
					(size 1.27 1.27)
				)
			)
		)
		(property "Value" "GAP-CLOSE-PWR-3-GP"
			(at 0.0254 -6.5786 0)
			(unlocked yes)
			(layer "F.Fab")
			(hide yes)
			(effects
				(font
					(size 1.016 1.016)
					(thickness 0.1524)
				)
			)
		)
		(property "Device Type" "GAP-CLOSE-PWR-3"
			(at 0.0254 -8.255 0)
			(unlocked yes)
			(layer "F.Fab")
			(hide yes)
			(effects
				(font
					(size 1.016 1.016)
					(thickness 0.1524)
				)
			)
		)
		(duplicate_pad_numbers_are_jumpers no)
		(fp_rect
			(start -0.7112 0.4572)
			(end 0.7112 -0.4572)
			(stroke
				(width 0)
				(type default)
			)
			(fill no)
			(layer "F.CrtYd")
		)
		(fp_poly
			(pts
				(xy -0.7112 -0.4572) (xy 0.7112 -0.4572) (xy 0.7112 0.4572) (xy -0.7112 0.4572)
			)
			(stroke
				(width 0)
				(type default)
			)
			(fill no)
			(layer "F.Fab")
		)
		(pad "1" smd rect
			(at -0.3048 0)
			(size 0.6604 0.762)
			(layers "F.Cu" "F.Mask" "F.Paste")
			(net "DUT_VDD")
		)
		(pad "2" smd rect
			(at 0.3048 0)
			(size 0.6604 0.762)
			(layers "F.Cu" "F.Mask" "F.Paste")
			(net "P0V9_E")
		)
	)
	(footprint ""
		(layer "F.Cu")
		(at 141.866874 -97.17532)
		(property "Reference" "PR75"
			(at 0 0 0)
			(layer "F.SilkS")
			(hide yes)
			(effects
				(font
					(size 1.27 1.27)
				)
			)
		)
		(property "Value" "0R2J-2-GP"
			(at 0.064008 -3.993896 0)
			(unlocked yes)
			(layer "F.Fab")
			(hide yes)
			(effects
				(font
					(size 1.016 1.016)
					(thickness 0.1524)
				)
			)
		)
		(property "Device Type" "R402H16"
			(at 0.064008 -5.517896 0)
			(unlocked yes)
			(layer "F.Fab")
			(hide yes)
			(effects
				(font
					(size 1.016 1.016)
					(thickness 0.1524)
				)
			)
		)
		(duplicate_pad_numbers_are_jumpers no)
		(fp_line
			(start -0.508 -0.9398)
			(end -0.508 0.9398)
			(stroke
				(width 0.1524)
				(type default)
			)
			(layer "F.SilkS")
		)
		(fp_line
			(start 0.508 -0.9398)
			(end -0.508 -0.9398)
			(stroke
				(width 0.1524)
				(type default)
			)
			(layer "F.SilkS")
		)
		(fp_rect
			(start -0.508 0.9398)
			(end 0.508 -0.9398)
			(stroke
				(width 0)
				(type default)
			)
			(fill no)
			(layer "F.CrtYd")
		)
		(fp_rect
			(start -0.508 0.9398)
			(end 0.508 -0.9398)
			(stroke
				(width 0)
				(type default)
			)
			(fill no)
			(layer "F.Fab")
		)
		(pad "1" smd custom
			(at 0 -0.4445)
			(size 0.1397 0.1397)
			(layers "F.Cu" "F.Mask" "F.Paste")
			(net "P5V_STBY")
			(options
				(clearance outline)
				(anchor circle)
			)
			(primitives
				(gr_poly
					(pts
						(arc
							(start -0.1778 -0.2794)
							(mid -0.249642 -0.249642)
							(end -0.2794 -0.1778)
						)
						(arc
							(start -0.2794 0.1778)
							(mid -0.249642 0.249642)
							(end -0.1778 0.2794)
						)
						(arc
							(start 0.1778 0.2794)
							(mid 0.249642 0.249642)
							(end 0.2794 0.1778)
						)
						(arc
							(start 0.2794 -0.1778)
							(mid 0.249642 -0.249642)
							(end 0.1778 -0.2794)
						)
					)
					(width 0)
					(fill yes)
				)
			)
		)
		(pad "2" smd custom
			(at 0 0.4445)
			(size 0.1397 0.1397)
			(layers "F.Cu" "F.Mask" "F.Paste")
			(net "VR_P1V8_STBY_BIAS")
			(options
				(clearance outline)
				(anchor circle)
			)
			(primitives
				(gr_poly
					(pts
						(arc
							(start -0.1778 -0.2794)
							(mid -0.249642 -0.249642)
							(end -0.2794 -0.1778)
						)
						(arc
							(start -0.2794 0.1778)
							(mid -0.249642 0.249642)
							(end -0.1778 0.2794)
						)
						(arc
							(start 0.1778 0.2794)
							(mid 0.249642 0.249642)
							(end 0.2794 0.1778)
						)
						(arc
							(start 0.2794 -0.1778)
							(mid 0.249642 -0.249642)
							(end 0.1778 -0.2794)
						)
					)
					(width 0)
					(fill yes)
				)
			)
		)
	)
	(footprint ""
		(layer "F.Cu")
		(at 156.718 -98.7044 180)
		(property "Reference" "R96"
			(at 0 0 180)
			(layer "F.SilkS")
			(hide yes)
			(effects
				(font
					(size 1.27 1.27)
				)
			)
		)
		(property "Value" "10KR2F-2-GP"
			(at 0.064008 -3.993896 180)
			(unlocked yes)
			(layer "F.Fab")
			(hide yes)
			(effects
				(font
					(size 1.016 1.016)
					(thickness 0.1524)
				)
			)
		)
		(property "Device Type" "R402H16"
			(at 0.064008 -5.517896 180)
			(unlocked yes)
			(layer "F.Fab")
			(hide yes)
			(effects
				(font
					(size 1.016 1.016)
					(thickness 0.1524)
				)
			)
		)
		(duplicate_pad_numbers_are_jumpers no)
		(fp_line
			(start 0.508 -0.9398)
			(end -0.508 -0.9398)
			(stroke
				(width 0.1524)
				(type default)
			)
			(layer "F.SilkS")
		)
		(fp_line
			(start -0.508 -0.9398)
			(end -0.508 0.9398)
			(stroke
				(width 0.1524)
				(type default)
			)
			(layer "F.SilkS")
		)
		(fp_rect
			(start -0.508 0.9398)
			(end 0.508 -0.9398)
			(stroke
				(width 0)
				(type default)
			)
			(fill no)
			(layer "F.CrtYd")
		)
		(fp_rect
			(start -0.508 0.9398)
			(end 0.508 -0.9398)
			(stroke
				(width 0)
				(type default)
			)
			(fill no)
			(layer "F.Fab")
		)
		(pad "1" smd custom
			(at 0 -0.4445 180)
			(size 0.1397 0.1397)
			(layers "F.Cu" "F.Mask" "F.Paste")
			(net "CLKGNE_SS_EN")
			(options
				(clearance outline)
				(anchor circle)
			)
			(primitives
				(gr_poly
					(pts
						(arc
							(start -0.1778 -0.2794)
							(mid -0.249642 -0.249642)
							(end -0.2794 -0.1778)
						)
						(arc
							(start -0.2794 0.1778)
							(mid -0.249642 0.249642)
							(end -0.1778 0.2794)
						)
						(arc
							(start 0.1778 0.2794)
							(mid 0.249642 0.249642)
							(end 0.2794 0.1778)
						)
						(arc
							(start 0.2794 -0.1778)
							(mid 0.249642 -0.249642)
							(end 0.1778 -0.2794)
						)
					)
					(width 0)
					(fill yes)
				)
			)
		)
		(pad "2" smd custom
			(at 0 0.4445 180)
			(size 0.1397 0.1397)
			(layers "F.Cu" "F.Mask" "F.Paste")
			(net "P1V8_STBY")
			(options
				(clearance outline)
				(anchor circle)
			)
			(primitives
				(gr_poly
					(pts
						(arc
							(start -0.1778 -0.2794)
							(mid -0.249642 -0.249642)
							(end -0.2794 -0.1778)
						)
						(arc
							(start -0.2794 0.1778)
							(mid -0.249642 0.249642)
							(end -0.1778 0.2794)
						)
						(arc
							(start 0.1778 0.2794)
							(mid 0.249642 0.249642)
							(end 0.2794 0.1778)
						)
						(arc
							(start 0.2794 -0.1778)
							(mid 0.249642 -0.249642)
							(end 0.1778 -0.2794)
						)
					)
					(width 0)
					(fill yes)
				)
			)
		)
	)
	(footprint ""
		(layer "F.Cu")
		(at 31.623 -53.721 -90)
		(property "Reference" "TC12"
			(at 0 0 270)
			(layer "F.SilkS")
			(hide yes)
			(effects
				(font
					(size 1.27 1.27)
				)
			)
		)
		(property "Value" "SC10U16V5KX-1-GP"
			(at -0.0762 -6.1214 270)
			(unlocked yes)
			(layer "F.Fab")
			(hide yes)
			(effects
				(font
					(size 1.016 1.016)
					(thickness 0.1524)
				)
			)
		)
		(property "Device Type" "C805H54"
			(at -0.0762 -8.1534 270)
			(unlocked yes)
			(layer "F.Fab")
			(hide yes)
			(effects
				(font
					(size 1.016 1.016)
					(thickness 0.1524)
				)
			)
		)
		(duplicate_pad_numbers_are_jumpers no)
		(fp_line
			(start 0.635 0)
			(end -0.635 0)
			(stroke
				(width 0.508)
				(type default)
			)
			(layer "F.SilkS")
		)
		(fp_rect
			(start -0.9652 1.778)
			(end 0.9652 -1.778)
			(stroke
				(width 0)
				(type default)
			)
			(fill no)
			(layer "F.CrtYd")
		)
		(fp_poly
			(pts
				(xy -0.9652 -1.778) (xy 0.9652 -1.778) (xy 0.9652 1.778) (xy -0.9652 1.778)
			)
			(stroke
				(width 0)
				(type default)
			)
			(fill no)
			(layer "F.Fab")
		)
		(pad "1" smd rect
			(at 0 -0.9652 270)
			(size 1.397 1.143)
			(layers "F.Cu" "F.Mask" "F.Paste")
			(net "P5V_USB")
		)
		(pad "2" smd rect
			(at 0 0.9652 270)
			(size 1.397 1.143)
			(layers "F.Cu" "F.Mask" "F.Paste")
			(net "GND")
		)
	)
	(footprint ""
		(layer "F.Cu")
		(at 345.217496 -43.97248)
		(property "Reference" "R694"
			(at 0 0 0)
			(layer "F.SilkS")
			(hide yes)
			(effects
				(font
					(size 1.27 1.27)
				)
			)
		)
		(property "Value" "4K7R2F-GP"
			(at 0.064008 -3.993896 0)
			(unlocked yes)
			(layer "F.Fab")
			(hide yes)
			(effects
				(font
					(size 1.016 1.016)
					(thickness 0.1524)
				)
			)
		)
		(property "Device Type" "R402H16"
			(at 0.064008 -5.517896 0)
			(unlocked yes)
			(layer "F.Fab")
			(hide yes)
			(effects
				(font
					(size 1.016 1.016)
					(thickness 0.1524)
				)
			)
		)
		(duplicate_pad_numbers_are_jumpers no)
		(fp_line
			(start -0.508 -0.9398)
			(end -0.508 0.9398)
			(stroke
				(width 0.1524)
				(type default)
			)
			(layer "F.SilkS")
		)
		(fp_line
			(start 0.508 -0.9398)
			(end -0.508 -0.9398)
			(stroke
				(width 0.1524)
				(type default)
			)
			(layer "F.SilkS")
		)
		(fp_rect
			(start -0.508 0.9398)
			(end 0.508 -0.9398)
			(stroke
				(width 0)
				(type default)
			)
			(fill no)
			(layer "F.CrtYd")
		)
		(fp_rect
			(start -0.508 0.9398)
			(end 0.508 -0.9398)
			(stroke
				(width 0)
				(type default)
			)
			(fill no)
			(layer "F.Fab")
		)
		(pad "1" smd custom
			(at 0 -0.4445)
			(size 0.1397 0.1397)
			(layers "F.Cu" "F.Mask" "F.Paste")
			(net "PM8536_RST#_LS")
			(options
				(clearance outline)
				(anchor circle)
			)
			(primitives
				(gr_poly
					(pts
						(arc
							(start -0.1778 -0.2794)
							(mid -0.249642 -0.249642)
							(end -0.2794 -0.1778)
						)
						(arc
							(start -0.2794 0.1778)
							(mid -0.249642 0.249642)
							(end -0.1778 0.2794)
						)
						(arc
							(start 0.1778 0.2794)
							(mid 0.249642 0.249642)
							(end 0.2794 0.1778)
						)
						(arc
							(start 0.2794 -0.1778)
							(mid 0.249642 -0.249642)
							(end 0.1778 -0.2794)
						)
					)
					(width 0)
					(fill yes)
				)
			)
		)
		(pad "2" smd custom
			(at 0 0.4445)
			(size 0.1397 0.1397)
			(layers "F.Cu" "F.Mask" "F.Paste")
			(net "P3V3_STBY")
			(options
				(clearance outline)
				(anchor circle)
			)
			(primitives
				(gr_poly
					(pts
						(arc
							(start -0.1778 -0.2794)
							(mid -0.249642 -0.249642)
							(end -0.2794 -0.1778)
						)
						(arc
							(start -0.2794 0.1778)
							(mid -0.249642 0.249642)
							(end -0.1778 0.2794)
						)
						(arc
							(start 0.1778 0.2794)
							(mid 0.249642 0.249642)
							(end 0.2794 0.1778)
						)
						(arc
							(start 0.2794 -0.1778)
							(mid 0.249642 -0.249642)
							(end 0.1778 -0.2794)
						)
					)
					(width 0)
					(fill yes)
				)
			)
		)
	)
	(footprint ""
		(layer "F.Cu")
		(at 151.527002 -69.699632 90)
		(property "Reference" "PC210"
			(at 0 0 90)
			(layer "F.SilkS")
			(hide yes)
			(effects
				(font
					(size 1.27 1.27)
				)
			)
		)
		(property "Value" "SC22U25V6KX-GP-U"
			(at -2.860802 -5.279644 90)
			(unlocked yes)
			(layer "F.Fab")
			(hide yes)
			(effects
				(font
					(size 1.016 1.016)
					(thickness 0.1524)
				)
			)
		)
		(property "Device Type" "C1206-TO0D3H75"
			(at -2.860802 -6.803644 90)
			(unlocked yes)
			(layer "F.Fab")
			(hide yes)
			(effects
				(font
					(size 1.016 1.016)
					(thickness 0.1524)
				)
			)
		)
		(duplicate_pad_numbers_are_jumpers no)
		(fp_line
			(start 1.3081 -2.3749)
			(end 1.3081 2.3749)
			(stroke
				(width 0.1524)
				(type default)
			)
			(layer "F.SilkS")
		)
		(fp_line
			(start -1.3081 -2.3749)
			(end 1.3081 -2.3749)
			(stroke
				(width 0.1524)
				(type default)
			)
			(layer "F.SilkS")
		)
		(fp_line
			(start 1.3081 2.3749)
			(end -1.3081 2.3749)
			(stroke
				(width 0.1524)
				(type default)
			)
			(layer "F.SilkS")
		)
		(fp_line
			(start -1.3081 2.3749)
			(end -1.3081 -2.3749)
			(stroke
				(width 0.1524)
				(type default)
			)
			(layer "F.SilkS")
		)
		(fp_rect
			(start -0.8001 1.6002)
			(end 0.8001 -1.6002)
			(stroke
				(width 0)
				(type default)
			)
			(fill no)
			(layer "F.CrtYd")
		)
		(fp_poly
			(pts
				(xy -1.5621 2.4511) (xy -1.5621 1.6002) (xy 0.8001 1.6002) (xy 0.8001 -1.6002) (xy -0.8001 -1.6002)
				(xy -0.8001 1.5875) (xy -1.5621 1.5875) (xy -1.5621 -2.4511) (xy 1.5621 -2.4511) (xy 1.5621 2.4511)
			)
			(stroke
				(width 0)
				(type default)
			)
			(fill no)
			(layer "F.CrtYd")
		)
		(fp_rect
			(start -1.5621 2.4511)
			(end 1.5621 -2.4511)
			(stroke
				(width 0)
				(type default)
			)
			(fill no)
			(layer "F.Fab")
		)
		(pad "1" smd rect
			(at 0 -1.392936 90)
			(size 2.1082 1.4478)
			(layers "F.Cu" "F.Mask" "F.Paste")
			(net "P0V9_VIN")
		)
		(pad "2" smd rect
			(at 0 1.392936 90)
			(size 2.1082 1.4478)
			(layers "F.Cu" "F.Mask" "F.Paste")
			(net "GND")
		)
	)
	(footprint ""
		(layer "F.Cu")
		(at 336.60588 -31.90748 180)
		(property "Reference" "Q29"
			(at 0 0 180)
			(layer "F.SilkS")
			(hide yes)
			(effects
				(font
					(size 1.27 1.27)
				)
			)
		)
		(property "Value" "2N7002K-1-GP"
			(at 0.127 -8.9662 180)
			(unlocked yes)
			(layer "F.Fab")
			(hide yes)
			(effects
				(font
					(size 1.016 1.016)
					(thickness 0.1524)
				)
			)
		)
		(property "Device Type" "SOT23DGS2D4H44"
			(at 0.127 -10.4902 180)
			(unlocked yes)
			(layer "F.Fab")
			(hide yes)
			(effects
				(font
					(size 1.016 1.016)
					(thickness 0.1524)
				)
			)
		)
		(duplicate_pad_numbers_are_jumpers no)
		(fp_line
			(start 1.651 1.778)
			(end 1.651 -1.778)
			(stroke
				(width 0.1524)
				(type default)
			)
			(layer "F.SilkS")
		)
		(fp_line
			(start 1.651 -1.778)
			(end -1.651 -1.778)
			(stroke
				(width 0.1524)
				(type default)
			)
			(layer "F.SilkS")
		)
		(fp_line
			(start -1.651 1.778)
			(end 1.651 1.778)
			(stroke
				(width 0.1524)
				(type default)
			)
			(layer "F.SilkS")
		)
		(fp_line
			(start -1.651 -1.778)
			(end -1.651 1.778)
			(stroke
				(width 0.1524)
				(type default)
			)
			(layer "F.SilkS")
		)
		(fp_poly
			(pts
				(xy -1.778 1.8796) (xy -1.778 -1.8796) (xy 1.778 -1.8796) (xy 1.778 1.8796)
			)
			(stroke
				(width 0)
				(type default)
			)
			(fill no)
			(layer "F.CrtYd")
		)
		(fp_poly
			(pts
				(xy -1.778 1.8796) (xy -1.778 -1.8796) (xy 1.778 -1.8796) (xy 1.778 1.8796)
			)
			(stroke
				(width 0)
				(type default)
			)
			(fill no)
			(layer "F.Fab")
		)
		(pad "D" smd custom
			(at 0 -0.9525 180)
			(size 0.1905 0.1905)
			(layers "F.Cu" "F.Mask" "F.Paste")
			(net "LED_Q_8")
			(options
				(clearance outline)
				(anchor circle)
			)
			(primitives
				(gr_poly
					(pts
						(arc
							(start -0.1778 0.5715)
							(mid -0.321484 0.511984)
							(end -0.381 0.3683)
						)
						(arc
							(start -0.381 -0.3683)
							(mid -0.321484 -0.511984)
							(end -0.1778 -0.5715)
						)
						(arc
							(start 0.1778 -0.5715)
							(mid 0.321484 -0.511984)
							(end 0.381 -0.3683)
						)
						(arc
							(start 0.381 0.3683)
							(mid 0.321484 0.511984)
							(end 0.1778 0.5715)
						)
					)
					(width 0)
					(fill yes)
				)
			)
		)
		(pad "G" smd custom
			(at -0.98425 0.9525 180)
			(size 0.1905 0.1905)
			(layers "F.Cu" "F.Mask" "F.Paste")
			(net "UPLINK8_R")
			(options
				(clearance outline)
				(anchor circle)
			)
			(primitives
				(gr_poly
					(pts
						(arc
							(start -0.1778 0.5715)
							(mid -0.321484 0.511984)
							(end -0.381 0.3683)
						)
						(arc
							(start -0.381 -0.3683)
							(mid -0.321484 -0.511984)
							(end -0.1778 -0.5715)
						)
						(arc
							(start 0.1778 -0.5715)
							(mid 0.321484 -0.511984)
							(end 0.381 -0.3683)
						)
						(arc
							(start 0.381 0.3683)
							(mid 0.321484 0.511984)
							(end 0.1778 0.5715)
						)
					)
					(width 0)
					(fill yes)
				)
			)
		)
		(pad "S" smd custom
			(at 0.98425 0.9525 180)
			(size 0.1905 0.1905)
			(layers "F.Cu" "F.Mask" "F.Paste")
			(net "GND")
			(options
				(clearance outline)
				(anchor circle)
			)
			(primitives
				(gr_poly
					(pts
						(arc
							(start -0.1778 0.5715)
							(mid -0.321484 0.511984)
							(end -0.381 0.3683)
						)
						(arc
							(start -0.381 -0.3683)
							(mid -0.321484 -0.511984)
							(end -0.1778 -0.5715)
						)
						(arc
							(start 0.1778 -0.5715)
							(mid 0.321484 -0.511984)
							(end 0.381 -0.3683)
						)
						(arc
							(start 0.381 0.3683)
							(mid 0.321484 0.511984)
							(end 0.1778 0.5715)
						)
					)
					(width 0)
					(fill yes)
				)
			)
		)
	)
	(footprint ""
		(layer "F.Cu")
		(at 191.897 -16.256 90)
		(property "Reference" "SR716"
			(at 0 0 90)
			(layer "F.SilkS")
			(hide yes)
			(effects
				(font
					(size 1.27 1.27)
				)
			)
		)
		(property "Value" "150R2F-1-GP"
			(at 0.064008 -3.993896 90)
			(unlocked yes)
			(layer "F.Fab")
			(hide yes)
			(effects
				(font
					(size 1.016 1.016)
					(thickness 0.1524)
				)
			)
		)
		(property "Device Type" "R402H16"
			(at 0.064008 -5.517896 90)
			(unlocked yes)
			(layer "F.Fab")
			(hide yes)
			(effects
				(font
					(size 1.016 1.016)
					(thickness 0.1524)
				)
			)
		)
		(duplicate_pad_numbers_are_jumpers no)
		(fp_line
			(start 0.508 -0.9398)
			(end -0.508 -0.9398)
			(stroke
				(width 0.1524)
				(type default)
			)
			(layer "F.SilkS")
		)
		(fp_line
			(start -0.508 -0.9398)
			(end -0.508 0.9398)
			(stroke
				(width 0.1524)
				(type default)
			)
			(layer "F.SilkS")
		)
		(fp_rect
			(start -0.508 0.9398)
			(end 0.508 -0.9398)
			(stroke
				(width 0)
				(type default)
			)
			(fill no)
			(layer "F.CrtYd")
		)
		(fp_rect
			(start -0.508 0.9398)
			(end 0.508 -0.9398)
			(stroke
				(width 0)
				(type default)
			)
			(fill no)
			(layer "F.Fab")
		)
		(pad "1" smd custom
			(at 0 -0.4445 90)
			(size 0.1397 0.1397)
			(layers "F.Cu" "F.Mask" "F.Paste")
			(net "P3V3_STBY")
			(options
				(clearance outline)
				(anchor circle)
			)
			(primitives
				(gr_poly
					(pts
						(arc
							(start -0.1778 -0.2794)
							(mid -0.249642 -0.249642)
							(end -0.2794 -0.1778)
						)
						(arc
							(start -0.2794 0.1778)
							(mid -0.249642 0.249642)
							(end -0.1778 0.2794)
						)
						(arc
							(start 0.1778 0.2794)
							(mid 0.249642 0.249642)
							(end 0.2794 0.1778)
						)
						(arc
							(start 0.2794 -0.1778)
							(mid 0.249642 -0.249642)
							(end 0.1778 -0.2794)
						)
					)
					(width 0)
					(fill yes)
				)
			)
		)
		(pad "2" smd custom
			(at 0 0.4445 90)
			(size 0.1397 0.1397)
			(layers "F.Cu" "F.Mask" "F.Paste")
			(net "LED_R_11")
			(options
				(clearance outline)
				(anchor circle)
			)
			(primitives
				(gr_poly
					(pts
						(arc
							(start -0.1778 -0.2794)
							(mid -0.249642 -0.249642)
							(end -0.2794 -0.1778)
						)
						(arc
							(start -0.2794 0.1778)
							(mid -0.249642 0.249642)
							(end -0.1778 0.2794)
						)
						(arc
							(start 0.1778 0.2794)
							(mid 0.249642 0.249642)
							(end 0.2794 0.1778)
						)
						(arc
							(start 0.2794 -0.1778)
							(mid 0.249642 -0.249642)
							(end 0.1778 -0.2794)
						)
					)
					(width 0)
					(fill yes)
				)
			)
		)
	)
	(footprint ""
		(layer "F.Cu")
		(at 38.1508 -186.5376)
		(property "Reference" "C700"
			(at 0 0 0)
			(layer "F.SilkS")
			(hide yes)
			(effects
				(font
					(size 1.27 1.27)
				)
			)
		)
		(property "Value" "SCD1U16V2KX-3GP"
			(at 1.1811 -2.7051 0)
			(unlocked yes)
			(layer "F.Fab")
			(hide yes)
			(effects
				(font
					(size 1.016 1.016)
					(thickness 0.1524)
				)
			)
		)
		(property "Device Type" "C402H22"
			(at 1.1811 -4.2291 0)
			(unlocked yes)
			(layer "F.Fab")
			(hide yes)
			(effects
				(font
					(size 1.016 1.016)
					(thickness 0.1524)
				)
			)
		)
		(duplicate_pad_numbers_are_jumpers no)
		(fp_rect
			(start -0.4318 0.9525)
			(end 0.4318 -0.9525)
			(stroke
				(width 0)
				(type default)
			)
			(fill no)
			(layer "F.CrtYd")
		)
		(fp_rect
			(start -0.4318 0.9525)
			(end 0.4318 -0.9525)
			(stroke
				(width 0)
				(type default)
			)
			(fill no)
			(layer "F.Fab")
		)
		(pad "1" smd custom
			(at 0 -0.4445)
			(size 0.1524 0.1524)
			(layers "F.Cu" "F.Mask" "F.Paste")
			(net "P3V3_STBY")
			(options
				(clearance outline)
				(anchor circle)
			)
			(primitives
				(gr_poly
					(pts
						(arc
							(start 0.3048 -0.2032)
							(mid 0.275042 -0.275042)
							(end 0.2032 -0.3048)
						)
						(arc
							(start -0.2032 -0.3048)
							(mid -0.275042 -0.275042)
							(end -0.3048 -0.2032)
						)
						(arc
							(start -0.3048 0.2032)
							(mid -0.275042 0.275042)
							(end -0.2032 0.3048)
						)
						(arc
							(start 0.2032 0.3048)
							(mid 0.275042 0.275042)
							(end 0.3048 0.2032)
						)
					)
					(width 0)
					(fill yes)
				)
			)
		)
		(pad "2" smd custom
			(at 0 0.4445)
			(size 0.1524 0.1524)
			(layers "F.Cu" "F.Mask" "F.Paste")
			(net "GND")
			(options
				(clearance outline)
				(anchor circle)
			)
			(primitives
				(gr_poly
					(pts
						(arc
							(start 0.3048 -0.2032)
							(mid 0.275042 -0.275042)
							(end 0.2032 -0.3048)
						)
						(arc
							(start -0.2032 -0.3048)
							(mid -0.275042 -0.275042)
							(end -0.3048 -0.2032)
						)
						(arc
							(start -0.3048 0.2032)
							(mid -0.275042 0.275042)
							(end -0.2032 0.3048)
						)
						(arc
							(start 0.2032 0.3048)
							(mid 0.275042 0.275042)
							(end 0.3048 0.2032)
						)
					)
					(width 0)
					(fill yes)
				)
			)
		)
	)
	(footprint ""
		(layer "F.Cu")
		(at 252.10516 -4.74345 180)
		(property "Reference" "TP234"
			(at 0 0 180)
			(layer "F.SilkS")
			(hide yes)
			(effects
				(font
					(size 1.27 1.27)
				)
			)
		)
		(property "Value" "TPAD28-2-GP"
			(at -0.0127 -1.6637 180)
			(unlocked yes)
			(layer "F.Fab")
			(hide yes)
			(effects
				(font
					(size 1.016 1.016)
					(thickness 0.1524)
				)
			)
		)
		(property "Device Type" "TPAD28"
			(at -0.0127 -3.1877 180)
			(unlocked yes)
			(layer "F.Fab")
			(hide yes)
			(effects
				(font
					(size 1.016 1.016)
					(thickness 0.1524)
				)
			)
		)
		(duplicate_pad_numbers_are_jumpers no)
		(fp_poly
			(pts
				(arc
					(start -0.3556 0)
					(mid 0.3556 0)
					(end -0.3556 0)
				)
			)
			(stroke
				(width 0)
				(type default)
			)
			(fill no)
			(layer "F.CrtYd")
		)
		(fp_poly
			(pts
				(arc
					(start -0.6096 0)
					(mid 0.6096 0)
					(end -0.6096 0)
				)
			)
			(stroke
				(width 0)
				(type default)
			)
			(fill no)
			(layer "F.Fab")
		)
		(pad "1" smd circle
			(at 0 0 180)
			(size 0.7112 0.7112)
			(layers "F.Cu" "F.Mask" "F.Paste")
			(net "MAX6654_ALERT#")
		)
	)
	(footprint ""
		(layer "F.Cu")
		(at 318.516 -99.568 180)
		(property "Reference" "C3701"
			(at 0 0 180)
			(layer "F.SilkS")
			(hide yes)
			(effects
				(font
					(size 1.27 1.27)
				)
			)
		)
		(property "Value" "SCD1U25V2KX-2-GP"
			(at 1.1811 -2.7051 180)
			(unlocked yes)
			(layer "F.Fab")
			(hide yes)
			(effects
				(font
					(size 1.016 1.016)
					(thickness 0.1524)
				)
			)
		)
		(property "Device Type" "C402H22"
			(at 1.1811 -4.2291 180)
			(unlocked yes)
			(layer "F.Fab")
			(hide yes)
			(effects
				(font
					(size 1.016 1.016)
					(thickness 0.1524)
				)
			)
		)
		(duplicate_pad_numbers_are_jumpers no)
		(fp_rect
			(start -0.4318 0.9525)
			(end 0.4318 -0.9525)
			(stroke
				(width 0)
				(type default)
			)
			(fill no)
			(layer "F.CrtYd")
		)
		(fp_rect
			(start -0.4318 0.9525)
			(end 0.4318 -0.9525)
			(stroke
				(width 0)
				(type default)
			)
			(fill no)
			(layer "F.Fab")
		)
		(pad "1" smd custom
			(at 0 -0.4445 180)
			(size 0.1524 0.1524)
			(layers "F.Cu" "F.Mask" "F.Paste")
			(net "P3V3_STBY")
			(options
				(clearance outline)
				(anchor circle)
			)
			(primitives
				(gr_poly
					(pts
						(arc
							(start 0.3048 -0.2032)
							(mid 0.275042 -0.275042)
							(end 0.2032 -0.3048)
						)
						(arc
							(start -0.2032 -0.3048)
							(mid -0.275042 -0.275042)
							(end -0.3048 -0.2032)
						)
						(arc
							(start -0.3048 0.2032)
							(mid -0.275042 0.275042)
							(end -0.2032 0.3048)
						)
						(arc
							(start 0.2032 0.3048)
							(mid 0.275042 0.275042)
							(end 0.3048 0.2032)
						)
					)
					(width 0)
					(fill yes)
				)
			)
		)
		(pad "2" smd custom
			(at 0 0.4445 180)
			(size 0.1524 0.1524)
			(layers "F.Cu" "F.Mask" "F.Paste")
			(net "GND")
			(options
				(clearance outline)
				(anchor circle)
			)
			(primitives
				(gr_poly
					(pts
						(arc
							(start 0.3048 -0.2032)
							(mid 0.275042 -0.275042)
							(end 0.2032 -0.3048)
						)
						(arc
							(start -0.2032 -0.3048)
							(mid -0.275042 -0.275042)
							(end -0.3048 -0.2032)
						)
						(arc
							(start -0.3048 0.2032)
							(mid -0.275042 0.275042)
							(end -0.2032 0.3048)
						)
						(arc
							(start 0.2032 0.3048)
							(mid 0.275042 0.275042)
							(end 0.3048 0.2032)
						)
					)
					(width 0)
					(fill yes)
				)
			)
		)
	)
	(footprint ""
		(layer "F.Cu")
		(at 134.1882 -40.05961 -90)
		(property "Reference" "R759"
			(at 0 0 270)
			(layer "F.SilkS")
			(hide yes)
			(effects
				(font
					(size 1.27 1.27)
				)
			)
		)
		(property "Value" "0R2J-2-GP"
			(at 0.064008 -3.993896 270)
			(unlocked yes)
			(layer "F.Fab")
			(hide yes)
			(effects
				(font
					(size 1.016 1.016)
					(thickness 0.1524)
				)
			)
		)
		(property "Device Type" "R402H16"
			(at 0.064008 -5.517896 270)
			(unlocked yes)
			(layer "F.Fab")
			(hide yes)
			(effects
				(font
					(size 1.016 1.016)
					(thickness 0.1524)
				)
			)
		)
		(duplicate_pad_numbers_are_jumpers no)
		(fp_line
			(start -0.508 -0.9398)
			(end -0.508 0.9398)
			(stroke
				(width 0.1524)
				(type default)
			)
			(layer "F.SilkS")
		)
		(fp_line
			(start 0.508 -0.9398)
			(end -0.508 -0.9398)
			(stroke
				(width 0.1524)
				(type default)
			)
			(layer "F.SilkS")
		)
		(fp_rect
			(start -0.508 0.9398)
			(end 0.508 -0.9398)
			(stroke
				(width 0)
				(type default)
			)
			(fill no)
			(layer "F.CrtYd")
		)
		(fp_rect
			(start -0.508 0.9398)
			(end 0.508 -0.9398)
			(stroke
				(width 0)
				(type default)
			)
			(fill no)
			(layer "F.Fab")
		)
		(pad "1" smd custom
			(at 0 -0.4445 270)
			(size 0.1397 0.1397)
			(layers "F.Cu" "F.Mask" "F.Paste")
			(net "DUT_TDI_R")
			(options
				(clearance outline)
				(anchor circle)
			)
			(primitives
				(gr_poly
					(pts
						(arc
							(start -0.1778 -0.2794)
							(mid -0.249642 -0.249642)
							(end -0.2794 -0.1778)
						)
						(arc
							(start -0.2794 0.1778)
							(mid -0.249642 0.249642)
							(end -0.1778 0.2794)
						)
						(arc
							(start 0.1778 0.2794)
							(mid 0.249642 0.249642)
							(end 0.2794 0.1778)
						)
						(arc
							(start 0.2794 -0.1778)
							(mid 0.249642 -0.249642)
							(end 0.1778 -0.2794)
						)
					)
					(width 0)
					(fill yes)
				)
			)
		)
		(pad "2" smd custom
			(at 0 0.4445 270)
			(size 0.1397 0.1397)
			(layers "F.Cu" "F.Mask" "F.Paste")
			(net "DUT_TDI")
			(options
				(clearance outline)
				(anchor circle)
			)
			(primitives
				(gr_poly
					(pts
						(arc
							(start -0.1778 -0.2794)
							(mid -0.249642 -0.249642)
							(end -0.2794 -0.1778)
						)
						(arc
							(start -0.2794 0.1778)
							(mid -0.249642 0.249642)
							(end -0.1778 0.2794)
						)
						(arc
							(start 0.1778 0.2794)
							(mid 0.249642 0.249642)
							(end 0.2794 0.1778)
						)
						(arc
							(start 0.2794 -0.1778)
							(mid 0.249642 -0.249642)
							(end 0.1778 -0.2794)
						)
					)
					(width 0)
					(fill yes)
				)
			)
		)
	)
	(footprint ""
		(layer "F.Cu")
		(at 166.116 -86.3854 90)
		(property "Reference" "R55"
			(at 0 0 90)
			(layer "F.SilkS")
			(hide yes)
			(effects
				(font
					(size 1.27 1.27)
				)
			)
		)
		(property "Value" "10KR2F-2-GP"
			(at 0.064008 -3.993896 90)
			(unlocked yes)
			(layer "F.Fab")
			(hide yes)
			(effects
				(font
					(size 1.016 1.016)
					(thickness 0.1524)
				)
			)
		)
		(property "Device Type" "R402H16"
			(at 0.064008 -5.517896 90)
			(unlocked yes)
			(layer "F.Fab")
			(hide yes)
			(effects
				(font
					(size 1.016 1.016)
					(thickness 0.1524)
				)
			)
		)
		(duplicate_pad_numbers_are_jumpers no)
		(fp_line
			(start 0.508 -0.9398)
			(end -0.508 -0.9398)
			(stroke
				(width 0.1524)
				(type default)
			)
			(layer "F.SilkS")
		)
		(fp_line
			(start -0.508 -0.9398)
			(end -0.508 0.9398)
			(stroke
				(width 0.1524)
				(type default)
			)
			(layer "F.SilkS")
		)
		(fp_rect
			(start -0.508 0.9398)
			(end 0.508 -0.9398)
			(stroke
				(width 0)
				(type default)
			)
			(fill no)
			(layer "F.CrtYd")
		)
		(fp_rect
			(start -0.508 0.9398)
			(end 0.508 -0.9398)
			(stroke
				(width 0)
				(type default)
			)
			(fill no)
			(layer "F.Fab")
		)
		(pad "1" smd custom
			(at 0 -0.4445 90)
			(size 0.1397 0.1397)
			(layers "F.Cu" "F.Mask" "F.Paste")
			(net "GND")
			(options
				(clearance outline)
				(anchor circle)
			)
			(primitives
				(gr_poly
					(pts
						(arc
							(start -0.1778 -0.2794)
							(mid -0.249642 -0.249642)
							(end -0.2794 -0.1778)
						)
						(arc
							(start -0.2794 0.1778)
							(mid -0.249642 0.249642)
							(end -0.1778 0.2794)
						)
						(arc
							(start 0.1778 0.2794)
							(mid 0.249642 0.249642)
							(end 0.2794 0.1778)
						)
						(arc
							(start 0.2794 -0.1778)
							(mid 0.249642 -0.249642)
							(end 0.1778 -0.2794)
						)
					)
					(width 0)
					(fill yes)
				)
			)
		)
		(pad "2" smd custom
			(at 0 0.4445 90)
			(size 0.1397 0.1397)
			(layers "F.Cu" "F.Mask" "F.Paste")
			(net "CLKGEN_OE1")
			(options
				(clearance outline)
				(anchor circle)
			)
			(primitives
				(gr_poly
					(pts
						(arc
							(start -0.1778 -0.2794)
							(mid -0.249642 -0.249642)
							(end -0.2794 -0.1778)
						)
						(arc
							(start -0.2794 0.1778)
							(mid -0.249642 0.249642)
							(end -0.1778 0.2794)
						)
						(arc
							(start 0.1778 0.2794)
							(mid 0.249642 0.249642)
							(end 0.2794 0.1778)
						)
						(arc
							(start 0.2794 -0.1778)
							(mid 0.249642 -0.249642)
							(end 0.1778 -0.2794)
						)
					)
					(width 0)
					(fill yes)
				)
			)
		)
	)
	(footprint ""
		(layer "F.Cu")
		(at 83.808062 -212.420454 180)
		(property "Reference" "C350"
			(at 0 0 180)
			(layer "F.SilkS")
			(hide yes)
			(effects
				(font
					(size 1.27 1.27)
				)
			)
		)
		(property "Value" "SCD22U10V2KX-1GP"
			(at 1.1811 -2.7051 180)
			(unlocked yes)
			(layer "F.Fab")
			(hide yes)
			(effects
				(font
					(size 1.016 1.016)
					(thickness 0.1524)
				)
			)
		)
		(property "Device Type" "C402H22"
			(at 1.1811 -4.2291 180)
			(unlocked yes)
			(layer "F.Fab")
			(hide yes)
			(effects
				(font
					(size 1.016 1.016)
					(thickness 0.1524)
				)
			)
		)
		(duplicate_pad_numbers_are_jumpers no)
		(fp_rect
			(start -0.4318 0.9525)
			(end 0.4318 -0.9525)
			(stroke
				(width 0)
				(type default)
			)
			(fill no)
			(layer "F.CrtYd")
		)
		(fp_rect
			(start -0.4318 0.9525)
			(end 0.4318 -0.9525)
			(stroke
				(width 0)
				(type default)
			)
			(fill no)
			(layer "F.Fab")
		)
		(pad "1" smd custom
			(at 0 -0.4445 180)
			(size 0.1524 0.1524)
			(layers "F.Cu" "F.Mask" "F.Paste")
			(net "PCIE_TX_CAP_N67")
			(options
				(clearance outline)
				(anchor circle)
			)
			(primitives
				(gr_poly
					(pts
						(arc
							(start 0.3048 -0.2032)
							(mid 0.275042 -0.275042)
							(end 0.2032 -0.3048)
						)
						(arc
							(start -0.2032 -0.3048)
							(mid -0.275042 -0.275042)
							(end -0.3048 -0.2032)
						)
						(arc
							(start -0.3048 0.2032)
							(mid -0.275042 0.275042)
							(end -0.2032 0.3048)
						)
						(arc
							(start 0.2032 0.3048)
							(mid 0.275042 0.275042)
							(end 0.3048 0.2032)
						)
					)
					(width 0)
					(fill yes)
				)
			)
		)
		(pad "2" smd custom
			(at 0 0.4445 180)
			(size 0.1524 0.1524)
			(layers "F.Cu" "F.Mask" "F.Paste")
			(net "PCIE_TX_N67")
			(options
				(clearance outline)
				(anchor circle)
			)
			(primitives
				(gr_poly
					(pts
						(arc
							(start 0.3048 -0.2032)
							(mid 0.275042 -0.275042)
							(end 0.2032 -0.3048)
						)
						(arc
							(start -0.2032 -0.3048)
							(mid -0.275042 -0.275042)
							(end -0.3048 -0.2032)
						)
						(arc
							(start -0.3048 0.2032)
							(mid -0.275042 0.275042)
							(end -0.2032 0.3048)
						)
						(arc
							(start 0.2032 0.3048)
							(mid 0.275042 0.275042)
							(end 0.3048 0.2032)
						)
					)
					(width 0)
					(fill yes)
				)
			)
		)
	)
	(footprint ""
		(layer "F.Cu")
		(at 144.792192 -212.420454 180)
		(property "Reference" "C315"
			(at 0 0 180)
			(layer "F.SilkS")
			(hide yes)
			(effects
				(font
					(size 1.27 1.27)
				)
			)
		)
		(property "Value" "SCD22U10V2KX-1GP"
			(at 1.1811 -2.7051 180)
			(unlocked yes)
			(layer "F.Fab")
			(hide yes)
			(effects
				(font
					(size 1.016 1.016)
					(thickness 0.1524)
				)
			)
		)
		(property "Device Type" "C402H22"
			(at 1.1811 -4.2291 180)
			(unlocked yes)
			(layer "F.Fab")
			(hide yes)
			(effects
				(font
					(size 1.016 1.016)
					(thickness 0.1524)
				)
			)
		)
		(duplicate_pad_numbers_are_jumpers no)
		(fp_rect
			(start -0.4318 0.9525)
			(end 0.4318 -0.9525)
			(stroke
				(width 0)
				(type default)
			)
			(fill no)
			(layer "F.CrtYd")
		)
		(fp_rect
			(start -0.4318 0.9525)
			(end 0.4318 -0.9525)
			(stroke
				(width 0)
				(type default)
			)
			(fill no)
			(layer "F.Fab")
		)
		(pad "1" smd custom
			(at 0 -0.4445 180)
			(size 0.1524 0.1524)
			(layers "F.Cu" "F.Mask" "F.Paste")
			(net "PCIE_TX_CAP_P57")
			(options
				(clearance outline)
				(anchor circle)
			)
			(primitives
				(gr_poly
					(pts
						(arc
							(start 0.3048 -0.2032)
							(mid 0.275042 -0.275042)
							(end 0.2032 -0.3048)
						)
						(arc
							(start -0.2032 -0.3048)
							(mid -0.275042 -0.275042)
							(end -0.3048 -0.2032)
						)
						(arc
							(start -0.3048 0.2032)
							(mid -0.275042 0.275042)
							(end -0.2032 0.3048)
						)
						(arc
							(start 0.2032 0.3048)
							(mid 0.275042 0.275042)
							(end 0.3048 0.2032)
						)
					)
					(width 0)
					(fill yes)
				)
			)
		)
		(pad "2" smd custom
			(at 0 0.4445 180)
			(size 0.1524 0.1524)
			(layers "F.Cu" "F.Mask" "F.Paste")
			(net "PCIE_TX_P57")
			(options
				(clearance outline)
				(anchor circle)
			)
			(primitives
				(gr_poly
					(pts
						(arc
							(start 0.3048 -0.2032)
							(mid 0.275042 -0.275042)
							(end 0.2032 -0.3048)
						)
						(arc
							(start -0.2032 -0.3048)
							(mid -0.275042 -0.275042)
							(end -0.3048 -0.2032)
						)
						(arc
							(start -0.3048 0.2032)
							(mid -0.275042 0.275042)
							(end -0.2032 0.3048)
						)
						(arc
							(start 0.2032 0.3048)
							(mid 0.275042 0.275042)
							(end 0.3048 0.2032)
						)
					)
					(width 0)
					(fill yes)
				)
			)
		)
	)
	(footprint ""
		(layer "F.Cu")
		(at 8.128 -120.65)
		(property "Reference" "R15"
			(at 0 0 0)
			(layer "F.SilkS")
			(hide yes)
			(effects
				(font
					(size 1.27 1.27)
				)
			)
		)
		(property "Value" "0R2J-2-GP"
			(at 0.064008 -3.993896 0)
			(unlocked yes)
			(layer "F.Fab")
			(hide yes)
			(effects
				(font
					(size 1.016 1.016)
					(thickness 0.1524)
				)
			)
		)
		(property "Device Type" "R402H16"
			(at 0.064008 -5.517896 0)
			(unlocked yes)
			(layer "F.Fab")
			(hide yes)
			(effects
				(font
					(size 1.016 1.016)
					(thickness 0.1524)
				)
			)
		)
		(duplicate_pad_numbers_are_jumpers no)
		(fp_line
			(start -0.508 -0.9398)
			(end -0.508 0.9398)
			(stroke
				(width 0.1524)
				(type default)
			)
			(layer "F.SilkS")
		)
		(fp_line
			(start 0.508 -0.9398)
			(end -0.508 -0.9398)
			(stroke
				(width 0.1524)
				(type default)
			)
			(layer "F.SilkS")
		)
		(fp_rect
			(start -0.508 0.9398)
			(end 0.508 -0.9398)
			(stroke
				(width 0)
				(type default)
			)
			(fill no)
			(layer "F.CrtYd")
		)
		(fp_rect
			(start -0.508 0.9398)
			(end 0.508 -0.9398)
			(stroke
				(width 0)
				(type default)
			)
			(fill no)
			(layer "F.Fab")
		)
		(pad "1" smd custom
			(at 0 -0.4445)
			(size 0.1397 0.1397)
			(layers "F.Cu" "F.Mask" "F.Paste")
			(net "BMC_I2C1_MINI1_SDA")
			(options
				(clearance outline)
				(anchor circle)
			)
			(primitives
				(gr_poly
					(pts
						(arc
							(start -0.1778 -0.2794)
							(mid -0.249642 -0.249642)
							(end -0.2794 -0.1778)
						)
						(arc
							(start -0.2794 0.1778)
							(mid -0.249642 0.249642)
							(end -0.1778 0.2794)
						)
						(arc
							(start 0.1778 0.2794)
							(mid 0.249642 0.249642)
							(end 0.2794 0.1778)
						)
						(arc
							(start 0.2794 -0.1778)
							(mid 0.249642 -0.249642)
							(end 0.1778 -0.2794)
						)
					)
					(width 0)
					(fill yes)
				)
			)
		)
		(pad "2" smd custom
			(at 0 0.4445)
			(size 0.1397 0.1397)
			(layers "F.Cu" "F.Mask" "F.Paste")
			(net "BMC_I2C1_MINI1_SDA_S")
			(options
				(clearance outline)
				(anchor circle)
			)
			(primitives
				(gr_poly
					(pts
						(arc
							(start -0.1778 -0.2794)
							(mid -0.249642 -0.249642)
							(end -0.2794 -0.1778)
						)
						(arc
							(start -0.2794 0.1778)
							(mid -0.249642 0.249642)
							(end -0.1778 0.2794)
						)
						(arc
							(start 0.1778 0.2794)
							(mid 0.249642 0.249642)
							(end 0.2794 0.1778)
						)
						(arc
							(start 0.2794 -0.1778)
							(mid 0.249642 -0.249642)
							(end 0.1778 -0.2794)
						)
					)
					(width 0)
					(fill yes)
				)
			)
		)
	)
	(footprint ""
		(layer "F.Cu")
		(at 168.021 -95.6564 90)
		(property "Reference" "R59"
			(at 0 0 90)
			(layer "F.SilkS")
			(hide yes)
			(effects
				(font
					(size 1.27 1.27)
				)
			)
		)
		(property "Value" "10KR2F-2-GP"
			(at 0.064008 -3.993896 90)
			(unlocked yes)
			(layer "F.Fab")
			(hide yes)
			(effects
				(font
					(size 1.016 1.016)
					(thickness 0.1524)
				)
			)
		)
		(property "Device Type" "R402H16"
			(at 0.064008 -5.517896 90)
			(unlocked yes)
			(layer "F.Fab")
			(hide yes)
			(effects
				(font
					(size 1.016 1.016)
					(thickness 0.1524)
				)
			)
		)
		(duplicate_pad_numbers_are_jumpers no)
		(fp_line
			(start 0.508 -0.9398)
			(end -0.508 -0.9398)
			(stroke
				(width 0.1524)
				(type default)
			)
			(layer "F.SilkS")
		)
		(fp_line
			(start -0.508 -0.9398)
			(end -0.508 0.9398)
			(stroke
				(width 0.1524)
				(type default)
			)
			(layer "F.SilkS")
		)
		(fp_rect
			(start -0.508 0.9398)
			(end 0.508 -0.9398)
			(stroke
				(width 0)
				(type default)
			)
			(fill no)
			(layer "F.CrtYd")
		)
		(fp_rect
			(start -0.508 0.9398)
			(end 0.508 -0.9398)
			(stroke
				(width 0)
				(type default)
			)
			(fill no)
			(layer "F.Fab")
		)
		(pad "1" smd custom
			(at 0 -0.4445 90)
			(size 0.1397 0.1397)
			(layers "F.Cu" "F.Mask" "F.Paste")
			(net "CLKGEN_OE2")
			(options
				(clearance outline)
				(anchor circle)
			)
			(primitives
				(gr_poly
					(pts
						(arc
							(start -0.1778 -0.2794)
							(mid -0.249642 -0.249642)
							(end -0.2794 -0.1778)
						)
						(arc
							(start -0.2794 0.1778)
							(mid -0.249642 0.249642)
							(end -0.1778 0.2794)
						)
						(arc
							(start 0.1778 0.2794)
							(mid 0.249642 0.249642)
							(end 0.2794 0.1778)
						)
						(arc
							(start 0.2794 -0.1778)
							(mid 0.249642 -0.249642)
							(end 0.1778 -0.2794)
						)
					)
					(width 0)
					(fill yes)
				)
			)
		)
		(pad "2" smd custom
			(at 0 0.4445 90)
			(size 0.1397 0.1397)
			(layers "F.Cu" "F.Mask" "F.Paste")
			(net "P1V8_CLKGEN")
			(options
				(clearance outline)
				(anchor circle)
			)
			(primitives
				(gr_poly
					(pts
						(arc
							(start -0.1778 -0.2794)
							(mid -0.249642 -0.249642)
							(end -0.2794 -0.1778)
						)
						(arc
							(start -0.2794 0.1778)
							(mid -0.249642 0.249642)
							(end -0.1778 0.2794)
						)
						(arc
							(start 0.1778 0.2794)
							(mid 0.249642 0.249642)
							(end 0.2794 0.1778)
						)
						(arc
							(start 0.2794 -0.1778)
							(mid 0.249642 -0.249642)
							(end 0.1778 -0.2794)
						)
					)
					(width 0)
					(fill yes)
				)
			)
		)
	)
	(footprint ""
		(layer "F.Cu")
		(at 9.906 -194.3354 180)
		(property "Reference" "R2103"
			(at 0 0 180)
			(layer "F.SilkS")
			(hide yes)
			(effects
				(font
					(size 1.27 1.27)
				)
			)
		)
		(property "Value" "150KR2J-GP"
			(at 0.064008 -3.993896 180)
			(unlocked yes)
			(layer "F.Fab")
			(hide yes)
			(effects
				(font
					(size 1.016 1.016)
					(thickness 0.1524)
				)
			)
		)
		(property "Device Type" "R402H16"
			(at 0.064008 -5.517896 180)
			(unlocked yes)
			(layer "F.Fab")
			(hide yes)
			(effects
				(font
					(size 1.016 1.016)
					(thickness 0.1524)
				)
			)
		)
		(duplicate_pad_numbers_are_jumpers no)
		(fp_line
			(start 0.508 -0.9398)
			(end -0.508 -0.9398)
			(stroke
				(width 0.1524)
				(type default)
			)
			(layer "F.SilkS")
		)
		(fp_line
			(start -0.508 -0.9398)
			(end -0.508 0.9398)
			(stroke
				(width 0.1524)
				(type default)
			)
			(layer "F.SilkS")
		)
		(fp_rect
			(start -0.508 0.9398)
			(end 0.508 -0.9398)
			(stroke
				(width 0)
				(type default)
			)
			(fill no)
			(layer "F.CrtYd")
		)
		(fp_rect
			(start -0.508 0.9398)
			(end 0.508 -0.9398)
			(stroke
				(width 0)
				(type default)
			)
			(fill no)
			(layer "F.Fab")
		)
		(pad "1" smd custom
			(at 0 -0.4445 180)
			(size 0.1397 0.1397)
			(layers "F.Cu" "F.Mask" "F.Paste")
			(net "MB0_CM_ADR1_R")
			(options
				(clearance outline)
				(anchor circle)
			)
			(primitives
				(gr_poly
					(pts
						(arc
							(start -0.1778 -0.2794)
							(mid -0.249642 -0.249642)
							(end -0.2794 -0.1778)
						)
						(arc
							(start -0.2794 0.1778)
							(mid -0.249642 0.249642)
							(end -0.1778 0.2794)
						)
						(arc
							(start 0.1778 0.2794)
							(mid 0.249642 0.249642)
							(end 0.2794 0.1778)
						)
						(arc
							(start 0.2794 -0.1778)
							(mid 0.249642 -0.249642)
							(end 0.1778 -0.2794)
						)
					)
					(width 0)
					(fill yes)
				)
			)
		)
		(pad "2" smd custom
			(at 0 0.4445 180)
			(size 0.1397 0.1397)
			(layers "F.Cu" "F.Mask" "F.Paste")
			(net "AGND_CURRENT_MON")
			(options
				(clearance outline)
				(anchor circle)
			)
			(primitives
				(gr_poly
					(pts
						(arc
							(start -0.1778 -0.2794)
							(mid -0.249642 -0.249642)
							(end -0.2794 -0.1778)
						)
						(arc
							(start -0.2794 0.1778)
							(mid -0.249642 0.249642)
							(end -0.1778 0.2794)
						)
						(arc
							(start 0.1778 0.2794)
							(mid 0.249642 0.249642)
							(end 0.2794 0.1778)
						)
						(arc
							(start 0.2794 -0.1778)
							(mid 0.249642 -0.249642)
							(end 0.1778 -0.2794)
						)
					)
					(width 0)
					(fill yes)
				)
			)
		)
	)
	(footprint ""
		(layer "F.Cu")
		(at 25.273 -70.1802 -90)
		(property "Reference" "R406"
			(at 0 0 270)
			(layer "F.SilkS")
			(hide yes)
			(effects
				(font
					(size 1.27 1.27)
				)
			)
		)
		(property "Value" "3K3R2F-2-GP"
			(at 0.064008 -3.993896 270)
			(unlocked yes)
			(layer "F.Fab")
			(hide yes)
			(effects
				(font
					(size 1.016 1.016)
					(thickness 0.1524)
				)
			)
		)
		(property "Device Type" "R402H16"
			(at 0.064008 -5.517896 270)
			(unlocked yes)
			(layer "F.Fab")
			(hide yes)
			(effects
				(font
					(size 1.016 1.016)
					(thickness 0.1524)
				)
			)
		)
		(duplicate_pad_numbers_are_jumpers no)
		(fp_line
			(start -0.508 -0.9398)
			(end -0.508 0.9398)
			(stroke
				(width 0.1524)
				(type default)
			)
			(layer "F.SilkS")
		)
		(fp_line
			(start 0.508 -0.9398)
			(end -0.508 -0.9398)
			(stroke
				(width 0.1524)
				(type default)
			)
			(layer "F.SilkS")
		)
		(fp_rect
			(start -0.508 0.9398)
			(end 0.508 -0.9398)
			(stroke
				(width 0)
				(type default)
			)
			(fill no)
			(layer "F.CrtYd")
		)
		(fp_rect
			(start -0.508 0.9398)
			(end 0.508 -0.9398)
			(stroke
				(width 0)
				(type default)
			)
			(fill no)
			(layer "F.Fab")
		)
		(pad "1" smd custom
			(at 0 -0.4445 270)
			(size 0.1397 0.1397)
			(layers "F.Cu" "F.Mask" "F.Paste")
			(net "P3V3_STBY")
			(options
				(clearance outline)
				(anchor circle)
			)
			(primitives
				(gr_poly
					(pts
						(arc
							(start -0.1778 -0.2794)
							(mid -0.249642 -0.249642)
							(end -0.2794 -0.1778)
						)
						(arc
							(start -0.2794 0.1778)
							(mid -0.249642 0.249642)
							(end -0.1778 0.2794)
						)
						(arc
							(start 0.1778 0.2794)
							(mid 0.249642 0.249642)
							(end 0.2794 0.1778)
						)
						(arc
							(start 0.2794 -0.1778)
							(mid 0.249642 -0.249642)
							(end 0.1778 -0.2794)
						)
					)
					(width 0)
					(fill yes)
				)
			)
		)
		(pad "2" smd custom
			(at 0 0.4445 270)
			(size 0.1397 0.1397)
			(layers "F.Cu" "F.Mask" "F.Paste")
			(net "LAN_MAIN_PWR_OK")
			(options
				(clearance outline)
				(anchor circle)
			)
			(primitives
				(gr_poly
					(pts
						(arc
							(start -0.1778 -0.2794)
							(mid -0.249642 -0.249642)
							(end -0.2794 -0.1778)
						)
						(arc
							(start -0.2794 0.1778)
							(mid -0.249642 0.249642)
							(end -0.1778 0.2794)
						)
						(arc
							(start 0.1778 0.2794)
							(mid 0.249642 0.249642)
							(end 0.2794 0.1778)
						)
						(arc
							(start 0.2794 -0.1778)
							(mid 0.249642 -0.249642)
							(end 0.1778 -0.2794)
						)
					)
					(width 0)
					(fill yes)
				)
			)
		)
	)
	(footprint ""
		(layer "F.Cu")
		(at 182.0164 -61.595)
		(property "Reference" "C560"
			(at 0 0 0)
			(layer "F.SilkS")
			(hide yes)
			(effects
				(font
					(size 1.27 1.27)
				)
			)
		)
		(property "Value" "SC4D7U16V5KX-1-GP"
			(at -0.0762 -6.1214 0)
			(unlocked yes)
			(layer "F.Fab")
			(hide yes)
			(effects
				(font
					(size 1.016 1.016)
					(thickness 0.1524)
				)
			)
		)
		(property "Device Type" "C805H56"
			(at -0.0762 -8.1534 0)
			(unlocked yes)
			(layer "F.Fab")
			(hide yes)
			(effects
				(font
					(size 1.016 1.016)
					(thickness 0.1524)
				)
			)
		)
		(duplicate_pad_numbers_are_jumpers no)
		(fp_line
			(start 0.635 0)
			(end -0.635 0)
			(stroke
				(width 0.508)
				(type default)
			)
			(layer "F.SilkS")
		)
		(fp_rect
			(start -0.9652 1.778)
			(end 0.9652 -1.778)
			(stroke
				(width 0)
				(type default)
			)
			(fill no)
			(layer "F.CrtYd")
		)
		(fp_poly
			(pts
				(xy -0.9652 -1.778) (xy 0.9652 -1.778) (xy 0.9652 1.778) (xy -0.9652 1.778)
			)
			(stroke
				(width 0)
				(type default)
			)
			(fill no)
			(layer "F.Fab")
		)
		(pad "1" smd rect
			(at 0 -0.9652)
			(size 1.397 1.143)
			(layers "F.Cu" "F.Mask" "F.Paste")
			(net "DUT_AVD_PCIE")
		)
		(pad "2" smd rect
			(at 0 0.9652)
			(size 1.397 1.143)
			(layers "F.Cu" "F.Mask" "F.Paste")
			(net "GND")
		)
	)
	(footprint ""
		(layer "F.Cu")
		(at 288.544 -59.563 -90)
		(property "Reference" "R424"
			(at 0 0 270)
			(layer "F.SilkS")
			(hide yes)
			(effects
				(font
					(size 1.27 1.27)
				)
			)
		)
		(property "Value" "0R2J-2-GP"
			(at 0.064008 -3.993896 270)
			(unlocked yes)
			(layer "F.Fab")
			(hide yes)
			(effects
				(font
					(size 1.016 1.016)
					(thickness 0.1524)
				)
			)
		)
		(property "Device Type" "R402H16"
			(at 0.064008 -5.517896 270)
			(unlocked yes)
			(layer "F.Fab")
			(hide yes)
			(effects
				(font
					(size 1.016 1.016)
					(thickness 0.1524)
				)
			)
		)
		(duplicate_pad_numbers_are_jumpers no)
		(fp_line
			(start -0.508 -0.9398)
			(end -0.508 0.9398)
			(stroke
				(width 0.1524)
				(type default)
			)
			(layer "F.SilkS")
		)
		(fp_line
			(start 0.508 -0.9398)
			(end -0.508 -0.9398)
			(stroke
				(width 0.1524)
				(type default)
			)
			(layer "F.SilkS")
		)
		(fp_rect
			(start -0.508 0.9398)
			(end 0.508 -0.9398)
			(stroke
				(width 0)
				(type default)
			)
			(fill no)
			(layer "F.CrtYd")
		)
		(fp_rect
			(start -0.508 0.9398)
			(end 0.508 -0.9398)
			(stroke
				(width 0)
				(type default)
			)
			(fill no)
			(layer "F.Fab")
		)
		(pad "1" smd custom
			(at 0 -0.4445 270)
			(size 0.1397 0.1397)
			(layers "F.Cu" "F.Mask" "F.Paste")
			(net "VS5_LED_R")
			(options
				(clearance outline)
				(anchor circle)
			)
			(primitives
				(gr_poly
					(pts
						(arc
							(start -0.1778 -0.2794)
							(mid -0.249642 -0.249642)
							(end -0.2794 -0.1778)
						)
						(arc
							(start -0.2794 0.1778)
							(mid -0.249642 0.249642)
							(end -0.1778 0.2794)
						)
						(arc
							(start 0.1778 0.2794)
							(mid 0.249642 0.249642)
							(end 0.2794 0.1778)
						)
						(arc
							(start 0.2794 -0.1778)
							(mid 0.249642 -0.249642)
							(end 0.1778 -0.2794)
						)
					)
					(width 0)
					(fill yes)
				)
			)
		)
		(pad "2" smd custom
			(at 0 0.4445 270)
			(size 0.1397 0.1397)
			(layers "F.Cu" "F.Mask" "F.Paste")
			(net "VS5_LED")
			(options
				(clearance outline)
				(anchor circle)
			)
			(primitives
				(gr_poly
					(pts
						(arc
							(start -0.1778 -0.2794)
							(mid -0.249642 -0.249642)
							(end -0.2794 -0.1778)
						)
						(arc
							(start -0.2794 0.1778)
							(mid -0.249642 0.249642)
							(end -0.1778 0.2794)
						)
						(arc
							(start 0.1778 0.2794)
							(mid 0.249642 0.249642)
							(end 0.2794 0.1778)
						)
						(arc
							(start 0.2794 -0.1778)
							(mid 0.249642 -0.249642)
							(end 0.1778 -0.2794)
						)
					)
					(width 0)
					(fill yes)
				)
			)
		)
	)
	(footprint ""
		(layer "F.Cu")
		(at 31.369 -45.974 -90)
		(property "Reference" "C337"
			(at 0 0 270)
			(layer "F.SilkS")
			(hide yes)
			(effects
				(font
					(size 1.27 1.27)
				)
			)
		)
		(property "Value" "SC1U10V2KX-4-GP"
			(at 1.1811 -2.7051 270)
			(unlocked yes)
			(layer "F.Fab")
			(hide yes)
			(effects
				(font
					(size 1.016 1.016)
					(thickness 0.1524)
				)
			)
		)
		(property "Device Type" "C402H22"
			(at 1.1811 -4.2291 270)
			(unlocked yes)
			(layer "F.Fab")
			(hide yes)
			(effects
				(font
					(size 1.016 1.016)
					(thickness 0.1524)
				)
			)
		)
		(duplicate_pad_numbers_are_jumpers no)
		(fp_rect
			(start -0.4318 0.9525)
			(end 0.4318 -0.9525)
			(stroke
				(width 0)
				(type default)
			)
			(fill no)
			(layer "F.CrtYd")
		)
		(fp_rect
			(start -0.4318 0.9525)
			(end 0.4318 -0.9525)
			(stroke
				(width 0)
				(type default)
			)
			(fill no)
			(layer "F.Fab")
		)
		(pad "1" smd custom
			(at 0 -0.4445 270)
			(size 0.1524 0.1524)
			(layers "F.Cu" "F.Mask" "F.Paste")
			(net "P5V_USB")
			(options
				(clearance outline)
				(anchor circle)
			)
			(primitives
				(gr_poly
					(pts
						(arc
							(start 0.3048 -0.2032)
							(mid 0.275042 -0.275042)
							(end 0.2032 -0.3048)
						)
						(arc
							(start -0.2032 -0.3048)
							(mid -0.275042 -0.275042)
							(end -0.3048 -0.2032)
						)
						(arc
							(start -0.3048 0.2032)
							(mid -0.275042 0.275042)
							(end -0.2032 0.3048)
						)
						(arc
							(start 0.2032 0.3048)
							(mid 0.275042 0.275042)
							(end 0.3048 0.2032)
						)
					)
					(width 0)
					(fill yes)
				)
			)
		)
		(pad "2" smd custom
			(at 0 0.4445 270)
			(size 0.1524 0.1524)
			(layers "F.Cu" "F.Mask" "F.Paste")
			(net "GND")
			(options
				(clearance outline)
				(anchor circle)
			)
			(primitives
				(gr_poly
					(pts
						(arc
							(start 0.3048 -0.2032)
							(mid 0.275042 -0.275042)
							(end 0.2032 -0.3048)
						)
						(arc
							(start -0.2032 -0.3048)
							(mid -0.275042 -0.275042)
							(end -0.3048 -0.2032)
						)
						(arc
							(start -0.3048 0.2032)
							(mid -0.275042 0.275042)
							(end -0.2032 0.3048)
						)
						(arc
							(start 0.2032 0.3048)
							(mid 0.275042 0.275042)
							(end 0.3048 0.2032)
						)
					)
					(width 0)
					(fill yes)
				)
			)
		)
	)
	(footprint ""
		(layer "F.Cu")
		(at 52.1208 -50.3174)
		(property "Reference" "C236"
			(at 0 0 0)
			(layer "F.SilkS")
			(hide yes)
			(effects
				(font
					(size 1.27 1.27)
				)
			)
		)
		(property "Value" "SC1U10V2KX-4-GP"
			(at 1.1811 -2.7051 0)
			(unlocked yes)
			(layer "F.Fab")
			(hide yes)
			(effects
				(font
					(size 1.016 1.016)
					(thickness 0.1524)
				)
			)
		)
		(property "Device Type" "C402H22"
			(at 1.1811 -4.2291 0)
			(unlocked yes)
			(layer "F.Fab")
			(hide yes)
			(effects
				(font
					(size 1.016 1.016)
					(thickness 0.1524)
				)
			)
		)
		(duplicate_pad_numbers_are_jumpers no)
		(fp_rect
			(start -0.4318 0.9525)
			(end 0.4318 -0.9525)
			(stroke
				(width 0)
				(type default)
			)
			(fill no)
			(layer "F.CrtYd")
		)
		(fp_rect
			(start -0.4318 0.9525)
			(end 0.4318 -0.9525)
			(stroke
				(width 0)
				(type default)
			)
			(fill no)
			(layer "F.Fab")
		)
		(pad "1" smd custom
			(at 0 -0.4445)
			(size 0.1524 0.1524)
			(layers "F.Cu" "F.Mask" "F.Paste")
			(net "P3V3_STBY")
			(options
				(clearance outline)
				(anchor circle)
			)
			(primitives
				(gr_poly
					(pts
						(arc
							(start 0.3048 -0.2032)
							(mid 0.275042 -0.275042)
							(end 0.2032 -0.3048)
						)
						(arc
							(start -0.2032 -0.3048)
							(mid -0.275042 -0.275042)
							(end -0.3048 -0.2032)
						)
						(arc
							(start -0.3048 0.2032)
							(mid -0.275042 0.275042)
							(end -0.2032 0.3048)
						)
						(arc
							(start 0.2032 0.3048)
							(mid 0.275042 0.275042)
							(end 0.3048 0.2032)
						)
					)
					(width 0)
					(fill yes)
				)
			)
		)
		(pad "2" smd custom
			(at 0 0.4445)
			(size 0.1524 0.1524)
			(layers "F.Cu" "F.Mask" "F.Paste")
			(net "GND")
			(options
				(clearance outline)
				(anchor circle)
			)
			(primitives
				(gr_poly
					(pts
						(arc
							(start 0.3048 -0.2032)
							(mid 0.275042 -0.275042)
							(end 0.2032 -0.3048)
						)
						(arc
							(start -0.2032 -0.3048)
							(mid -0.275042 -0.275042)
							(end -0.3048 -0.2032)
						)
						(arc
							(start -0.3048 0.2032)
							(mid -0.275042 0.275042)
							(end -0.2032 0.3048)
						)
						(arc
							(start 0.2032 0.3048)
							(mid 0.275042 0.275042)
							(end 0.3048 0.2032)
						)
					)
					(width 0)
					(fill yes)
				)
			)
		)
	)
	(footprint ""
		(layer "F.Cu")
		(at 335.6356 -76.1746 180)
		(property "Reference" "PR182"
			(at 0 0 180)
			(layer "F.SilkS")
			(hide yes)
			(effects
				(font
					(size 1.27 1.27)
				)
			)
		)
		(property "Value" "80K6R2F-GP"
			(at 0.064008 -3.993896 180)
			(unlocked yes)
			(layer "F.Fab")
			(hide yes)
			(effects
				(font
					(size 1.016 1.016)
					(thickness 0.1524)
				)
			)
		)
		(property "Device Type" "R402H16"
			(at 0.064008 -5.517896 180)
			(unlocked yes)
			(layer "F.Fab")
			(hide yes)
			(effects
				(font
					(size 1.016 1.016)
					(thickness 0.1524)
				)
			)
		)
		(duplicate_pad_numbers_are_jumpers no)
		(fp_line
			(start 0.508 -0.9398)
			(end -0.508 -0.9398)
			(stroke
				(width 0.1524)
				(type default)
			)
			(layer "F.SilkS")
		)
		(fp_line
			(start -0.508 -0.9398)
			(end -0.508 0.9398)
			(stroke
				(width 0.1524)
				(type default)
			)
			(layer "F.SilkS")
		)
		(fp_rect
			(start -0.508 0.9398)
			(end 0.508 -0.9398)
			(stroke
				(width 0)
				(type default)
			)
			(fill no)
			(layer "F.CrtYd")
		)
		(fp_rect
			(start -0.508 0.9398)
			(end 0.508 -0.9398)
			(stroke
				(width 0)
				(type default)
			)
			(fill no)
			(layer "F.Fab")
		)
		(pad "1" smd custom
			(at 0 -0.4445 180)
			(size 0.1397 0.1397)
			(layers "F.Cu" "F.Mask" "F.Paste")
			(net "P0V9_E_VFB")
			(options
				(clearance outline)
				(anchor circle)
			)
			(primitives
				(gr_poly
					(pts
						(arc
							(start -0.1778 -0.2794)
							(mid -0.249642 -0.249642)
							(end -0.2794 -0.1778)
						)
						(arc
							(start -0.2794 0.1778)
							(mid -0.249642 0.249642)
							(end -0.1778 0.2794)
						)
						(arc
							(start 0.1778 0.2794)
							(mid 0.249642 0.249642)
							(end 0.2794 0.1778)
						)
						(arc
							(start 0.2794 -0.1778)
							(mid 0.249642 -0.249642)
							(end 0.1778 -0.2794)
						)
					)
					(width 0)
					(fill yes)
				)
			)
		)
		(pad "2" smd custom
			(at 0 0.4445 180)
			(size 0.1397 0.1397)
			(layers "F.Cu" "F.Mask" "F.Paste")
			(net "P0V9_E_VFB_AVS")
			(options
				(clearance outline)
				(anchor circle)
			)
			(primitives
				(gr_poly
					(pts
						(arc
							(start -0.1778 -0.2794)
							(mid -0.249642 -0.249642)
							(end -0.2794 -0.1778)
						)
						(arc
							(start -0.2794 0.1778)
							(mid -0.249642 0.249642)
							(end -0.1778 0.2794)
						)
						(arc
							(start 0.1778 0.2794)
							(mid 0.249642 0.249642)
							(end 0.2794 0.1778)
						)
						(arc
							(start 0.2794 -0.1778)
							(mid 0.249642 -0.249642)
							(end 0.1778 -0.2794)
						)
					)
					(width 0)
					(fill yes)
				)
			)
		)
	)
	(footprint ""
		(layer "F.Cu")
		(at 45.618146 -116.199666)
		(property "Reference" "TP217"
			(at 0 0 0)
			(layer "F.SilkS")
			(hide yes)
			(effects
				(font
					(size 1.27 1.27)
				)
			)
		)
		(property "Value" "TPAD28-2-GP"
			(at -0.0127 -1.6637 0)
			(unlocked yes)
			(layer "F.Fab")
			(hide yes)
			(effects
				(font
					(size 1.016 1.016)
					(thickness 0.1524)
				)
			)
		)
		(property "Device Type" "TPAD28"
			(at -0.0127 -3.1877 0)
			(unlocked yes)
			(layer "F.Fab")
			(hide yes)
			(effects
				(font
					(size 1.016 1.016)
					(thickness 0.1524)
				)
			)
		)
		(duplicate_pad_numbers_are_jumpers no)
		(fp_poly
			(pts
				(arc
					(start 0.3556 0)
					(mid -0.3556 0)
					(end 0.3556 0)
				)
			)
			(stroke
				(width 0)
				(type default)
			)
			(fill no)
			(layer "F.CrtYd")
		)
		(fp_poly
			(pts
				(arc
					(start 0.6096 0)
					(mid -0.6096 0)
					(end 0.6096 0)
				)
			)
			(stroke
				(width 0)
				(type default)
			)
			(fill no)
			(layer "F.Fab")
		)
		(pad "1" smd circle
			(at 0 0)
			(size 0.7112 0.7112)
			(layers "F.Cu" "F.Mask" "F.Paste")
			(net "GPIOH2")
		)
	)
	(footprint ""
		(layer "F.Cu")
		(at 58.928 -148.844 -90)
		(property "Reference" "R159"
			(at 0 0 270)
			(layer "F.SilkS")
			(hide yes)
			(effects
				(font
					(size 1.27 1.27)
				)
			)
		)
		(property "Value" "0R2J-2-GP"
			(at 0.064008 -3.993896 270)
			(unlocked yes)
			(layer "F.Fab")
			(hide yes)
			(effects
				(font
					(size 1.016 1.016)
					(thickness 0.1524)
				)
			)
		)
		(property "Device Type" "R402H16"
			(at 0.064008 -5.517896 270)
			(unlocked yes)
			(layer "F.Fab")
			(hide yes)
			(effects
				(font
					(size 1.016 1.016)
					(thickness 0.1524)
				)
			)
		)
		(duplicate_pad_numbers_are_jumpers no)
		(fp_line
			(start -0.508 -0.9398)
			(end -0.508 0.9398)
			(stroke
				(width 0.1524)
				(type default)
			)
			(layer "F.SilkS")
		)
		(fp_line
			(start 0.508 -0.9398)
			(end -0.508 -0.9398)
			(stroke
				(width 0.1524)
				(type default)
			)
			(layer "F.SilkS")
		)
		(fp_rect
			(start -0.508 0.9398)
			(end 0.508 -0.9398)
			(stroke
				(width 0)
				(type default)
			)
			(fill no)
			(layer "F.CrtYd")
		)
		(fp_rect
			(start -0.508 0.9398)
			(end 0.508 -0.9398)
			(stroke
				(width 0)
				(type default)
			)
			(fill no)
			(layer "F.Fab")
		)
		(pad "1" smd custom
			(at 0 -0.4445 270)
			(size 0.1397 0.1397)
			(layers "F.Cu" "F.Mask" "F.Paste")
			(net "BMC_I2C5_D_PEB_SDA")
			(options
				(clearance outline)
				(anchor circle)
			)
			(primitives
				(gr_poly
					(pts
						(arc
							(start -0.1778 -0.2794)
							(mid -0.249642 -0.249642)
							(end -0.2794 -0.1778)
						)
						(arc
							(start -0.2794 0.1778)
							(mid -0.249642 0.249642)
							(end -0.1778 0.2794)
						)
						(arc
							(start 0.1778 0.2794)
							(mid 0.249642 0.249642)
							(end 0.2794 0.1778)
						)
						(arc
							(start 0.2794 -0.1778)
							(mid 0.249642 -0.249642)
							(end 0.1778 -0.2794)
						)
					)
					(width 0)
					(fill yes)
				)
			)
		)
		(pad "2" smd custom
			(at 0 0.4445 270)
			(size 0.1397 0.1397)
			(layers "F.Cu" "F.Mask" "F.Paste")
			(net "TEMP_2_SDA")
			(options
				(clearance outline)
				(anchor circle)
			)
			(primitives
				(gr_poly
					(pts
						(arc
							(start -0.1778 -0.2794)
							(mid -0.249642 -0.249642)
							(end -0.2794 -0.1778)
						)
						(arc
							(start -0.2794 0.1778)
							(mid -0.249642 0.249642)
							(end -0.1778 0.2794)
						)
						(arc
							(start 0.1778 0.2794)
							(mid 0.249642 0.249642)
							(end 0.2794 0.1778)
						)
						(arc
							(start 0.2794 -0.1778)
							(mid 0.249642 -0.249642)
							(end 0.1778 -0.2794)
						)
					)
					(width 0)
					(fill yes)
				)
			)
		)
	)
	(footprint ""
		(layer "F.Cu")
		(at 212.916008 -4.064)
		(property "Reference" "R677"
			(at 0 0 0)
			(layer "F.SilkS")
			(hide yes)
			(effects
				(font
					(size 1.27 1.27)
				)
			)
		)
		(property "Value" "100KR2F-L1-GP"
			(at 0.064008 -3.993896 0)
			(unlocked yes)
			(layer "F.Fab")
			(hide yes)
			(effects
				(font
					(size 1.016 1.016)
					(thickness 0.1524)
				)
			)
		)
		(property "Device Type" "R402H16"
			(at 0.064008 -5.517896 0)
			(unlocked yes)
			(layer "F.Fab")
			(hide yes)
			(effects
				(font
					(size 1.016 1.016)
					(thickness 0.1524)
				)
			)
		)
		(duplicate_pad_numbers_are_jumpers no)
		(fp_line
			(start -0.508 -0.9398)
			(end -0.508 0.9398)
			(stroke
				(width 0.1524)
				(type default)
			)
			(layer "F.SilkS")
		)
		(fp_line
			(start 0.508 -0.9398)
			(end -0.508 -0.9398)
			(stroke
				(width 0.1524)
				(type default)
			)
			(layer "F.SilkS")
		)
		(fp_rect
			(start -0.508 0.9398)
			(end 0.508 -0.9398)
			(stroke
				(width 0)
				(type default)
			)
			(fill no)
			(layer "F.CrtYd")
		)
		(fp_rect
			(start -0.508 0.9398)
			(end 0.508 -0.9398)
			(stroke
				(width 0)
				(type default)
			)
			(fill no)
			(layer "F.Fab")
		)
		(pad "1" smd custom
			(at 0 -0.4445)
			(size 0.1397 0.1397)
			(layers "F.Cu" "F.Mask" "F.Paste")
			(net "HOST4_RST_N")
			(options
				(clearance outline)
				(anchor circle)
			)
			(primitives
				(gr_poly
					(pts
						(arc
							(start -0.1778 -0.2794)
							(mid -0.249642 -0.249642)
							(end -0.2794 -0.1778)
						)
						(arc
							(start -0.2794 0.1778)
							(mid -0.249642 0.249642)
							(end -0.1778 0.2794)
						)
						(arc
							(start 0.1778 0.2794)
							(mid 0.249642 0.249642)
							(end 0.2794 0.1778)
						)
						(arc
							(start 0.2794 -0.1778)
							(mid 0.249642 -0.249642)
							(end 0.1778 -0.2794)
						)
					)
					(width 0)
					(fill yes)
				)
			)
		)
		(pad "2" smd custom
			(at 0 0.4445)
			(size 0.1397 0.1397)
			(layers "F.Cu" "F.Mask" "F.Paste")
			(net "GND")
			(options
				(clearance outline)
				(anchor circle)
			)
			(primitives
				(gr_poly
					(pts
						(arc
							(start -0.1778 -0.2794)
							(mid -0.249642 -0.249642)
							(end -0.2794 -0.1778)
						)
						(arc
							(start -0.2794 0.1778)
							(mid -0.249642 0.249642)
							(end -0.1778 0.2794)
						)
						(arc
							(start 0.1778 0.2794)
							(mid 0.249642 0.249642)
							(end 0.2794 0.1778)
						)
						(arc
							(start 0.2794 -0.1778)
							(mid 0.249642 -0.249642)
							(end 0.1778 -0.2794)
						)
					)
					(width 0)
					(fill yes)
				)
			)
		)
	)
	(footprint ""
		(layer "F.Cu")
		(at 22.1996 -91.44 90)
		(property "Reference" "R2942"
			(at 0 0 90)
			(layer "F.SilkS")
			(hide yes)
			(effects
				(font
					(size 1.27 1.27)
				)
			)
		)
		(property "Value" "47KR2F-GP"
			(at 0.064008 -3.993896 90)
			(unlocked yes)
			(layer "F.Fab")
			(hide yes)
			(effects
				(font
					(size 1.016 1.016)
					(thickness 0.1524)
				)
			)
		)
		(property "Device Type" "R402H16"
			(at 0.064008 -5.517896 90)
			(unlocked yes)
			(layer "F.Fab")
			(hide yes)
			(effects
				(font
					(size 1.016 1.016)
					(thickness 0.1524)
				)
			)
		)
		(duplicate_pad_numbers_are_jumpers no)
		(fp_line
			(start 0.508 -0.9398)
			(end -0.508 -0.9398)
			(stroke
				(width 0.1524)
				(type default)
			)
			(layer "F.SilkS")
		)
		(fp_line
			(start -0.508 -0.9398)
			(end -0.508 0.9398)
			(stroke
				(width 0.1524)
				(type default)
			)
			(layer "F.SilkS")
		)
		(fp_rect
			(start -0.508 0.9398)
			(end 0.508 -0.9398)
			(stroke
				(width 0)
				(type default)
			)
			(fill no)
			(layer "F.CrtYd")
		)
		(fp_rect
			(start -0.508 0.9398)
			(end 0.508 -0.9398)
			(stroke
				(width 0)
				(type default)
			)
			(fill no)
			(layer "F.Fab")
		)
		(pad "1" smd custom
			(at 0 -0.4445 90)
			(size 0.1397 0.1397)
			(layers "F.Cu" "F.Mask" "F.Paste")
			(net "FM_TPM_PRES_RST_N")
			(options
				(clearance outline)
				(anchor circle)
			)
			(primitives
				(gr_poly
					(pts
						(arc
							(start -0.1778 -0.2794)
							(mid -0.249642 -0.249642)
							(end -0.2794 -0.1778)
						)
						(arc
							(start -0.2794 0.1778)
							(mid -0.249642 0.249642)
							(end -0.1778 0.2794)
						)
						(arc
							(start 0.1778 0.2794)
							(mid 0.249642 0.249642)
							(end 0.2794 0.1778)
						)
						(arc
							(start 0.2794 -0.1778)
							(mid 0.249642 -0.249642)
							(end 0.1778 -0.2794)
						)
					)
					(width 0)
					(fill yes)
				)
			)
		)
		(pad "2" smd custom
			(at 0 0.4445 90)
			(size 0.1397 0.1397)
			(layers "F.Cu" "F.Mask" "F.Paste")
			(net "FM_TPM_PRES_RST_N_R")
			(options
				(clearance outline)
				(anchor circle)
			)
			(primitives
				(gr_poly
					(pts
						(arc
							(start -0.1778 -0.2794)
							(mid -0.249642 -0.249642)
							(end -0.2794 -0.1778)
						)
						(arc
							(start -0.2794 0.1778)
							(mid -0.249642 0.249642)
							(end -0.1778 0.2794)
						)
						(arc
							(start 0.1778 0.2794)
							(mid 0.249642 0.249642)
							(end 0.2794 0.1778)
						)
						(arc
							(start 0.2794 -0.1778)
							(mid 0.249642 -0.249642)
							(end 0.1778 -0.2794)
						)
					)
					(width 0)
					(fill yes)
				)
			)
		)
	)
	(footprint ""
		(layer "F.Cu")
		(at 235.95838 -5.97916 90)
		(property "Reference" "R174"
			(at 0 0 90)
			(layer "F.SilkS")
			(hide yes)
			(effects
				(font
					(size 1.27 1.27)
				)
			)
		)
		(property "Value" "4K7R2F-GP"
			(at 0.064008 -3.993896 90)
			(unlocked yes)
			(layer "F.Fab")
			(hide yes)
			(effects
				(font
					(size 1.016 1.016)
					(thickness 0.1524)
				)
			)
		)
		(property "Device Type" "R402H16"
			(at 0.064008 -5.517896 90)
			(unlocked yes)
			(layer "F.Fab")
			(hide yes)
			(effects
				(font
					(size 1.016 1.016)
					(thickness 0.1524)
				)
			)
		)
		(duplicate_pad_numbers_are_jumpers no)
		(fp_line
			(start 0.508 -0.9398)
			(end -0.508 -0.9398)
			(stroke
				(width 0.1524)
				(type default)
			)
			(layer "F.SilkS")
		)
		(fp_line
			(start -0.508 -0.9398)
			(end -0.508 0.9398)
			(stroke
				(width 0.1524)
				(type default)
			)
			(layer "F.SilkS")
		)
		(fp_rect
			(start -0.508 0.9398)
			(end 0.508 -0.9398)
			(stroke
				(width 0)
				(type default)
			)
			(fill no)
			(layer "F.CrtYd")
		)
		(fp_rect
			(start -0.508 0.9398)
			(end 0.508 -0.9398)
			(stroke
				(width 0)
				(type default)
			)
			(fill no)
			(layer "F.Fab")
		)
		(pad "1" smd custom
			(at 0 -0.4445 90)
			(size 0.1397 0.1397)
			(layers "F.Cu" "F.Mask" "F.Paste")
			(net "P3V3_STBY")
			(options
				(clearance outline)
				(anchor circle)
			)
			(primitives
				(gr_poly
					(pts
						(arc
							(start -0.1778 -0.2794)
							(mid -0.249642 -0.249642)
							(end -0.2794 -0.1778)
						)
						(arc
							(start -0.2794 0.1778)
							(mid -0.249642 0.249642)
							(end -0.1778 0.2794)
						)
						(arc
							(start 0.1778 0.2794)
							(mid 0.249642 0.249642)
							(end 0.2794 0.1778)
						)
						(arc
							(start 0.2794 -0.1778)
							(mid 0.249642 -0.249642)
							(end 0.1778 -0.2794)
						)
					)
					(width 0)
					(fill yes)
				)
			)
		)
		(pad "2" smd custom
			(at 0 0.4445 90)
			(size 0.1397 0.1397)
			(layers "F.Cu" "F.Mask" "F.Paste")
			(net "DP_RST_N")
			(options
				(clearance outline)
				(anchor circle)
			)
			(primitives
				(gr_poly
					(pts
						(arc
							(start -0.1778 -0.2794)
							(mid -0.249642 -0.249642)
							(end -0.2794 -0.1778)
						)
						(arc
							(start -0.2794 0.1778)
							(mid -0.249642 0.249642)
							(end -0.1778 0.2794)
						)
						(arc
							(start 0.1778 0.2794)
							(mid 0.249642 0.249642)
							(end 0.2794 0.1778)
						)
						(arc
							(start 0.2794 -0.1778)
							(mid 0.249642 -0.249642)
							(end 0.1778 -0.2794)
						)
					)
					(width 0)
					(fill yes)
				)
			)
		)
	)
	(footprint ""
		(layer "F.Cu")
		(at 145.177002 -76.430632 -90)
		(property "Reference" "PC214"
			(at 0 0 270)
			(layer "F.SilkS")
			(hide yes)
			(effects
				(font
					(size 1.27 1.27)
				)
			)
		)
		(property "Value" "SC22U25V6KX-GP-U"
			(at -2.860802 -5.279644 270)
			(unlocked yes)
			(layer "F.Fab")
			(hide yes)
			(effects
				(font
					(size 1.016 1.016)
					(thickness 0.1524)
				)
			)
		)
		(property "Device Type" "C1206-TO0D3H75"
			(at -2.860802 -6.803644 270)
			(unlocked yes)
			(layer "F.Fab")
			(hide yes)
			(effects
				(font
					(size 1.016 1.016)
					(thickness 0.1524)
				)
			)
		)
		(duplicate_pad_numbers_are_jumpers no)
		(fp_line
			(start -1.3081 2.3749)
			(end -1.3081 -2.3749)
			(stroke
				(width 0.1524)
				(type default)
			)
			(layer "F.SilkS")
		)
		(fp_line
			(start 1.3081 2.3749)
			(end -1.3081 2.3749)
			(stroke
				(width 0.1524)
				(type default)
			)
			(layer "F.SilkS")
		)
		(fp_line
			(start -1.3081 -2.3749)
			(end 1.3081 -2.3749)
			(stroke
				(width 0.1524)
				(type default)
			)
			(layer "F.SilkS")
		)
		(fp_line
			(start 1.3081 -2.3749)
			(end 1.3081 2.3749)
			(stroke
				(width 0.1524)
				(type default)
			)
			(layer "F.SilkS")
		)
		(fp_rect
			(start -0.8001 1.6002)
			(end 0.8001 -1.6002)
			(stroke
				(width 0)
				(type default)
			)
			(fill no)
			(layer "F.CrtYd")
		)
		(fp_poly
			(pts
				(xy -1.5621 2.4511) (xy -1.5621 1.6002) (xy 0.8001 1.6002) (xy 0.8001 -1.6002) (xy -0.8001 -1.6002)
				(xy -0.8001 1.5875) (xy -1.5621 1.5875) (xy -1.5621 -2.4511) (xy 1.5621 -2.4511) (xy 1.5621 2.4511)
			)
			(stroke
				(width 0)
				(type default)
			)
			(fill no)
			(layer "F.CrtYd")
		)
		(fp_rect
			(start -1.5621 2.4511)
			(end 1.5621 -2.4511)
			(stroke
				(width 0)
				(type default)
			)
			(fill no)
			(layer "F.Fab")
		)
		(pad "1" smd rect
			(at 0 -1.392936 270)
			(size 2.1082 1.4478)
			(layers "F.Cu" "F.Mask" "F.Paste")
			(net "P0V9_VIN")
		)
		(pad "2" smd rect
			(at 0 1.392936 270)
			(size 2.1082 1.4478)
			(layers "F.Cu" "F.Mask" "F.Paste")
			(net "GND")
		)
	)
	(footprint ""
		(layer "F.Cu")
		(at 40.9956 -77.5716 180)
		(property "Reference" "PC68"
			(at 0 0 180)
			(layer "F.SilkS")
			(hide yes)
			(effects
				(font
					(size 1.27 1.27)
				)
			)
		)
		(property "Value" "SC22U16V5MX-4-GP"
			(at -0.0762 -6.1214 180)
			(unlocked yes)
			(layer "F.Fab")
			(hide yes)
			(effects
				(font
					(size 1.016 1.016)
					(thickness 0.1524)
				)
			)
		)
		(property "Device Type" "C805H58"
			(at -0.0762 -8.1534 180)
			(unlocked yes)
			(layer "F.Fab")
			(hide yes)
			(effects
				(font
					(size 1.016 1.016)
					(thickness 0.1524)
				)
			)
		)
		(duplicate_pad_numbers_are_jumpers no)
		(fp_line
			(start 0.635 0)
			(end -0.635 0)
			(stroke
				(width 0.508)
				(type default)
			)
			(layer "F.SilkS")
		)
		(fp_rect
			(start -0.9652 1.778)
			(end 0.9652 -1.778)
			(stroke
				(width 0)
				(type default)
			)
			(fill no)
			(layer "F.CrtYd")
		)
		(fp_poly
			(pts
				(xy -0.9652 -1.778) (xy 0.9652 -1.778) (xy 0.9652 1.778) (xy -0.9652 1.778)
			)
			(stroke
				(width 0)
				(type default)
			)
			(fill no)
			(layer "F.Fab")
		)
		(pad "1" smd rect
			(at 0 -0.9652 180)
			(size 1.397 1.143)
			(layers "F.Cu" "F.Mask" "F.Paste")
			(net "P5V_STBY_LR")
		)
		(pad "2" smd rect
			(at 0 0.9652 180)
			(size 1.397 1.143)
			(layers "F.Cu" "F.Mask" "F.Paste")
			(net "GND")
		)
	)
	(footprint ""
		(layer "F.Cu")
		(at 188.6458 -3.3782)
		(property "Reference" "R943"
			(at 0 0 0)
			(layer "F.SilkS")
			(hide yes)
			(effects
				(font
					(size 1.27 1.27)
				)
			)
		)
		(property "Value" "4K7R2F-GP"
			(at 0.064008 -3.993896 0)
			(unlocked yes)
			(layer "F.Fab")
			(hide yes)
			(effects
				(font
					(size 1.016 1.016)
					(thickness 0.1524)
				)
			)
		)
		(property "Device Type" "R402H16"
			(at 0.064008 -5.517896 0)
			(unlocked yes)
			(layer "F.Fab")
			(hide yes)
			(effects
				(font
					(size 1.016 1.016)
					(thickness 0.1524)
				)
			)
		)
		(duplicate_pad_numbers_are_jumpers no)
		(fp_line
			(start -0.508 -0.9398)
			(end -0.508 0.9398)
			(stroke
				(width 0.1524)
				(type default)
			)
			(layer "F.SilkS")
		)
		(fp_line
			(start 0.508 -0.9398)
			(end -0.508 -0.9398)
			(stroke
				(width 0.1524)
				(type default)
			)
			(layer "F.SilkS")
		)
		(fp_rect
			(start -0.508 0.9398)
			(end 0.508 -0.9398)
			(stroke
				(width 0)
				(type default)
			)
			(fill no)
			(layer "F.CrtYd")
		)
		(fp_rect
			(start -0.508 0.9398)
			(end 0.508 -0.9398)
			(stroke
				(width 0)
				(type default)
			)
			(fill no)
			(layer "F.Fab")
		)
		(pad "1" smd custom
			(at 0 -0.4445)
			(size 0.1397 0.1397)
			(layers "F.Cu" "F.Mask" "F.Paste")
			(net "P3V3_STBY")
			(options
				(clearance outline)
				(anchor circle)
			)
			(primitives
				(gr_poly
					(pts
						(arc
							(start -0.1778 -0.2794)
							(mid -0.249642 -0.249642)
							(end -0.2794 -0.1778)
						)
						(arc
							(start -0.2794 0.1778)
							(mid -0.249642 0.249642)
							(end -0.1778 0.2794)
						)
						(arc
							(start 0.1778 0.2794)
							(mid 0.249642 0.249642)
							(end 0.2794 0.1778)
						)
						(arc
							(start 0.2794 -0.1778)
							(mid 0.249642 -0.249642)
							(end 0.1778 -0.2794)
						)
					)
					(width 0)
					(fill yes)
				)
			)
		)
		(pad "2" smd custom
			(at 0 0.4445)
			(size 0.1397 0.1397)
			(layers "F.Cu" "F.Mask" "F.Paste")
			(net "WP_DISABLE")
			(options
				(clearance outline)
				(anchor circle)
			)
			(primitives
				(gr_poly
					(pts
						(arc
							(start -0.1778 -0.2794)
							(mid -0.249642 -0.249642)
							(end -0.2794 -0.1778)
						)
						(arc
							(start -0.2794 0.1778)
							(mid -0.249642 0.249642)
							(end -0.1778 0.2794)
						)
						(arc
							(start 0.1778 0.2794)
							(mid 0.249642 0.249642)
							(end 0.2794 0.1778)
						)
						(arc
							(start 0.2794 -0.1778)
							(mid 0.249642 -0.249642)
							(end 0.1778 -0.2794)
						)
					)
					(width 0)
					(fill yes)
				)
			)
		)
	)
	(footprint ""
		(layer "F.Cu")
		(at 255.524762 -6.097778 180)
		(property "Reference" "U4"
			(at 0 0 180)
			(layer "F.SilkS")
			(hide yes)
			(effects
				(font
					(size 1.27 1.27)
				)
			)
		)
		(property "Value" "MAX6654MEE-2-GP"
			(at -0.127 -12.4968 180)
			(unlocked yes)
			(layer "F.Fab")
			(hide yes)
			(effects
				(font
					(size 1.016 1.016)
					(thickness 0.1524)
				)
			)
		)
		(property "Device Type" "QSOIC16H69"
			(at -0.2032 -14.1478 180)
			(unlocked yes)
			(layer "F.Fab")
			(hide yes)
			(effects
				(font
					(size 1.016 1.016)
					(thickness 0.1524)
				)
			)
		)
		(duplicate_pad_numbers_are_jumpers no)
		(fp_line
			(start 2.3114 1.5748)
			(end 2.3114 -1.5748)
			(stroke
				(width 0.1524)
				(type default)
			)
			(layer "F.SilkS")
		)
		(fp_line
			(start 2.3114 1.5748)
			(end -2.794 1.5748)
			(stroke
				(width 0.1524)
				(type default)
			)
			(layer "F.SilkS")
		)
		(fp_line
			(start 2.3114 -1.5748)
			(end -2.7178 -1.5748)
			(stroke
				(width 0.1524)
				(type default)
			)
			(layer "F.SilkS")
		)
		(fp_line
			(start -2.4638 0)
			(end -2.7178 0.254)
			(stroke
				(width 0.1524)
				(type default)
			)
			(layer "F.SilkS")
		)
		(fp_line
			(start -2.7178 1.5748)
			(end -2.7178 -1.5748)
			(stroke
				(width 0.1524)
				(type default)
			)
			(layer "F.SilkS")
		)
		(fp_line
			(start -2.7178 -0.254)
			(end -2.4638 0)
			(stroke
				(width 0.1524)
				(type default)
			)
			(layer "F.SilkS")
		)
		(fp_line
			(start -2.794 1.5748)
			(end -2.794 3.302)
			(stroke
				(width 0.508)
				(type default)
			)
			(layer "F.SilkS")
		)
		(fp_poly
			(pts
				(xy -2.3876 -1.5748) (xy 2.3114 -1.5748) (xy 2.3114 1.5748) (xy -2.3876 1.5748)
			)
			(stroke
				(width 0)
				(type default)
			)
			(fill yes)
			(layer "F.SilkS")
		)
		(fp_rect
			(start -2.794 3.556)
			(end 2.794 -3.556)
			(stroke
				(width 0)
				(type default)
			)
			(fill no)
			(layer "F.CrtYd")
		)
		(fp_poly
			(pts
				(xy -2.794 -3.556) (xy 2.794 -3.556) (xy 2.794 3.556) (xy -2.794 3.556)
			)
			(stroke
				(width 0)
				(type default)
			)
			(fill no)
			(layer "F.Fab")
		)
		(pad "1" smd rect
			(at -2.2225 2.6162 180)
			(size 0.3556 1.524)
			(layers "F.Cu" "F.Mask" "F.Paste")
			(net "Net_2088")
		)
		(pad "2" smd rect
			(at -1.5875 2.6162 180)
			(size 0.3556 1.524)
			(layers "F.Cu" "F.Mask" "F.Paste")
			(net "P3V3_STBY")
		)
		(pad "3" smd rect
			(at -0.9525 2.6162 180)
			(size 0.3556 1.524)
			(layers "F.Cu" "F.Mask" "F.Paste")
			(net "THERM_EMIT_R")
		)
		(pad "4" smd rect
			(at -0.3175 2.6162 180)
			(size 0.3556 1.524)
			(layers "F.Cu" "F.Mask" "F.Paste")
			(net "THERM_BASE_R")
		)
		(pad "5" smd rect
			(at 0.3175 2.6162 180)
			(size 0.3556 1.524)
			(layers "F.Cu" "F.Mask" "F.Paste")
			(net "Net_2087")
		)
		(pad "6" smd rect
			(at 0.9525 2.6162 180)
			(size 0.3556 1.524)
			(layers "F.Cu" "F.Mask" "F.Paste")
			(net "MAX6654_ADD1")
		)
		(pad "7" smd rect
			(at 1.5875 2.6162 180)
			(size 0.3556 1.524)
			(layers "F.Cu" "F.Mask" "F.Paste")
			(net "GND")
		)
		(pad "8" smd rect
			(at 2.2225 2.6162 180)
			(size 0.3556 1.524)
			(layers "F.Cu" "F.Mask" "F.Paste")
			(net "GND")
		)
		(pad "9" smd rect
			(at 2.2225 -2.6162 180)
			(size 0.3556 1.524)
			(layers "F.Cu" "F.Mask" "F.Paste")
			(net "Net_2086")
		)
		(pad "10" smd rect
			(at 1.5875 -2.6162 180)
			(size 0.3556 1.524)
			(layers "F.Cu" "F.Mask" "F.Paste")
			(net "MAX6654_ADD0")
		)
		(pad "11" smd rect
			(at 0.9525 -2.6162 180)
			(size 0.3556 1.524)
			(layers "F.Cu" "F.Mask" "F.Paste")
			(net "MAX6654_ALERT#")
		)
		(pad "12" smd rect
			(at 0.3175 -2.6162 180)
			(size 0.3556 1.524)
			(layers "F.Cu" "F.Mask" "F.Paste")
			(net "I2C_MAX6654_DAT")
		)
		(pad "13" smd rect
			(at -0.3175 -2.6162 180)
			(size 0.3556 1.524)
			(layers "F.Cu" "F.Mask" "F.Paste")
			(net "Net_2085")
		)
		(pad "14" smd rect
			(at -0.9525 -2.6162 180)
			(size 0.3556 1.524)
			(layers "F.Cu" "F.Mask" "F.Paste")
			(net "I2C_MAX6654_CLK")
		)
		(pad "15" smd rect
			(at -1.5875 -2.6162 180)
			(size 0.3556 1.524)
			(layers "F.Cu" "F.Mask" "F.Paste")
			(net "P3V3_STBY")
		)
		(pad "16" smd rect
			(at -2.2225 -2.6162 180)
			(size 0.3556 1.524)
			(layers "F.Cu" "F.Mask" "F.Paste")
			(net "Net_2084")
		)
	)
	(footprint ""
		(layer "F.Cu")
		(at 71.501 -34.417 180)
		(property "Reference" "PR18"
			(at 0 0 180)
			(layer "F.SilkS")
			(hide yes)
			(effects
				(font
					(size 1.27 1.27)
				)
			)
		)
		(property "Value" "1K4R2F-1-GP"
			(at 0.064008 -3.993896 180)
			(unlocked yes)
			(layer "F.Fab")
			(hide yes)
			(effects
				(font
					(size 1.016 1.016)
					(thickness 0.1524)
				)
			)
		)
		(property "Device Type" "R402H16"
			(at 0.064008 -5.517896 180)
			(unlocked yes)
			(layer "F.Fab")
			(hide yes)
			(effects
				(font
					(size 1.016 1.016)
					(thickness 0.1524)
				)
			)
		)
		(duplicate_pad_numbers_are_jumpers no)
		(fp_line
			(start 0.508 -0.9398)
			(end -0.508 -0.9398)
			(stroke
				(width 0.1524)
				(type default)
			)
			(layer "F.SilkS")
		)
		(fp_line
			(start -0.508 -0.9398)
			(end -0.508 0.9398)
			(stroke
				(width 0.1524)
				(type default)
			)
			(layer "F.SilkS")
		)
		(fp_rect
			(start -0.508 0.9398)
			(end 0.508 -0.9398)
			(stroke
				(width 0)
				(type default)
			)
			(fill no)
			(layer "F.CrtYd")
		)
		(fp_rect
			(start -0.508 0.9398)
			(end 0.508 -0.9398)
			(stroke
				(width 0)
				(type default)
			)
			(fill no)
			(layer "F.Fab")
		)
		(pad "1" smd custom
			(at 0 -0.4445 180)
			(size 0.1397 0.1397)
			(layers "F.Cu" "F.Mask" "F.Paste")
			(net "P5V_STBY")
			(options
				(clearance outline)
				(anchor circle)
			)
			(primitives
				(gr_poly
					(pts
						(arc
							(start -0.1778 -0.2794)
							(mid -0.249642 -0.249642)
							(end -0.2794 -0.1778)
						)
						(arc
							(start -0.2794 0.1778)
							(mid -0.249642 0.249642)
							(end -0.1778 0.2794)
						)
						(arc
							(start 0.1778 0.2794)
							(mid 0.249642 0.249642)
							(end 0.2794 0.1778)
						)
						(arc
							(start 0.2794 -0.1778)
							(mid 0.249642 -0.249642)
							(end 0.1778 -0.2794)
						)
					)
					(width 0)
					(fill yes)
				)
			)
		)
		(pad "2" smd custom
			(at 0 0.4445 180)
			(size 0.1397 0.1397)
			(layers "F.Cu" "F.Mask" "F.Paste")
			(net "P3V3_STBY_EN")
			(options
				(clearance outline)
				(anchor circle)
			)
			(primitives
				(gr_poly
					(pts
						(arc
							(start -0.1778 -0.2794)
							(mid -0.249642 -0.249642)
							(end -0.2794 -0.1778)
						)
						(arc
							(start -0.2794 0.1778)
							(mid -0.249642 0.249642)
							(end -0.1778 0.2794)
						)
						(arc
							(start 0.1778 0.2794)
							(mid 0.249642 0.249642)
							(end 0.2794 0.1778)
						)
						(arc
							(start 0.2794 -0.1778)
							(mid 0.249642 -0.249642)
							(end 0.1778 -0.2794)
						)
					)
					(width 0)
					(fill yes)
				)
			)
		)
	)
	(footprint ""
		(layer "F.Cu")
		(at 229.108 -91.059 -90)
		(property "Reference" "R592"
			(at 0 0 270)
			(layer "F.SilkS")
			(hide yes)
			(effects
				(font
					(size 1.27 1.27)
				)
			)
		)
		(property "Value" "4K7R2F-GP"
			(at 0.064008 -3.993896 270)
			(unlocked yes)
			(layer "F.Fab")
			(hide yes)
			(effects
				(font
					(size 1.016 1.016)
					(thickness 0.1524)
				)
			)
		)
		(property "Device Type" "R402H16"
			(at 0.064008 -5.517896 270)
			(unlocked yes)
			(layer "F.Fab")
			(hide yes)
			(effects
				(font
					(size 1.016 1.016)
					(thickness 0.1524)
				)
			)
		)
		(duplicate_pad_numbers_are_jumpers no)
		(fp_line
			(start -0.508 -0.9398)
			(end -0.508 0.9398)
			(stroke
				(width 0.1524)
				(type default)
			)
			(layer "F.SilkS")
		)
		(fp_line
			(start 0.508 -0.9398)
			(end -0.508 -0.9398)
			(stroke
				(width 0.1524)
				(type default)
			)
			(layer "F.SilkS")
		)
		(fp_rect
			(start -0.508 0.9398)
			(end 0.508 -0.9398)
			(stroke
				(width 0)
				(type default)
			)
			(fill no)
			(layer "F.CrtYd")
		)
		(fp_rect
			(start -0.508 0.9398)
			(end 0.508 -0.9398)
			(stroke
				(width 0)
				(type default)
			)
			(fill no)
			(layer "F.Fab")
		)
		(pad "1" smd custom
			(at 0 -0.4445 270)
			(size 0.1397 0.1397)
			(layers "F.Cu" "F.Mask" "F.Paste")
			(net "P3V3_STBY")
			(options
				(clearance outline)
				(anchor circle)
			)
			(primitives
				(gr_poly
					(pts
						(arc
							(start -0.1778 -0.2794)
							(mid -0.249642 -0.249642)
							(end -0.2794 -0.1778)
						)
						(arc
							(start -0.2794 0.1778)
							(mid -0.249642 0.249642)
							(end -0.1778 0.2794)
						)
						(arc
							(start 0.1778 0.2794)
							(mid 0.249642 0.249642)
							(end 0.2794 0.1778)
						)
						(arc
							(start 0.2794 -0.1778)
							(mid 0.249642 -0.249642)
							(end 0.1778 -0.2794)
						)
					)
					(width 0)
					(fill yes)
				)
			)
		)
		(pad "2" smd custom
			(at 0 0.4445 270)
			(size 0.1397 0.1397)
			(layers "F.Cu" "F.Mask" "F.Paste")
			(net "TEMP_3_A0")
			(options
				(clearance outline)
				(anchor circle)
			)
			(primitives
				(gr_poly
					(pts
						(arc
							(start -0.1778 -0.2794)
							(mid -0.249642 -0.249642)
							(end -0.2794 -0.1778)
						)
						(arc
							(start -0.2794 0.1778)
							(mid -0.249642 0.249642)
							(end -0.1778 0.2794)
						)
						(arc
							(start 0.1778 0.2794)
							(mid 0.249642 0.249642)
							(end 0.2794 0.1778)
						)
						(arc
							(start 0.2794 -0.1778)
							(mid 0.249642 -0.249642)
							(end 0.1778 -0.2794)
						)
					)
					(width 0)
					(fill yes)
				)
			)
		)
	)
	(footprint ""
		(layer "F.Cu")
		(at 322.58127 -33.507934 180)
		(property "Reference" "R718"
			(at 0 0 180)
			(layer "F.SilkS")
			(hide yes)
			(effects
				(font
					(size 1.27 1.27)
				)
			)
		)
		(property "Value" "0R2J-2-GP"
			(at 0.064008 -3.993896 180)
			(unlocked yes)
			(layer "F.Fab")
			(hide yes)
			(effects
				(font
					(size 1.016 1.016)
					(thickness 0.1524)
				)
			)
		)
		(property "Device Type" "R402H16"
			(at 0.064008 -5.517896 180)
			(unlocked yes)
			(layer "F.Fab")
			(hide yes)
			(effects
				(font
					(size 1.016 1.016)
					(thickness 0.1524)
				)
			)
		)
		(duplicate_pad_numbers_are_jumpers no)
		(fp_line
			(start 0.508 -0.9398)
			(end -0.508 -0.9398)
			(stroke
				(width 0.1524)
				(type default)
			)
			(layer "F.SilkS")
		)
		(fp_line
			(start -0.508 -0.9398)
			(end -0.508 0.9398)
			(stroke
				(width 0.1524)
				(type default)
			)
			(layer "F.SilkS")
		)
		(fp_rect
			(start -0.508 0.9398)
			(end 0.508 -0.9398)
			(stroke
				(width 0)
				(type default)
			)
			(fill no)
			(layer "F.CrtYd")
		)
		(fp_rect
			(start -0.508 0.9398)
			(end 0.508 -0.9398)
			(stroke
				(width 0)
				(type default)
			)
			(fill no)
			(layer "F.Fab")
		)
		(pad "1" smd custom
			(at 0 -0.4445 180)
			(size 0.1397 0.1397)
			(layers "F.Cu" "F.Mask" "F.Paste")
			(net "8644_USB_DP8")
			(options
				(clearance outline)
				(anchor circle)
			)
			(primitives
				(gr_poly
					(pts
						(arc
							(start -0.1778 -0.2794)
							(mid -0.249642 -0.249642)
							(end -0.2794 -0.1778)
						)
						(arc
							(start -0.2794 0.1778)
							(mid -0.249642 0.249642)
							(end -0.1778 0.2794)
						)
						(arc
							(start 0.1778 0.2794)
							(mid 0.249642 0.249642)
							(end 0.2794 0.1778)
						)
						(arc
							(start 0.2794 -0.1778)
							(mid 0.249642 -0.249642)
							(end 0.1778 -0.2794)
						)
					)
					(width 0)
					(fill yes)
				)
			)
		)
		(pad "2" smd custom
			(at 0 0.4445 180)
			(size 0.1397 0.1397)
			(layers "F.Cu" "F.Mask" "F.Paste")
			(net "P3V3_STBY")
			(options
				(clearance outline)
				(anchor circle)
			)
			(primitives
				(gr_poly
					(pts
						(arc
							(start -0.1778 -0.2794)
							(mid -0.249642 -0.249642)
							(end -0.2794 -0.1778)
						)
						(arc
							(start -0.2794 0.1778)
							(mid -0.249642 0.249642)
							(end -0.1778 0.2794)
						)
						(arc
							(start 0.1778 0.2794)
							(mid 0.249642 0.249642)
							(end 0.2794 0.1778)
						)
						(arc
							(start 0.2794 -0.1778)
							(mid 0.249642 -0.249642)
							(end 0.1778 -0.2794)
						)
					)
					(width 0)
					(fill yes)
				)
			)
		)
	)
	(footprint ""
		(layer "F.Cu")
		(at 14.036294 -129.321814)
		(property "Reference" "R163"
			(at 0 0 0)
			(layer "F.SilkS")
			(hide yes)
			(effects
				(font
					(size 1.27 1.27)
				)
			)
		)
		(property "Value" "4K7R2F-GP"
			(at 0.064008 -3.993896 0)
			(unlocked yes)
			(layer "F.Fab")
			(hide yes)
			(effects
				(font
					(size 1.016 1.016)
					(thickness 0.1524)
				)
			)
		)
		(property "Device Type" "R402H16"
			(at 0.064008 -5.517896 0)
			(unlocked yes)
			(layer "F.Fab")
			(hide yes)
			(effects
				(font
					(size 1.016 1.016)
					(thickness 0.1524)
				)
			)
		)
		(duplicate_pad_numbers_are_jumpers no)
		(fp_line
			(start -0.508 -0.9398)
			(end -0.508 0.9398)
			(stroke
				(width 0.1524)
				(type default)
			)
			(layer "F.SilkS")
		)
		(fp_line
			(start 0.508 -0.9398)
			(end -0.508 -0.9398)
			(stroke
				(width 0.1524)
				(type default)
			)
			(layer "F.SilkS")
		)
		(fp_rect
			(start -0.508 0.9398)
			(end 0.508 -0.9398)
			(stroke
				(width 0)
				(type default)
			)
			(fill no)
			(layer "F.CrtYd")
		)
		(fp_rect
			(start -0.508 0.9398)
			(end 0.508 -0.9398)
			(stroke
				(width 0)
				(type default)
			)
			(fill no)
			(layer "F.Fab")
		)
		(pad "1" smd custom
			(at 0 -0.4445)
			(size 0.1397 0.1397)
			(layers "F.Cu" "F.Mask" "F.Paste")
			(net "FLA_CS")
			(options
				(clearance outline)
				(anchor circle)
			)
			(primitives
				(gr_poly
					(pts
						(arc
							(start -0.1778 -0.2794)
							(mid -0.249642 -0.249642)
							(end -0.2794 -0.1778)
						)
						(arc
							(start -0.2794 0.1778)
							(mid -0.249642 0.249642)
							(end -0.1778 0.2794)
						)
						(arc
							(start 0.1778 0.2794)
							(mid 0.249642 0.249642)
							(end 0.2794 0.1778)
						)
						(arc
							(start 0.2794 -0.1778)
							(mid 0.249642 -0.249642)
							(end 0.1778 -0.2794)
						)
					)
					(width 0)
					(fill yes)
				)
			)
		)
		(pad "2" smd custom
			(at 0 0.4445)
			(size 0.1397 0.1397)
			(layers "F.Cu" "F.Mask" "F.Paste")
			(net "P3V3_STBY")
			(options
				(clearance outline)
				(anchor circle)
			)
			(primitives
				(gr_poly
					(pts
						(arc
							(start -0.1778 -0.2794)
							(mid -0.249642 -0.249642)
							(end -0.2794 -0.1778)
						)
						(arc
							(start -0.2794 0.1778)
							(mid -0.249642 0.249642)
							(end -0.1778 0.2794)
						)
						(arc
							(start 0.1778 0.2794)
							(mid 0.249642 0.249642)
							(end 0.2794 0.1778)
						)
						(arc
							(start 0.2794 -0.1778)
							(mid 0.249642 -0.249642)
							(end 0.1778 -0.2794)
						)
					)
					(width 0)
					(fill yes)
				)
			)
		)
	)
	(footprint ""
		(layer "F.Cu")
		(at 49.7078 -63.7794 -90)
		(property "Reference" "R508"
			(at 0 0 270)
			(layer "F.SilkS")
			(hide yes)
			(effects
				(font
					(size 1.27 1.27)
				)
			)
		)
		(property "Value" "3K3R2F-2-GP"
			(at 0.064008 -3.993896 270)
			(unlocked yes)
			(layer "F.Fab")
			(hide yes)
			(effects
				(font
					(size 1.016 1.016)
					(thickness 0.1524)
				)
			)
		)
		(property "Device Type" "R402H16"
			(at 0.064008 -5.517896 270)
			(unlocked yes)
			(layer "F.Fab")
			(hide yes)
			(effects
				(font
					(size 1.016 1.016)
					(thickness 0.1524)
				)
			)
		)
		(duplicate_pad_numbers_are_jumpers no)
		(fp_line
			(start -0.508 -0.9398)
			(end -0.508 0.9398)
			(stroke
				(width 0.1524)
				(type default)
			)
			(layer "F.SilkS")
		)
		(fp_line
			(start 0.508 -0.9398)
			(end -0.508 -0.9398)
			(stroke
				(width 0.1524)
				(type default)
			)
			(layer "F.SilkS")
		)
		(fp_rect
			(start -0.508 0.9398)
			(end 0.508 -0.9398)
			(stroke
				(width 0)
				(type default)
			)
			(fill no)
			(layer "F.CrtYd")
		)
		(fp_rect
			(start -0.508 0.9398)
			(end 0.508 -0.9398)
			(stroke
				(width 0)
				(type default)
			)
			(fill no)
			(layer "F.Fab")
		)
		(pad "1" smd custom
			(at 0 -0.4445 270)
			(size 0.1397 0.1397)
			(layers "F.Cu" "F.Mask" "F.Paste")
			(net "P3V3_STBY")
			(options
				(clearance outline)
				(anchor circle)
			)
			(primitives
				(gr_poly
					(pts
						(arc
							(start -0.1778 -0.2794)
							(mid -0.249642 -0.249642)
							(end -0.2794 -0.1778)
						)
						(arc
							(start -0.2794 0.1778)
							(mid -0.249642 0.249642)
							(end -0.1778 0.2794)
						)
						(arc
							(start 0.1778 0.2794)
							(mid 0.249642 0.249642)
							(end 0.2794 0.1778)
						)
						(arc
							(start 0.2794 -0.1778)
							(mid 0.249642 -0.249642)
							(end 0.1778 -0.2794)
						)
					)
					(width 0)
					(fill yes)
				)
			)
		)
		(pad "2" smd custom
			(at 0 0.4445 270)
			(size 0.1397 0.1397)
			(layers "F.Cu" "F.Mask" "F.Paste")
			(net "U44_WP_N")
			(options
				(clearance outline)
				(anchor circle)
			)
			(primitives
				(gr_poly
					(pts
						(arc
							(start -0.1778 -0.2794)
							(mid -0.249642 -0.249642)
							(end -0.2794 -0.1778)
						)
						(arc
							(start -0.2794 0.1778)
							(mid -0.249642 0.249642)
							(end -0.1778 0.2794)
						)
						(arc
							(start 0.1778 0.2794)
							(mid 0.249642 0.249642)
							(end 0.2794 0.1778)
						)
						(arc
							(start 0.2794 -0.1778)
							(mid 0.249642 -0.249642)
							(end 0.1778 -0.2794)
						)
					)
					(width 0)
					(fill yes)
				)
			)
		)
	)
	(footprint ""
		(layer "F.Cu")
		(at 158.496 -85.2424 180)
		(property "Reference" "R74"
			(at 0 0 180)
			(layer "F.SilkS")
			(hide yes)
			(effects
				(font
					(size 1.27 1.27)
				)
			)
		)
		(property "Value" "0R2J-2-GP"
			(at 0.064008 -3.993896 180)
			(unlocked yes)
			(layer "F.Fab")
			(hide yes)
			(effects
				(font
					(size 1.016 1.016)
					(thickness 0.1524)
				)
			)
		)
		(property "Device Type" "R402H16"
			(at 0.064008 -5.517896 180)
			(unlocked yes)
			(layer "F.Fab")
			(hide yes)
			(effects
				(font
					(size 1.016 1.016)
					(thickness 0.1524)
				)
			)
		)
		(duplicate_pad_numbers_are_jumpers no)
		(fp_line
			(start 0.508 -0.9398)
			(end -0.508 -0.9398)
			(stroke
				(width 0.1524)
				(type default)
			)
			(layer "F.SilkS")
		)
		(fp_line
			(start -0.508 -0.9398)
			(end -0.508 0.9398)
			(stroke
				(width 0.1524)
				(type default)
			)
			(layer "F.SilkS")
		)
		(fp_rect
			(start -0.508 0.9398)
			(end 0.508 -0.9398)
			(stroke
				(width 0)
				(type default)
			)
			(fill no)
			(layer "F.CrtYd")
		)
		(fp_rect
			(start -0.508 0.9398)
			(end 0.508 -0.9398)
			(stroke
				(width 0)
				(type default)
			)
			(fill no)
			(layer "F.Fab")
		)
		(pad "1" smd custom
			(at 0 -0.4445 180)
			(size 0.1397 0.1397)
			(layers "F.Cu" "F.Mask" "F.Paste")
			(net "BMC_I2C5_D_PEB_SCL")
			(options
				(clearance outline)
				(anchor circle)
			)
			(primitives
				(gr_poly
					(pts
						(arc
							(start -0.1778 -0.2794)
							(mid -0.249642 -0.249642)
							(end -0.2794 -0.1778)
						)
						(arc
							(start -0.2794 0.1778)
							(mid -0.249642 0.249642)
							(end -0.1778 0.2794)
						)
						(arc
							(start 0.1778 0.2794)
							(mid 0.249642 0.249642)
							(end 0.2794 0.1778)
						)
						(arc
							(start 0.2794 -0.1778)
							(mid 0.249642 -0.249642)
							(end 0.1778 -0.2794)
						)
					)
					(width 0)
					(fill yes)
				)
			)
		)
		(pad "2" smd custom
			(at 0 0.4445 180)
			(size 0.1397 0.1397)
			(layers "F.Cu" "F.Mask" "F.Paste")
			(net "CLKGEN_SCL")
			(options
				(clearance outline)
				(anchor circle)
			)
			(primitives
				(gr_poly
					(pts
						(arc
							(start -0.1778 -0.2794)
							(mid -0.249642 -0.249642)
							(end -0.2794 -0.1778)
						)
						(arc
							(start -0.2794 0.1778)
							(mid -0.249642 0.249642)
							(end -0.1778 0.2794)
						)
						(arc
							(start 0.1778 0.2794)
							(mid 0.249642 0.249642)
							(end 0.2794 0.1778)
						)
						(arc
							(start 0.2794 -0.1778)
							(mid 0.249642 -0.249642)
							(end 0.1778 -0.2794)
						)
					)
					(width 0)
					(fill yes)
				)
			)
		)
	)
	(footprint ""
		(layer "F.Cu")
		(at 51.9938 -121.870216)
		(property "Reference" "TP172"
			(at 0 0 0)
			(layer "F.SilkS")
			(hide yes)
			(effects
				(font
					(size 1.27 1.27)
				)
			)
		)
		(property "Value" "TPAD28-2-GP"
			(at -0.0127 -1.6637 0)
			(unlocked yes)
			(layer "F.Fab")
			(hide yes)
			(effects
				(font
					(size 1.016 1.016)
					(thickness 0.1524)
				)
			)
		)
		(property "Device Type" "TPAD28"
			(at -0.0127 -3.1877 0)
			(unlocked yes)
			(layer "F.Fab")
			(hide yes)
			(effects
				(font
					(size 1.016 1.016)
					(thickness 0.1524)
				)
			)
		)
		(duplicate_pad_numbers_are_jumpers no)
		(fp_poly
			(pts
				(arc
					(start 0.3556 0)
					(mid -0.3556 0)
					(end 0.3556 0)
				)
			)
			(stroke
				(width 0)
				(type default)
			)
			(fill no)
			(layer "F.CrtYd")
		)
		(fp_poly
			(pts
				(arc
					(start 0.6096 0)
					(mid -0.6096 0)
					(end 0.6096 0)
				)
			)
			(stroke
				(width 0)
				(type default)
			)
			(fill no)
			(layer "F.Fab")
		)
		(pad "1" smd circle
			(at 0 0)
			(size 0.7112 0.7112)
			(layers "F.Cu" "F.Mask" "F.Paste")
			(net "JTAG_BMC_TRST_N")
		)
	)
	(footprint ""
		(layer "F.Cu")
		(at 81.407 -45.085 180)
		(property "Reference" "PTC38"
			(at 0 0 180)
			(layer "F.SilkS")
			(hide yes)
			(effects
				(font
					(size 1.27 1.27)
				)
			)
		)
		(property "Value" "ST150U6D3VDM-28-GP"
			(at 0 -9.6012 180)
			(unlocked yes)
			(layer "F.Fab")
			(hide yes)
			(effects
				(font
					(size 1.016 1.016)
					(thickness 0.1524)
				)
			)
		)
		(property "Device Type" "CT7343H83"
			(at 0 -11.1252 180)
			(unlocked yes)
			(layer "F.Fab")
			(hide yes)
			(effects
				(font
					(size 1.016 1.016)
					(thickness 0.1524)
				)
			)
		)
		(duplicate_pad_numbers_are_jumpers no)
		(fp_line
			(start 2.286 4.8768)
			(end -2.286 4.8768)
			(stroke
				(width 0.1524)
				(type default)
			)
			(layer "F.SilkS")
		)
		(fp_line
			(start 2.286 2.032)
			(end 2.286 4.8768)
			(stroke
				(width 0.1524)
				(type default)
			)
			(layer "F.SilkS")
		)
		(fp_line
			(start 2.286 -2.032)
			(end 2.286 -4.8768)
			(stroke
				(width 0.1524)
				(type default)
			)
			(layer "F.SilkS")
		)
		(fp_line
			(start 2.286 -4.8768)
			(end -2.286 -4.8768)
			(stroke
				(width 0.1524)
				(type default)
			)
			(layer "F.SilkS")
		)
		(fp_line
			(start 2.1082 -4.699)
			(end -2.1082 -4.699)
			(stroke
				(width 0.508)
				(type default)
			)
			(layer "F.SilkS")
		)
		(fp_line
			(start -2.286 4.8768)
			(end -2.286 2.032)
			(stroke
				(width 0.1524)
				(type default)
			)
			(layer "F.SilkS")
		)
		(fp_line
			(start -2.286 -4.8768)
			(end -2.286 -2.032)
			(stroke
				(width 0.1524)
				(type default)
			)
			(layer "F.SilkS")
		)
		(fp_rect
			(start -2.1463 3.6449)
			(end 2.1463 -3.6449)
			(stroke
				(width 0)
				(type default)
			)
			(fill no)
			(layer "F.CrtYd")
		)
		(fp_poly
			(pts
				(xy -2.54 4.953) (xy -2.54 4.2926) (xy -3.81 4.2926) (xy -3.81 -4.2926) (xy -2.54 -4.2926) (xy -2.54 -4.953)
				(xy 2.54 -4.953) (xy 2.54 -4.2926) (xy 3.81 -4.2926) (xy 3.81 -1.6256) (xy 2.1463 -1.6256) (xy 2.1463 -3.6449)
				(xy -2.1463 -3.6449) (xy -2.1463 3.6449) (xy 2.1463 3.6449) (xy 2.1463 -1.6129) (xy 3.81 -1.6129)
				(xy 3.81 4.2926) (xy 2.54 4.2926) (xy 2.54 4.953)
			)
			(stroke
				(width 0)
				(type default)
			)
			(fill no)
			(layer "F.CrtYd")
		)
		(fp_rect
			(start 2.54 4.2926)
			(end 3.81 -4.2926)
			(stroke
				(width 0)
				(type default)
			)
			(fill no)
			(layer "F.Fab")
		)
		(fp_rect
			(start -2.54 4.953)
			(end 2.54 -4.953)
			(stroke
				(width 0)
				(type default)
			)
			(fill no)
			(layer "F.Fab")
		)
		(fp_rect
			(start -3.81 4.2926)
			(end -2.54 -4.2926)
			(stroke
				(width 0)
				(type default)
			)
			(fill no)
			(layer "F.Fab")
		)
		(pad "1" smd rect
			(at 0 -3.1496 180)
			(size 2.413 2.286)
			(layers "F.Cu" "F.Mask" "F.Paste")
			(net "P3V3_PWR")
		)
		(pad "2" smd rect
			(at 0 3.1496 180)
			(size 2.413 2.286)
			(layers "F.Cu" "F.Mask" "F.Paste")
			(net "GND")
		)
		(zone
			(layer "F.Cu")
			(hatch none 0.5)
			(connect_pads
				(clearance 0)
			)
			(min_thickness 0.25)
			(keepout
				(tracks allowed)
				(vias not_allowed)
				(pads allowed)
				(copperpour not_allowed)
				(footprints allowed)
			)
			(placement
				(enabled no)
				(sheetname "")
			)
			(fill
				(thermal_gap 0.5)
				(thermal_bridge_width 0.5)
				(island_removal_mode 0)
			)
			(polygon
				(pts
					(xy 79.8957 -43.3959) (xy 79.8957 -40.4876) (xy 82.9183 -40.4876) (xy 82.9183 -43.3832) (xy 82.9183 -43.7134)
					(xy 79.8957 -43.7134)
				)
			)
		)
		(zone
			(layer "F.Cu")
			(hatch none 0.5)
			(connect_pads
				(clearance 0)
			)
			(min_thickness 0.25)
			(keepout
				(tracks allowed)
				(vias not_allowed)
				(pads allowed)
				(copperpour not_allowed)
				(footprints allowed)
			)
			(placement
				(enabled no)
				(sheetname "")
			)
			(fill
				(thermal_gap 0.5)
				(thermal_bridge_width 0.5)
				(island_removal_mode 0)
			)
			(polygon
				(pts
					(xy 82.9183 -49.6824) (xy 79.8957 -49.6824) (xy 79.8957 -46.7868) (xy 79.8957 -46.4566) (xy 82.9183 -46.4566)
					(xy 82.9183 -46.7868)
				)
			)
		)
	)
	(footprint ""
		(layer "F.Cu")
		(at 153.254202 -56.542432)
		(property "Reference" "PSP3"
			(at 0 0 0)
			(layer "F.SilkS")
			(hide yes)
			(effects
				(font
					(size 1.27 1.27)
				)
			)
		)
		(property "Value" "COPPER-CLOSE-GP-U"
			(at 0.0762 -2.8702 0)
			(unlocked yes)
			(layer "F.Fab")
			(hide yes)
			(effects
				(font
					(size 1.016 1.016)
					(thickness 0.1524)
				)
			)
		)
		(property "Device Type" "CON2C-U"
			(at 0.0762 -4.3942 0)
			(unlocked yes)
			(layer "F.Fab")
			(hide yes)
			(effects
				(font
					(size 1.016 1.016)
					(thickness 0.1524)
				)
			)
		)
		(duplicate_pad_numbers_are_jumpers no)
		(fp_rect
			(start -0.9398 0.9652)
			(end 0.9398 -0.9652)
			(stroke
				(width 0)
				(type default)
			)
			(fill no)
			(layer "F.CrtYd")
		)
		(fp_rect
			(start -0.9398 0.9652)
			(end 0.9398 -0.9652)
			(stroke
				(width 0)
				(type default)
			)
			(fill no)
			(layer "F.Fab")
		)
		(pad "1" smd custom
			(at 0 -0.5334)
			(size 0.17145 0.17145)
			(layers "F.Cu" "F.Mask" "F.Paste")
			(net "GND")
			(options
				(clearance outline)
				(anchor circle)
			)
			(primitives
				(gr_poly
					(pts
						(xy -0.127 0.3429) (xy -0.127 0.1651) (xy -0.635 -0.3429) (xy 0.635 -0.3429) (xy 0.127 0.1651)
						(xy 0.127 0.3429)
					)
					(width 0)
					(fill yes)
				)
			)
		)
		(pad "2" smd custom
			(at 0 0.5334)
			(size 0.17145 0.17145)
			(layers "F.Cu" "F.Mask" "F.Paste")
			(net "AGND_P0V9")
			(options
				(clearance outline)
				(anchor circle)
			)
			(primitives
				(gr_poly
					(pts
						(xy -0.635 0.3429) (xy -0.127 -0.1651) (xy -0.127 -0.3429) (xy 0.127 -0.3429) (xy 0.127 -0.1651)
						(xy 0.635 0.3429)
					)
					(width 0)
					(fill yes)
				)
			)
		)
	)
	(footprint ""
		(layer "F.Cu")
		(at 72.0852 -163.5506 -90)
		(property "Reference" "PR17"
			(at 0 0 270)
			(layer "F.SilkS")
			(hide yes)
			(effects
				(font
					(size 1.27 1.27)
				)
			)
		)
		(property "Value" "0R2J-2-GP"
			(at 0.064008 -3.993896 270)
			(unlocked yes)
			(layer "F.Fab")
			(hide yes)
			(effects
				(font
					(size 1.016 1.016)
					(thickness 0.1524)
				)
			)
		)
		(property "Device Type" "R402H16"
			(at 0.064008 -5.517896 270)
			(unlocked yes)
			(layer "F.Fab")
			(hide yes)
			(effects
				(font
					(size 1.016 1.016)
					(thickness 0.1524)
				)
			)
		)
		(duplicate_pad_numbers_are_jumpers no)
		(fp_line
			(start -0.508 -0.9398)
			(end -0.508 0.9398)
			(stroke
				(width 0.1524)
				(type default)
			)
			(layer "F.SilkS")
		)
		(fp_line
			(start 0.508 -0.9398)
			(end -0.508 -0.9398)
			(stroke
				(width 0.1524)
				(type default)
			)
			(layer "F.SilkS")
		)
		(fp_rect
			(start -0.508 0.9398)
			(end 0.508 -0.9398)
			(stroke
				(width 0)
				(type default)
			)
			(fill no)
			(layer "F.CrtYd")
		)
		(fp_rect
			(start -0.508 0.9398)
			(end 0.508 -0.9398)
			(stroke
				(width 0)
				(type default)
			)
			(fill no)
			(layer "F.Fab")
		)
		(pad "1" smd custom
			(at 0 -0.4445 270)
			(size 0.1397 0.1397)
			(layers "F.Cu" "F.Mask" "F.Paste")
			(net "P5V_STBY")
			(options
				(clearance outline)
				(anchor circle)
			)
			(primitives
				(gr_poly
					(pts
						(arc
							(start -0.1778 -0.2794)
							(mid -0.249642 -0.249642)
							(end -0.2794 -0.1778)
						)
						(arc
							(start -0.2794 0.1778)
							(mid -0.249642 0.249642)
							(end -0.1778 0.2794)
						)
						(arc
							(start 0.1778 0.2794)
							(mid 0.249642 0.249642)
							(end 0.2794 0.1778)
						)
						(arc
							(start 0.2794 -0.1778)
							(mid 0.249642 -0.249642)
							(end 0.1778 -0.2794)
						)
					)
					(width 0)
					(fill yes)
				)
			)
		)
		(pad "2" smd custom
			(at 0 0.4445 270)
			(size 0.1397 0.1397)
			(layers "F.Cu" "F.Mask" "F.Paste")
			(net "VR_P1V538_STBY_BIAS")
			(options
				(clearance outline)
				(anchor circle)
			)
			(primitives
				(gr_poly
					(pts
						(arc
							(start -0.1778 -0.2794)
							(mid -0.249642 -0.249642)
							(end -0.2794 -0.1778)
						)
						(arc
							(start -0.2794 0.1778)
							(mid -0.249642 0.249642)
							(end -0.1778 0.2794)
						)
						(arc
							(start 0.1778 0.2794)
							(mid 0.249642 0.249642)
							(end 0.2794 0.1778)
						)
						(arc
							(start 0.2794 -0.1778)
							(mid 0.249642 -0.249642)
							(end 0.1778 -0.2794)
						)
					)
					(width 0)
					(fill yes)
				)
			)
		)
	)
	(footprint ""
		(layer "F.Cu")
		(at 126.721362 -42.390568 180)
		(property "Reference" "R622"
			(at 0 0 180)
			(layer "F.SilkS")
			(hide yes)
			(effects
				(font
					(size 1.27 1.27)
				)
			)
		)
		(property "Value" "0R2J-2-GP"
			(at 0.064008 -3.993896 180)
			(unlocked yes)
			(layer "F.Fab")
			(hide yes)
			(effects
				(font
					(size 1.016 1.016)
					(thickness 0.1524)
				)
			)
		)
		(property "Device Type" "R402H16"
			(at 0.064008 -5.517896 180)
			(unlocked yes)
			(layer "F.Fab")
			(hide yes)
			(effects
				(font
					(size 1.016 1.016)
					(thickness 0.1524)
				)
			)
		)
		(duplicate_pad_numbers_are_jumpers no)
		(fp_line
			(start 0.508 -0.9398)
			(end -0.508 -0.9398)
			(stroke
				(width 0.1524)
				(type default)
			)
			(layer "F.SilkS")
		)
		(fp_line
			(start -0.508 -0.9398)
			(end -0.508 0.9398)
			(stroke
				(width 0.1524)
				(type default)
			)
			(layer "F.SilkS")
		)
		(fp_rect
			(start -0.508 0.9398)
			(end 0.508 -0.9398)
			(stroke
				(width 0)
				(type default)
			)
			(fill no)
			(layer "F.CrtYd")
		)
		(fp_rect
			(start -0.508 0.9398)
			(end 0.508 -0.9398)
			(stroke
				(width 0)
				(type default)
			)
			(fill no)
			(layer "F.Fab")
		)
		(pad "1" smd custom
			(at 0 -0.4445 180)
			(size 0.1397 0.1397)
			(layers "F.Cu" "F.Mask" "F.Paste")
			(net "UPLINK3_R")
			(options
				(clearance outline)
				(anchor circle)
			)
			(primitives
				(gr_poly
					(pts
						(arc
							(start -0.1778 -0.2794)
							(mid -0.249642 -0.249642)
							(end -0.2794 -0.1778)
						)
						(arc
							(start -0.2794 0.1778)
							(mid -0.249642 0.249642)
							(end -0.1778 0.2794)
						)
						(arc
							(start 0.1778 0.2794)
							(mid 0.249642 0.249642)
							(end 0.2794 0.1778)
						)
						(arc
							(start 0.2794 -0.1778)
							(mid 0.249642 -0.249642)
							(end 0.1778 -0.2794)
						)
					)
					(width 0)
					(fill yes)
				)
			)
		)
		(pad "2" smd custom
			(at 0 0.4445 180)
			(size 0.1397 0.1397)
			(layers "F.Cu" "F.Mask" "F.Paste")
			(net "UPLINK3")
			(options
				(clearance outline)
				(anchor circle)
			)
			(primitives
				(gr_poly
					(pts
						(arc
							(start -0.1778 -0.2794)
							(mid -0.249642 -0.249642)
							(end -0.2794 -0.1778)
						)
						(arc
							(start -0.2794 0.1778)
							(mid -0.249642 0.249642)
							(end -0.1778 0.2794)
						)
						(arc
							(start 0.1778 0.2794)
							(mid 0.249642 0.249642)
							(end 0.2794 0.1778)
						)
						(arc
							(start 0.2794 -0.1778)
							(mid 0.249642 -0.249642)
							(end 0.1778 -0.2794)
						)
					)
					(width 0)
					(fill yes)
				)
			)
		)
	)
	(footprint ""
		(layer "F.Cu")
		(at 20.955 -138.7602 -90)
		(property "Reference" "R645"
			(at 0 0 270)
			(layer "F.SilkS")
			(hide yes)
			(effects
				(font
					(size 1.27 1.27)
				)
			)
		)
		(property "Value" "0R2J-2-GP"
			(at 0.064008 -3.993896 270)
			(unlocked yes)
			(layer "F.Fab")
			(hide yes)
			(effects
				(font
					(size 1.016 1.016)
					(thickness 0.1524)
				)
			)
		)
		(property "Device Type" "R402H16"
			(at 0.064008 -5.517896 270)
			(unlocked yes)
			(layer "F.Fab")
			(hide yes)
			(effects
				(font
					(size 1.016 1.016)
					(thickness 0.1524)
				)
			)
		)
		(duplicate_pad_numbers_are_jumpers no)
		(fp_line
			(start -0.508 -0.9398)
			(end -0.508 0.9398)
			(stroke
				(width 0.1524)
				(type default)
			)
			(layer "F.SilkS")
		)
		(fp_line
			(start 0.508 -0.9398)
			(end -0.508 -0.9398)
			(stroke
				(width 0.1524)
				(type default)
			)
			(layer "F.SilkS")
		)
		(fp_rect
			(start -0.508 0.9398)
			(end 0.508 -0.9398)
			(stroke
				(width 0)
				(type default)
			)
			(fill no)
			(layer "F.CrtYd")
		)
		(fp_rect
			(start -0.508 0.9398)
			(end 0.508 -0.9398)
			(stroke
				(width 0)
				(type default)
			)
			(fill no)
			(layer "F.Fab")
		)
		(pad "1" smd custom
			(at 0 -0.4445 270)
			(size 0.1397 0.1397)
			(layers "F.Cu" "F.Mask" "F.Paste")
			(net "GPIOR2_R")
			(options
				(clearance outline)
				(anchor circle)
			)
			(primitives
				(gr_poly
					(pts
						(arc
							(start -0.1778 -0.2794)
							(mid -0.249642 -0.249642)
							(end -0.2794 -0.1778)
						)
						(arc
							(start -0.2794 0.1778)
							(mid -0.249642 0.249642)
							(end -0.1778 0.2794)
						)
						(arc
							(start 0.1778 0.2794)
							(mid 0.249642 0.249642)
							(end 0.2794 0.1778)
						)
						(arc
							(start 0.2794 -0.1778)
							(mid 0.249642 -0.249642)
							(end 0.1778 -0.2794)
						)
					)
					(width 0)
					(fill yes)
				)
			)
		)
		(pad "2" smd custom
			(at 0 0.4445 270)
			(size 0.1397 0.1397)
			(layers "F.Cu" "F.Mask" "F.Paste")
			(net "TRAY_ID2")
			(options
				(clearance outline)
				(anchor circle)
			)
			(primitives
				(gr_poly
					(pts
						(arc
							(start -0.1778 -0.2794)
							(mid -0.249642 -0.249642)
							(end -0.2794 -0.1778)
						)
						(arc
							(start -0.2794 0.1778)
							(mid -0.249642 0.249642)
							(end -0.1778 0.2794)
						)
						(arc
							(start 0.1778 0.2794)
							(mid 0.249642 0.249642)
							(end 0.2794 0.1778)
						)
						(arc
							(start 0.2794 -0.1778)
							(mid 0.249642 -0.249642)
							(end 0.1778 -0.2794)
						)
					)
					(width 0)
					(fill yes)
				)
			)
		)
	)
	(footprint ""
		(layer "F.Cu")
		(at 22.733 -160.528 180)
		(property "Reference" "U35"
			(at 0 0 180)
			(layer "F.SilkS")
			(hide yes)
			(effects
				(font
					(size 1.27 1.27)
				)
			)
		)
		(property "Value" "SN74LVC1G07DCKRG4-2-GP"
			(at -2.3368 -8.6868 180)
			(unlocked yes)
			(layer "F.Fab")
			(hide yes)
			(effects
				(font
					(size 1.016 1.016)
					(thickness 0.1524)
				)
			)
		)
		(property "Device Type" "SC70-5H44"
			(at -2.3114 -10.414 180)
			(unlocked yes)
			(layer "F.Fab")
			(hide yes)
			(effects
				(font
					(size 1.016 1.016)
					(thickness 0.1524)
				)
			)
		)
		(duplicate_pad_numbers_are_jumpers no)
		(fp_line
			(start 1.3843 -1.8034)
			(end 1.3843 -1.1176)
			(stroke
				(width 0.3302)
				(type default)
			)
			(layer "F.SilkS")
		)
		(fp_line
			(start 1.27 1.7018)
			(end -1.27 1.7018)
			(stroke
				(width 0.1524)
				(type default)
			)
			(layer "F.SilkS")
		)
		(fp_line
			(start 1.27 -1.7018)
			(end 1.27 1.7018)
			(stroke
				(width 0.1524)
				(type default)
			)
			(layer "F.SilkS")
		)
		(fp_line
			(start 0.6604 -1.8034)
			(end 1.3843 -1.8034)
			(stroke
				(width 0.3302)
				(type default)
			)
			(layer "F.SilkS")
		)
		(fp_line
			(start -1.27 1.7018)
			(end -1.27 -1.7018)
			(stroke
				(width 0.1524)
				(type default)
			)
			(layer "F.SilkS")
		)
		(fp_line
			(start -1.27 -1.7018)
			(end 1.27 -1.7018)
			(stroke
				(width 0.1524)
				(type default)
			)
			(layer "F.SilkS")
		)
		(fp_rect
			(start -1.524 1.9558)
			(end 1.524 -1.9558)
			(stroke
				(width 0)
				(type default)
			)
			(fill no)
			(layer "F.CrtYd")
		)
		(fp_poly
			(pts
				(xy -1.524 -1.9558) (xy 1.524 -1.9558) (xy 1.524 1.9558) (xy -1.524 1.9558)
			)
			(stroke
				(width 0)
				(type default)
			)
			(fill no)
			(layer "F.Fab")
		)
		(pad "1" smd rect
			(at 0.65024 -0.8255 180)
			(size 0.4064 1.2192)
			(layers "F.Cu" "F.Mask" "F.Paste")
			(net "Net_516")
		)
		(pad "2" smd rect
			(at 0 -0.8255 180)
			(size 0.4064 1.2192)
			(layers "F.Cu" "F.Mask" "F.Paste")
			(net "BMC_RESET#_DDR3")
		)
		(pad "3" smd rect
			(at -0.65024 -0.8255 180)
			(size 0.4064 1.2192)
			(layers "F.Cu" "F.Mask" "F.Paste")
			(net "GND")
		)
		(pad "4" smd rect
			(at -0.65024 0.8255 180)
			(size 0.4064 1.2192)
			(layers "F.Cu" "F.Mask" "F.Paste")
			(net "BMC_RESET#_DDR3_BUF")
		)
		(pad "5" smd rect
			(at 0.65024 0.8255 180)
			(size 0.4064 1.2192)
			(layers "F.Cu" "F.Mask" "F.Paste")
			(net "P3V3_STBY")
		)
	)
	(footprint ""
		(layer "F.Cu")
		(at 43.457876 -61.204094 180)
		(property "Reference" "R635"
			(at 0 0 180)
			(layer "F.SilkS")
			(hide yes)
			(effects
				(font
					(size 1.27 1.27)
				)
			)
		)
		(property "Value" "0R3J-0-U-GP"
			(at -0.0254 -2.5146 180)
			(unlocked yes)
			(layer "F.Fab")
			(hide yes)
			(effects
				(font
					(size 1.016 1.016)
					(thickness 0.1524)
				)
			)
		)
		(property "Device Type" "R603H22"
			(at -0.0254 -4.0386 180)
			(unlocked yes)
			(layer "F.Fab")
			(hide yes)
			(effects
				(font
					(size 1.016 1.016)
					(thickness 0.1524)
				)
			)
		)
		(duplicate_pad_numbers_are_jumpers no)
		(fp_line
			(start 0.2032 0)
			(end 0.4826 0)
			(stroke
				(width 0.2032)
				(type default)
			)
			(layer "F.SilkS")
		)
		(fp_line
			(start -0.4826 0)
			(end -0.2032 0)
			(stroke
				(width 0.2032)
				(type default)
			)
			(layer "F.SilkS")
		)
		(fp_rect
			(start -0.5842 1.3335)
			(end 0.5842 -1.3335)
			(stroke
				(width 0)
				(type default)
			)
			(fill no)
			(layer "F.CrtYd")
		)
		(fp_rect
			(start -0.5842 1.3335)
			(end 0.5842 -1.3335)
			(stroke
				(width 0)
				(type default)
			)
			(fill no)
			(layer "F.Fab")
		)
		(pad "1" smd custom
			(at 0 -0.762 180)
			(size 0.2159 0.2159)
			(layers "F.Cu" "F.Mask" "F.Paste")
			(net "USB5V_EN")
			(options
				(clearance outline)
				(anchor circle)
			)
			(primitives
				(gr_poly
					(pts
						(arc
							(start -0.3302 -0.4318)
							(mid -0.402042 -0.402042)
							(end -0.4318 -0.3302)
						)
						(arc
							(start -0.4318 0.3302)
							(mid -0.402042 0.402042)
							(end -0.3302 0.4318)
						)
						(arc
							(start 0.3302 0.4318)
							(mid 0.402042 0.402042)
							(end 0.4318 0.3302)
						)
						(arc
							(start 0.4318 -0.3302)
							(mid 0.402042 -0.402042)
							(end 0.3302 -0.4318)
						)
					)
					(width 0)
					(fill yes)
				)
			)
		)
		(pad "2" smd custom
			(at 0 0.762 180)
			(size 0.2159 0.2159)
			(layers "F.Cu" "F.Mask" "F.Paste")
			(net "BMC_USB_EN_1")
			(options
				(clearance outline)
				(anchor circle)
			)
			(primitives
				(gr_poly
					(pts
						(arc
							(start -0.3302 -0.4318)
							(mid -0.402042 -0.402042)
							(end -0.4318 -0.3302)
						)
						(arc
							(start -0.4318 0.3302)
							(mid -0.402042 0.402042)
							(end -0.3302 0.4318)
						)
						(arc
							(start 0.3302 0.4318)
							(mid 0.402042 0.402042)
							(end 0.4318 0.3302)
						)
						(arc
							(start 0.4318 -0.3302)
							(mid 0.402042 -0.402042)
							(end 0.3302 -0.4318)
						)
					)
					(width 0)
					(fill yes)
				)
			)
		)
	)
	(footprint ""
		(layer "F.Cu")
		(at 159.807402 -54.231032 90)
		(property "Reference" "R79"
			(at 0 0 90)
			(layer "F.SilkS")
			(hide yes)
			(effects
				(font
					(size 1.27 1.27)
				)
			)
		)
		(property "Value" "0R2J-2-GP"
			(at 0.064008 -3.993896 90)
			(unlocked yes)
			(layer "F.Fab")
			(hide yes)
			(effects
				(font
					(size 1.016 1.016)
					(thickness 0.1524)
				)
			)
		)
		(property "Device Type" "R402H16"
			(at 0.064008 -5.517896 90)
			(unlocked yes)
			(layer "F.Fab")
			(hide yes)
			(effects
				(font
					(size 1.016 1.016)
					(thickness 0.1524)
				)
			)
		)
		(duplicate_pad_numbers_are_jumpers no)
		(fp_line
			(start 0.508 -0.9398)
			(end -0.508 -0.9398)
			(stroke
				(width 0.1524)
				(type default)
			)
			(layer "F.SilkS")
		)
		(fp_line
			(start -0.508 -0.9398)
			(end -0.508 0.9398)
			(stroke
				(width 0.1524)
				(type default)
			)
			(layer "F.SilkS")
		)
		(fp_rect
			(start -0.508 0.9398)
			(end 0.508 -0.9398)
			(stroke
				(width 0)
				(type default)
			)
			(fill no)
			(layer "F.CrtYd")
		)
		(fp_rect
			(start -0.508 0.9398)
			(end 0.508 -0.9398)
			(stroke
				(width 0)
				(type default)
			)
			(fill no)
			(layer "F.Fab")
		)
		(pad "1" smd custom
			(at 0 -0.4445 90)
			(size 0.1397 0.1397)
			(layers "F.Cu" "F.Mask" "F.Paste")
			(net "P0V9_VFB_R")
			(options
				(clearance outline)
				(anchor circle)
			)
			(primitives
				(gr_poly
					(pts
						(arc
							(start -0.1778 -0.2794)
							(mid -0.249642 -0.249642)
							(end -0.2794 -0.1778)
						)
						(arc
							(start -0.2794 0.1778)
							(mid -0.249642 0.249642)
							(end -0.1778 0.2794)
						)
						(arc
							(start 0.1778 0.2794)
							(mid 0.249642 0.249642)
							(end 0.2794 0.1778)
						)
						(arc
							(start 0.2794 -0.1778)
							(mid 0.249642 -0.249642)
							(end 0.1778 -0.2794)
						)
					)
					(width 0)
					(fill yes)
				)
			)
		)
		(pad "2" smd custom
			(at 0 0.4445 90)
			(size 0.1397 0.1397)
			(layers "F.Cu" "F.Mask" "F.Paste")
			(net "DUT_AVD_TX")
			(options
				(clearance outline)
				(anchor circle)
			)
			(primitives
				(gr_poly
					(pts
						(arc
							(start -0.1778 -0.2794)
							(mid -0.249642 -0.249642)
							(end -0.2794 -0.1778)
						)
						(arc
							(start -0.2794 0.1778)
							(mid -0.249642 0.249642)
							(end -0.1778 0.2794)
						)
						(arc
							(start 0.1778 0.2794)
							(mid 0.249642 0.249642)
							(end 0.2794 0.1778)
						)
						(arc
							(start 0.2794 -0.1778)
							(mid 0.249642 -0.249642)
							(end 0.1778 -0.2794)
						)
					)
					(width 0)
					(fill yes)
				)
			)
		)
	)
	(footprint ""
		(layer "F.Cu")
		(at 90.2208 -83.947)
		(property "Reference" "SR842"
			(at 0 0 0)
			(layer "F.SilkS")
			(hide yes)
			(effects
				(font
					(size 1.27 1.27)
				)
			)
		)
		(property "Value" "10KR2F-2-GP"
			(at 0.064008 -3.993896 0)
			(unlocked yes)
			(layer "F.Fab")
			(hide yes)
			(effects
				(font
					(size 1.016 1.016)
					(thickness 0.1524)
				)
			)
		)
		(property "Device Type" "R402H16"
			(at 0.064008 -5.517896 0)
			(unlocked yes)
			(layer "F.Fab")
			(hide yes)
			(effects
				(font
					(size 1.016 1.016)
					(thickness 0.1524)
				)
			)
		)
		(duplicate_pad_numbers_are_jumpers no)
		(fp_line
			(start -0.508 -0.9398)
			(end -0.508 0.9398)
			(stroke
				(width 0.1524)
				(type default)
			)
			(layer "F.SilkS")
		)
		(fp_line
			(start 0.508 -0.9398)
			(end -0.508 -0.9398)
			(stroke
				(width 0.1524)
				(type default)
			)
			(layer "F.SilkS")
		)
		(fp_rect
			(start -0.508 0.9398)
			(end 0.508 -0.9398)
			(stroke
				(width 0)
				(type default)
			)
			(fill no)
			(layer "F.CrtYd")
		)
		(fp_rect
			(start -0.508 0.9398)
			(end 0.508 -0.9398)
			(stroke
				(width 0)
				(type default)
			)
			(fill no)
			(layer "F.Fab")
		)
		(pad "1" smd custom
			(at 0 -0.4445)
			(size 0.1397 0.1397)
			(layers "F.Cu" "F.Mask" "F.Paste")
			(net "P1V8_STBY")
			(options
				(clearance outline)
				(anchor circle)
			)
			(primitives
				(gr_poly
					(pts
						(arc
							(start -0.1778 -0.2794)
							(mid -0.249642 -0.249642)
							(end -0.2794 -0.1778)
						)
						(arc
							(start -0.2794 0.1778)
							(mid -0.249642 0.249642)
							(end -0.1778 0.2794)
						)
						(arc
							(start 0.1778 0.2794)
							(mid 0.249642 0.249642)
							(end 0.2794 0.1778)
						)
						(arc
							(start 0.2794 -0.1778)
							(mid 0.249642 -0.249642)
							(end 0.1778 -0.2794)
						)
					)
					(width 0)
					(fill yes)
				)
			)
		)
		(pad "2" smd custom
			(at 0 0.4445)
			(size 0.1397 0.1397)
			(layers "F.Cu" "F.Mask" "F.Paste")
			(net "SMART_UART_EN")
			(options
				(clearance outline)
				(anchor circle)
			)
			(primitives
				(gr_poly
					(pts
						(arc
							(start -0.1778 -0.2794)
							(mid -0.249642 -0.249642)
							(end -0.2794 -0.1778)
						)
						(arc
							(start -0.2794 0.1778)
							(mid -0.249642 0.249642)
							(end -0.1778 0.2794)
						)
						(arc
							(start 0.1778 0.2794)
							(mid 0.249642 0.249642)
							(end 0.2794 0.1778)
						)
						(arc
							(start 0.2794 -0.1778)
							(mid 0.249642 -0.249642)
							(end 0.1778 -0.2794)
						)
					)
					(width 0)
					(fill yes)
				)
			)
		)
	)
	(footprint ""
		(layer "F.Cu")
		(at 88.9 -42.2148)
		(property "Reference" "PG5"
			(at 0 0 0)
			(layer "F.SilkS")
			(hide yes)
			(effects
				(font
					(size 1.27 1.27)
				)
			)
		)
		(property "Value" "GAP-CLOSE-PWR-3-GP"
			(at 0.0254 -6.5786 0)
			(unlocked yes)
			(layer "F.Fab")
			(hide yes)
			(effects
				(font
					(size 1.016 1.016)
					(thickness 0.1524)
				)
			)
		)
		(property "Device Type" "GAP-CLOSE-PWR-3"
			(at 0.0254 -8.255 0)
			(unlocked yes)
			(layer "F.Fab")
			(hide yes)
			(effects
				(font
					(size 1.016 1.016)
					(thickness 0.1524)
				)
			)
		)
		(duplicate_pad_numbers_are_jumpers no)
		(fp_rect
			(start -0.7112 0.4572)
			(end 0.7112 -0.4572)
			(stroke
				(width 0)
				(type default)
			)
			(fill no)
			(layer "F.CrtYd")
		)
		(fp_poly
			(pts
				(xy -0.7112 -0.4572) (xy 0.7112 -0.4572) (xy 0.7112 0.4572) (xy -0.7112 0.4572)
			)
			(stroke
				(width 0)
				(type default)
			)
			(fill no)
			(layer "F.Fab")
		)
		(pad "1" smd rect
			(at -0.3048 0)
			(size 0.6604 0.762)
			(layers "F.Cu" "F.Mask" "F.Paste")
			(net "P3V3_PWR")
		)
		(pad "2" smd rect
			(at 0.3048 0)
			(size 0.6604 0.762)
			(layers "F.Cu" "F.Mask" "F.Paste")
			(net "P3V3_STBY")
		)
	)
	(footprint ""
		(layer "F.Cu")
		(at 24.715978 -71.521828 90)
		(property "Reference" "R379"
			(at 0 0 90)
			(layer "F.SilkS")
			(hide yes)
			(effects
				(font
					(size 1.27 1.27)
				)
			)
		)
		(property "Value" "33R2J-2-GP"
			(at 0.064008 -3.993896 90)
			(unlocked yes)
			(layer "F.Fab")
			(hide yes)
			(effects
				(font
					(size 1.016 1.016)
					(thickness 0.1524)
				)
			)
		)
		(property "Device Type" "R402H16"
			(at 0.064008 -5.517896 90)
			(unlocked yes)
			(layer "F.Fab")
			(hide yes)
			(effects
				(font
					(size 1.016 1.016)
					(thickness 0.1524)
				)
			)
		)
		(duplicate_pad_numbers_are_jumpers no)
		(fp_line
			(start 0.508 -0.9398)
			(end -0.508 -0.9398)
			(stroke
				(width 0.1524)
				(type default)
			)
			(layer "F.SilkS")
		)
		(fp_line
			(start -0.508 -0.9398)
			(end -0.508 0.9398)
			(stroke
				(width 0.1524)
				(type default)
			)
			(layer "F.SilkS")
		)
		(fp_rect
			(start -0.508 0.9398)
			(end 0.508 -0.9398)
			(stroke
				(width 0)
				(type default)
			)
			(fill no)
			(layer "F.CrtYd")
		)
		(fp_rect
			(start -0.508 0.9398)
			(end 0.508 -0.9398)
			(stroke
				(width 0)
				(type default)
			)
			(fill no)
			(layer "F.Fab")
		)
		(pad "1" smd custom
			(at 0 -0.4445 90)
			(size 0.1397 0.1397)
			(layers "F.Cu" "F.Mask" "F.Paste")
			(net "CLK_50M_RMII_PHY_IN")
			(options
				(clearance outline)
				(anchor circle)
			)
			(primitives
				(gr_poly
					(pts
						(arc
							(start -0.1778 -0.2794)
							(mid -0.249642 -0.249642)
							(end -0.2794 -0.1778)
						)
						(arc
							(start -0.2794 0.1778)
							(mid -0.249642 0.249642)
							(end -0.1778 0.2794)
						)
						(arc
							(start 0.1778 0.2794)
							(mid 0.249642 0.249642)
							(end 0.2794 0.1778)
						)
						(arc
							(start 0.2794 -0.1778)
							(mid 0.249642 -0.249642)
							(end 0.1778 -0.2794)
						)
					)
					(width 0)
					(fill yes)
				)
			)
		)
		(pad "2" smd custom
			(at 0 0.4445 90)
			(size 0.1397 0.1397)
			(layers "F.Cu" "F.Mask" "F.Paste")
			(net "CLK_50M_RMII_PHY")
			(options
				(clearance outline)
				(anchor circle)
			)
			(primitives
				(gr_poly
					(pts
						(arc
							(start -0.1778 -0.2794)
							(mid -0.249642 -0.249642)
							(end -0.2794 -0.1778)
						)
						(arc
							(start -0.2794 0.1778)
							(mid -0.249642 0.249642)
							(end -0.1778 0.2794)
						)
						(arc
							(start 0.1778 0.2794)
							(mid 0.249642 0.249642)
							(end 0.2794 0.1778)
						)
						(arc
							(start 0.2794 -0.1778)
							(mid 0.249642 -0.249642)
							(end 0.1778 -0.2794)
						)
					)
					(width 0)
					(fill yes)
				)
			)
		)
	)
	(footprint ""
		(layer "F.Cu")
		(at 192.9384 -24.0538 90)
		(property "Reference" "R834"
			(at 0 0 90)
			(layer "F.SilkS")
			(hide yes)
			(effects
				(font
					(size 1.27 1.27)
				)
			)
		)
		(property "Value" "4K7R2F-GP"
			(at 0.064008 -3.993896 90)
			(unlocked yes)
			(layer "F.Fab")
			(hide yes)
			(effects
				(font
					(size 1.016 1.016)
					(thickness 0.1524)
				)
			)
		)
		(property "Device Type" "R402H16"
			(at 0.064008 -5.517896 90)
			(unlocked yes)
			(layer "F.Fab")
			(hide yes)
			(effects
				(font
					(size 1.016 1.016)
					(thickness 0.1524)
				)
			)
		)
		(duplicate_pad_numbers_are_jumpers no)
		(fp_line
			(start 0.508 -0.9398)
			(end -0.508 -0.9398)
			(stroke
				(width 0.1524)
				(type default)
			)
			(layer "F.SilkS")
		)
		(fp_line
			(start -0.508 -0.9398)
			(end -0.508 0.9398)
			(stroke
				(width 0.1524)
				(type default)
			)
			(layer "F.SilkS")
		)
		(fp_rect
			(start -0.508 0.9398)
			(end 0.508 -0.9398)
			(stroke
				(width 0)
				(type default)
			)
			(fill no)
			(layer "F.CrtYd")
		)
		(fp_rect
			(start -0.508 0.9398)
			(end 0.508 -0.9398)
			(stroke
				(width 0)
				(type default)
			)
			(fill no)
			(layer "F.Fab")
		)
		(pad "1" smd custom
			(at 0 -0.4445 90)
			(size 0.1397 0.1397)
			(layers "F.Cu" "F.Mask" "F.Paste")
			(net "GND")
			(options
				(clearance outline)
				(anchor circle)
			)
			(primitives
				(gr_poly
					(pts
						(arc
							(start -0.1778 -0.2794)
							(mid -0.249642 -0.249642)
							(end -0.2794 -0.1778)
						)
						(arc
							(start -0.2794 0.1778)
							(mid -0.249642 0.249642)
							(end -0.1778 0.2794)
						)
						(arc
							(start 0.1778 0.2794)
							(mid 0.249642 0.249642)
							(end 0.2794 0.1778)
						)
						(arc
							(start 0.2794 -0.1778)
							(mid 0.249642 -0.249642)
							(end 0.1778 -0.2794)
						)
					)
					(width 0)
					(fill yes)
				)
			)
		)
		(pad "2" smd custom
			(at 0 0.4445 90)
			(size 0.1397 0.1397)
			(layers "F.Cu" "F.Mask" "F.Paste")
			(net "U56_A2")
			(options
				(clearance outline)
				(anchor circle)
			)
			(primitives
				(gr_poly
					(pts
						(arc
							(start -0.1778 -0.2794)
							(mid -0.249642 -0.249642)
							(end -0.2794 -0.1778)
						)
						(arc
							(start -0.2794 0.1778)
							(mid -0.249642 0.249642)
							(end -0.1778 0.2794)
						)
						(arc
							(start 0.1778 0.2794)
							(mid 0.249642 0.249642)
							(end 0.2794 0.1778)
						)
						(arc
							(start 0.2794 -0.1778)
							(mid 0.249642 -0.249642)
							(end 0.1778 -0.2794)
						)
					)
					(width 0)
					(fill yes)
				)
			)
		)
	)
	(footprint ""
		(layer "F.Cu")
		(at 208.284572 -12.542266 180)
		(property "Reference" "R7892"
			(at 0 0 180)
			(layer "F.SilkS")
			(hide yes)
			(effects
				(font
					(size 1.27 1.27)
				)
			)
		)
		(property "Value" "0R2J-2-GP"
			(at 0.064008 -3.993896 180)
			(unlocked yes)
			(layer "F.Fab")
			(hide yes)
			(effects
				(font
					(size 1.016 1.016)
					(thickness 0.1524)
				)
			)
		)
		(property "Device Type" "R402H16"
			(at 0.064008 -5.517896 180)
			(unlocked yes)
			(layer "F.Fab")
			(hide yes)
			(effects
				(font
					(size 1.016 1.016)
					(thickness 0.1524)
				)
			)
		)
		(duplicate_pad_numbers_are_jumpers no)
		(fp_line
			(start 0.508 -0.9398)
			(end -0.508 -0.9398)
			(stroke
				(width 0.1524)
				(type default)
			)
			(layer "F.SilkS")
		)
		(fp_line
			(start -0.508 -0.9398)
			(end -0.508 0.9398)
			(stroke
				(width 0.1524)
				(type default)
			)
			(layer "F.SilkS")
		)
		(fp_rect
			(start -0.508 0.9398)
			(end 0.508 -0.9398)
			(stroke
				(width 0)
				(type default)
			)
			(fill no)
			(layer "F.CrtYd")
		)
		(fp_rect
			(start -0.508 0.9398)
			(end 0.508 -0.9398)
			(stroke
				(width 0)
				(type default)
			)
			(fill no)
			(layer "F.Fab")
		)
		(pad "1" smd custom
			(at 0 -0.4445 180)
			(size 0.1397 0.1397)
			(layers "F.Cu" "F.Mask" "F.Paste")
			(net "LED_DR_LED1")
			(options
				(clearance outline)
				(anchor circle)
			)
			(primitives
				(gr_poly
					(pts
						(arc
							(start -0.1778 -0.2794)
							(mid -0.249642 -0.249642)
							(end -0.2794 -0.1778)
						)
						(arc
							(start -0.2794 0.1778)
							(mid -0.249642 0.249642)
							(end -0.1778 0.2794)
						)
						(arc
							(start 0.1778 0.2794)
							(mid 0.249642 0.249642)
							(end 0.2794 0.1778)
						)
						(arc
							(start 0.2794 -0.1778)
							(mid 0.249642 -0.249642)
							(end 0.1778 -0.2794)
						)
					)
					(width 0)
					(fill yes)
				)
			)
		)
		(pad "2" smd custom
			(at 0 0.4445 180)
			(size 0.1397 0.1397)
			(layers "F.Cu" "F.Mask" "F.Paste")
			(net "BMC_ID_LED_R")
			(options
				(clearance outline)
				(anchor circle)
			)
			(primitives
				(gr_poly
					(pts
						(arc
							(start -0.1778 -0.2794)
							(mid -0.249642 -0.249642)
							(end -0.2794 -0.1778)
						)
						(arc
							(start -0.2794 0.1778)
							(mid -0.249642 0.249642)
							(end -0.1778 0.2794)
						)
						(arc
							(start 0.1778 0.2794)
							(mid 0.249642 0.249642)
							(end 0.2794 0.1778)
						)
						(arc
							(start 0.2794 -0.1778)
							(mid 0.249642 -0.249642)
							(end 0.1778 -0.2794)
						)
					)
					(width 0)
					(fill yes)
				)
			)
		)
	)
	(footprint ""
		(layer "F.Cu")
		(at 194.8688 -31.8262 90)
		(property "Reference" "R774"
			(at 0 0 90)
			(layer "F.SilkS")
			(hide yes)
			(effects
				(font
					(size 1.27 1.27)
				)
			)
		)
		(property "Value" "4K7R2F-GP"
			(at 0.064008 -3.993896 90)
			(unlocked yes)
			(layer "F.Fab")
			(hide yes)
			(effects
				(font
					(size 1.016 1.016)
					(thickness 0.1524)
				)
			)
		)
		(property "Device Type" "R402H16"
			(at 0.064008 -5.517896 90)
			(unlocked yes)
			(layer "F.Fab")
			(hide yes)
			(effects
				(font
					(size 1.016 1.016)
					(thickness 0.1524)
				)
			)
		)
		(duplicate_pad_numbers_are_jumpers no)
		(fp_line
			(start 0.508 -0.9398)
			(end -0.508 -0.9398)
			(stroke
				(width 0.1524)
				(type default)
			)
			(layer "F.SilkS")
		)
		(fp_line
			(start -0.508 -0.9398)
			(end -0.508 0.9398)
			(stroke
				(width 0.1524)
				(type default)
			)
			(layer "F.SilkS")
		)
		(fp_rect
			(start -0.508 0.9398)
			(end 0.508 -0.9398)
			(stroke
				(width 0)
				(type default)
			)
			(fill no)
			(layer "F.CrtYd")
		)
		(fp_rect
			(start -0.508 0.9398)
			(end 0.508 -0.9398)
			(stroke
				(width 0)
				(type default)
			)
			(fill no)
			(layer "F.Fab")
		)
		(pad "1" smd custom
			(at 0 -0.4445 90)
			(size 0.1397 0.1397)
			(layers "F.Cu" "F.Mask" "F.Paste")
			(net "GND")
			(options
				(clearance outline)
				(anchor circle)
			)
			(primitives
				(gr_poly
					(pts
						(arc
							(start -0.1778 -0.2794)
							(mid -0.249642 -0.249642)
							(end -0.2794 -0.1778)
						)
						(arc
							(start -0.2794 0.1778)
							(mid -0.249642 0.249642)
							(end -0.1778 0.2794)
						)
						(arc
							(start 0.1778 0.2794)
							(mid 0.249642 0.249642)
							(end 0.2794 0.1778)
						)
						(arc
							(start 0.2794 -0.1778)
							(mid 0.249642 -0.249642)
							(end 0.1778 -0.2794)
						)
					)
					(width 0)
					(fill yes)
				)
			)
		)
		(pad "2" smd custom
			(at 0 0.4445 90)
			(size 0.1397 0.1397)
			(layers "F.Cu" "F.Mask" "F.Paste")
			(net "U55_A2")
			(options
				(clearance outline)
				(anchor circle)
			)
			(primitives
				(gr_poly
					(pts
						(arc
							(start -0.1778 -0.2794)
							(mid -0.249642 -0.249642)
							(end -0.2794 -0.1778)
						)
						(arc
							(start -0.2794 0.1778)
							(mid -0.249642 0.249642)
							(end -0.1778 0.2794)
						)
						(arc
							(start 0.1778 0.2794)
							(mid 0.249642 0.249642)
							(end 0.2794 0.1778)
						)
						(arc
							(start 0.2794 -0.1778)
							(mid 0.249642 -0.249642)
							(end 0.1778 -0.2794)
						)
					)
					(width 0)
					(fill yes)
				)
			)
		)
	)
	(footprint ""
		(layer "F.Cu")
		(at 34.5186 -67.1322 -90)
		(property "Reference" "C332"
			(at 0 0 270)
			(layer "F.SilkS")
			(hide yes)
			(effects
				(font
					(size 1.27 1.27)
				)
			)
		)
		(property "Value" "SCD1U16V2JX-1-GP"
			(at 1.1811 -2.7051 270)
			(unlocked yes)
			(layer "F.Fab")
			(hide yes)
			(effects
				(font
					(size 1.016 1.016)
					(thickness 0.1524)
				)
			)
		)
		(property "Device Type" "C402H22"
			(at 1.1811 -4.2291 270)
			(unlocked yes)
			(layer "F.Fab")
			(hide yes)
			(effects
				(font
					(size 1.016 1.016)
					(thickness 0.1524)
				)
			)
		)
		(duplicate_pad_numbers_are_jumpers no)
		(fp_rect
			(start -0.4318 0.9525)
			(end 0.4318 -0.9525)
			(stroke
				(width 0)
				(type default)
			)
			(fill no)
			(layer "F.CrtYd")
		)
		(fp_rect
			(start -0.4318 0.9525)
			(end 0.4318 -0.9525)
			(stroke
				(width 0)
				(type default)
			)
			(fill no)
			(layer "F.Fab")
		)
		(pad "1" smd custom
			(at 0 -0.4445 270)
			(size 0.1524 0.1524)
			(layers "F.Cu" "F.Mask" "F.Paste")
			(net "P5V_USB_BP1_F")
			(options
				(clearance outline)
				(anchor circle)
			)
			(primitives
				(gr_poly
					(pts
						(arc
							(start 0.3048 -0.2032)
							(mid 0.275042 -0.275042)
							(end 0.2032 -0.3048)
						)
						(arc
							(start -0.2032 -0.3048)
							(mid -0.275042 -0.275042)
							(end -0.3048 -0.2032)
						)
						(arc
							(start -0.3048 0.2032)
							(mid -0.275042 0.275042)
							(end -0.2032 0.3048)
						)
						(arc
							(start 0.2032 0.3048)
							(mid 0.275042 0.275042)
							(end 0.3048 0.2032)
						)
					)
					(width 0)
					(fill yes)
				)
			)
		)
		(pad "2" smd custom
			(at 0 0.4445 270)
			(size 0.1524 0.1524)
			(layers "F.Cu" "F.Mask" "F.Paste")
			(net "GND")
			(options
				(clearance outline)
				(anchor circle)
			)
			(primitives
				(gr_poly
					(pts
						(arc
							(start 0.3048 -0.2032)
							(mid 0.275042 -0.275042)
							(end 0.2032 -0.3048)
						)
						(arc
							(start -0.2032 -0.3048)
							(mid -0.275042 -0.275042)
							(end -0.3048 -0.2032)
						)
						(arc
							(start -0.3048 0.2032)
							(mid -0.275042 0.275042)
							(end -0.2032 0.3048)
						)
						(arc
							(start 0.2032 0.3048)
							(mid 0.275042 0.275042)
							(end 0.3048 0.2032)
						)
					)
					(width 0)
					(fill yes)
				)
			)
		)
	)
	(footprint ""
		(layer "F.Cu")
		(at 80.6196 -136.7282 90)
		(property "Reference" "R3099"
			(at 0 0 90)
			(layer "F.SilkS")
			(hide yes)
			(effects
				(font
					(size 1.27 1.27)
				)
			)
		)
		(property "Value" "1KR2F-3-GP"
			(at 0.064008 -3.993896 90)
			(unlocked yes)
			(layer "F.Fab")
			(hide yes)
			(effects
				(font
					(size 1.016 1.016)
					(thickness 0.1524)
				)
			)
		)
		(property "Device Type" "R402H16"
			(at 0.064008 -5.517896 90)
			(unlocked yes)
			(layer "F.Fab")
			(hide yes)
			(effects
				(font
					(size 1.016 1.016)
					(thickness 0.1524)
				)
			)
		)
		(duplicate_pad_numbers_are_jumpers no)
		(fp_line
			(start 0.508 -0.9398)
			(end -0.508 -0.9398)
			(stroke
				(width 0.1524)
				(type default)
			)
			(layer "F.SilkS")
		)
		(fp_line
			(start -0.508 -0.9398)
			(end -0.508 0.9398)
			(stroke
				(width 0.1524)
				(type default)
			)
			(layer "F.SilkS")
		)
		(fp_rect
			(start -0.508 0.9398)
			(end 0.508 -0.9398)
			(stroke
				(width 0)
				(type default)
			)
			(fill no)
			(layer "F.CrtYd")
		)
		(fp_rect
			(start -0.508 0.9398)
			(end 0.508 -0.9398)
			(stroke
				(width 0)
				(type default)
			)
			(fill no)
			(layer "F.Fab")
		)
		(pad "1" smd custom
			(at 0 -0.4445 90)
			(size 0.1397 0.1397)
			(layers "F.Cu" "F.Mask" "F.Paste")
			(net "ADC_P1V26")
			(options
				(clearance outline)
				(anchor circle)
			)
			(primitives
				(gr_poly
					(pts
						(arc
							(start -0.1778 -0.2794)
							(mid -0.249642 -0.249642)
							(end -0.2794 -0.1778)
						)
						(arc
							(start -0.2794 0.1778)
							(mid -0.249642 0.249642)
							(end -0.1778 0.2794)
						)
						(arc
							(start 0.1778 0.2794)
							(mid 0.249642 0.249642)
							(end 0.2794 0.1778)
						)
						(arc
							(start 0.2794 -0.1778)
							(mid 0.249642 -0.249642)
							(end 0.1778 -0.2794)
						)
					)
					(width 0)
					(fill yes)
				)
			)
		)
		(pad "2" smd custom
			(at 0 0.4445 90)
			(size 0.1397 0.1397)
			(layers "F.Cu" "F.Mask" "F.Paste")
			(net "GND")
			(options
				(clearance outline)
				(anchor circle)
			)
			(primitives
				(gr_poly
					(pts
						(arc
							(start -0.1778 -0.2794)
							(mid -0.249642 -0.249642)
							(end -0.2794 -0.1778)
						)
						(arc
							(start -0.2794 0.1778)
							(mid -0.249642 0.249642)
							(end -0.1778 0.2794)
						)
						(arc
							(start 0.1778 0.2794)
							(mid 0.249642 0.249642)
							(end 0.2794 0.1778)
						)
						(arc
							(start 0.2794 -0.1778)
							(mid 0.249642 -0.249642)
							(end 0.1778 -0.2794)
						)
					)
					(width 0)
					(fill yes)
				)
			)
		)
	)
	(footprint ""
		(layer "F.Cu")
		(at 8.7376 -52.0446 -90)
		(property "Reference" "D11"
			(at 0 0 270)
			(layer "F.SilkS")
			(hide yes)
			(effects
				(font
					(size 1.27 1.27)
				)
			)
		)
		(property "Value" "PGB1010603MR-GP"
			(at -0.0254 -2.8956 270)
			(unlocked yes)
			(layer "F.Fab")
			(hide yes)
			(effects
				(font
					(size 1.016 1.016)
					(thickness 0.1524)
				)
			)
		)
		(property "Device Type" "L1608-UH15"
			(at -0.0254 -4.4196 270)
			(unlocked yes)
			(layer "F.Fab")
			(hide yes)
			(effects
				(font
					(size 1.016 1.016)
					(thickness 0.1524)
				)
			)
		)
		(duplicate_pad_numbers_are_jumpers no)
		(fp_line
			(start 0.254 0)
			(end -0.254 0)
			(stroke
				(width 0.2032)
				(type default)
			)
			(layer "F.SilkS")
		)
		(fp_rect
			(start -0.5842 1.3335)
			(end 0.5842 -1.3335)
			(stroke
				(width 0)
				(type default)
			)
			(fill no)
			(layer "F.CrtYd")
		)
		(fp_rect
			(start -0.5842 1.3335)
			(end 0.5842 -1.3335)
			(stroke
				(width 0)
				(type default)
			)
			(fill no)
			(layer "F.Fab")
		)
		(pad "1" smd custom
			(at 0 -0.762 270)
			(size 0.2159 0.2159)
			(layers "F.Cu" "F.Mask" "F.Paste")
			(net "NIC0_MDI0_P0_R")
			(options
				(clearance outline)
				(anchor circle)
			)
			(primitives
				(gr_poly
					(pts
						(arc
							(start -0.3302 -0.4318)
							(mid -0.402042 -0.402042)
							(end -0.4318 -0.3302)
						)
						(arc
							(start -0.4318 0.3302)
							(mid -0.402042 0.402042)
							(end -0.3302 0.4318)
						)
						(arc
							(start 0.3302 0.4318)
							(mid 0.402042 0.402042)
							(end 0.4318 0.3302)
						)
						(arc
							(start 0.4318 -0.3302)
							(mid 0.402042 -0.402042)
							(end 0.3302 -0.4318)
						)
					)
					(width 0)
					(fill yes)
				)
			)
		)
		(pad "2" smd custom
			(at 0 0.762 270)
			(size 0.2159 0.2159)
			(layers "F.Cu" "F.Mask" "F.Paste")
			(net "GND")
			(options
				(clearance outline)
				(anchor circle)
			)
			(primitives
				(gr_poly
					(pts
						(arc
							(start -0.3302 -0.4318)
							(mid -0.402042 -0.402042)
							(end -0.4318 -0.3302)
						)
						(arc
							(start -0.4318 0.3302)
							(mid -0.402042 0.402042)
							(end -0.3302 0.4318)
						)
						(arc
							(start 0.3302 0.4318)
							(mid 0.402042 0.402042)
							(end 0.4318 0.3302)
						)
						(arc
							(start 0.4318 -0.3302)
							(mid 0.402042 -0.402042)
							(end 0.3302 -0.4318)
						)
					)
					(width 0)
					(fill yes)
				)
			)
		)
	)
	(footprint ""
		(layer "F.Cu")
		(at 166.392098 -212.420454 180)
		(property "Reference" "C160"
			(at 0 0 180)
			(layer "F.SilkS")
			(hide yes)
			(effects
				(font
					(size 1.27 1.27)
				)
			)
		)
		(property "Value" "SCD22U10V2KX-1GP"
			(at 1.1811 -2.7051 180)
			(unlocked yes)
			(layer "F.Fab")
			(hide yes)
			(effects
				(font
					(size 1.016 1.016)
					(thickness 0.1524)
				)
			)
		)
		(property "Device Type" "C402H22"
			(at 1.1811 -4.2291 180)
			(unlocked yes)
			(layer "F.Fab")
			(hide yes)
			(effects
				(font
					(size 1.016 1.016)
					(thickness 0.1524)
				)
			)
		)
		(duplicate_pad_numbers_are_jumpers no)
		(fp_rect
			(start -0.4318 0.9525)
			(end 0.4318 -0.9525)
			(stroke
				(width 0)
				(type default)
			)
			(fill no)
			(layer "F.CrtYd")
		)
		(fp_rect
			(start -0.4318 0.9525)
			(end 0.4318 -0.9525)
			(stroke
				(width 0)
				(type default)
			)
			(fill no)
			(layer "F.Fab")
		)
		(pad "1" smd custom
			(at 0 -0.4445 180)
			(size 0.1524 0.1524)
			(layers "F.Cu" "F.Mask" "F.Paste")
			(net "PCIE_TX_CAP_P51")
			(options
				(clearance outline)
				(anchor circle)
			)
			(primitives
				(gr_poly
					(pts
						(arc
							(start 0.3048 -0.2032)
							(mid 0.275042 -0.275042)
							(end 0.2032 -0.3048)
						)
						(arc
							(start -0.2032 -0.3048)
							(mid -0.275042 -0.275042)
							(end -0.3048 -0.2032)
						)
						(arc
							(start -0.3048 0.2032)
							(mid -0.275042 0.275042)
							(end -0.2032 0.3048)
						)
						(arc
							(start 0.2032 0.3048)
							(mid 0.275042 0.275042)
							(end 0.3048 0.2032)
						)
					)
					(width 0)
					(fill yes)
				)
			)
		)
		(pad "2" smd custom
			(at 0 0.4445 180)
			(size 0.1524 0.1524)
			(layers "F.Cu" "F.Mask" "F.Paste")
			(net "PCIE_TX_P51")
			(options
				(clearance outline)
				(anchor circle)
			)
			(primitives
				(gr_poly
					(pts
						(arc
							(start 0.3048 -0.2032)
							(mid 0.275042 -0.275042)
							(end 0.2032 -0.3048)
						)
						(arc
							(start -0.2032 -0.3048)
							(mid -0.275042 -0.275042)
							(end -0.3048 -0.2032)
						)
						(arc
							(start -0.3048 0.2032)
							(mid -0.275042 0.275042)
							(end -0.2032 0.3048)
						)
						(arc
							(start 0.2032 0.3048)
							(mid 0.275042 0.275042)
							(end 0.3048 0.2032)
						)
					)
					(width 0)
					(fill yes)
				)
			)
		)
	)
	(footprint ""
		(layer "F.Cu")
		(at 80.113124 -195.681092 180)
		(property "Reference" "R7933"
			(at 0 0 180)
			(layer "F.SilkS")
			(hide yes)
			(effects
				(font
					(size 1.27 1.27)
				)
			)
		)
		(property "Value" "0R2J-2-GP"
			(at 0.064008 -3.993896 180)
			(unlocked yes)
			(layer "F.Fab")
			(hide yes)
			(effects
				(font
					(size 1.016 1.016)
					(thickness 0.1524)
				)
			)
		)
		(property "Device Type" "R402H16"
			(at 0.064008 -5.517896 180)
			(unlocked yes)
			(layer "F.Fab")
			(hide yes)
			(effects
				(font
					(size 1.016 1.016)
					(thickness 0.1524)
				)
			)
		)
		(duplicate_pad_numbers_are_jumpers no)
		(fp_line
			(start 0.508 -0.9398)
			(end -0.508 -0.9398)
			(stroke
				(width 0.1524)
				(type default)
			)
			(layer "F.SilkS")
		)
		(fp_line
			(start -0.508 -0.9398)
			(end -0.508 0.9398)
			(stroke
				(width 0.1524)
				(type default)
			)
			(layer "F.SilkS")
		)
		(fp_rect
			(start -0.508 0.9398)
			(end 0.508 -0.9398)
			(stroke
				(width 0)
				(type default)
			)
			(fill no)
			(layer "F.CrtYd")
		)
		(fp_rect
			(start -0.508 0.9398)
			(end 0.508 -0.9398)
			(stroke
				(width 0)
				(type default)
			)
			(fill no)
			(layer "F.Fab")
		)
		(pad "1" smd custom
			(at 0 -0.4445 180)
			(size 0.1397 0.1397)
			(layers "F.Cu" "F.Mask" "F.Paste")
			(net "SSD_PRSNT#10")
			(options
				(clearance outline)
				(anchor circle)
			)
			(primitives
				(gr_poly
					(pts
						(arc
							(start -0.1778 -0.2794)
							(mid -0.249642 -0.249642)
							(end -0.2794 -0.1778)
						)
						(arc
							(start -0.2794 0.1778)
							(mid -0.249642 0.249642)
							(end -0.1778 0.2794)
						)
						(arc
							(start 0.1778 0.2794)
							(mid 0.249642 0.249642)
							(end 0.2794 0.1778)
						)
						(arc
							(start 0.2794 -0.1778)
							(mid 0.249642 -0.249642)
							(end 0.1778 -0.2794)
						)
					)
					(width 0)
					(fill yes)
				)
			)
		)
		(pad "2" smd custom
			(at 0 0.4445 180)
			(size 0.1397 0.1397)
			(layers "F.Cu" "F.Mask" "F.Paste")
			(net "SSD_PRSNT#10_R")
			(options
				(clearance outline)
				(anchor circle)
			)
			(primitives
				(gr_poly
					(pts
						(arc
							(start -0.1778 -0.2794)
							(mid -0.249642 -0.249642)
							(end -0.2794 -0.1778)
						)
						(arc
							(start -0.2794 0.1778)
							(mid -0.249642 0.249642)
							(end -0.1778 0.2794)
						)
						(arc
							(start 0.1778 0.2794)
							(mid 0.249642 0.249642)
							(end 0.2794 0.1778)
						)
						(arc
							(start 0.2794 -0.1778)
							(mid 0.249642 -0.249642)
							(end 0.1778 -0.2794)
						)
					)
					(width 0)
					(fill yes)
				)
			)
		)
	)
	(footprint ""
		(layer "F.Cu")
		(at 50.292 -132.842)
		(property "Reference" "TP219"
			(at 0 0 0)
			(layer "F.SilkS")
			(hide yes)
			(effects
				(font
					(size 1.27 1.27)
				)
			)
		)
		(property "Value" "TPAD28-2-GP"
			(at -0.0127 -1.6637 0)
			(unlocked yes)
			(layer "F.Fab")
			(hide yes)
			(effects
				(font
					(size 1.016 1.016)
					(thickness 0.1524)
				)
			)
		)
		(property "Device Type" "TPAD28"
			(at -0.0127 -3.1877 0)
			(unlocked yes)
			(layer "F.Fab")
			(hide yes)
			(effects
				(font
					(size 1.016 1.016)
					(thickness 0.1524)
				)
			)
		)
		(duplicate_pad_numbers_are_jumpers no)
		(fp_poly
			(pts
				(arc
					(start 0.3556 0)
					(mid -0.3556 0)
					(end 0.3556 0)
				)
			)
			(stroke
				(width 0)
				(type default)
			)
			(fill no)
			(layer "F.CrtYd")
		)
		(fp_poly
			(pts
				(arc
					(start 0.6096 0)
					(mid -0.6096 0)
					(end 0.6096 0)
				)
			)
			(stroke
				(width 0)
				(type default)
			)
			(fill no)
			(layer "F.Fab")
		)
		(pad "1" smd circle
			(at 0 0)
			(size 0.7112 0.7112)
			(layers "F.Cu" "F.Mask" "F.Paste")
			(net "DACR")
		)
	)
	(footprint ""
		(layer "F.Cu")
		(at 77.0382 -195.6562 180)
		(property "Reference" "R9039"
			(at 0 0 180)
			(layer "F.SilkS")
			(hide yes)
			(effects
				(font
					(size 1.27 1.27)
				)
			)
		)
		(property "Value" "4K7R2F-GP"
			(at 0.064008 -3.993896 180)
			(unlocked yes)
			(layer "F.Fab")
			(hide yes)
			(effects
				(font
					(size 1.016 1.016)
					(thickness 0.1524)
				)
			)
		)
		(property "Device Type" "R402H16"
			(at 0.064008 -5.517896 180)
			(unlocked yes)
			(layer "F.Fab")
			(hide yes)
			(effects
				(font
					(size 1.016 1.016)
					(thickness 0.1524)
				)
			)
		)
		(duplicate_pad_numbers_are_jumpers no)
		(fp_line
			(start 0.508 -0.9398)
			(end -0.508 -0.9398)
			(stroke
				(width 0.1524)
				(type default)
			)
			(layer "F.SilkS")
		)
		(fp_line
			(start -0.508 -0.9398)
			(end -0.508 0.9398)
			(stroke
				(width 0.1524)
				(type default)
			)
			(layer "F.SilkS")
		)
		(fp_rect
			(start -0.508 0.9398)
			(end 0.508 -0.9398)
			(stroke
				(width 0)
				(type default)
			)
			(fill no)
			(layer "F.CrtYd")
		)
		(fp_rect
			(start -0.508 0.9398)
			(end 0.508 -0.9398)
			(stroke
				(width 0)
				(type default)
			)
			(fill no)
			(layer "F.Fab")
		)
		(pad "1" smd custom
			(at 0 -0.4445 180)
			(size 0.1397 0.1397)
			(layers "F.Cu" "F.Mask" "F.Paste")
			(net "SSD_PERST#10")
			(options
				(clearance outline)
				(anchor circle)
			)
			(primitives
				(gr_poly
					(pts
						(arc
							(start -0.1778 -0.2794)
							(mid -0.249642 -0.249642)
							(end -0.2794 -0.1778)
						)
						(arc
							(start -0.2794 0.1778)
							(mid -0.249642 0.249642)
							(end -0.1778 0.2794)
						)
						(arc
							(start 0.1778 0.2794)
							(mid 0.249642 0.249642)
							(end 0.2794 0.1778)
						)
						(arc
							(start 0.2794 -0.1778)
							(mid 0.249642 -0.249642)
							(end 0.1778 -0.2794)
						)
					)
					(width 0)
					(fill yes)
				)
			)
		)
		(pad "2" smd custom
			(at 0 0.4445 180)
			(size 0.1397 0.1397)
			(layers "F.Cu" "F.Mask" "F.Paste")
			(net "GND")
			(options
				(clearance outline)
				(anchor circle)
			)
			(primitives
				(gr_poly
					(pts
						(arc
							(start -0.1778 -0.2794)
							(mid -0.249642 -0.249642)
							(end -0.2794 -0.1778)
						)
						(arc
							(start -0.2794 0.1778)
							(mid -0.249642 0.249642)
							(end -0.1778 0.2794)
						)
						(arc
							(start 0.1778 0.2794)
							(mid 0.249642 0.249642)
							(end 0.2794 0.1778)
						)
						(arc
							(start 0.2794 -0.1778)
							(mid 0.249642 -0.249642)
							(end 0.1778 -0.2794)
						)
					)
					(width 0)
					(fill yes)
				)
			)
		)
	)
	(footprint ""
		(layer "F.Cu")
		(at 64.389 -131.953 180)
		(property "Reference" "R5766"
			(at 0 0 180)
			(layer "F.SilkS")
			(hide yes)
			(effects
				(font
					(size 1.27 1.27)
				)
			)
		)
		(property "Value" "1KR2F-3-GP"
			(at 0.064008 -3.993896 180)
			(unlocked yes)
			(layer "F.Fab")
			(hide yes)
			(effects
				(font
					(size 1.016 1.016)
					(thickness 0.1524)
				)
			)
		)
		(property "Device Type" "R402H16"
			(at 0.064008 -5.517896 180)
			(unlocked yes)
			(layer "F.Fab")
			(hide yes)
			(effects
				(font
					(size 1.016 1.016)
					(thickness 0.1524)
				)
			)
		)
		(duplicate_pad_numbers_are_jumpers no)
		(fp_line
			(start 0.508 -0.9398)
			(end -0.508 -0.9398)
			(stroke
				(width 0.1524)
				(type default)
			)
			(layer "F.SilkS")
		)
		(fp_line
			(start -0.508 -0.9398)
			(end -0.508 0.9398)
			(stroke
				(width 0.1524)
				(type default)
			)
			(layer "F.SilkS")
		)
		(fp_rect
			(start -0.508 0.9398)
			(end 0.508 -0.9398)
			(stroke
				(width 0)
				(type default)
			)
			(fill no)
			(layer "F.CrtYd")
		)
		(fp_rect
			(start -0.508 0.9398)
			(end 0.508 -0.9398)
			(stroke
				(width 0)
				(type default)
			)
			(fill no)
			(layer "F.Fab")
		)
		(pad "1" smd custom
			(at 0 -0.4445 180)
			(size 0.1397 0.1397)
			(layers "F.Cu" "F.Mask" "F.Paste")
			(net "ADC_12V")
			(options
				(clearance outline)
				(anchor circle)
			)
			(primitives
				(gr_poly
					(pts
						(arc
							(start -0.1778 -0.2794)
							(mid -0.249642 -0.249642)
							(end -0.2794 -0.1778)
						)
						(arc
							(start -0.2794 0.1778)
							(mid -0.249642 0.249642)
							(end -0.1778 0.2794)
						)
						(arc
							(start 0.1778 0.2794)
							(mid 0.249642 0.249642)
							(end 0.2794 0.1778)
						)
						(arc
							(start 0.2794 -0.1778)
							(mid 0.249642 -0.249642)
							(end 0.1778 -0.2794)
						)
					)
					(width 0)
					(fill yes)
				)
			)
		)
		(pad "2" smd custom
			(at 0 0.4445 180)
			(size 0.1397 0.1397)
			(layers "F.Cu" "F.Mask" "F.Paste")
			(net "GND")
			(options
				(clearance outline)
				(anchor circle)
			)
			(primitives
				(gr_poly
					(pts
						(arc
							(start -0.1778 -0.2794)
							(mid -0.249642 -0.249642)
							(end -0.2794 -0.1778)
						)
						(arc
							(start -0.2794 0.1778)
							(mid -0.249642 0.249642)
							(end -0.1778 0.2794)
						)
						(arc
							(start 0.1778 0.2794)
							(mid 0.249642 0.249642)
							(end 0.2794 0.1778)
						)
						(arc
							(start 0.2794 -0.1778)
							(mid 0.249642 -0.249642)
							(end 0.1778 -0.2794)
						)
					)
					(width 0)
					(fill yes)
				)
			)
		)
	)
	(footprint ""
		(layer "F.Cu")
		(at 159.385 -97.9424 180)
		(property "Reference" "R60"
			(at 0 0 180)
			(layer "F.SilkS")
			(hide yes)
			(effects
				(font
					(size 1.27 1.27)
				)
			)
		)
		(property "Value" "10KR2F-2-GP"
			(at 0.064008 -3.993896 180)
			(unlocked yes)
			(layer "F.Fab")
			(hide yes)
			(effects
				(font
					(size 1.016 1.016)
					(thickness 0.1524)
				)
			)
		)
		(property "Device Type" "R402H16"
			(at 0.064008 -5.517896 180)
			(unlocked yes)
			(layer "F.Fab")
			(hide yes)
			(effects
				(font
					(size 1.016 1.016)
					(thickness 0.1524)
				)
			)
		)
		(duplicate_pad_numbers_are_jumpers no)
		(fp_line
			(start 0.508 -0.9398)
			(end -0.508 -0.9398)
			(stroke
				(width 0.1524)
				(type default)
			)
			(layer "F.SilkS")
		)
		(fp_line
			(start -0.508 -0.9398)
			(end -0.508 0.9398)
			(stroke
				(width 0.1524)
				(type default)
			)
			(layer "F.SilkS")
		)
		(fp_rect
			(start -0.508 0.9398)
			(end 0.508 -0.9398)
			(stroke
				(width 0)
				(type default)
			)
			(fill no)
			(layer "F.CrtYd")
		)
		(fp_rect
			(start -0.508 0.9398)
			(end 0.508 -0.9398)
			(stroke
				(width 0)
				(type default)
			)
			(fill no)
			(layer "F.Fab")
		)
		(pad "1" smd custom
			(at 0 -0.4445 180)
			(size 0.1397 0.1397)
			(layers "F.Cu" "F.Mask" "F.Paste")
			(net "CLKGEN_OE3")
			(options
				(clearance outline)
				(anchor circle)
			)
			(primitives
				(gr_poly
					(pts
						(arc
							(start -0.1778 -0.2794)
							(mid -0.249642 -0.249642)
							(end -0.2794 -0.1778)
						)
						(arc
							(start -0.2794 0.1778)
							(mid -0.249642 0.249642)
							(end -0.1778 0.2794)
						)
						(arc
							(start 0.1778 0.2794)
							(mid 0.249642 0.249642)
							(end 0.2794 0.1778)
						)
						(arc
							(start 0.2794 -0.1778)
							(mid 0.249642 -0.249642)
							(end 0.1778 -0.2794)
						)
					)
					(width 0)
					(fill yes)
				)
			)
		)
		(pad "2" smd custom
			(at 0 0.4445 180)
			(size 0.1397 0.1397)
			(layers "F.Cu" "F.Mask" "F.Paste")
			(net "P1V8_CLKGEN")
			(options
				(clearance outline)
				(anchor circle)
			)
			(primitives
				(gr_poly
					(pts
						(arc
							(start -0.1778 -0.2794)
							(mid -0.249642 -0.249642)
							(end -0.2794 -0.1778)
						)
						(arc
							(start -0.2794 0.1778)
							(mid -0.249642 0.249642)
							(end -0.1778 0.2794)
						)
						(arc
							(start 0.1778 0.2794)
							(mid 0.249642 0.249642)
							(end 0.2794 0.1778)
						)
						(arc
							(start 0.2794 -0.1778)
							(mid 0.249642 -0.249642)
							(end 0.1778 -0.2794)
						)
					)
					(width 0)
					(fill yes)
				)
			)
		)
	)
	(footprint ""
		(layer "F.Cu")
		(at 219.456 -13.4112 -90)
		(property "Reference" "R714"
			(at 0 0 270)
			(layer "F.SilkS")
			(hide yes)
			(effects
				(font
					(size 1.27 1.27)
				)
			)
		)
		(property "Value" "4K7R2F-GP"
			(at 0.064008 -3.993896 270)
			(unlocked yes)
			(layer "F.Fab")
			(hide yes)
			(effects
				(font
					(size 1.016 1.016)
					(thickness 0.1524)
				)
			)
		)
		(property "Device Type" "R402H16"
			(at 0.064008 -5.517896 270)
			(unlocked yes)
			(layer "F.Fab")
			(hide yes)
			(effects
				(font
					(size 1.016 1.016)
					(thickness 0.1524)
				)
			)
		)
		(duplicate_pad_numbers_are_jumpers no)
		(fp_line
			(start -0.508 -0.9398)
			(end -0.508 0.9398)
			(stroke
				(width 0.1524)
				(type default)
			)
			(layer "F.SilkS")
		)
		(fp_line
			(start 0.508 -0.9398)
			(end -0.508 -0.9398)
			(stroke
				(width 0.1524)
				(type default)
			)
			(layer "F.SilkS")
		)
		(fp_rect
			(start -0.508 0.9398)
			(end 0.508 -0.9398)
			(stroke
				(width 0)
				(type default)
			)
			(fill no)
			(layer "F.CrtYd")
		)
		(fp_rect
			(start -0.508 0.9398)
			(end 0.508 -0.9398)
			(stroke
				(width 0)
				(type default)
			)
			(fill no)
			(layer "F.Fab")
		)
		(pad "1" smd custom
			(at 0 -0.4445 270)
			(size 0.1397 0.1397)
			(layers "F.Cu" "F.Mask" "F.Paste")
			(net "U81_Y")
			(options
				(clearance outline)
				(anchor circle)
			)
			(primitives
				(gr_poly
					(pts
						(arc
							(start -0.1778 -0.2794)
							(mid -0.249642 -0.249642)
							(end -0.2794 -0.1778)
						)
						(arc
							(start -0.2794 0.1778)
							(mid -0.249642 0.249642)
							(end -0.1778 0.2794)
						)
						(arc
							(start 0.1778 0.2794)
							(mid 0.249642 0.249642)
							(end 0.2794 0.1778)
						)
						(arc
							(start 0.2794 -0.1778)
							(mid 0.249642 -0.249642)
							(end 0.1778 -0.2794)
						)
					)
					(width 0)
					(fill yes)
				)
			)
		)
		(pad "2" smd custom
			(at 0 0.4445 270)
			(size 0.1397 0.1397)
			(layers "F.Cu" "F.Mask" "F.Paste")
			(net "P3V3_STBY")
			(options
				(clearance outline)
				(anchor circle)
			)
			(primitives
				(gr_poly
					(pts
						(arc
							(start -0.1778 -0.2794)
							(mid -0.249642 -0.249642)
							(end -0.2794 -0.1778)
						)
						(arc
							(start -0.2794 0.1778)
							(mid -0.249642 0.249642)
							(end -0.1778 0.2794)
						)
						(arc
							(start 0.1778 0.2794)
							(mid 0.249642 0.249642)
							(end 0.2794 0.1778)
						)
						(arc
							(start 0.2794 -0.1778)
							(mid 0.249642 -0.249642)
							(end 0.1778 -0.2794)
						)
					)
					(width 0)
					(fill yes)
				)
			)
		)
	)
	(footprint ""
		(layer "F.Cu")
		(at 11.176 -70.3072 -90)
		(property "Reference" "R385"
			(at 0 0 270)
			(layer "F.SilkS")
			(hide yes)
			(effects
				(font
					(size 1.27 1.27)
				)
			)
		)
		(property "Value" "0R2J-2-GP"
			(at 0.064008 -3.993896 270)
			(unlocked yes)
			(layer "F.Fab")
			(hide yes)
			(effects
				(font
					(size 1.016 1.016)
					(thickness 0.1524)
				)
			)
		)
		(property "Device Type" "R402H16"
			(at 0.064008 -5.517896 270)
			(unlocked yes)
			(layer "F.Fab")
			(hide yes)
			(effects
				(font
					(size 1.016 1.016)
					(thickness 0.1524)
				)
			)
		)
		(duplicate_pad_numbers_are_jumpers no)
		(fp_line
			(start -0.508 -0.9398)
			(end -0.508 0.9398)
			(stroke
				(width 0.1524)
				(type default)
			)
			(layer "F.SilkS")
		)
		(fp_line
			(start 0.508 -0.9398)
			(end -0.508 -0.9398)
			(stroke
				(width 0.1524)
				(type default)
			)
			(layer "F.SilkS")
		)
		(fp_rect
			(start -0.508 0.9398)
			(end 0.508 -0.9398)
			(stroke
				(width 0)
				(type default)
			)
			(fill no)
			(layer "F.CrtYd")
		)
		(fp_rect
			(start -0.508 0.9398)
			(end 0.508 -0.9398)
			(stroke
				(width 0)
				(type default)
			)
			(fill no)
			(layer "F.Fab")
		)
		(pad "1" smd custom
			(at 0 -0.4445 270)
			(size 0.1397 0.1397)
			(layers "F.Cu" "F.Mask" "F.Paste")
			(net "XTAL_IN_I210")
			(options
				(clearance outline)
				(anchor circle)
			)
			(primitives
				(gr_poly
					(pts
						(arc
							(start -0.1778 -0.2794)
							(mid -0.249642 -0.249642)
							(end -0.2794 -0.1778)
						)
						(arc
							(start -0.2794 0.1778)
							(mid -0.249642 0.249642)
							(end -0.1778 0.2794)
						)
						(arc
							(start 0.1778 0.2794)
							(mid 0.249642 0.249642)
							(end 0.2794 0.1778)
						)
						(arc
							(start 0.2794 -0.1778)
							(mid 0.249642 -0.249642)
							(end 0.1778 -0.2794)
						)
					)
					(width 0)
					(fill yes)
				)
			)
		)
		(pad "2" smd custom
			(at 0 0.4445 270)
			(size 0.1397 0.1397)
			(layers "F.Cu" "F.Mask" "F.Paste")
			(net "XTAL_IN_I210_R")
			(options
				(clearance outline)
				(anchor circle)
			)
			(primitives
				(gr_poly
					(pts
						(arc
							(start -0.1778 -0.2794)
							(mid -0.249642 -0.249642)
							(end -0.2794 -0.1778)
						)
						(arc
							(start -0.2794 0.1778)
							(mid -0.249642 0.249642)
							(end -0.1778 0.2794)
						)
						(arc
							(start 0.1778 0.2794)
							(mid 0.249642 0.249642)
							(end 0.2794 0.1778)
						)
						(arc
							(start 0.2794 -0.1778)
							(mid 0.249642 -0.249642)
							(end 0.1778 -0.2794)
						)
					)
					(width 0)
					(fill yes)
				)
			)
		)
	)
	(footprint ""
		(layer "F.Cu")
		(at 42.4688 -183.2356)
		(property "Reference" "R865"
			(at 0 0 0)
			(layer "F.SilkS")
			(hide yes)
			(effects
				(font
					(size 1.27 1.27)
				)
			)
		)
		(property "Value" "0R2J-2-GP"
			(at 0.064008 -3.993896 0)
			(unlocked yes)
			(layer "F.Fab")
			(hide yes)
			(effects
				(font
					(size 1.016 1.016)
					(thickness 0.1524)
				)
			)
		)
		(property "Device Type" "R402H16"
			(at 0.064008 -5.517896 0)
			(unlocked yes)
			(layer "F.Fab")
			(hide yes)
			(effects
				(font
					(size 1.016 1.016)
					(thickness 0.1524)
				)
			)
		)
		(duplicate_pad_numbers_are_jumpers no)
		(fp_line
			(start -0.508 -0.9398)
			(end -0.508 0.9398)
			(stroke
				(width 0.1524)
				(type default)
			)
			(layer "F.SilkS")
		)
		(fp_line
			(start 0.508 -0.9398)
			(end -0.508 -0.9398)
			(stroke
				(width 0.1524)
				(type default)
			)
			(layer "F.SilkS")
		)
		(fp_rect
			(start -0.508 0.9398)
			(end 0.508 -0.9398)
			(stroke
				(width 0)
				(type default)
			)
			(fill no)
			(layer "F.CrtYd")
		)
		(fp_rect
			(start -0.508 0.9398)
			(end 0.508 -0.9398)
			(stroke
				(width 0)
				(type default)
			)
			(fill no)
			(layer "F.Fab")
		)
		(pad "1" smd custom
			(at 0 -0.4445)
			(size 0.1397 0.1397)
			(layers "F.Cu" "F.Mask" "F.Paste")
			(net "BMC_I2C9_CLKBUF2_SDA_R")
			(options
				(clearance outline)
				(anchor circle)
			)
			(primitives
				(gr_poly
					(pts
						(arc
							(start -0.1778 -0.2794)
							(mid -0.249642 -0.249642)
							(end -0.2794 -0.1778)
						)
						(arc
							(start -0.2794 0.1778)
							(mid -0.249642 0.249642)
							(end -0.1778 0.2794)
						)
						(arc
							(start 0.1778 0.2794)
							(mid 0.249642 0.249642)
							(end 0.2794 0.1778)
						)
						(arc
							(start 0.2794 -0.1778)
							(mid 0.249642 -0.249642)
							(end 0.1778 -0.2794)
						)
					)
					(width 0)
					(fill yes)
				)
			)
		)
		(pad "2" smd custom
			(at 0 0.4445)
			(size 0.1397 0.1397)
			(layers "F.Cu" "F.Mask" "F.Paste")
			(net "BMC_I2C9_CLKBUF2_SDA")
			(options
				(clearance outline)
				(anchor circle)
			)
			(primitives
				(gr_poly
					(pts
						(arc
							(start -0.1778 -0.2794)
							(mid -0.249642 -0.249642)
							(end -0.2794 -0.1778)
						)
						(arc
							(start -0.2794 0.1778)
							(mid -0.249642 0.249642)
							(end -0.1778 0.2794)
						)
						(arc
							(start 0.1778 0.2794)
							(mid 0.249642 0.249642)
							(end 0.2794 0.1778)
						)
						(arc
							(start 0.2794 -0.1778)
							(mid 0.249642 -0.249642)
							(end 0.1778 -0.2794)
						)
					)
					(width 0)
					(fill yes)
				)
			)
		)
	)
	(footprint ""
		(layer "F.Cu")
		(at 310.007 -67.7926)
		(property "Reference" "PG65"
			(at 0 0 0)
			(layer "F.SilkS")
			(hide yes)
			(effects
				(font
					(size 1.27 1.27)
				)
			)
		)
		(property "Value" "GAP-CLOSE-PWR-3-GP"
			(at 0.0254 -6.5786 0)
			(unlocked yes)
			(layer "F.Fab")
			(hide yes)
			(effects
				(font
					(size 1.016 1.016)
					(thickness 0.1524)
				)
			)
		)
		(property "Device Type" "GAP-CLOSE-PWR-3"
			(at 0.0254 -8.255 0)
			(unlocked yes)
			(layer "F.Fab")
			(hide yes)
			(effects
				(font
					(size 1.016 1.016)
					(thickness 0.1524)
				)
			)
		)
		(duplicate_pad_numbers_are_jumpers no)
		(fp_rect
			(start -0.7112 0.4572)
			(end 0.7112 -0.4572)
			(stroke
				(width 0)
				(type default)
			)
			(fill no)
			(layer "F.CrtYd")
		)
		(fp_poly
			(pts
				(xy -0.7112 -0.4572) (xy 0.7112 -0.4572) (xy 0.7112 0.4572) (xy -0.7112 0.4572)
			)
			(stroke
				(width 0)
				(type default)
			)
			(fill no)
			(layer "F.Fab")
		)
		(pad "1" smd rect
			(at -0.3048 0)
			(size 0.6604 0.762)
			(layers "F.Cu" "F.Mask" "F.Paste")
			(net "DUT_VDD")
		)
		(pad "2" smd rect
			(at 0.3048 0)
			(size 0.6604 0.762)
			(layers "F.Cu" "F.Mask" "F.Paste")
			(net "P0V9_E")
		)
	)
	(footprint ""
		(layer "F.Cu")
		(at 187.071 -6.604)
		(property "Reference" "R529"
			(at 0 0 0)
			(layer "F.SilkS")
			(hide yes)
			(effects
				(font
					(size 1.27 1.27)
				)
			)
		)
		(property "Value" "1KR2F-3-GP"
			(at 0.064008 -3.993896 0)
			(unlocked yes)
			(layer "F.Fab")
			(hide yes)
			(effects
				(font
					(size 1.016 1.016)
					(thickness 0.1524)
				)
			)
		)
		(property "Device Type" "R402H16"
			(at 0.064008 -5.517896 0)
			(unlocked yes)
			(layer "F.Fab")
			(hide yes)
			(effects
				(font
					(size 1.016 1.016)
					(thickness 0.1524)
				)
			)
		)
		(duplicate_pad_numbers_are_jumpers no)
		(fp_line
			(start -0.508 -0.9398)
			(end -0.508 0.9398)
			(stroke
				(width 0.1524)
				(type default)
			)
			(layer "F.SilkS")
		)
		(fp_line
			(start 0.508 -0.9398)
			(end -0.508 -0.9398)
			(stroke
				(width 0.1524)
				(type default)
			)
			(layer "F.SilkS")
		)
		(fp_rect
			(start -0.508 0.9398)
			(end 0.508 -0.9398)
			(stroke
				(width 0)
				(type default)
			)
			(fill no)
			(layer "F.CrtYd")
		)
		(fp_rect
			(start -0.508 0.9398)
			(end 0.508 -0.9398)
			(stroke
				(width 0)
				(type default)
			)
			(fill no)
			(layer "F.Fab")
		)
		(pad "1" smd custom
			(at 0 -0.4445)
			(size 0.1397 0.1397)
			(layers "F.Cu" "F.Mask" "F.Paste")
			(net "ENCLO_LED_RED_G")
			(options
				(clearance outline)
				(anchor circle)
			)
			(primitives
				(gr_poly
					(pts
						(arc
							(start -0.1778 -0.2794)
							(mid -0.249642 -0.249642)
							(end -0.2794 -0.1778)
						)
						(arc
							(start -0.2794 0.1778)
							(mid -0.249642 0.249642)
							(end -0.1778 0.2794)
						)
						(arc
							(start 0.1778 0.2794)
							(mid 0.249642 0.249642)
							(end 0.2794 0.1778)
						)
						(arc
							(start 0.2794 -0.1778)
							(mid 0.249642 -0.249642)
							(end 0.1778 -0.2794)
						)
					)
					(width 0)
					(fill yes)
				)
			)
		)
		(pad "2" smd custom
			(at 0 0.4445)
			(size 0.1397 0.1397)
			(layers "F.Cu" "F.Mask" "F.Paste")
			(net "GND")
			(options
				(clearance outline)
				(anchor circle)
			)
			(primitives
				(gr_poly
					(pts
						(arc
							(start -0.1778 -0.2794)
							(mid -0.249642 -0.249642)
							(end -0.2794 -0.1778)
						)
						(arc
							(start -0.2794 0.1778)
							(mid -0.249642 0.249642)
							(end -0.1778 0.2794)
						)
						(arc
							(start 0.1778 0.2794)
							(mid 0.249642 0.249642)
							(end 0.2794 0.1778)
						)
						(arc
							(start 0.2794 -0.1778)
							(mid 0.249642 -0.249642)
							(end 0.1778 -0.2794)
						)
					)
					(width 0)
					(fill yes)
				)
			)
		)
	)
	(footprint ""
		(layer "F.Cu")
		(at 18.796 -145.796 180)
		(property "Reference" "C194"
			(at 0 0 180)
			(layer "F.SilkS")
			(hide yes)
			(effects
				(font
					(size 1.27 1.27)
				)
			)
		)
		(property "Value" "SC1U10V2KX-4-GP"
			(at 1.1811 -2.7051 180)
			(unlocked yes)
			(layer "F.Fab")
			(hide yes)
			(effects
				(font
					(size 1.016 1.016)
					(thickness 0.1524)
				)
			)
		)
		(property "Device Type" "C402H22"
			(at 1.1811 -4.2291 180)
			(unlocked yes)
			(layer "F.Fab")
			(hide yes)
			(effects
				(font
					(size 1.016 1.016)
					(thickness 0.1524)
				)
			)
		)
		(duplicate_pad_numbers_are_jumpers no)
		(fp_rect
			(start -0.4318 0.9525)
			(end 0.4318 -0.9525)
			(stroke
				(width 0)
				(type default)
			)
			(fill no)
			(layer "F.CrtYd")
		)
		(fp_rect
			(start -0.4318 0.9525)
			(end 0.4318 -0.9525)
			(stroke
				(width 0)
				(type default)
			)
			(fill no)
			(layer "F.Fab")
		)
		(pad "1" smd custom
			(at 0 -0.4445 180)
			(size 0.1524 0.1524)
			(layers "F.Cu" "F.Mask" "F.Paste")
			(net "MPLLAV33")
			(options
				(clearance outline)
				(anchor circle)
			)
			(primitives
				(gr_poly
					(pts
						(arc
							(start 0.3048 -0.2032)
							(mid 0.275042 -0.275042)
							(end 0.2032 -0.3048)
						)
						(arc
							(start -0.2032 -0.3048)
							(mid -0.275042 -0.275042)
							(end -0.3048 -0.2032)
						)
						(arc
							(start -0.3048 0.2032)
							(mid -0.275042 0.275042)
							(end -0.2032 0.3048)
						)
						(arc
							(start 0.2032 0.3048)
							(mid 0.275042 0.275042)
							(end 0.3048 0.2032)
						)
					)
					(width 0)
					(fill yes)
				)
			)
		)
		(pad "2" smd custom
			(at 0 0.4445 180)
			(size 0.1524 0.1524)
			(layers "F.Cu" "F.Mask" "F.Paste")
			(net "GND")
			(options
				(clearance outline)
				(anchor circle)
			)
			(primitives
				(gr_poly
					(pts
						(arc
							(start 0.3048 -0.2032)
							(mid 0.275042 -0.275042)
							(end 0.2032 -0.3048)
						)
						(arc
							(start -0.2032 -0.3048)
							(mid -0.275042 -0.275042)
							(end -0.3048 -0.2032)
						)
						(arc
							(start -0.3048 0.2032)
							(mid -0.275042 0.275042)
							(end -0.2032 0.3048)
						)
						(arc
							(start 0.2032 0.3048)
							(mid 0.275042 0.275042)
							(end 0.3048 0.2032)
						)
					)
					(width 0)
					(fill yes)
				)
			)
		)
	)
	(footprint ""
		(layer "F.Cu")
		(at 87.007954 -212.420454 180)
		(property "Reference" "C348"
			(at 0 0 180)
			(layer "F.SilkS")
			(hide yes)
			(effects
				(font
					(size 1.27 1.27)
				)
			)
		)
		(property "Value" "SCD22U10V2KX-1GP"
			(at 1.1811 -2.7051 180)
			(unlocked yes)
			(layer "F.Fab")
			(hide yes)
			(effects
				(font
					(size 1.016 1.016)
					(thickness 0.1524)
				)
			)
		)
		(property "Device Type" "C402H22"
			(at 1.1811 -4.2291 180)
			(unlocked yes)
			(layer "F.Fab")
			(hide yes)
			(effects
				(font
					(size 1.016 1.016)
					(thickness 0.1524)
				)
			)
		)
		(duplicate_pad_numbers_are_jumpers no)
		(fp_rect
			(start -0.4318 0.9525)
			(end 0.4318 -0.9525)
			(stroke
				(width 0)
				(type default)
			)
			(fill no)
			(layer "F.CrtYd")
		)
		(fp_rect
			(start -0.4318 0.9525)
			(end 0.4318 -0.9525)
			(stroke
				(width 0)
				(type default)
			)
			(fill no)
			(layer "F.Fab")
		)
		(pad "1" smd custom
			(at 0 -0.4445 180)
			(size 0.1524 0.1524)
			(layers "F.Cu" "F.Mask" "F.Paste")
			(net "PCIE_TX_CAP_N66")
			(options
				(clearance outline)
				(anchor circle)
			)
			(primitives
				(gr_poly
					(pts
						(arc
							(start 0.3048 -0.2032)
							(mid 0.275042 -0.275042)
							(end 0.2032 -0.3048)
						)
						(arc
							(start -0.2032 -0.3048)
							(mid -0.275042 -0.275042)
							(end -0.3048 -0.2032)
						)
						(arc
							(start -0.3048 0.2032)
							(mid -0.275042 0.275042)
							(end -0.2032 0.3048)
						)
						(arc
							(start 0.2032 0.3048)
							(mid 0.275042 0.275042)
							(end 0.3048 0.2032)
						)
					)
					(width 0)
					(fill yes)
				)
			)
		)
		(pad "2" smd custom
			(at 0 0.4445 180)
			(size 0.1524 0.1524)
			(layers "F.Cu" "F.Mask" "F.Paste")
			(net "PCIE_TX_N66")
			(options
				(clearance outline)
				(anchor circle)
			)
			(primitives
				(gr_poly
					(pts
						(arc
							(start 0.3048 -0.2032)
							(mid 0.275042 -0.275042)
							(end 0.2032 -0.3048)
						)
						(arc
							(start -0.2032 -0.3048)
							(mid -0.275042 -0.275042)
							(end -0.3048 -0.2032)
						)
						(arc
							(start -0.3048 0.2032)
							(mid -0.275042 0.275042)
							(end -0.2032 0.3048)
						)
						(arc
							(start 0.2032 0.3048)
							(mid 0.275042 0.275042)
							(end 0.3048 0.2032)
						)
					)
					(width 0)
					(fill yes)
				)
			)
		)
	)
	(footprint ""
		(layer "F.Cu")
		(at 41.3766 -60.77966 180)
		(property "Reference" "R46"
			(at 0 0 180)
			(layer "F.SilkS")
			(hide yes)
			(effects
				(font
					(size 1.27 1.27)
				)
			)
		)
		(property "Value" "100KR2F-L1-GP"
			(at 0.064008 -3.993896 180)
			(unlocked yes)
			(layer "F.Fab")
			(hide yes)
			(effects
				(font
					(size 1.016 1.016)
					(thickness 0.1524)
				)
			)
		)
		(property "Device Type" "R402H16"
			(at 0.064008 -5.517896 180)
			(unlocked yes)
			(layer "F.Fab")
			(hide yes)
			(effects
				(font
					(size 1.016 1.016)
					(thickness 0.1524)
				)
			)
		)
		(duplicate_pad_numbers_are_jumpers no)
		(fp_line
			(start 0.508 -0.9398)
			(end -0.508 -0.9398)
			(stroke
				(width 0.1524)
				(type default)
			)
			(layer "F.SilkS")
		)
		(fp_line
			(start -0.508 -0.9398)
			(end -0.508 0.9398)
			(stroke
				(width 0.1524)
				(type default)
			)
			(layer "F.SilkS")
		)
		(fp_rect
			(start -0.508 0.9398)
			(end 0.508 -0.9398)
			(stroke
				(width 0)
				(type default)
			)
			(fill no)
			(layer "F.CrtYd")
		)
		(fp_rect
			(start -0.508 0.9398)
			(end 0.508 -0.9398)
			(stroke
				(width 0)
				(type default)
			)
			(fill no)
			(layer "F.Fab")
		)
		(pad "1" smd custom
			(at 0 -0.4445 180)
			(size 0.1397 0.1397)
			(layers "F.Cu" "F.Mask" "F.Paste")
			(net "USB5V_EN")
			(options
				(clearance outline)
				(anchor circle)
			)
			(primitives
				(gr_poly
					(pts
						(arc
							(start -0.1778 -0.2794)
							(mid -0.249642 -0.249642)
							(end -0.2794 -0.1778)
						)
						(arc
							(start -0.2794 0.1778)
							(mid -0.249642 0.249642)
							(end -0.1778 0.2794)
						)
						(arc
							(start 0.1778 0.2794)
							(mid 0.249642 0.249642)
							(end 0.2794 0.1778)
						)
						(arc
							(start 0.2794 -0.1778)
							(mid 0.249642 -0.249642)
							(end 0.1778 -0.2794)
						)
					)
					(width 0)
					(fill yes)
				)
			)
		)
		(pad "2" smd custom
			(at 0 0.4445 180)
			(size 0.1397 0.1397)
			(layers "F.Cu" "F.Mask" "F.Paste")
			(net "P5V_STBY")
			(options
				(clearance outline)
				(anchor circle)
			)
			(primitives
				(gr_poly
					(pts
						(arc
							(start -0.1778 -0.2794)
							(mid -0.249642 -0.249642)
							(end -0.2794 -0.1778)
						)
						(arc
							(start -0.2794 0.1778)
							(mid -0.249642 0.249642)
							(end -0.1778 0.2794)
						)
						(arc
							(start 0.1778 0.2794)
							(mid 0.249642 0.249642)
							(end 0.2794 0.1778)
						)
						(arc
							(start 0.2794 -0.1778)
							(mid 0.249642 -0.249642)
							(end 0.1778 -0.2794)
						)
					)
					(width 0)
					(fill yes)
				)
			)
		)
	)
	(footprint ""
		(layer "F.Cu")
		(at 246.7356 -9.0424)
		(property "Reference" "C477"
			(at 0 0 0)
			(layer "F.SilkS")
			(hide yes)
			(effects
				(font
					(size 1.27 1.27)
				)
			)
		)
		(property "Value" "SC4D7U16V5KX-1-GP"
			(at -0.0762 -6.1214 0)
			(unlocked yes)
			(layer "F.Fab")
			(hide yes)
			(effects
				(font
					(size 1.016 1.016)
					(thickness 0.1524)
				)
			)
		)
		(property "Device Type" "C805H56"
			(at -0.0762 -8.1534 0)
			(unlocked yes)
			(layer "F.Fab")
			(hide yes)
			(effects
				(font
					(size 1.016 1.016)
					(thickness 0.1524)
				)
			)
		)
		(duplicate_pad_numbers_are_jumpers no)
		(fp_line
			(start 0.635 0)
			(end -0.635 0)
			(stroke
				(width 0.508)
				(type default)
			)
			(layer "F.SilkS")
		)
		(fp_rect
			(start -0.9652 1.778)
			(end 0.9652 -1.778)
			(stroke
				(width 0)
				(type default)
			)
			(fill no)
			(layer "F.CrtYd")
		)
		(fp_poly
			(pts
				(xy -0.9652 -1.778) (xy 0.9652 -1.778) (xy 0.9652 1.778) (xy -0.9652 1.778)
			)
			(stroke
				(width 0)
				(type default)
			)
			(fill no)
			(layer "F.Fab")
		)
		(pad "1" smd rect
			(at 0 -0.9652)
			(size 1.397 1.143)
			(layers "F.Cu" "F.Mask" "F.Paste")
			(net "DUT_VDDO")
		)
		(pad "2" smd rect
			(at 0 0.9652)
			(size 1.397 1.143)
			(layers "F.Cu" "F.Mask" "F.Paste")
			(net "GND")
		)
	)
	(footprint ""
		(layer "F.Cu")
		(at 53.721 -122.428 -90)
		(property "Reference" "R801"
			(at 0 0 270)
			(layer "F.SilkS")
			(hide yes)
			(effects
				(font
					(size 1.27 1.27)
				)
			)
		)
		(property "Value" "4K7R2F-GP"
			(at 0.064008 -3.993896 270)
			(unlocked yes)
			(layer "F.Fab")
			(hide yes)
			(effects
				(font
					(size 1.016 1.016)
					(thickness 0.1524)
				)
			)
		)
		(property "Device Type" "R402H16"
			(at 0.064008 -5.517896 270)
			(unlocked yes)
			(layer "F.Fab")
			(hide yes)
			(effects
				(font
					(size 1.016 1.016)
					(thickness 0.1524)
				)
			)
		)
		(duplicate_pad_numbers_are_jumpers no)
		(fp_line
			(start -0.508 -0.9398)
			(end -0.508 0.9398)
			(stroke
				(width 0.1524)
				(type default)
			)
			(layer "F.SilkS")
		)
		(fp_line
			(start 0.508 -0.9398)
			(end -0.508 -0.9398)
			(stroke
				(width 0.1524)
				(type default)
			)
			(layer "F.SilkS")
		)
		(fp_rect
			(start -0.508 0.9398)
			(end 0.508 -0.9398)
			(stroke
				(width 0)
				(type default)
			)
			(fill no)
			(layer "F.CrtYd")
		)
		(fp_rect
			(start -0.508 0.9398)
			(end 0.508 -0.9398)
			(stroke
				(width 0)
				(type default)
			)
			(fill no)
			(layer "F.Fab")
		)
		(pad "1" smd custom
			(at 0 -0.4445 270)
			(size 0.1397 0.1397)
			(layers "F.Cu" "F.Mask" "F.Paste")
			(net "P3V3_STBY")
			(options
				(clearance outline)
				(anchor circle)
			)
			(primitives
				(gr_poly
					(pts
						(arc
							(start -0.1778 -0.2794)
							(mid -0.249642 -0.249642)
							(end -0.2794 -0.1778)
						)
						(arc
							(start -0.2794 0.1778)
							(mid -0.249642 0.249642)
							(end -0.1778 0.2794)
						)
						(arc
							(start 0.1778 0.2794)
							(mid 0.249642 0.249642)
							(end 0.2794 0.1778)
						)
						(arc
							(start 0.2794 -0.1778)
							(mid 0.249642 -0.249642)
							(end 0.1778 -0.2794)
						)
					)
					(width 0)
					(fill yes)
				)
			)
		)
		(pad "2" smd custom
			(at 0 0.4445 270)
			(size 0.1397 0.1397)
			(layers "F.Cu" "F.Mask" "F.Paste")
			(net "JTAG_BMC_TRST_N")
			(options
				(clearance outline)
				(anchor circle)
			)
			(primitives
				(gr_poly
					(pts
						(arc
							(start -0.1778 -0.2794)
							(mid -0.249642 -0.249642)
							(end -0.2794 -0.1778)
						)
						(arc
							(start -0.2794 0.1778)
							(mid -0.249642 0.249642)
							(end -0.1778 0.2794)
						)
						(arc
							(start 0.1778 0.2794)
							(mid 0.249642 0.249642)
							(end 0.2794 0.1778)
						)
						(arc
							(start 0.2794 -0.1778)
							(mid 0.249642 -0.249642)
							(end 0.1778 -0.2794)
						)
					)
					(width 0)
					(fill yes)
				)
			)
		)
	)
	(footprint ""
		(layer "F.Cu")
		(at 183.555386 -7.267702 -90)
		(property "Reference" "R2955"
			(at 0 0 270)
			(layer "F.SilkS")
			(hide yes)
			(effects
				(font
					(size 1.27 1.27)
				)
			)
		)
		(property "Value" "0R2J-2-GP"
			(at 0.064008 -3.993896 270)
			(unlocked yes)
			(layer "F.Fab")
			(hide yes)
			(effects
				(font
					(size 1.016 1.016)
					(thickness 0.1524)
				)
			)
		)
		(property "Device Type" "R402H16"
			(at 0.064008 -5.517896 270)
			(unlocked yes)
			(layer "F.Fab")
			(hide yes)
			(effects
				(font
					(size 1.016 1.016)
					(thickness 0.1524)
				)
			)
		)
		(duplicate_pad_numbers_are_jumpers no)
		(fp_line
			(start -0.508 -0.9398)
			(end -0.508 0.9398)
			(stroke
				(width 0.1524)
				(type default)
			)
			(layer "F.SilkS")
		)
		(fp_line
			(start 0.508 -0.9398)
			(end -0.508 -0.9398)
			(stroke
				(width 0.1524)
				(type default)
			)
			(layer "F.SilkS")
		)
		(fp_rect
			(start -0.508 0.9398)
			(end 0.508 -0.9398)
			(stroke
				(width 0)
				(type default)
			)
			(fill no)
			(layer "F.CrtYd")
		)
		(fp_rect
			(start -0.508 0.9398)
			(end 0.508 -0.9398)
			(stroke
				(width 0)
				(type default)
			)
			(fill no)
			(layer "F.Fab")
		)
		(pad "1" smd custom
			(at 0 -0.4445 270)
			(size 0.1397 0.1397)
			(layers "F.Cu" "F.Mask" "F.Paste")
			(net "HOST4_RST_N")
			(options
				(clearance outline)
				(anchor circle)
			)
			(primitives
				(gr_poly
					(pts
						(arc
							(start -0.1778 -0.2794)
							(mid -0.249642 -0.249642)
							(end -0.2794 -0.1778)
						)
						(arc
							(start -0.2794 0.1778)
							(mid -0.249642 0.249642)
							(end -0.1778 0.2794)
						)
						(arc
							(start 0.1778 0.2794)
							(mid 0.249642 0.249642)
							(end 0.2794 0.1778)
						)
						(arc
							(start 0.2794 -0.1778)
							(mid 0.249642 -0.249642)
							(end 0.1778 -0.2794)
						)
					)
					(width 0)
					(fill yes)
				)
			)
		)
		(pad "2" smd custom
			(at 0 0.4445 270)
			(size 0.1397 0.1397)
			(layers "F.Cu" "F.Mask" "F.Paste")
			(net "HOST4_RST_N_C")
			(options
				(clearance outline)
				(anchor circle)
			)
			(primitives
				(gr_poly
					(pts
						(arc
							(start -0.1778 -0.2794)
							(mid -0.249642 -0.249642)
							(end -0.2794 -0.1778)
						)
						(arc
							(start -0.2794 0.1778)
							(mid -0.249642 0.249642)
							(end -0.1778 0.2794)
						)
						(arc
							(start 0.1778 0.2794)
							(mid 0.249642 0.249642)
							(end 0.2794 0.1778)
						)
						(arc
							(start 0.2794 -0.1778)
							(mid 0.249642 -0.249642)
							(end 0.1778 -0.2794)
						)
					)
					(width 0)
					(fill yes)
				)
			)
		)
	)
	(footprint ""
		(layer "F.Cu")
		(at 122.0978 -101.4222)
		(property "Reference" "R862"
			(at 0 0 0)
			(layer "F.SilkS")
			(hide yes)
			(effects
				(font
					(size 1.27 1.27)
				)
			)
		)
		(property "Value" "0R2J-2-GP"
			(at 0.064008 -3.993896 0)
			(unlocked yes)
			(layer "F.Fab")
			(hide yes)
			(effects
				(font
					(size 1.016 1.016)
					(thickness 0.1524)
				)
			)
		)
		(property "Device Type" "R402H16"
			(at 0.064008 -5.517896 0)
			(unlocked yes)
			(layer "F.Fab")
			(hide yes)
			(effects
				(font
					(size 1.016 1.016)
					(thickness 0.1524)
				)
			)
		)
		(duplicate_pad_numbers_are_jumpers no)
		(fp_line
			(start -0.508 -0.9398)
			(end -0.508 0.9398)
			(stroke
				(width 0.1524)
				(type default)
			)
			(layer "F.SilkS")
		)
		(fp_line
			(start 0.508 -0.9398)
			(end -0.508 -0.9398)
			(stroke
				(width 0.1524)
				(type default)
			)
			(layer "F.SilkS")
		)
		(fp_rect
			(start -0.508 0.9398)
			(end 0.508 -0.9398)
			(stroke
				(width 0)
				(type default)
			)
			(fill no)
			(layer "F.CrtYd")
		)
		(fp_rect
			(start -0.508 0.9398)
			(end 0.508 -0.9398)
			(stroke
				(width 0)
				(type default)
			)
			(fill no)
			(layer "F.Fab")
		)
		(pad "1" smd custom
			(at 0 -0.4445)
			(size 0.1397 0.1397)
			(layers "F.Cu" "F.Mask" "F.Paste")
			(net "TWI_SCL0")
			(options
				(clearance outline)
				(anchor circle)
			)
			(primitives
				(gr_poly
					(pts
						(arc
							(start -0.1778 -0.2794)
							(mid -0.249642 -0.249642)
							(end -0.2794 -0.1778)
						)
						(arc
							(start -0.2794 0.1778)
							(mid -0.249642 0.249642)
							(end -0.1778 0.2794)
						)
						(arc
							(start 0.1778 0.2794)
							(mid 0.249642 0.249642)
							(end 0.2794 0.1778)
						)
						(arc
							(start 0.2794 -0.1778)
							(mid 0.249642 -0.249642)
							(end 0.1778 -0.2794)
						)
					)
					(width 0)
					(fill yes)
				)
			)
		)
		(pad "2" smd custom
			(at 0 0.4445)
			(size 0.1397 0.1397)
			(layers "F.Cu" "F.Mask" "F.Paste")
			(net "BUF_I2C_SCL_2_R")
			(options
				(clearance outline)
				(anchor circle)
			)
			(primitives
				(gr_poly
					(pts
						(arc
							(start -0.1778 -0.2794)
							(mid -0.249642 -0.249642)
							(end -0.2794 -0.1778)
						)
						(arc
							(start -0.2794 0.1778)
							(mid -0.249642 0.249642)
							(end -0.1778 0.2794)
						)
						(arc
							(start 0.1778 0.2794)
							(mid 0.249642 0.249642)
							(end 0.2794 0.1778)
						)
						(arc
							(start 0.2794 -0.1778)
							(mid 0.249642 -0.249642)
							(end 0.1778 -0.2794)
						)
					)
					(width 0)
					(fill yes)
				)
			)
		)
	)
	(footprint ""
		(layer "F.Cu")
		(at 35.2806 -184.8612 90)
		(property "Reference" "R964"
			(at 0 0 90)
			(layer "F.SilkS")
			(hide yes)
			(effects
				(font
					(size 1.27 1.27)
				)
			)
		)
		(property "Value" "0R2J-2-GP"
			(at 0.064008 -3.993896 90)
			(unlocked yes)
			(layer "F.Fab")
			(hide yes)
			(effects
				(font
					(size 1.016 1.016)
					(thickness 0.1524)
				)
			)
		)
		(property "Device Type" "R402H16"
			(at 0.064008 -5.517896 90)
			(unlocked yes)
			(layer "F.Fab")
			(hide yes)
			(effects
				(font
					(size 1.016 1.016)
					(thickness 0.1524)
				)
			)
		)
		(duplicate_pad_numbers_are_jumpers no)
		(fp_line
			(start 0.508 -0.9398)
			(end -0.508 -0.9398)
			(stroke
				(width 0.1524)
				(type default)
			)
			(layer "F.SilkS")
		)
		(fp_line
			(start -0.508 -0.9398)
			(end -0.508 0.9398)
			(stroke
				(width 0.1524)
				(type default)
			)
			(layer "F.SilkS")
		)
		(fp_rect
			(start -0.508 0.9398)
			(end 0.508 -0.9398)
			(stroke
				(width 0)
				(type default)
			)
			(fill no)
			(layer "F.CrtYd")
		)
		(fp_rect
			(start -0.508 0.9398)
			(end 0.508 -0.9398)
			(stroke
				(width 0)
				(type default)
			)
			(fill no)
			(layer "F.Fab")
		)
		(pad "1" smd custom
			(at 0 -0.4445 90)
			(size 0.1397 0.1397)
			(layers "F.Cu" "F.Mask" "F.Paste")
			(net "BUF_I2C5_SDA_R")
			(options
				(clearance outline)
				(anchor circle)
			)
			(primitives
				(gr_poly
					(pts
						(arc
							(start -0.1778 -0.2794)
							(mid -0.249642 -0.249642)
							(end -0.2794 -0.1778)
						)
						(arc
							(start -0.2794 0.1778)
							(mid -0.249642 0.249642)
							(end -0.1778 0.2794)
						)
						(arc
							(start 0.1778 0.2794)
							(mid 0.249642 0.249642)
							(end 0.2794 0.1778)
						)
						(arc
							(start 0.2794 -0.1778)
							(mid 0.249642 -0.249642)
							(end 0.1778 -0.2794)
						)
					)
					(width 0)
					(fill yes)
				)
			)
		)
		(pad "2" smd custom
			(at 0 0.4445 90)
			(size 0.1397 0.1397)
			(layers "F.Cu" "F.Mask" "F.Paste")
			(net "BMC_I2C5_D_PEB_DEVICE_SDA")
			(options
				(clearance outline)
				(anchor circle)
			)
			(primitives
				(gr_poly
					(pts
						(arc
							(start -0.1778 -0.2794)
							(mid -0.249642 -0.249642)
							(end -0.2794 -0.1778)
						)
						(arc
							(start -0.2794 0.1778)
							(mid -0.249642 0.249642)
							(end -0.1778 0.2794)
						)
						(arc
							(start 0.1778 0.2794)
							(mid 0.249642 0.249642)
							(end 0.2794 0.1778)
						)
						(arc
							(start 0.2794 -0.1778)
							(mid 0.249642 -0.249642)
							(end 0.1778 -0.2794)
						)
					)
					(width 0)
					(fill yes)
				)
			)
		)
	)
	(footprint ""
		(layer "F.Cu")
		(at 13.812012 -60.300108 90)
		(property "Reference" "PAD5"
			(at 0 0 90)
			(layer "F.SilkS")
			(hide yes)
			(effects
				(font
					(size 1.27 1.27)
				)
			)
		)
		(property "Value" "STF256R168H278-GP"
			(at -4.826 0.0508 90)
			(unlocked yes)
			(layer "F.Fab")
			(hide yes)
			(effects
				(font
					(size 1.016 1.016)
					(thickness 0.1524)
				)
			)
		)
		(property "Device Type" "STF256R168H278"
			(at -4.826 -1.4732 90)
			(unlocked yes)
			(layer "F.Fab")
			(hide yes)
			(effects
				(font
					(size 1.016 1.016)
					(thickness 0.1524)
				)
			)
		)
		(duplicate_pad_numbers_are_jumpers no)
		(fp_circle
			(center 0 0)
			(end 0 3.6068)
			(stroke
				(width 0.3048)
				(type default)
			)
			(fill no)
			(layer "F.SilkS")
		)
		(fp_poly
			(pts
				(arc
					(start 0 3.7592)
					(mid 0 -3.7592)
					(end 0 3.7592)
				)
			)
			(stroke
				(width 0)
				(type default)
			)
			(fill no)
			(layer "B.CrtYd")
		)
		(fp_poly
			(pts
				(arc
					(start 0 2.5019)
					(mid 0 -2.5019)
					(end 0 2.5019)
				)
			)
			(stroke
				(width 0)
				(type default)
			)
			(fill no)
			(layer "F.CrtYd")
		)
		(fp_poly
			(pts
				(arc
					(start 3.7592 0.00635)
					(mid -3.759205 0)
					(end 3.7592 -0.00635)
				)
				(arc
					(start 2.5019 -0.00635)
					(mid -2.501908 0)
					(end 2.5019 0.00635)
				)
			)
			(stroke
				(width 0)
				(type default)
			)
			(fill no)
			(layer "F.CrtYd")
		)
		(fp_poly
			(pts
				(arc
					(start 0 3.7592)
					(mid 0 -3.7592)
					(end 0 3.7592)
				)
			)
			(stroke
				(width 0)
				(type default)
			)
			(fill no)
			(layer "B.Fab")
		)
		(fp_poly
			(pts
				(arc
					(start 0 3.7592)
					(mid 0 -3.7592)
					(end 0 3.7592)
				)
			)
			(stroke
				(width 0)
				(type default)
			)
			(fill no)
			(layer "F.Fab")
		)
		(pad "1" thru_hole circle
			(at 0 0 90)
			(size 6.5024 6.5024)
			(drill 4.2672)
			(layers "*.Cu" "*.Mask")
			(remove_unused_layers no)
			(net "GND")
			(clearance -0.6096)
			(thermal_gap 0.3048)
			(padstack
				(mode front_inner_back)
				(layer "Inner"
					(shape circle)
					(size 4.6736 4.6736)
					(clearance 0.3048)
				)
				(layer "B.Cu"
					(shape circle)
					(size 6.5024 6.5024)
					(clearance -0.6096)
				)
			)
		)
	)
	(footprint ""
		(layer "F.Cu")
		(at 9.99998 -203.499974)
		(property "Reference" ""
			(at 0 0 0)
			(layer "F.SilkS")
			(hide yes)
			(effects
				(font
					(size 1.27 1.27)
				)
			)
		)
		(property "Value" "*"
			(at -0.1524 -7.3914 0)
			(unlocked yes)
			(layer "F.Fab")
			(hide yes)
			(effects
				(font
					(size 1.016 1.016)
					(thickness 0.1524)
				)
			)
		)
		(duplicate_pad_numbers_are_jumpers no)
		(fp_poly
			(pts
				(arc
					(start 4.3053 0)
					(mid -4.3053 0)
					(end 4.3053 0)
				)
			)
			(stroke
				(width 0)
				(type default)
			)
			(fill no)
			(layer "B.CrtYd")
		)
		(fp_poly
			(pts
				(arc
					(start 4.3053 0)
					(mid -4.3053 0)
					(end 4.3053 0)
				)
			)
			(stroke
				(width 0)
				(type default)
			)
			(fill no)
			(layer "F.CrtYd")
		)
		(fp_poly
			(pts
				(arc
					(start 4.3053 0)
					(mid -4.3053 0)
					(end 4.3053 0)
				)
			)
			(stroke
				(width 0)
				(type default)
			)
			(fill no)
			(layer "B.Fab")
		)
		(fp_poly
			(pts
				(arc
					(start 4.3053 0)
					(mid -4.3053 0)
					(end 4.3053 0)
				)
			)
			(stroke
				(width 0)
				(type default)
			)
			(fill no)
			(layer "F.Fab")
		)
		(pad "1" thru_hole circle
			(at 0 0)
			(size 8.001 8.001)
			(drill 3.81)
			(layers "*.Cu" "*.Mask")
			(remove_unused_layers no)
			(net "Net_114")
			(clearance -1.5875)
			(thermal_gap 0.3048)
			(padstack
				(mode front_inner_back)
				(layer "Inner"
					(shape circle)
					(size 4.2164 4.2164)
					(clearance 0.3048)
				)
				(layer "B.Cu"
					(shape circle)
					(size 8.001 8.001)
					(clearance -1.5875)
				)
			)
		)
	)
	(footprint ""
		(layer "F.Cu")
		(at 324.739 -86.487)
		(property "Reference" "R4159"
			(at 0 0 0)
			(layer "F.SilkS")
			(hide yes)
			(effects
				(font
					(size 1.27 1.27)
				)
			)
		)
		(property "Value" "4K7R2F-GP"
			(at 0.064008 -3.993896 0)
			(unlocked yes)
			(layer "F.Fab")
			(hide yes)
			(effects
				(font
					(size 1.016 1.016)
					(thickness 0.1524)
				)
			)
		)
		(property "Device Type" "R402H16"
			(at 0.064008 -5.517896 0)
			(unlocked yes)
			(layer "F.Fab")
			(hide yes)
			(effects
				(font
					(size 1.016 1.016)
					(thickness 0.1524)
				)
			)
		)
		(duplicate_pad_numbers_are_jumpers no)
		(fp_line
			(start -0.508 -0.9398)
			(end -0.508 0.9398)
			(stroke
				(width 0.1524)
				(type default)
			)
			(layer "F.SilkS")
		)
		(fp_line
			(start 0.508 -0.9398)
			(end -0.508 -0.9398)
			(stroke
				(width 0.1524)
				(type default)
			)
			(layer "F.SilkS")
		)
		(fp_rect
			(start -0.508 0.9398)
			(end 0.508 -0.9398)
			(stroke
				(width 0)
				(type default)
			)
			(fill no)
			(layer "F.CrtYd")
		)
		(fp_rect
			(start -0.508 0.9398)
			(end 0.508 -0.9398)
			(stroke
				(width 0)
				(type default)
			)
			(fill no)
			(layer "F.Fab")
		)
		(pad "1" smd custom
			(at 0 -0.4445)
			(size 0.1397 0.1397)
			(layers "F.Cu" "F.Mask" "F.Paste")
			(net "UPLINK2")
			(options
				(clearance outline)
				(anchor circle)
			)
			(primitives
				(gr_poly
					(pts
						(arc
							(start -0.1778 -0.2794)
							(mid -0.249642 -0.249642)
							(end -0.2794 -0.1778)
						)
						(arc
							(start -0.2794 0.1778)
							(mid -0.249642 0.249642)
							(end -0.1778 0.2794)
						)
						(arc
							(start 0.1778 0.2794)
							(mid 0.249642 0.249642)
							(end 0.2794 0.1778)
						)
						(arc
							(start 0.2794 -0.1778)
							(mid 0.249642 -0.249642)
							(end 0.1778 -0.2794)
						)
					)
					(width 0)
					(fill yes)
				)
			)
		)
		(pad "2" smd custom
			(at 0 0.4445)
			(size 0.1397 0.1397)
			(layers "F.Cu" "F.Mask" "F.Paste")
			(net "P3V3_STBY")
			(options
				(clearance outline)
				(anchor circle)
			)
			(primitives
				(gr_poly
					(pts
						(arc
							(start -0.1778 -0.2794)
							(mid -0.249642 -0.249642)
							(end -0.2794 -0.1778)
						)
						(arc
							(start -0.2794 0.1778)
							(mid -0.249642 0.249642)
							(end -0.1778 0.2794)
						)
						(arc
							(start 0.1778 0.2794)
							(mid 0.249642 0.249642)
							(end 0.2794 0.1778)
						)
						(arc
							(start 0.2794 -0.1778)
							(mid 0.249642 -0.249642)
							(end 0.1778 -0.2794)
						)
					)
					(width 0)
					(fill yes)
				)
			)
		)
	)
	(footprint ""
		(layer "F.Cu")
		(at 10.5791 -53.594 180)
		(property "Reference" "R595"
			(at 0 0 180)
			(layer "F.SilkS")
			(hide yes)
			(effects
				(font
					(size 1.27 1.27)
				)
			)
		)
		(property "Value" "0R2J-2-GP"
			(at 0.064008 -3.993896 180)
			(unlocked yes)
			(layer "F.Fab")
			(hide yes)
			(effects
				(font
					(size 1.016 1.016)
					(thickness 0.1524)
				)
			)
		)
		(property "Device Type" "R402H16"
			(at 0.064008 -5.517896 180)
			(unlocked yes)
			(layer "F.Fab")
			(hide yes)
			(effects
				(font
					(size 1.016 1.016)
					(thickness 0.1524)
				)
			)
		)
		(duplicate_pad_numbers_are_jumpers no)
		(fp_line
			(start 0.508 -0.9398)
			(end -0.508 -0.9398)
			(stroke
				(width 0.1524)
				(type default)
			)
			(layer "F.SilkS")
		)
		(fp_line
			(start -0.508 -0.9398)
			(end -0.508 0.9398)
			(stroke
				(width 0.1524)
				(type default)
			)
			(layer "F.SilkS")
		)
		(fp_rect
			(start -0.508 0.9398)
			(end 0.508 -0.9398)
			(stroke
				(width 0)
				(type default)
			)
			(fill no)
			(layer "F.CrtYd")
		)
		(fp_rect
			(start -0.508 0.9398)
			(end 0.508 -0.9398)
			(stroke
				(width 0)
				(type default)
			)
			(fill no)
			(layer "F.Fab")
		)
		(pad "1" smd custom
			(at 0 -0.4445 180)
			(size 0.1397 0.1397)
			(layers "F.Cu" "F.Mask" "F.Paste")
			(net "NIC0_MDI0_N0_R")
			(options
				(clearance outline)
				(anchor circle)
			)
			(primitives
				(gr_poly
					(pts
						(arc
							(start -0.1778 -0.2794)
							(mid -0.249642 -0.249642)
							(end -0.2794 -0.1778)
						)
						(arc
							(start -0.2794 0.1778)
							(mid -0.249642 0.249642)
							(end -0.1778 0.2794)
						)
						(arc
							(start 0.1778 0.2794)
							(mid 0.249642 0.249642)
							(end 0.2794 0.1778)
						)
						(arc
							(start 0.2794 -0.1778)
							(mid 0.249642 -0.249642)
							(end 0.1778 -0.2794)
						)
					)
					(width 0)
					(fill yes)
				)
			)
		)
		(pad "2" smd custom
			(at 0 0.4445 180)
			(size 0.1397 0.1397)
			(layers "F.Cu" "F.Mask" "F.Paste")
			(net "NIC0_MDI0_N0")
			(options
				(clearance outline)
				(anchor circle)
			)
			(primitives
				(gr_poly
					(pts
						(arc
							(start -0.1778 -0.2794)
							(mid -0.249642 -0.249642)
							(end -0.2794 -0.1778)
						)
						(arc
							(start -0.2794 0.1778)
							(mid -0.249642 0.249642)
							(end -0.1778 0.2794)
						)
						(arc
							(start 0.1778 0.2794)
							(mid 0.249642 0.249642)
							(end 0.2794 0.1778)
						)
						(arc
							(start 0.2794 -0.1778)
							(mid 0.249642 -0.249642)
							(end 0.1778 -0.2794)
						)
					)
					(width 0)
					(fill yes)
				)
			)
		)
	)
	(footprint ""
		(layer "F.Cu")
		(at 127.060452 -33.5915)
		(property "Reference" "R2934"
			(at 0 0 0)
			(layer "F.SilkS")
			(hide yes)
			(effects
				(font
					(size 1.27 1.27)
				)
			)
		)
		(property "Value" "0R2J-2-GP"
			(at 0.064008 -3.993896 0)
			(unlocked yes)
			(layer "F.Fab")
			(hide yes)
			(effects
				(font
					(size 1.016 1.016)
					(thickness 0.1524)
				)
			)
		)
		(property "Device Type" "R402H16"
			(at 0.064008 -5.517896 0)
			(unlocked yes)
			(layer "F.Fab")
			(hide yes)
			(effects
				(font
					(size 1.016 1.016)
					(thickness 0.1524)
				)
			)
		)
		(duplicate_pad_numbers_are_jumpers no)
		(fp_line
			(start -0.508 -0.9398)
			(end -0.508 0.9398)
			(stroke
				(width 0.1524)
				(type default)
			)
			(layer "F.SilkS")
		)
		(fp_line
			(start 0.508 -0.9398)
			(end -0.508 -0.9398)
			(stroke
				(width 0.1524)
				(type default)
			)
			(layer "F.SilkS")
		)
		(fp_rect
			(start -0.508 0.9398)
			(end 0.508 -0.9398)
			(stroke
				(width 0)
				(type default)
			)
			(fill no)
			(layer "F.CrtYd")
		)
		(fp_rect
			(start -0.508 0.9398)
			(end 0.508 -0.9398)
			(stroke
				(width 0)
				(type default)
			)
			(fill no)
			(layer "F.Fab")
		)
		(pad "1" smd custom
			(at 0 -0.4445)
			(size 0.1397 0.1397)
			(layers "F.Cu" "F.Mask" "F.Paste")
			(net "USB2_BMC_DN")
			(options
				(clearance outline)
				(anchor circle)
			)
			(primitives
				(gr_poly
					(pts
						(arc
							(start -0.1778 -0.2794)
							(mid -0.249642 -0.249642)
							(end -0.2794 -0.1778)
						)
						(arc
							(start -0.2794 0.1778)
							(mid -0.249642 0.249642)
							(end -0.1778 0.2794)
						)
						(arc
							(start 0.1778 0.2794)
							(mid 0.249642 0.249642)
							(end 0.2794 0.1778)
						)
						(arc
							(start 0.2794 -0.1778)
							(mid 0.249642 -0.249642)
							(end 0.1778 -0.2794)
						)
					)
					(width 0)
					(fill yes)
				)
			)
		)
		(pad "2" smd custom
			(at 0 0.4445)
			(size 0.1397 0.1397)
			(layers "F.Cu" "F.Mask" "F.Paste")
			(net "8644_USB_DN1")
			(options
				(clearance outline)
				(anchor circle)
			)
			(primitives
				(gr_poly
					(pts
						(arc
							(start -0.1778 -0.2794)
							(mid -0.249642 -0.249642)
							(end -0.2794 -0.1778)
						)
						(arc
							(start -0.2794 0.1778)
							(mid -0.249642 0.249642)
							(end -0.1778 0.2794)
						)
						(arc
							(start 0.1778 0.2794)
							(mid 0.249642 0.249642)
							(end 0.2794 0.1778)
						)
						(arc
							(start 0.2794 -0.1778)
							(mid 0.249642 -0.249642)
							(end 0.1778 -0.2794)
						)
					)
					(width 0)
					(fill yes)
				)
			)
		)
	)
	(footprint ""
		(layer "F.Cu")
		(at 298.063666 -33.495234 180)
		(property "Reference" "R720"
			(at 0 0 180)
			(layer "F.SilkS")
			(hide yes)
			(effects
				(font
					(size 1.27 1.27)
				)
			)
		)
		(property "Value" "0R2J-2-GP"
			(at 0.064008 -3.993896 180)
			(unlocked yes)
			(layer "F.Fab")
			(hide yes)
			(effects
				(font
					(size 1.016 1.016)
					(thickness 0.1524)
				)
			)
		)
		(property "Device Type" "R402H16"
			(at 0.064008 -5.517896 180)
			(unlocked yes)
			(layer "F.Fab")
			(hide yes)
			(effects
				(font
					(size 1.016 1.016)
					(thickness 0.1524)
				)
			)
		)
		(duplicate_pad_numbers_are_jumpers no)
		(fp_line
			(start 0.508 -0.9398)
			(end -0.508 -0.9398)
			(stroke
				(width 0.1524)
				(type default)
			)
			(layer "F.SilkS")
		)
		(fp_line
			(start -0.508 -0.9398)
			(end -0.508 0.9398)
			(stroke
				(width 0.1524)
				(type default)
			)
			(layer "F.SilkS")
		)
		(fp_rect
			(start -0.508 0.9398)
			(end 0.508 -0.9398)
			(stroke
				(width 0)
				(type default)
			)
			(fill no)
			(layer "F.CrtYd")
		)
		(fp_rect
			(start -0.508 0.9398)
			(end 0.508 -0.9398)
			(stroke
				(width 0)
				(type default)
			)
			(fill no)
			(layer "F.Fab")
		)
		(pad "1" smd custom
			(at 0 -0.4445 180)
			(size 0.1397 0.1397)
			(layers "F.Cu" "F.Mask" "F.Paste")
			(net "8644_USB_DP6")
			(options
				(clearance outline)
				(anchor circle)
			)
			(primitives
				(gr_poly
					(pts
						(arc
							(start -0.1778 -0.2794)
							(mid -0.249642 -0.249642)
							(end -0.2794 -0.1778)
						)
						(arc
							(start -0.2794 0.1778)
							(mid -0.249642 0.249642)
							(end -0.1778 0.2794)
						)
						(arc
							(start 0.1778 0.2794)
							(mid 0.249642 0.249642)
							(end 0.2794 0.1778)
						)
						(arc
							(start 0.2794 -0.1778)
							(mid 0.249642 -0.249642)
							(end 0.1778 -0.2794)
						)
					)
					(width 0)
					(fill yes)
				)
			)
		)
		(pad "2" smd custom
			(at 0 0.4445 180)
			(size 0.1397 0.1397)
			(layers "F.Cu" "F.Mask" "F.Paste")
			(net "P3V3_STBY")
			(options
				(clearance outline)
				(anchor circle)
			)
			(primitives
				(gr_poly
					(pts
						(arc
							(start -0.1778 -0.2794)
							(mid -0.249642 -0.249642)
							(end -0.2794 -0.1778)
						)
						(arc
							(start -0.2794 0.1778)
							(mid -0.249642 0.249642)
							(end -0.1778 0.2794)
						)
						(arc
							(start 0.1778 0.2794)
							(mid 0.249642 0.249642)
							(end 0.2794 0.1778)
						)
						(arc
							(start 0.2794 -0.1778)
							(mid 0.249642 -0.249642)
							(end 0.1778 -0.2794)
						)
					)
					(width 0)
					(fill yes)
				)
			)
		)
	)
	(footprint ""
		(layer "F.Cu")
		(at 158.461202 -60.479432 90)
		(property "Reference" "PR628"
			(at 0 0 90)
			(layer "F.SilkS")
			(hide yes)
			(effects
				(font
					(size 1.27 1.27)
				)
			)
		)
		(property "Value" "4K7R2F-GP"
			(at 0.064008 -3.993896 90)
			(unlocked yes)
			(layer "F.Fab")
			(hide yes)
			(effects
				(font
					(size 1.016 1.016)
					(thickness 0.1524)
				)
			)
		)
		(property "Device Type" "R402H16"
			(at 0.064008 -5.517896 90)
			(unlocked yes)
			(layer "F.Fab")
			(hide yes)
			(effects
				(font
					(size 1.016 1.016)
					(thickness 0.1524)
				)
			)
		)
		(duplicate_pad_numbers_are_jumpers no)
		(fp_line
			(start 0.508 -0.9398)
			(end -0.508 -0.9398)
			(stroke
				(width 0.1524)
				(type default)
			)
			(layer "F.SilkS")
		)
		(fp_line
			(start -0.508 -0.9398)
			(end -0.508 0.9398)
			(stroke
				(width 0.1524)
				(type default)
			)
			(layer "F.SilkS")
		)
		(fp_rect
			(start -0.508 0.9398)
			(end 0.508 -0.9398)
			(stroke
				(width 0)
				(type default)
			)
			(fill no)
			(layer "F.CrtYd")
		)
		(fp_rect
			(start -0.508 0.9398)
			(end 0.508 -0.9398)
			(stroke
				(width 0)
				(type default)
			)
			(fill no)
			(layer "F.Fab")
		)
		(pad "1" smd custom
			(at 0 -0.4445 90)
			(size 0.1397 0.1397)
			(layers "F.Cu" "F.Mask" "F.Paste")
			(net "P0V9_PG")
			(options
				(clearance outline)
				(anchor circle)
			)
			(primitives
				(gr_poly
					(pts
						(arc
							(start -0.1778 -0.2794)
							(mid -0.249642 -0.249642)
							(end -0.2794 -0.1778)
						)
						(arc
							(start -0.2794 0.1778)
							(mid -0.249642 0.249642)
							(end -0.1778 0.2794)
						)
						(arc
							(start 0.1778 0.2794)
							(mid 0.249642 0.249642)
							(end 0.2794 0.1778)
						)
						(arc
							(start 0.2794 -0.1778)
							(mid 0.249642 -0.249642)
							(end 0.1778 -0.2794)
						)
					)
					(width 0)
					(fill yes)
				)
			)
		)
		(pad "2" smd custom
			(at 0 0.4445 90)
			(size 0.1397 0.1397)
			(layers "F.Cu" "F.Mask" "F.Paste")
			(net "P3V3_STBY")
			(options
				(clearance outline)
				(anchor circle)
			)
			(primitives
				(gr_poly
					(pts
						(arc
							(start -0.1778 -0.2794)
							(mid -0.249642 -0.249642)
							(end -0.2794 -0.1778)
						)
						(arc
							(start -0.2794 0.1778)
							(mid -0.249642 0.249642)
							(end -0.1778 0.2794)
						)
						(arc
							(start 0.1778 0.2794)
							(mid 0.249642 0.249642)
							(end 0.2794 0.1778)
						)
						(arc
							(start 0.2794 -0.1778)
							(mid 0.249642 -0.249642)
							(end 0.1778 -0.2794)
						)
					)
					(width 0)
					(fill yes)
				)
			)
		)
	)
	(footprint ""
		(layer "F.Cu")
		(at 339.598 -71.501 180)
		(property "Reference" "PSP2"
			(at 0 0 180)
			(layer "F.SilkS")
			(hide yes)
			(effects
				(font
					(size 1.27 1.27)
				)
			)
		)
		(property "Value" "COPPER-CLOSE-GP-U"
			(at 0.0762 -2.8702 180)
			(unlocked yes)
			(layer "F.Fab")
			(hide yes)
			(effects
				(font
					(size 1.016 1.016)
					(thickness 0.1524)
				)
			)
		)
		(property "Device Type" "CON2C-U"
			(at 0.0762 -4.3942 180)
			(unlocked yes)
			(layer "F.Fab")
			(hide yes)
			(effects
				(font
					(size 1.016 1.016)
					(thickness 0.1524)
				)
			)
		)
		(duplicate_pad_numbers_are_jumpers no)
		(fp_rect
			(start -0.9398 0.9652)
			(end 0.9398 -0.9652)
			(stroke
				(width 0)
				(type default)
			)
			(fill no)
			(layer "F.CrtYd")
		)
		(fp_rect
			(start -0.9398 0.9652)
			(end 0.9398 -0.9652)
			(stroke
				(width 0)
				(type default)
			)
			(fill no)
			(layer "F.Fab")
		)
		(pad "1" smd custom
			(at 0 -0.5334 180)
			(size 0.17145 0.17145)
			(layers "F.Cu" "F.Mask" "F.Paste")
			(net "GND")
			(options
				(clearance outline)
				(anchor circle)
			)
			(primitives
				(gr_poly
					(pts
						(xy -0.127 0.3429) (xy -0.127 0.1651) (xy -0.635 -0.3429) (xy 0.635 -0.3429) (xy 0.127 0.1651)
						(xy 0.127 0.3429)
					)
					(width 0)
					(fill yes)
				)
			)
		)
		(pad "2" smd custom
			(at 0 0.5334 180)
			(size 0.17145 0.17145)
			(layers "F.Cu" "F.Mask" "F.Paste")
			(net "AGND_P0V9_E")
			(options
				(clearance outline)
				(anchor circle)
			)
			(primitives
				(gr_poly
					(pts
						(xy -0.635 0.3429) (xy -0.127 -0.1651) (xy -0.127 -0.3429) (xy 0.127 -0.3429) (xy 0.127 -0.1651)
						(xy 0.635 0.3429)
					)
					(width 0)
					(fill yes)
				)
			)
		)
	)
	(footprint ""
		(layer "F.Cu")
		(at 310.007 -62.4586)
		(property "Reference" "PG44"
			(at 0 0 0)
			(layer "F.SilkS")
			(hide yes)
			(effects
				(font
					(size 1.27 1.27)
				)
			)
		)
		(property "Value" "GAP-CLOSE-PWR-3-GP"
			(at 0.0254 -6.5786 0)
			(unlocked yes)
			(layer "F.Fab")
			(hide yes)
			(effects
				(font
					(size 1.016 1.016)
					(thickness 0.1524)
				)
			)
		)
		(property "Device Type" "GAP-CLOSE-PWR-3"
			(at 0.0254 -8.255 0)
			(unlocked yes)
			(layer "F.Fab")
			(hide yes)
			(effects
				(font
					(size 1.016 1.016)
					(thickness 0.1524)
				)
			)
		)
		(duplicate_pad_numbers_are_jumpers no)
		(fp_rect
			(start -0.7112 0.4572)
			(end 0.7112 -0.4572)
			(stroke
				(width 0)
				(type default)
			)
			(fill no)
			(layer "F.CrtYd")
		)
		(fp_poly
			(pts
				(xy -0.7112 -0.4572) (xy 0.7112 -0.4572) (xy 0.7112 0.4572) (xy -0.7112 0.4572)
			)
			(stroke
				(width 0)
				(type default)
			)
			(fill no)
			(layer "F.Fab")
		)
		(pad "1" smd rect
			(at -0.3048 0)
			(size 0.6604 0.762)
			(layers "F.Cu" "F.Mask" "F.Paste")
			(net "DUT_VDD")
		)
		(pad "2" smd rect
			(at 0.3048 0)
			(size 0.6604 0.762)
			(layers "F.Cu" "F.Mask" "F.Paste")
			(net "P0V9_E")
		)
	)
	(footprint ""
		(layer "F.Cu")
		(at 340.233 -52.07 -90)
		(property "Reference" "PC216"
			(at 0 0 270)
			(layer "F.SilkS")
			(hide yes)
			(effects
				(font
					(size 1.27 1.27)
				)
			)
		)
		(property "Value" "SC22U25V6KX-GP-U"
			(at -2.860802 -5.279644 270)
			(unlocked yes)
			(layer "F.Fab")
			(hide yes)
			(effects
				(font
					(size 1.016 1.016)
					(thickness 0.1524)
				)
			)
		)
		(property "Device Type" "C1206-TO0D3H75"
			(at -2.860802 -6.803644 270)
			(unlocked yes)
			(layer "F.Fab")
			(hide yes)
			(effects
				(font
					(size 1.016 1.016)
					(thickness 0.1524)
				)
			)
		)
		(duplicate_pad_numbers_are_jumpers no)
		(fp_line
			(start -1.3081 2.3749)
			(end -1.3081 -2.3749)
			(stroke
				(width 0.1524)
				(type default)
			)
			(layer "F.SilkS")
		)
		(fp_line
			(start 1.3081 2.3749)
			(end -1.3081 2.3749)
			(stroke
				(width 0.1524)
				(type default)
			)
			(layer "F.SilkS")
		)
		(fp_line
			(start -1.3081 -2.3749)
			(end 1.3081 -2.3749)
			(stroke
				(width 0.1524)
				(type default)
			)
			(layer "F.SilkS")
		)
		(fp_line
			(start 1.3081 -2.3749)
			(end 1.3081 2.3749)
			(stroke
				(width 0.1524)
				(type default)
			)
			(layer "F.SilkS")
		)
		(fp_rect
			(start -0.8001 1.6002)
			(end 0.8001 -1.6002)
			(stroke
				(width 0)
				(type default)
			)
			(fill no)
			(layer "F.CrtYd")
		)
		(fp_poly
			(pts
				(xy -1.5621 2.4511) (xy -1.5621 1.6002) (xy 0.8001 1.6002) (xy 0.8001 -1.6002) (xy -0.8001 -1.6002)
				(xy -0.8001 1.5875) (xy -1.5621 1.5875) (xy -1.5621 -2.4511) (xy 1.5621 -2.4511) (xy 1.5621 2.4511)
			)
			(stroke
				(width 0)
				(type default)
			)
			(fill no)
			(layer "F.CrtYd")
		)
		(fp_rect
			(start -1.5621 2.4511)
			(end 1.5621 -2.4511)
			(stroke
				(width 0)
				(type default)
			)
			(fill no)
			(layer "F.Fab")
		)
		(pad "1" smd rect
			(at 0 -1.392936 270)
			(size 2.1082 1.4478)
			(layers "F.Cu" "F.Mask" "F.Paste")
			(net "P0V9_E_VIN")
		)
		(pad "2" smd rect
			(at 0 1.392936 270)
			(size 2.1082 1.4478)
			(layers "F.Cu" "F.Mask" "F.Paste")
			(net "GND")
		)
	)
	(footprint ""
		(layer "F.Cu")
		(at 205.359 -21.971 -90)
		(property "Reference" "R69"
			(at 0 0 270)
			(layer "F.SilkS")
			(hide yes)
			(effects
				(font
					(size 1.27 1.27)
				)
			)
		)
		(property "Value" "0R2J-2-GP"
			(at 0.064008 -3.993896 270)
			(unlocked yes)
			(layer "F.Fab")
			(hide yes)
			(effects
				(font
					(size 1.016 1.016)
					(thickness 0.1524)
				)
			)
		)
		(property "Device Type" "R402H16"
			(at 0.064008 -5.517896 270)
			(unlocked yes)
			(layer "F.Fab")
			(hide yes)
			(effects
				(font
					(size 1.016 1.016)
					(thickness 0.1524)
				)
			)
		)
		(duplicate_pad_numbers_are_jumpers no)
		(fp_line
			(start -0.508 -0.9398)
			(end -0.508 0.9398)
			(stroke
				(width 0.1524)
				(type default)
			)
			(layer "F.SilkS")
		)
		(fp_line
			(start 0.508 -0.9398)
			(end -0.508 -0.9398)
			(stroke
				(width 0.1524)
				(type default)
			)
			(layer "F.SilkS")
		)
		(fp_rect
			(start -0.508 0.9398)
			(end 0.508 -0.9398)
			(stroke
				(width 0)
				(type default)
			)
			(fill no)
			(layer "F.CrtYd")
		)
		(fp_rect
			(start -0.508 0.9398)
			(end 0.508 -0.9398)
			(stroke
				(width 0)
				(type default)
			)
			(fill no)
			(layer "F.Fab")
		)
		(pad "1" smd custom
			(at 0 -0.4445 270)
			(size 0.1397 0.1397)
			(layers "F.Cu" "F.Mask" "F.Paste")
			(net "TCA9554_INT_N")
			(options
				(clearance outline)
				(anchor circle)
			)
			(primitives
				(gr_poly
					(pts
						(arc
							(start -0.1778 -0.2794)
							(mid -0.249642 -0.249642)
							(end -0.2794 -0.1778)
						)
						(arc
							(start -0.2794 0.1778)
							(mid -0.249642 0.249642)
							(end -0.1778 0.2794)
						)
						(arc
							(start 0.1778 0.2794)
							(mid 0.249642 0.249642)
							(end 0.2794 0.1778)
						)
						(arc
							(start 0.2794 -0.1778)
							(mid 0.249642 -0.249642)
							(end 0.1778 -0.2794)
						)
					)
					(width 0)
					(fill yes)
				)
			)
		)
		(pad "2" smd custom
			(at 0 0.4445 270)
			(size 0.1397 0.1397)
			(layers "F.Cu" "F.Mask" "F.Paste")
			(net "U56_INT_N")
			(options
				(clearance outline)
				(anchor circle)
			)
			(primitives
				(gr_poly
					(pts
						(arc
							(start -0.1778 -0.2794)
							(mid -0.249642 -0.249642)
							(end -0.2794 -0.1778)
						)
						(arc
							(start -0.2794 0.1778)
							(mid -0.249642 0.249642)
							(end -0.1778 0.2794)
						)
						(arc
							(start 0.1778 0.2794)
							(mid 0.249642 0.249642)
							(end 0.2794 0.1778)
						)
						(arc
							(start 0.2794 -0.1778)
							(mid 0.249642 -0.249642)
							(end 0.1778 -0.2794)
						)
					)
					(width 0)
					(fill yes)
				)
			)
		)
	)
	(footprint ""
		(layer "F.Cu")
		(at 51.562 -135.763)
		(property "Reference" "TP160"
			(at 0 0 0)
			(layer "F.SilkS")
			(hide yes)
			(effects
				(font
					(size 1.27 1.27)
				)
			)
		)
		(property "Value" "TPAD28-2-GP"
			(at -0.0127 -1.6637 0)
			(unlocked yes)
			(layer "F.Fab")
			(hide yes)
			(effects
				(font
					(size 1.016 1.016)
					(thickness 0.1524)
				)
			)
		)
		(property "Device Type" "TPAD28"
			(at -0.0127 -3.1877 0)
			(unlocked yes)
			(layer "F.Fab")
			(hide yes)
			(effects
				(font
					(size 1.016 1.016)
					(thickness 0.1524)
				)
			)
		)
		(duplicate_pad_numbers_are_jumpers no)
		(fp_poly
			(pts
				(arc
					(start 0.3556 0)
					(mid -0.3556 0)
					(end 0.3556 0)
				)
			)
			(stroke
				(width 0)
				(type default)
			)
			(fill no)
			(layer "F.CrtYd")
		)
		(fp_poly
			(pts
				(arc
					(start 0.6096 0)
					(mid -0.6096 0)
					(end 0.6096 0)
				)
			)
			(stroke
				(width 0)
				(type default)
			)
			(fill no)
			(layer "F.Fab")
		)
		(pad "1" smd circle
			(at 0 0)
			(size 0.7112 0.7112)
			(layers "F.Cu" "F.Mask" "F.Paste")
			(net "TP_BMC_GPIOJ5")
		)
	)
	(footprint ""
		(layer "F.Cu")
		(at 121.276364 -46.86808)
		(property "Reference" "R933"
			(at 0 0 0)
			(layer "F.SilkS")
			(hide yes)
			(effects
				(font
					(size 1.27 1.27)
				)
			)
		)
		(property "Value" "4K7R2F-GP"
			(at 0.064008 -3.993896 0)
			(unlocked yes)
			(layer "F.Fab")
			(hide yes)
			(effects
				(font
					(size 1.016 1.016)
					(thickness 0.1524)
				)
			)
		)
		(property "Device Type" "R402H16"
			(at 0.064008 -5.517896 0)
			(unlocked yes)
			(layer "F.Fab")
			(hide yes)
			(effects
				(font
					(size 1.016 1.016)
					(thickness 0.1524)
				)
			)
		)
		(duplicate_pad_numbers_are_jumpers no)
		(fp_line
			(start -0.508 -0.9398)
			(end -0.508 0.9398)
			(stroke
				(width 0.1524)
				(type default)
			)
			(layer "F.SilkS")
		)
		(fp_line
			(start 0.508 -0.9398)
			(end -0.508 -0.9398)
			(stroke
				(width 0.1524)
				(type default)
			)
			(layer "F.SilkS")
		)
		(fp_rect
			(start -0.508 0.9398)
			(end 0.508 -0.9398)
			(stroke
				(width 0)
				(type default)
			)
			(fill no)
			(layer "F.CrtYd")
		)
		(fp_rect
			(start -0.508 0.9398)
			(end 0.508 -0.9398)
			(stroke
				(width 0)
				(type default)
			)
			(fill no)
			(layer "F.Fab")
		)
		(pad "1" smd custom
			(at 0 -0.4445)
			(size 0.1397 0.1397)
			(layers "F.Cu" "F.Mask" "F.Paste")
			(net "P3V3_STBY")
			(options
				(clearance outline)
				(anchor circle)
			)
			(primitives
				(gr_poly
					(pts
						(arc
							(start -0.1778 -0.2794)
							(mid -0.249642 -0.249642)
							(end -0.2794 -0.1778)
						)
						(arc
							(start -0.2794 0.1778)
							(mid -0.249642 0.249642)
							(end -0.1778 0.2794)
						)
						(arc
							(start 0.1778 0.2794)
							(mid 0.249642 0.249642)
							(end 0.2794 0.1778)
						)
						(arc
							(start 0.2794 -0.1778)
							(mid 0.249642 -0.249642)
							(end 0.1778 -0.2794)
						)
					)
					(width 0)
					(fill yes)
				)
			)
		)
		(pad "2" smd custom
			(at 0 0.4445)
			(size 0.1397 0.1397)
			(layers "F.Cu" "F.Mask" "F.Paste")
			(net "BMC_ADD2_PWR")
			(options
				(clearance outline)
				(anchor circle)
			)
			(primitives
				(gr_poly
					(pts
						(arc
							(start -0.1778 -0.2794)
							(mid -0.249642 -0.249642)
							(end -0.2794 -0.1778)
						)
						(arc
							(start -0.2794 0.1778)
							(mid -0.249642 0.249642)
							(end -0.1778 0.2794)
						)
						(arc
							(start 0.1778 0.2794)
							(mid 0.249642 0.249642)
							(end 0.2794 0.1778)
						)
						(arc
							(start 0.2794 -0.1778)
							(mid 0.249642 -0.249642)
							(end 0.1778 -0.2794)
						)
					)
					(width 0)
					(fill yes)
				)
			)
		)
	)
	(footprint ""
		(layer "F.Cu")
		(at 217.0176 -4.064)
		(property "Reference" "R665"
			(at 0 0 0)
			(layer "F.SilkS")
			(hide yes)
			(effects
				(font
					(size 1.27 1.27)
				)
			)
		)
		(property "Value" "4K7R2F-GP"
			(at 0.064008 -3.993896 0)
			(unlocked yes)
			(layer "F.Fab")
			(hide yes)
			(effects
				(font
					(size 1.016 1.016)
					(thickness 0.1524)
				)
			)
		)
		(property "Device Type" "R402H16"
			(at 0.064008 -5.517896 0)
			(unlocked yes)
			(layer "F.Fab")
			(hide yes)
			(effects
				(font
					(size 1.016 1.016)
					(thickness 0.1524)
				)
			)
		)
		(duplicate_pad_numbers_are_jumpers no)
		(fp_line
			(start -0.508 -0.9398)
			(end -0.508 0.9398)
			(stroke
				(width 0.1524)
				(type default)
			)
			(layer "F.SilkS")
		)
		(fp_line
			(start 0.508 -0.9398)
			(end -0.508 -0.9398)
			(stroke
				(width 0.1524)
				(type default)
			)
			(layer "F.SilkS")
		)
		(fp_rect
			(start -0.508 0.9398)
			(end 0.508 -0.9398)
			(stroke
				(width 0)
				(type default)
			)
			(fill no)
			(layer "F.CrtYd")
		)
		(fp_rect
			(start -0.508 0.9398)
			(end 0.508 -0.9398)
			(stroke
				(width 0)
				(type default)
			)
			(fill no)
			(layer "F.Fab")
		)
		(pad "1" smd custom
			(at 0 -0.4445)
			(size 0.1397 0.1397)
			(layers "F.Cu" "F.Mask" "F.Paste")
			(net "Q3202_D")
			(options
				(clearance outline)
				(anchor circle)
			)
			(primitives
				(gr_poly
					(pts
						(arc
							(start -0.1778 -0.2794)
							(mid -0.249642 -0.249642)
							(end -0.2794 -0.1778)
						)
						(arc
							(start -0.2794 0.1778)
							(mid -0.249642 0.249642)
							(end -0.1778 0.2794)
						)
						(arc
							(start 0.1778 0.2794)
							(mid 0.249642 0.249642)
							(end 0.2794 0.1778)
						)
						(arc
							(start 0.2794 -0.1778)
							(mid 0.249642 -0.249642)
							(end 0.1778 -0.2794)
						)
					)
					(width 0)
					(fill yes)
				)
			)
		)
		(pad "2" smd custom
			(at 0 0.4445)
			(size 0.1397 0.1397)
			(layers "F.Cu" "F.Mask" "F.Paste")
			(net "DUT_VDDO")
			(options
				(clearance outline)
				(anchor circle)
			)
			(primitives
				(gr_poly
					(pts
						(arc
							(start -0.1778 -0.2794)
							(mid -0.249642 -0.249642)
							(end -0.2794 -0.1778)
						)
						(arc
							(start -0.2794 0.1778)
							(mid -0.249642 0.249642)
							(end -0.1778 0.2794)
						)
						(arc
							(start 0.1778 0.2794)
							(mid 0.249642 0.249642)
							(end 0.2794 0.1778)
						)
						(arc
							(start 0.2794 -0.1778)
							(mid 0.249642 -0.249642)
							(end 0.1778 -0.2794)
						)
					)
					(width 0)
					(fill yes)
				)
			)
		)
	)
	(footprint ""
		(layer "F.Cu")
		(at 184.785 -71.628 180)
		(property "Reference" "C552"
			(at 0 0 180)
			(layer "F.SilkS")
			(hide yes)
			(effects
				(font
					(size 1.27 1.27)
				)
			)
		)
		(property "Value" "SC4D7U16V5KX-1-GP"
			(at -0.0762 -6.1214 180)
			(unlocked yes)
			(layer "F.Fab")
			(hide yes)
			(effects
				(font
					(size 1.016 1.016)
					(thickness 0.1524)
				)
			)
		)
		(property "Device Type" "C805H56"
			(at -0.0762 -8.1534 180)
			(unlocked yes)
			(layer "F.Fab")
			(hide yes)
			(effects
				(font
					(size 1.016 1.016)
					(thickness 0.1524)
				)
			)
		)
		(duplicate_pad_numbers_are_jumpers no)
		(fp_line
			(start 0.635 0)
			(end -0.635 0)
			(stroke
				(width 0.508)
				(type default)
			)
			(layer "F.SilkS")
		)
		(fp_rect
			(start -0.9652 1.778)
			(end 0.9652 -1.778)
			(stroke
				(width 0)
				(type default)
			)
			(fill no)
			(layer "F.CrtYd")
		)
		(fp_poly
			(pts
				(xy -0.9652 -1.778) (xy 0.9652 -1.778) (xy 0.9652 1.778) (xy -0.9652 1.778)
			)
			(stroke
				(width 0)
				(type default)
			)
			(fill no)
			(layer "F.Fab")
		)
		(pad "1" smd rect
			(at 0 -0.9652 180)
			(size 1.397 1.143)
			(layers "F.Cu" "F.Mask" "F.Paste")
			(net "DUT_AVD_PCIE")
		)
		(pad "2" smd rect
			(at 0 0.9652 180)
			(size 1.397 1.143)
			(layers "F.Cu" "F.Mask" "F.Paste")
			(net "GND")
		)
	)
	(footprint ""
		(layer "F.Cu")
		(at 32.3596 -103.2764 180)
		(property "Reference" "R695"
			(at 0 0 180)
			(layer "F.SilkS")
			(hide yes)
			(effects
				(font
					(size 1.27 1.27)
				)
			)
		)
		(property "Value" "4K7R2F-GP"
			(at 0.064008 -3.993896 180)
			(unlocked yes)
			(layer "F.Fab")
			(hide yes)
			(effects
				(font
					(size 1.016 1.016)
					(thickness 0.1524)
				)
			)
		)
		(property "Device Type" "R402H16"
			(at 0.064008 -5.517896 180)
			(unlocked yes)
			(layer "F.Fab")
			(hide yes)
			(effects
				(font
					(size 1.016 1.016)
					(thickness 0.1524)
				)
			)
		)
		(duplicate_pad_numbers_are_jumpers no)
		(fp_line
			(start 0.508 -0.9398)
			(end -0.508 -0.9398)
			(stroke
				(width 0.1524)
				(type default)
			)
			(layer "F.SilkS")
		)
		(fp_line
			(start -0.508 -0.9398)
			(end -0.508 0.9398)
			(stroke
				(width 0.1524)
				(type default)
			)
			(layer "F.SilkS")
		)
		(fp_rect
			(start -0.508 0.9398)
			(end 0.508 -0.9398)
			(stroke
				(width 0)
				(type default)
			)
			(fill no)
			(layer "F.CrtYd")
		)
		(fp_rect
			(start -0.508 0.9398)
			(end 0.508 -0.9398)
			(stroke
				(width 0)
				(type default)
			)
			(fill no)
			(layer "F.Fab")
		)
		(pad "1" smd custom
			(at 0 -0.4445 180)
			(size 0.1397 0.1397)
			(layers "F.Cu" "F.Mask" "F.Paste")
			(net "SPICS0_N")
			(options
				(clearance outline)
				(anchor circle)
			)
			(primitives
				(gr_poly
					(pts
						(arc
							(start -0.1778 -0.2794)
							(mid -0.249642 -0.249642)
							(end -0.2794 -0.1778)
						)
						(arc
							(start -0.2794 0.1778)
							(mid -0.249642 0.249642)
							(end -0.1778 0.2794)
						)
						(arc
							(start 0.1778 0.2794)
							(mid 0.249642 0.249642)
							(end 0.2794 0.1778)
						)
						(arc
							(start 0.2794 -0.1778)
							(mid 0.249642 -0.249642)
							(end 0.1778 -0.2794)
						)
					)
					(width 0)
					(fill yes)
				)
			)
		)
		(pad "2" smd custom
			(at 0 0.4445 180)
			(size 0.1397 0.1397)
			(layers "F.Cu" "F.Mask" "F.Paste")
			(net "P3V3_STBY")
			(options
				(clearance outline)
				(anchor circle)
			)
			(primitives
				(gr_poly
					(pts
						(arc
							(start -0.1778 -0.2794)
							(mid -0.249642 -0.249642)
							(end -0.2794 -0.1778)
						)
						(arc
							(start -0.2794 0.1778)
							(mid -0.249642 0.249642)
							(end -0.1778 0.2794)
						)
						(arc
							(start 0.1778 0.2794)
							(mid 0.249642 0.249642)
							(end 0.2794 0.1778)
						)
						(arc
							(start 0.2794 -0.1778)
							(mid 0.249642 -0.249642)
							(end 0.1778 -0.2794)
						)
					)
					(width 0)
					(fill yes)
				)
			)
		)
	)
	(footprint ""
		(layer "F.Cu")
		(at 133.891274 -59.73572 180)
		(property "Reference" "R955"
			(at 0 0 180)
			(layer "F.SilkS")
			(hide yes)
			(effects
				(font
					(size 1.27 1.27)
				)
			)
		)
		(property "Value" "33R2J-2-GP"
			(at 0.064008 -3.993896 180)
			(unlocked yes)
			(layer "F.Fab")
			(hide yes)
			(effects
				(font
					(size 1.016 1.016)
					(thickness 0.1524)
				)
			)
		)
		(property "Device Type" "R402H16"
			(at 0.064008 -5.517896 180)
			(unlocked yes)
			(layer "F.Fab")
			(hide yes)
			(effects
				(font
					(size 1.016 1.016)
					(thickness 0.1524)
				)
			)
		)
		(duplicate_pad_numbers_are_jumpers no)
		(fp_line
			(start 0.508 -0.9398)
			(end -0.508 -0.9398)
			(stroke
				(width 0.1524)
				(type default)
			)
			(layer "F.SilkS")
		)
		(fp_line
			(start -0.508 -0.9398)
			(end -0.508 0.9398)
			(stroke
				(width 0.1524)
				(type default)
			)
			(layer "F.SilkS")
		)
		(fp_rect
			(start -0.508 0.9398)
			(end 0.508 -0.9398)
			(stroke
				(width 0)
				(type default)
			)
			(fill no)
			(layer "F.CrtYd")
		)
		(fp_rect
			(start -0.508 0.9398)
			(end 0.508 -0.9398)
			(stroke
				(width 0)
				(type default)
			)
			(fill no)
			(layer "F.Fab")
		)
		(pad "1" smd custom
			(at 0 -0.4445 180)
			(size 0.1397 0.1397)
			(layers "F.Cu" "F.Mask" "F.Paste")
			(net "SPI_DATA0_1")
			(options
				(clearance outline)
				(anchor circle)
			)
			(primitives
				(gr_poly
					(pts
						(arc
							(start -0.1778 -0.2794)
							(mid -0.249642 -0.249642)
							(end -0.2794 -0.1778)
						)
						(arc
							(start -0.2794 0.1778)
							(mid -0.249642 0.249642)
							(end -0.1778 0.2794)
						)
						(arc
							(start 0.1778 0.2794)
							(mid 0.249642 0.249642)
							(end 0.2794 0.1778)
						)
						(arc
							(start 0.2794 -0.1778)
							(mid 0.249642 -0.249642)
							(end 0.1778 -0.2794)
						)
					)
					(width 0)
					(fill yes)
				)
			)
		)
		(pad "2" smd custom
			(at 0 0.4445 180)
			(size 0.1397 0.1397)
			(layers "F.Cu" "F.Mask" "F.Paste")
			(net "SPI_DATA0_1_R")
			(options
				(clearance outline)
				(anchor circle)
			)
			(primitives
				(gr_poly
					(pts
						(arc
							(start -0.1778 -0.2794)
							(mid -0.249642 -0.249642)
							(end -0.2794 -0.1778)
						)
						(arc
							(start -0.2794 0.1778)
							(mid -0.249642 0.249642)
							(end -0.1778 0.2794)
						)
						(arc
							(start 0.1778 0.2794)
							(mid 0.249642 0.249642)
							(end 0.2794 0.1778)
						)
						(arc
							(start 0.2794 -0.1778)
							(mid 0.249642 -0.249642)
							(end 0.1778 -0.2794)
						)
					)
					(width 0)
					(fill yes)
				)
			)
		)
	)
	(footprint ""
		(layer "F.Cu")
		(at 27.686 -143.637 -90)
		(property "Reference" "R450"
			(at 0 0 270)
			(layer "F.SilkS")
			(hide yes)
			(effects
				(font
					(size 1.27 1.27)
				)
			)
		)
		(property "Value" "0R2J-2-GP"
			(at 0.064008 -3.993896 270)
			(unlocked yes)
			(layer "F.Fab")
			(hide yes)
			(effects
				(font
					(size 1.016 1.016)
					(thickness 0.1524)
				)
			)
		)
		(property "Device Type" "R402H16"
			(at 0.064008 -5.517896 270)
			(unlocked yes)
			(layer "F.Fab")
			(hide yes)
			(effects
				(font
					(size 1.016 1.016)
					(thickness 0.1524)
				)
			)
		)
		(duplicate_pad_numbers_are_jumpers no)
		(fp_line
			(start -0.508 -0.9398)
			(end -0.508 0.9398)
			(stroke
				(width 0.1524)
				(type default)
			)
			(layer "F.SilkS")
		)
		(fp_line
			(start 0.508 -0.9398)
			(end -0.508 -0.9398)
			(stroke
				(width 0.1524)
				(type default)
			)
			(layer "F.SilkS")
		)
		(fp_rect
			(start -0.508 0.9398)
			(end 0.508 -0.9398)
			(stroke
				(width 0)
				(type default)
			)
			(fill no)
			(layer "F.CrtYd")
		)
		(fp_rect
			(start -0.508 0.9398)
			(end 0.508 -0.9398)
			(stroke
				(width 0)
				(type default)
			)
			(fill no)
			(layer "F.Fab")
		)
		(pad "1" smd custom
			(at 0 -0.4445 270)
			(size 0.1397 0.1397)
			(layers "F.Cu" "F.Mask" "F.Paste")
			(net "BMC_USB2_HDN")
			(options
				(clearance outline)
				(anchor circle)
			)
			(primitives
				(gr_poly
					(pts
						(arc
							(start -0.1778 -0.2794)
							(mid -0.249642 -0.249642)
							(end -0.2794 -0.1778)
						)
						(arc
							(start -0.2794 0.1778)
							(mid -0.249642 0.249642)
							(end -0.1778 0.2794)
						)
						(arc
							(start 0.1778 0.2794)
							(mid 0.249642 0.249642)
							(end 0.2794 0.1778)
						)
						(arc
							(start 0.2794 -0.1778)
							(mid 0.249642 -0.249642)
							(end 0.1778 -0.2794)
						)
					)
					(width 0)
					(fill yes)
				)
			)
		)
		(pad "2" smd custom
			(at 0 0.4445 270)
			(size 0.1397 0.1397)
			(layers "F.Cu" "F.Mask" "F.Paste")
			(net "USB2_BMC_DN")
			(options
				(clearance outline)
				(anchor circle)
			)
			(primitives
				(gr_poly
					(pts
						(arc
							(start -0.1778 -0.2794)
							(mid -0.249642 -0.249642)
							(end -0.2794 -0.1778)
						)
						(arc
							(start -0.2794 0.1778)
							(mid -0.249642 0.249642)
							(end -0.1778 0.2794)
						)
						(arc
							(start 0.1778 0.2794)
							(mid 0.249642 0.249642)
							(end 0.2794 0.1778)
						)
						(arc
							(start 0.2794 -0.1778)
							(mid 0.249642 -0.249642)
							(end 0.1778 -0.2794)
						)
					)
					(width 0)
					(fill yes)
				)
			)
		)
	)
	(footprint ""
		(layer "F.Cu")
		(at 137.69848 -55.06847 180)
		(property "Reference" "SC1307"
			(at 0 0 180)
			(layer "F.SilkS")
			(hide yes)
			(effects
				(font
					(size 1.27 1.27)
				)
			)
		)
		(property "Value" "SCD1U16V2KX-3GP"
			(at 1.1811 -2.7051 180)
			(unlocked yes)
			(layer "F.Fab")
			(hide yes)
			(effects
				(font
					(size 1.016 1.016)
					(thickness 0.1524)
				)
			)
		)
		(property "Device Type" "C402H22"
			(at 1.1811 -4.2291 180)
			(unlocked yes)
			(layer "F.Fab")
			(hide yes)
			(effects
				(font
					(size 1.016 1.016)
					(thickness 0.1524)
				)
			)
		)
		(duplicate_pad_numbers_are_jumpers no)
		(fp_rect
			(start -0.4318 0.9525)
			(end 0.4318 -0.9525)
			(stroke
				(width 0)
				(type default)
			)
			(fill no)
			(layer "F.CrtYd")
		)
		(fp_rect
			(start -0.4318 0.9525)
			(end 0.4318 -0.9525)
			(stroke
				(width 0)
				(type default)
			)
			(fill no)
			(layer "F.Fab")
		)
		(pad "1" smd custom
			(at 0 -0.4445 180)
			(size 0.1524 0.1524)
			(layers "F.Cu" "F.Mask" "F.Paste")
			(net "P5V_STBY")
			(options
				(clearance outline)
				(anchor circle)
			)
			(primitives
				(gr_poly
					(pts
						(arc
							(start 0.3048 -0.2032)
							(mid 0.275042 -0.275042)
							(end 0.2032 -0.3048)
						)
						(arc
							(start -0.2032 -0.3048)
							(mid -0.275042 -0.275042)
							(end -0.3048 -0.2032)
						)
						(arc
							(start -0.3048 0.2032)
							(mid -0.275042 0.275042)
							(end -0.2032 0.3048)
						)
						(arc
							(start 0.2032 0.3048)
							(mid 0.275042 0.275042)
							(end 0.3048 0.2032)
						)
					)
					(width 0)
					(fill yes)
				)
			)
		)
		(pad "2" smd custom
			(at 0 0.4445 180)
			(size 0.1524 0.1524)
			(layers "F.Cu" "F.Mask" "F.Paste")
			(net "GND")
			(options
				(clearance outline)
				(anchor circle)
			)
			(primitives
				(gr_poly
					(pts
						(arc
							(start 0.3048 -0.2032)
							(mid 0.275042 -0.275042)
							(end 0.2032 -0.3048)
						)
						(arc
							(start -0.2032 -0.3048)
							(mid -0.275042 -0.275042)
							(end -0.3048 -0.2032)
						)
						(arc
							(start -0.3048 0.2032)
							(mid -0.275042 0.275042)
							(end -0.2032 0.3048)
						)
						(arc
							(start 0.2032 0.3048)
							(mid 0.275042 0.275042)
							(end 0.3048 0.2032)
						)
					)
					(width 0)
					(fill yes)
				)
			)
		)
	)
	(footprint ""
		(layer "F.Cu")
		(at 88.9 -45.974)
		(property "Reference" "PG4"
			(at 0 0 0)
			(layer "F.SilkS")
			(hide yes)
			(effects
				(font
					(size 1.27 1.27)
				)
			)
		)
		(property "Value" "GAP-CLOSE-PWR-3-GP"
			(at 0.0254 -6.5786 0)
			(unlocked yes)
			(layer "F.Fab")
			(hide yes)
			(effects
				(font
					(size 1.016 1.016)
					(thickness 0.1524)
				)
			)
		)
		(property "Device Type" "GAP-CLOSE-PWR-3"
			(at 0.0254 -8.255 0)
			(unlocked yes)
			(layer "F.Fab")
			(hide yes)
			(effects
				(font
					(size 1.016 1.016)
					(thickness 0.1524)
				)
			)
		)
		(duplicate_pad_numbers_are_jumpers no)
		(fp_rect
			(start -0.7112 0.4572)
			(end 0.7112 -0.4572)
			(stroke
				(width 0)
				(type default)
			)
			(fill no)
			(layer "F.CrtYd")
		)
		(fp_poly
			(pts
				(xy -0.7112 -0.4572) (xy 0.7112 -0.4572) (xy 0.7112 0.4572) (xy -0.7112 0.4572)
			)
			(stroke
				(width 0)
				(type default)
			)
			(fill no)
			(layer "F.Fab")
		)
		(pad "1" smd rect
			(at -0.3048 0)
			(size 0.6604 0.762)
			(layers "F.Cu" "F.Mask" "F.Paste")
			(net "P3V3_PWR")
		)
		(pad "2" smd rect
			(at 0.3048 0)
			(size 0.6604 0.762)
			(layers "F.Cu" "F.Mask" "F.Paste")
			(net "P3V3_STBY")
		)
	)
	(footprint ""
		(layer "F.Cu")
		(at 122.557286 -84.846414 -90)
		(property "Reference" "R5200"
			(at 0 0 270)
			(layer "F.SilkS")
			(hide yes)
			(effects
				(font
					(size 1.27 1.27)
				)
			)
		)
		(property "Value" "0R2J-2-GP"
			(at 0.064008 -3.993896 270)
			(unlocked yes)
			(layer "F.Fab")
			(hide yes)
			(effects
				(font
					(size 1.016 1.016)
					(thickness 0.1524)
				)
			)
		)
		(property "Device Type" "R402H16"
			(at 0.064008 -5.517896 270)
			(unlocked yes)
			(layer "F.Fab")
			(hide yes)
			(effects
				(font
					(size 1.016 1.016)
					(thickness 0.1524)
				)
			)
		)
		(duplicate_pad_numbers_are_jumpers no)
		(fp_line
			(start -0.508 -0.9398)
			(end -0.508 0.9398)
			(stroke
				(width 0.1524)
				(type default)
			)
			(layer "F.SilkS")
		)
		(fp_line
			(start 0.508 -0.9398)
			(end -0.508 -0.9398)
			(stroke
				(width 0.1524)
				(type default)
			)
			(layer "F.SilkS")
		)
		(fp_rect
			(start -0.508 0.9398)
			(end 0.508 -0.9398)
			(stroke
				(width 0)
				(type default)
			)
			(fill no)
			(layer "F.CrtYd")
		)
		(fp_rect
			(start -0.508 0.9398)
			(end 0.508 -0.9398)
			(stroke
				(width 0)
				(type default)
			)
			(fill no)
			(layer "F.Fab")
		)
		(pad "1" smd custom
			(at 0 -0.4445 270)
			(size 0.1397 0.1397)
			(layers "F.Cu" "F.Mask" "F.Paste")
			(net "RTC_I2C_SCL")
			(options
				(clearance outline)
				(anchor circle)
			)
			(primitives
				(gr_poly
					(pts
						(arc
							(start -0.1778 -0.2794)
							(mid -0.249642 -0.249642)
							(end -0.2794 -0.1778)
						)
						(arc
							(start -0.2794 0.1778)
							(mid -0.249642 0.249642)
							(end -0.1778 0.2794)
						)
						(arc
							(start 0.1778 0.2794)
							(mid 0.249642 0.249642)
							(end 0.2794 0.1778)
						)
						(arc
							(start 0.2794 -0.1778)
							(mid 0.249642 -0.249642)
							(end 0.1778 -0.2794)
						)
					)
					(width 0)
					(fill yes)
				)
			)
		)
		(pad "2" smd custom
			(at 0 0.4445 270)
			(size 0.1397 0.1397)
			(layers "F.Cu" "F.Mask" "F.Paste")
			(net "BMC_I2C5_D_PEB_SCL")
			(options
				(clearance outline)
				(anchor circle)
			)
			(primitives
				(gr_poly
					(pts
						(arc
							(start -0.1778 -0.2794)
							(mid -0.249642 -0.249642)
							(end -0.2794 -0.1778)
						)
						(arc
							(start -0.2794 0.1778)
							(mid -0.249642 0.249642)
							(end -0.1778 0.2794)
						)
						(arc
							(start 0.1778 0.2794)
							(mid 0.249642 0.249642)
							(end 0.2794 0.1778)
						)
						(arc
							(start 0.2794 -0.1778)
							(mid 0.249642 -0.249642)
							(end 0.1778 -0.2794)
						)
					)
					(width 0)
					(fill yes)
				)
			)
		)
	)
	(footprint ""
		(layer "F.Cu")
		(at 154.392122 -212.420454 180)
		(property "Reference" "C250"
			(at 0 0 180)
			(layer "F.SilkS")
			(hide yes)
			(effects
				(font
					(size 1.27 1.27)
				)
			)
		)
		(property "Value" "SCD22U10V2KX-1GP"
			(at 1.1811 -2.7051 180)
			(unlocked yes)
			(layer "F.Fab")
			(hide yes)
			(effects
				(font
					(size 1.016 1.016)
					(thickness 0.1524)
				)
			)
		)
		(property "Device Type" "C402H22"
			(at 1.1811 -4.2291 180)
			(unlocked yes)
			(layer "F.Fab")
			(hide yes)
			(effects
				(font
					(size 1.016 1.016)
					(thickness 0.1524)
				)
			)
		)
		(duplicate_pad_numbers_are_jumpers no)
		(fp_rect
			(start -0.4318 0.9525)
			(end 0.4318 -0.9525)
			(stroke
				(width 0)
				(type default)
			)
			(fill no)
			(layer "F.CrtYd")
		)
		(fp_rect
			(start -0.4318 0.9525)
			(end 0.4318 -0.9525)
			(stroke
				(width 0)
				(type default)
			)
			(fill no)
			(layer "F.Fab")
		)
		(pad "1" smd custom
			(at 0 -0.4445 180)
			(size 0.1524 0.1524)
			(layers "F.Cu" "F.Mask" "F.Paste")
			(net "PCIE_TX_CAP_P54")
			(options
				(clearance outline)
				(anchor circle)
			)
			(primitives
				(gr_poly
					(pts
						(arc
							(start 0.3048 -0.2032)
							(mid 0.275042 -0.275042)
							(end 0.2032 -0.3048)
						)
						(arc
							(start -0.2032 -0.3048)
							(mid -0.275042 -0.275042)
							(end -0.3048 -0.2032)
						)
						(arc
							(start -0.3048 0.2032)
							(mid -0.275042 0.275042)
							(end -0.2032 0.3048)
						)
						(arc
							(start 0.2032 0.3048)
							(mid 0.275042 0.275042)
							(end 0.3048 0.2032)
						)
					)
					(width 0)
					(fill yes)
				)
			)
		)
		(pad "2" smd custom
			(at 0 0.4445 180)
			(size 0.1524 0.1524)
			(layers "F.Cu" "F.Mask" "F.Paste")
			(net "PCIE_TX_P54")
			(options
				(clearance outline)
				(anchor circle)
			)
			(primitives
				(gr_poly
					(pts
						(arc
							(start 0.3048 -0.2032)
							(mid 0.275042 -0.275042)
							(end 0.2032 -0.3048)
						)
						(arc
							(start -0.2032 -0.3048)
							(mid -0.275042 -0.275042)
							(end -0.3048 -0.2032)
						)
						(arc
							(start -0.3048 0.2032)
							(mid -0.275042 0.275042)
							(end -0.2032 0.3048)
						)
						(arc
							(start 0.2032 0.3048)
							(mid 0.275042 0.275042)
							(end 0.3048 0.2032)
						)
					)
					(width 0)
					(fill yes)
				)
			)
		)
	)
	(footprint ""
		(layer "F.Cu")
		(at 21.6281 -50.6476 -90)
		(property "Reference" "D17"
			(at 0 0 270)
			(layer "F.SilkS")
			(hide yes)
			(effects
				(font
					(size 1.27 1.27)
				)
			)
		)
		(property "Value" "PGB1010603MR-GP"
			(at -0.0254 -2.8956 270)
			(unlocked yes)
			(layer "F.Fab")
			(hide yes)
			(effects
				(font
					(size 1.016 1.016)
					(thickness 0.1524)
				)
			)
		)
		(property "Device Type" "L1608-UH15"
			(at -0.0254 -4.4196 270)
			(unlocked yes)
			(layer "F.Fab")
			(hide yes)
			(effects
				(font
					(size 1.016 1.016)
					(thickness 0.1524)
				)
			)
		)
		(duplicate_pad_numbers_are_jumpers no)
		(fp_line
			(start 0.254 0)
			(end -0.254 0)
			(stroke
				(width 0.2032)
				(type default)
			)
			(layer "F.SilkS")
		)
		(fp_rect
			(start -0.5842 1.3335)
			(end 0.5842 -1.3335)
			(stroke
				(width 0)
				(type default)
			)
			(fill no)
			(layer "F.CrtYd")
		)
		(fp_rect
			(start -0.5842 1.3335)
			(end 0.5842 -1.3335)
			(stroke
				(width 0)
				(type default)
			)
			(fill no)
			(layer "F.Fab")
		)
		(pad "1" smd custom
			(at 0 -0.762 270)
			(size 0.2159 0.2159)
			(layers "F.Cu" "F.Mask" "F.Paste")
			(net "NIC0_MDI0_N3_R")
			(options
				(clearance outline)
				(anchor circle)
			)
			(primitives
				(gr_poly
					(pts
						(arc
							(start -0.3302 -0.4318)
							(mid -0.402042 -0.402042)
							(end -0.4318 -0.3302)
						)
						(arc
							(start -0.4318 0.3302)
							(mid -0.402042 0.402042)
							(end -0.3302 0.4318)
						)
						(arc
							(start 0.3302 0.4318)
							(mid 0.402042 0.402042)
							(end 0.4318 0.3302)
						)
						(arc
							(start 0.4318 -0.3302)
							(mid 0.402042 -0.402042)
							(end 0.3302 -0.4318)
						)
					)
					(width 0)
					(fill yes)
				)
			)
		)
		(pad "2" smd custom
			(at 0 0.762 270)
			(size 0.2159 0.2159)
			(layers "F.Cu" "F.Mask" "F.Paste")
			(net "GND")
			(options
				(clearance outline)
				(anchor circle)
			)
			(primitives
				(gr_poly
					(pts
						(arc
							(start -0.3302 -0.4318)
							(mid -0.402042 -0.402042)
							(end -0.4318 -0.3302)
						)
						(arc
							(start -0.4318 0.3302)
							(mid -0.402042 0.402042)
							(end -0.3302 0.4318)
						)
						(arc
							(start 0.3302 0.4318)
							(mid 0.402042 0.402042)
							(end 0.4318 0.3302)
						)
						(arc
							(start 0.4318 -0.3302)
							(mid 0.402042 -0.402042)
							(end 0.3302 -0.4318)
						)
					)
					(width 0)
					(fill yes)
				)
			)
		)
	)
	(footprint ""
		(layer "F.Cu")
		(at 218.77274 -31.142432)
		(property "Reference" "TP267"
			(at 0 0 0)
			(layer "F.SilkS")
			(hide yes)
			(effects
				(font
					(size 1.27 1.27)
				)
			)
		)
		(property "Value" "TPAD28-2-GP"
			(at -0.0127 -1.6637 0)
			(unlocked yes)
			(layer "F.Fab")
			(hide yes)
			(effects
				(font
					(size 1.016 1.016)
					(thickness 0.1524)
				)
			)
		)
		(property "Device Type" "TPAD28"
			(at -0.0127 -3.1877 0)
			(unlocked yes)
			(layer "F.Fab")
			(hide yes)
			(effects
				(font
					(size 1.016 1.016)
					(thickness 0.1524)
				)
			)
		)
		(duplicate_pad_numbers_are_jumpers no)
		(fp_poly
			(pts
				(arc
					(start 0.3556 0)
					(mid -0.3556 0)
					(end 0.3556 0)
				)
			)
			(stroke
				(width 0)
				(type default)
			)
			(fill no)
			(layer "F.CrtYd")
		)
		(fp_poly
			(pts
				(arc
					(start 0.6096 0)
					(mid -0.6096 0)
					(end 0.6096 0)
				)
			)
			(stroke
				(width 0)
				(type default)
			)
			(fill no)
			(layer "F.Fab")
		)
		(pad "1" smd circle
			(at 0 0)
			(size 0.7112 0.7112)
			(layers "F.Cu" "F.Mask" "F.Paste")
			(net "LBI_DATA_8")
		)
	)
	(footprint ""
		(layer "F.Cu")
		(at 8.982964 -86.437978 90)
		(property "Reference" "X1"
			(at 0 0 90)
			(layer "F.SilkS")
			(hide yes)
			(effects
				(font
					(size 1.27 1.27)
				)
			)
		)
		(property "Value" "OSC-50MHZ-8-GP-U"
			(at -5.183886 1.282192 90)
			(unlocked yes)
			(layer "F.Fab")
			(hide yes)
			(effects
				(font
					(size 1.016 1.016)
					(thickness 0.1524)
				)
			)
		)
		(property "Device Type" "S-OSC4-7349H75"
			(at -5.183886 -0.241808 90)
			(unlocked yes)
			(layer "F.Fab")
			(hide yes)
			(effects
				(font
					(size 1.016 1.016)
					(thickness 0.1524)
				)
			)
		)
		(duplicate_pad_numbers_are_jumpers no)
		(fp_line
			(start 3.8989 -3.2131)
			(end 3.8989 3.2131)
			(stroke
				(width 0.1524)
				(type default)
			)
			(layer "F.SilkS")
		)
		(fp_line
			(start -3.8989 -3.2131)
			(end 3.8989 -3.2131)
			(stroke
				(width 0.1524)
				(type default)
			)
			(layer "F.SilkS")
		)
		(fp_line
			(start -3.9878 2.0447)
			(end -3.9878 3.3147)
			(stroke
				(width 0.3302)
				(type default)
			)
			(layer "F.SilkS")
		)
		(fp_line
			(start 3.8989 3.2131)
			(end -3.8989 3.2131)
			(stroke
				(width 0.1524)
				(type default)
			)
			(layer "F.SilkS")
		)
		(fp_line
			(start -3.8989 3.2131)
			(end -3.8989 -3.2131)
			(stroke
				(width 0.1524)
				(type default)
			)
			(layer "F.SilkS")
		)
		(fp_line
			(start -3.9878 3.3147)
			(end -2.7178 3.3147)
			(stroke
				(width 0.3302)
				(type default)
			)
			(layer "F.SilkS")
		)
		(fp_poly
			(pts
				(xy -3.175 3.9243) (xy -1.905 3.9243) (xy -2.54 3.2893)
			)
			(stroke
				(width 0)
				(type default)
			)
			(fill yes)
			(layer "F.SilkS")
		)
		(fp_rect
			(start -3.6449 2.4511)
			(end 3.6449 -2.4511)
			(stroke
				(width 0)
				(type default)
			)
			(fill no)
			(layer "F.CrtYd")
		)
		(fp_poly
			(pts
				(xy -4.1529 3.4671) (xy -4.1529 -0.5842) (xy -3.6449 -0.5842) (xy -3.6449 2.4511) (xy 3.6449 2.4511)
				(xy 3.6449 -2.4511) (xy -3.6449 -2.4511) (xy -3.6449 -0.5969) (xy -4.1529 -0.5969) (xy -4.1529 -3.4671)
				(xy 4.1529 -3.4671) (xy 4.1529 3.4671)
			)
			(stroke
				(width 0)
				(type default)
			)
			(fill no)
			(layer "F.CrtYd")
		)
		(fp_rect
			(start -4.1529 3.4671)
			(end 4.1529 -3.4671)
			(stroke
				(width 0)
				(type default)
			)
			(fill no)
			(layer "F.Fab")
		)
		(pad "1" smd rect
			(at -2.54 2.005584 90)
			(size 1.651 1.905)
			(layers "F.Cu" "F.Mask" "F.Paste")
			(net "FM_OSC_50M_EN")
		)
		(pad "2" smd rect
			(at 2.54 2.005584 90)
			(size 1.651 1.905)
			(layers "F.Cu" "F.Mask" "F.Paste")
			(net "GND")
		)
		(pad "3" smd rect
			(at 2.54 -2.005584 90)
			(size 1.651 1.905)
			(layers "F.Cu" "F.Mask" "F.Paste")
			(net "50M_CLK_OUT")
		)
		(pad "4" smd rect
			(at -2.54 -2.005584 90)
			(size 1.651 1.905)
			(layers "F.Cu" "F.Mask" "F.Paste")
			(net "P3V3_STBY")
		)
		(zone
			(layer "F.Cu")
			(hatch none 0.5)
			(connect_pads
				(clearance 0)
			)
			(min_thickness 0.25)
			(keepout
				(tracks not_allowed)
				(vias allowed)
				(pads allowed)
				(copperpour not_allowed)
				(footprints allowed)
			)
			(placement
				(enabled no)
				(sheetname "")
			)
			(fill
				(thermal_gap 0.5)
				(thermal_bridge_width 0.5)
				(island_removal_mode 0)
			)
			(polygon
				(pts
					(xy 9.706864 -85.040978) (xy 8.259064 -85.040978) (xy 8.259064 -87.834978) (xy 9.706864 -87.834978)
				)
			)
		)
		(zone
			(layer "F.Cu")
			(hatch none 0.5)
			(connect_pads
				(clearance 0)
			)
			(min_thickness 0.25)
			(keepout
				(tracks allowed)
				(vias not_allowed)
				(pads allowed)
				(copperpour not_allowed)
				(footprints allowed)
			)
			(placement
				(enabled no)
				(sheetname "")
			)
			(fill
				(thermal_gap 0.5)
				(thermal_bridge_width 0.5)
				(island_removal_mode 0)
			)
			(polygon
				(pts
					(xy 11.941048 -84.723478) (xy 10.036048 -84.723478) (xy 10.036048 -83.072478) (xy 7.92988 -83.072478)
					(xy 7.92988 -84.723478) (xy 6.02488 -84.723478) (xy 6.02488 -88.152478) (xy 7.92988 -88.152478)
					(xy 7.92988 -89.803478) (xy 10.036048 -89.803478) (xy 10.036048 -88.152478) (xy 11.941048 -88.152478)
				)
			)
		)
	)
	(footprint ""
		(layer "F.Cu")
		(at 120.9548 -101.4222 180)
		(property "Reference" "R864"
			(at 0 0 180)
			(layer "F.SilkS")
			(hide yes)
			(effects
				(font
					(size 1.27 1.27)
				)
			)
		)
		(property "Value" "0R2J-2-GP"
			(at 0.064008 -3.993896 180)
			(unlocked yes)
			(layer "F.Fab")
			(hide yes)
			(effects
				(font
					(size 1.016 1.016)
					(thickness 0.1524)
				)
			)
		)
		(property "Device Type" "R402H16"
			(at 0.064008 -5.517896 180)
			(unlocked yes)
			(layer "F.Fab")
			(hide yes)
			(effects
				(font
					(size 1.016 1.016)
					(thickness 0.1524)
				)
			)
		)
		(duplicate_pad_numbers_are_jumpers no)
		(fp_line
			(start 0.508 -0.9398)
			(end -0.508 -0.9398)
			(stroke
				(width 0.1524)
				(type default)
			)
			(layer "F.SilkS")
		)
		(fp_line
			(start -0.508 -0.9398)
			(end -0.508 0.9398)
			(stroke
				(width 0.1524)
				(type default)
			)
			(layer "F.SilkS")
		)
		(fp_rect
			(start -0.508 0.9398)
			(end 0.508 -0.9398)
			(stroke
				(width 0)
				(type default)
			)
			(fill no)
			(layer "F.CrtYd")
		)
		(fp_rect
			(start -0.508 0.9398)
			(end 0.508 -0.9398)
			(stroke
				(width 0)
				(type default)
			)
			(fill no)
			(layer "F.Fab")
		)
		(pad "1" smd custom
			(at 0 -0.4445 180)
			(size 0.1397 0.1397)
			(layers "F.Cu" "F.Mask" "F.Paste")
			(net "BUF_I2C_SDA_2_R")
			(options
				(clearance outline)
				(anchor circle)
			)
			(primitives
				(gr_poly
					(pts
						(arc
							(start -0.1778 -0.2794)
							(mid -0.249642 -0.249642)
							(end -0.2794 -0.1778)
						)
						(arc
							(start -0.2794 0.1778)
							(mid -0.249642 0.249642)
							(end -0.1778 0.2794)
						)
						(arc
							(start 0.1778 0.2794)
							(mid 0.249642 0.249642)
							(end 0.2794 0.1778)
						)
						(arc
							(start 0.2794 -0.1778)
							(mid 0.249642 -0.249642)
							(end 0.1778 -0.2794)
						)
					)
					(width 0)
					(fill yes)
				)
			)
		)
		(pad "2" smd custom
			(at 0 0.4445 180)
			(size 0.1397 0.1397)
			(layers "F.Cu" "F.Mask" "F.Paste")
			(net "TWI_SDA0")
			(options
				(clearance outline)
				(anchor circle)
			)
			(primitives
				(gr_poly
					(pts
						(arc
							(start -0.1778 -0.2794)
							(mid -0.249642 -0.249642)
							(end -0.2794 -0.1778)
						)
						(arc
							(start -0.2794 0.1778)
							(mid -0.249642 0.249642)
							(end -0.1778 0.2794)
						)
						(arc
							(start 0.1778 0.2794)
							(mid 0.249642 0.249642)
							(end 0.2794 0.1778)
						)
						(arc
							(start 0.2794 -0.1778)
							(mid 0.249642 -0.249642)
							(end 0.1778 -0.2794)
						)
					)
					(width 0)
					(fill yes)
				)
			)
		)
	)
	(footprint ""
		(layer "F.Cu")
		(at 275.599906 -17.500092 90)
		(property "Reference" "LED23"
			(at 0 0 90)
			(layer "F.SilkS")
			(hide yes)
			(effects
				(font
					(size 1.27 1.27)
				)
			)
		)
		(property "Value" "LED-YG-51-GP"
			(at -2.6924 -1.4224 90)
			(unlocked yes)
			(layer "F.Fab")
			(hide yes)
			(effects
				(font
					(size 1.016 1.016)
					(thickness 0.1524)
				)
			)
		)
		(property "Device Type" "LED1608AKH40"
			(at -2.6924 -2.9464 90)
			(unlocked yes)
			(layer "F.Fab")
			(hide yes)
			(effects
				(font
					(size 1.016 1.016)
					(thickness 0.1524)
				)
			)
		)
		(duplicate_pad_numbers_are_jumpers no)
		(fp_line
			(start 0.6604 -1.3716)
			(end 0.6604 1.3716)
			(stroke
				(width 0.1524)
				(type default)
			)
			(layer "F.SilkS")
		)
		(fp_line
			(start -0.6604 -1.3716)
			(end 0.6604 -1.3716)
			(stroke
				(width 0.1524)
				(type default)
			)
			(layer "F.SilkS")
		)
		(fp_line
			(start 0.6604 1.3716)
			(end -0.6604 1.3716)
			(stroke
				(width 0.1524)
				(type default)
			)
			(layer "F.SilkS")
		)
		(fp_line
			(start -0.6604 1.3716)
			(end -0.6604 -1.3716)
			(stroke
				(width 0.1524)
				(type default)
			)
			(layer "F.SilkS")
		)
		(fp_line
			(start -0.5969 1.5494)
			(end 0.5842 1.5494)
			(stroke
				(width 0.508)
				(type default)
			)
			(layer "F.SilkS")
		)
		(fp_line
			(start 0.7493 1.651)
			(end 0.7493 1.1811)
			(stroke
				(width 0.3302)
				(type default)
			)
			(layer "F.SilkS")
		)
		(fp_line
			(start -0.7493 1.651)
			(end -0.7493 1.1811)
			(stroke
				(width 0.3302)
				(type default)
			)
			(layer "F.SilkS")
		)
		(fp_rect
			(start -0.6223 1.3335)
			(end 0.6223 -1.3335)
			(stroke
				(width 0)
				(type default)
			)
			(fill no)
			(layer "F.CrtYd")
		)
		(fp_rect
			(start -0.6223 1.3335)
			(end 0.6223 -1.3335)
			(stroke
				(width 0)
				(type default)
			)
			(fill no)
			(layer "F.Fab")
		)
		(pad "A" smd custom
			(at 0 -0.762 90)
			(size 0.2159 0.2159)
			(layers "F.Cu" "F.Mask" "F.Paste")
			(net "LED_R_14")
			(options
				(clearance outline)
				(anchor circle)
			)
			(primitives
				(gr_poly
					(pts
						(arc
							(start -0.3302 -0.4318)
							(mid -0.402042 -0.402042)
							(end -0.4318 -0.3302)
						)
						(arc
							(start -0.4318 0.3302)
							(mid -0.402042 0.402042)
							(end -0.3302 0.4318)
						)
						(arc
							(start 0.3302 0.4318)
							(mid 0.402042 0.402042)
							(end 0.4318 0.3302)
						)
						(arc
							(start 0.4318 -0.3302)
							(mid 0.402042 -0.402042)
							(end 0.3302 -0.4318)
						)
					)
					(width 0)
					(fill yes)
				)
			)
		)
		(pad "K" smd custom
			(at 0 0.762 90)
			(size 0.2159 0.2159)
			(layers "F.Cu" "F.Mask" "F.Paste")
			(net "LED_Q_14")
			(options
				(clearance outline)
				(anchor circle)
			)
			(primitives
				(gr_poly
					(pts
						(arc
							(start -0.3302 -0.4318)
							(mid -0.402042 -0.402042)
							(end -0.4318 -0.3302)
						)
						(arc
							(start -0.4318 0.3302)
							(mid -0.402042 0.402042)
							(end -0.3302 0.4318)
						)
						(arc
							(start 0.3302 0.4318)
							(mid 0.402042 0.402042)
							(end 0.4318 0.3302)
						)
						(arc
							(start 0.4318 -0.3302)
							(mid 0.402042 -0.402042)
							(end 0.3302 -0.4318)
						)
					)
					(width 0)
					(fill yes)
				)
			)
		)
	)
	(footprint ""
		(layer "F.Cu")
		(at 168.021 -86.3854 90)
		(property "Reference" "R45"
			(at 0 0 90)
			(layer "F.SilkS")
			(hide yes)
			(effects
				(font
					(size 1.27 1.27)
				)
			)
		)
		(property "Value" "10KR2F-2-GP"
			(at 0.064008 -3.993896 90)
			(unlocked yes)
			(layer "F.Fab")
			(hide yes)
			(effects
				(font
					(size 1.016 1.016)
					(thickness 0.1524)
				)
			)
		)
		(property "Device Type" "R402H16"
			(at 0.064008 -5.517896 90)
			(unlocked yes)
			(layer "F.Fab")
			(hide yes)
			(effects
				(font
					(size 1.016 1.016)
					(thickness 0.1524)
				)
			)
		)
		(duplicate_pad_numbers_are_jumpers no)
		(fp_line
			(start 0.508 -0.9398)
			(end -0.508 -0.9398)
			(stroke
				(width 0.1524)
				(type default)
			)
			(layer "F.SilkS")
		)
		(fp_line
			(start -0.508 -0.9398)
			(end -0.508 0.9398)
			(stroke
				(width 0.1524)
				(type default)
			)
			(layer "F.SilkS")
		)
		(fp_rect
			(start -0.508 0.9398)
			(end 0.508 -0.9398)
			(stroke
				(width 0)
				(type default)
			)
			(fill no)
			(layer "F.CrtYd")
		)
		(fp_rect
			(start -0.508 0.9398)
			(end 0.508 -0.9398)
			(stroke
				(width 0)
				(type default)
			)
			(fill no)
			(layer "F.Fab")
		)
		(pad "1" smd custom
			(at 0 -0.4445 90)
			(size 0.1397 0.1397)
			(layers "F.Cu" "F.Mask" "F.Paste")
			(net "CLKGEN_OE1")
			(options
				(clearance outline)
				(anchor circle)
			)
			(primitives
				(gr_poly
					(pts
						(arc
							(start -0.1778 -0.2794)
							(mid -0.249642 -0.249642)
							(end -0.2794 -0.1778)
						)
						(arc
							(start -0.2794 0.1778)
							(mid -0.249642 0.249642)
							(end -0.1778 0.2794)
						)
						(arc
							(start 0.1778 0.2794)
							(mid 0.249642 0.249642)
							(end 0.2794 0.1778)
						)
						(arc
							(start 0.2794 -0.1778)
							(mid 0.249642 -0.249642)
							(end 0.1778 -0.2794)
						)
					)
					(width 0)
					(fill yes)
				)
			)
		)
		(pad "2" smd custom
			(at 0 0.4445 90)
			(size 0.1397 0.1397)
			(layers "F.Cu" "F.Mask" "F.Paste")
			(net "P1V8_CLKGEN")
			(options
				(clearance outline)
				(anchor circle)
			)
			(primitives
				(gr_poly
					(pts
						(arc
							(start -0.1778 -0.2794)
							(mid -0.249642 -0.249642)
							(end -0.2794 -0.1778)
						)
						(arc
							(start -0.2794 0.1778)
							(mid -0.249642 0.249642)
							(end -0.1778 0.2794)
						)
						(arc
							(start 0.1778 0.2794)
							(mid 0.249642 0.249642)
							(end 0.2794 0.1778)
						)
						(arc
							(start 0.2794 -0.1778)
							(mid 0.249642 -0.249642)
							(end 0.1778 -0.2794)
						)
					)
					(width 0)
					(fill yes)
				)
			)
		)
	)
	(footprint ""
		(layer "F.Cu")
		(at 47.350172 -50.306224 180)
		(property "Reference" "R497"
			(at 0 0 180)
			(layer "F.SilkS")
			(hide yes)
			(effects
				(font
					(size 1.27 1.27)
				)
			)
		)
		(property "Value" "33K2R2F-GP"
			(at 0.064008 -3.993896 180)
			(unlocked yes)
			(layer "F.Fab")
			(hide yes)
			(effects
				(font
					(size 1.016 1.016)
					(thickness 0.1524)
				)
			)
		)
		(property "Device Type" "R402H16"
			(at 0.064008 -5.517896 180)
			(unlocked yes)
			(layer "F.Fab")
			(hide yes)
			(effects
				(font
					(size 1.016 1.016)
					(thickness 0.1524)
				)
			)
		)
		(duplicate_pad_numbers_are_jumpers no)
		(fp_line
			(start 0.508 -0.9398)
			(end -0.508 -0.9398)
			(stroke
				(width 0.1524)
				(type default)
			)
			(layer "F.SilkS")
		)
		(fp_line
			(start -0.508 -0.9398)
			(end -0.508 0.9398)
			(stroke
				(width 0.1524)
				(type default)
			)
			(layer "F.SilkS")
		)
		(fp_rect
			(start -0.508 0.9398)
			(end 0.508 -0.9398)
			(stroke
				(width 0)
				(type default)
			)
			(fill no)
			(layer "F.CrtYd")
		)
		(fp_rect
			(start -0.508 0.9398)
			(end 0.508 -0.9398)
			(stroke
				(width 0)
				(type default)
			)
			(fill no)
			(layer "F.Fab")
		)
		(pad "1" smd custom
			(at 0 -0.4445 180)
			(size 0.1397 0.1397)
			(layers "F.Cu" "F.Mask" "F.Paste")
			(net "P3V3_STBY")
			(options
				(clearance outline)
				(anchor circle)
			)
			(primitives
				(gr_poly
					(pts
						(arc
							(start -0.1778 -0.2794)
							(mid -0.249642 -0.249642)
							(end -0.2794 -0.1778)
						)
						(arc
							(start -0.2794 0.1778)
							(mid -0.249642 0.249642)
							(end -0.1778 0.2794)
						)
						(arc
							(start 0.1778 0.2794)
							(mid 0.249642 0.249642)
							(end 0.2794 0.1778)
						)
						(arc
							(start 0.2794 -0.1778)
							(mid 0.249642 -0.249642)
							(end 0.1778 -0.2794)
						)
					)
					(width 0)
					(fill yes)
				)
			)
		)
		(pad "2" smd custom
			(at 0 0.4445 180)
			(size 0.1397 0.1397)
			(layers "F.Cu" "F.Mask" "F.Paste")
			(net "NVM_SI_R")
			(options
				(clearance outline)
				(anchor circle)
			)
			(primitives
				(gr_poly
					(pts
						(arc
							(start -0.1778 -0.2794)
							(mid -0.249642 -0.249642)
							(end -0.2794 -0.1778)
						)
						(arc
							(start -0.2794 0.1778)
							(mid -0.249642 0.249642)
							(end -0.1778 0.2794)
						)
						(arc
							(start 0.1778 0.2794)
							(mid 0.249642 0.249642)
							(end 0.2794 0.1778)
						)
						(arc
							(start 0.2794 -0.1778)
							(mid 0.249642 -0.249642)
							(end 0.1778 -0.2794)
						)
					)
					(width 0)
					(fill yes)
				)
			)
		)
	)
	(footprint ""
		(layer "F.Cu")
		(at 64.3636 -114.0968)
		(property "Reference" "R487"
			(at 0 0 0)
			(layer "F.SilkS")
			(hide yes)
			(effects
				(font
					(size 1.27 1.27)
				)
			)
		)
		(property "Value" "0R2J-2-GP"
			(at 0.064008 -3.993896 0)
			(unlocked yes)
			(layer "F.Fab")
			(hide yes)
			(effects
				(font
					(size 1.016 1.016)
					(thickness 0.1524)
				)
			)
		)
		(property "Device Type" "R402H16"
			(at 0.064008 -5.517896 0)
			(unlocked yes)
			(layer "F.Fab")
			(hide yes)
			(effects
				(font
					(size 1.016 1.016)
					(thickness 0.1524)
				)
			)
		)
		(duplicate_pad_numbers_are_jumpers no)
		(fp_line
			(start -0.508 -0.9398)
			(end -0.508 0.9398)
			(stroke
				(width 0.1524)
				(type default)
			)
			(layer "F.SilkS")
		)
		(fp_line
			(start 0.508 -0.9398)
			(end -0.508 -0.9398)
			(stroke
				(width 0.1524)
				(type default)
			)
			(layer "F.SilkS")
		)
		(fp_rect
			(start -0.508 0.9398)
			(end 0.508 -0.9398)
			(stroke
				(width 0)
				(type default)
			)
			(fill no)
			(layer "F.CrtYd")
		)
		(fp_rect
			(start -0.508 0.9398)
			(end 0.508 -0.9398)
			(stroke
				(width 0)
				(type default)
			)
			(fill no)
			(layer "F.Fab")
		)
		(pad "1" smd custom
			(at 0 -0.4445)
			(size 0.1397 0.1397)
			(layers "F.Cu" "F.Mask" "F.Paste")
			(net "BMC0_SDA11_R")
			(options
				(clearance outline)
				(anchor circle)
			)
			(primitives
				(gr_poly
					(pts
						(arc
							(start -0.1778 -0.2794)
							(mid -0.249642 -0.249642)
							(end -0.2794 -0.1778)
						)
						(arc
							(start -0.2794 0.1778)
							(mid -0.249642 0.249642)
							(end -0.1778 0.2794)
						)
						(arc
							(start 0.1778 0.2794)
							(mid 0.249642 0.249642)
							(end 0.2794 0.1778)
						)
						(arc
							(start 0.2794 -0.1778)
							(mid 0.249642 -0.249642)
							(end 0.1778 -0.2794)
						)
					)
					(width 0)
					(fill yes)
				)
			)
		)
		(pad "2" smd custom
			(at 0 0.4445)
			(size 0.1397 0.1397)
			(layers "F.Cu" "F.Mask" "F.Paste")
			(net "BMC_I2C11_MINI5_SDA_S")
			(options
				(clearance outline)
				(anchor circle)
			)
			(primitives
				(gr_poly
					(pts
						(arc
							(start -0.1778 -0.2794)
							(mid -0.249642 -0.249642)
							(end -0.2794 -0.1778)
						)
						(arc
							(start -0.2794 0.1778)
							(mid -0.249642 0.249642)
							(end -0.1778 0.2794)
						)
						(arc
							(start 0.1778 0.2794)
							(mid 0.249642 0.249642)
							(end 0.2794 0.1778)
						)
						(arc
							(start 0.2794 -0.1778)
							(mid 0.249642 -0.249642)
							(end 0.1778 -0.2794)
						)
					)
					(width 0)
					(fill yes)
				)
			)
		)
	)
	(footprint ""
		(layer "F.Cu")
		(at 229.108 -88.9 -90)
		(property "Reference" "R586"
			(at 0 0 270)
			(layer "F.SilkS")
			(hide yes)
			(effects
				(font
					(size 1.27 1.27)
				)
			)
		)
		(property "Value" "4K7R2F-GP"
			(at 0.064008 -3.993896 270)
			(unlocked yes)
			(layer "F.Fab")
			(hide yes)
			(effects
				(font
					(size 1.016 1.016)
					(thickness 0.1524)
				)
			)
		)
		(property "Device Type" "R402H16"
			(at 0.064008 -5.517896 270)
			(unlocked yes)
			(layer "F.Fab")
			(hide yes)
			(effects
				(font
					(size 1.016 1.016)
					(thickness 0.1524)
				)
			)
		)
		(duplicate_pad_numbers_are_jumpers no)
		(fp_line
			(start -0.508 -0.9398)
			(end -0.508 0.9398)
			(stroke
				(width 0.1524)
				(type default)
			)
			(layer "F.SilkS")
		)
		(fp_line
			(start 0.508 -0.9398)
			(end -0.508 -0.9398)
			(stroke
				(width 0.1524)
				(type default)
			)
			(layer "F.SilkS")
		)
		(fp_rect
			(start -0.508 0.9398)
			(end 0.508 -0.9398)
			(stroke
				(width 0)
				(type default)
			)
			(fill no)
			(layer "F.CrtYd")
		)
		(fp_rect
			(start -0.508 0.9398)
			(end 0.508 -0.9398)
			(stroke
				(width 0)
				(type default)
			)
			(fill no)
			(layer "F.Fab")
		)
		(pad "1" smd custom
			(at 0 -0.4445 270)
			(size 0.1397 0.1397)
			(layers "F.Cu" "F.Mask" "F.Paste")
			(net "P3V3_STBY")
			(options
				(clearance outline)
				(anchor circle)
			)
			(primitives
				(gr_poly
					(pts
						(arc
							(start -0.1778 -0.2794)
							(mid -0.249642 -0.249642)
							(end -0.2794 -0.1778)
						)
						(arc
							(start -0.2794 0.1778)
							(mid -0.249642 0.249642)
							(end -0.1778 0.2794)
						)
						(arc
							(start 0.1778 0.2794)
							(mid 0.249642 0.249642)
							(end 0.2794 0.1778)
						)
						(arc
							(start 0.2794 -0.1778)
							(mid 0.249642 -0.249642)
							(end 0.1778 -0.2794)
						)
					)
					(width 0)
					(fill yes)
				)
			)
		)
		(pad "2" smd custom
			(at 0 0.4445 270)
			(size 0.1397 0.1397)
			(layers "F.Cu" "F.Mask" "F.Paste")
			(net "TEMP_3_A1")
			(options
				(clearance outline)
				(anchor circle)
			)
			(primitives
				(gr_poly
					(pts
						(arc
							(start -0.1778 -0.2794)
							(mid -0.249642 -0.249642)
							(end -0.2794 -0.1778)
						)
						(arc
							(start -0.2794 0.1778)
							(mid -0.249642 0.249642)
							(end -0.1778 0.2794)
						)
						(arc
							(start 0.1778 0.2794)
							(mid 0.249642 0.249642)
							(end 0.2794 0.1778)
						)
						(arc
							(start 0.2794 -0.1778)
							(mid 0.249642 -0.249642)
							(end 0.1778 -0.2794)
						)
					)
					(width 0)
					(fill yes)
				)
			)
		)
	)
	(footprint ""
		(layer "F.Cu")
		(at 85.5726 -56.388 -90)
		(property "Reference" "R339"
			(at 0 0 270)
			(layer "F.SilkS")
			(hide yes)
			(effects
				(font
					(size 1.27 1.27)
				)
			)
		)
		(property "Value" "3K3R2F-2-GP"
			(at 0.064008 -3.993896 270)
			(unlocked yes)
			(layer "F.Fab")
			(hide yes)
			(effects
				(font
					(size 1.016 1.016)
					(thickness 0.1524)
				)
			)
		)
		(property "Device Type" "R402H16"
			(at 0.064008 -5.517896 270)
			(unlocked yes)
			(layer "F.Fab")
			(hide yes)
			(effects
				(font
					(size 1.016 1.016)
					(thickness 0.1524)
				)
			)
		)
		(duplicate_pad_numbers_are_jumpers no)
		(fp_line
			(start -0.508 -0.9398)
			(end -0.508 0.9398)
			(stroke
				(width 0.1524)
				(type default)
			)
			(layer "F.SilkS")
		)
		(fp_line
			(start 0.508 -0.9398)
			(end -0.508 -0.9398)
			(stroke
				(width 0.1524)
				(type default)
			)
			(layer "F.SilkS")
		)
		(fp_rect
			(start -0.508 0.9398)
			(end 0.508 -0.9398)
			(stroke
				(width 0)
				(type default)
			)
			(fill no)
			(layer "F.CrtYd")
		)
		(fp_rect
			(start -0.508 0.9398)
			(end 0.508 -0.9398)
			(stroke
				(width 0)
				(type default)
			)
			(fill no)
			(layer "F.Fab")
		)
		(pad "1" smd custom
			(at 0 -0.4445 270)
			(size 0.1397 0.1397)
			(layers "F.Cu" "F.Mask" "F.Paste")
			(net "AS_ROMA0_R")
			(options
				(clearance outline)
				(anchor circle)
			)
			(primitives
				(gr_poly
					(pts
						(arc
							(start -0.1778 -0.2794)
							(mid -0.249642 -0.249642)
							(end -0.2794 -0.1778)
						)
						(arc
							(start -0.2794 0.1778)
							(mid -0.249642 0.249642)
							(end -0.1778 0.2794)
						)
						(arc
							(start 0.1778 0.2794)
							(mid 0.249642 0.249642)
							(end 0.2794 0.1778)
						)
						(arc
							(start 0.2794 -0.1778)
							(mid 0.249642 -0.249642)
							(end 0.1778 -0.2794)
						)
					)
					(width 0)
					(fill yes)
				)
			)
		)
		(pad "2" smd custom
			(at 0 0.4445 270)
			(size 0.1397 0.1397)
			(layers "F.Cu" "F.Mask" "F.Paste")
			(net "P3V3_STBY")
			(options
				(clearance outline)
				(anchor circle)
			)
			(primitives
				(gr_poly
					(pts
						(arc
							(start -0.1778 -0.2794)
							(mid -0.249642 -0.249642)
							(end -0.2794 -0.1778)
						)
						(arc
							(start -0.2794 0.1778)
							(mid -0.249642 0.249642)
							(end -0.1778 0.2794)
						)
						(arc
							(start 0.1778 0.2794)
							(mid 0.249642 0.249642)
							(end 0.2794 0.1778)
						)
						(arc
							(start 0.2794 -0.1778)
							(mid 0.249642 -0.249642)
							(end 0.1778 -0.2794)
						)
					)
					(width 0)
					(fill yes)
				)
			)
		)
	)
	(footprint ""
		(layer "F.Cu")
		(at 224.79 -9.779 -90)
		(property "Reference" "U10"
			(at 0 0 270)
			(layer "F.SilkS")
			(hide yes)
			(effects
				(font
					(size 1.27 1.27)
				)
			)
		)
		(property "Value" "CAT24C128WI-GT3-GP"
			(at -3.707384 -1.5367 270)
			(unlocked yes)
			(layer "F.Fab")
			(hide yes)
			(effects
				(font
					(size 1.016 1.016)
					(thickness 0.1524)
				)
			)
		)
		(property "Device Type" "SOIC8H69"
			(at -3.707384 -3.0607 270)
			(unlocked yes)
			(layer "F.Fab")
			(hide yes)
			(effects
				(font
					(size 1.016 1.016)
					(thickness 0.1524)
				)
			)
		)
		(duplicate_pad_numbers_are_jumpers no)
		(fp_line
			(start -2.6289 3.4417)
			(end -2.6289 1.4732)
			(stroke
				(width 0.381)
				(type default)
			)
			(layer "F.SilkS")
		)
		(fp_line
			(start -2.7432 1.4224)
			(end -2.6416 1.4224)
			(stroke
				(width 0.1524)
				(type default)
			)
			(layer "F.SilkS")
		)
		(fp_line
			(start -2.7432 1.4224)
			(end 2.1336 1.4224)
			(stroke
				(width 0.1524)
				(type default)
			)
			(layer "F.SilkS")
		)
		(fp_line
			(start 2.1336 1.4224)
			(end 2.1336 -1.4224)
			(stroke
				(width 0.1524)
				(type default)
			)
			(layer "F.SilkS")
		)
		(fp_line
			(start -2.1844 -0.0508)
			(end -2.7178 0.508)
			(stroke
				(width 0.1524)
				(type default)
			)
			(layer "F.SilkS")
		)
		(fp_line
			(start -2.7178 -0.508)
			(end -2.1844 -0.0508)
			(stroke
				(width 0.1524)
				(type default)
			)
			(layer "F.SilkS")
		)
		(fp_line
			(start -2.7432 -1.4224)
			(end -2.7432 1.4224)
			(stroke
				(width 0.1524)
				(type default)
			)
			(layer "F.SilkS")
		)
		(fp_line
			(start 2.1336 -1.4224)
			(end -2.7432 -1.4224)
			(stroke
				(width 0.1524)
				(type default)
			)
			(layer "F.SilkS")
		)
		(fp_poly
			(pts
				(xy -2.2098 -1.4224) (xy -2.2098 1.4224) (xy 2.2098 1.4224) (xy 2.2098 -1.4224)
			)
			(stroke
				(width 0)
				(type default)
			)
			(fill yes)
			(layer "F.SilkS")
		)
		(fp_rect
			(start -2.450084 2.999994)
			(end 2.450084 -2.999994)
			(stroke
				(width 0)
				(type default)
			)
			(fill no)
			(layer "F.CrtYd")
		)
		(fp_poly
			(pts
				(xy -2.8194 3.6322) (xy -2.8194 -3.6322) (xy 2.8194 -3.6322) (xy 2.8194 1.18364) (xy 2.450084 1.18364)
				(xy 2.450084 -2.999994) (xy -2.450084 -2.999994) (xy -2.450084 2.999994) (xy 2.450084 2.999994)
				(xy 2.450084 1.18618) (xy 2.8194 1.18618) (xy 2.8194 3.6322)
			)
			(stroke
				(width 0)
				(type default)
			)
			(fill no)
			(layer "F.CrtYd")
		)
		(fp_rect
			(start -2.8194 3.6322)
			(end 2.8194 -3.6322)
			(stroke
				(width 0)
				(type default)
			)
			(fill no)
			(layer "F.Fab")
		)
		(pad "1" smd rect
			(at -1.905 2.54 270)
			(size 0.635 1.651)
			(layers "F.Cu" "F.Mask" "F.Paste")
			(net "EEPROM_A0")
		)
		(pad "2" smd rect
			(at -0.635 2.54 270)
			(size 0.635 1.651)
			(layers "F.Cu" "F.Mask" "F.Paste")
			(net "EEPROM_A1")
		)
		(pad "3" smd rect
			(at 0.635 2.54 270)
			(size 0.635 1.651)
			(layers "F.Cu" "F.Mask" "F.Paste")
			(net "EEPROM_A2")
		)
		(pad "4" smd rect
			(at 1.905 2.54 270)
			(size 0.635 1.651)
			(layers "F.Cu" "F.Mask" "F.Paste")
			(net "GND")
		)
		(pad "5" smd rect
			(at 1.905 -2.54 270)
			(size 0.635 1.651)
			(layers "F.Cu" "F.Mask" "F.Paste")
			(net "TWI_SDA2_R")
		)
		(pad "6" smd rect
			(at 0.635 -2.54 270)
			(size 0.635 1.651)
			(layers "F.Cu" "F.Mask" "F.Paste")
			(net "TWI_SCL2_R")
		)
		(pad "7" smd rect
			(at -0.635 -2.54 270)
			(size 0.635 1.651)
			(layers "F.Cu" "F.Mask" "F.Paste")
			(net "EEPROM_WP_8536")
		)
		(pad "8" smd rect
			(at -1.905 -2.54 270)
			(size 0.635 1.651)
			(layers "F.Cu" "F.Mask" "F.Paste")
			(net "P3V3_STBY")
		)
	)
	(footprint ""
		(layer "F.Cu")
		(at 28.2956 -184.0992)
		(property "Reference" "C261"
			(at 0 0 0)
			(layer "F.SilkS")
			(hide yes)
			(effects
				(font
					(size 1.27 1.27)
				)
			)
		)
		(property "Value" "SC220P50V3JN-GP"
			(at 0 -2.8194 0)
			(unlocked yes)
			(layer "F.Fab")
			(hide yes)
			(effects
				(font
					(size 1.016 1.016)
					(thickness 0.1524)
				)
			)
		)
		(property "Device Type" "C603H36"
			(at 0 -4.3434 0)
			(unlocked yes)
			(layer "F.Fab")
			(hide yes)
			(effects
				(font
					(size 1.016 1.016)
					(thickness 0.1524)
				)
			)
		)
		(duplicate_pad_numbers_are_jumpers no)
		(fp_line
			(start 0.508 0)
			(end -0.508 0)
			(stroke
				(width 0.2032)
				(type default)
			)
			(layer "F.SilkS")
		)
		(fp_rect
			(start -0.5842 1.3335)
			(end 0.5842 -1.3335)
			(stroke
				(width 0)
				(type default)
			)
			(fill no)
			(layer "F.CrtYd")
		)
		(fp_rect
			(start -0.5842 1.3335)
			(end 0.5842 -1.3335)
			(stroke
				(width 0)
				(type default)
			)
			(fill no)
			(layer "F.Fab")
		)
		(pad "1" smd custom
			(at 0 -0.762)
			(size 0.2159 0.2159)
			(layers "F.Cu" "F.Mask" "F.Paste")
			(net "BMC_I2C5_SDA_R")
			(options
				(clearance outline)
				(anchor circle)
			)
			(primitives
				(gr_poly
					(pts
						(arc
							(start -0.3302 -0.4318)
							(mid -0.402042 -0.402042)
							(end -0.4318 -0.3302)
						)
						(arc
							(start -0.4318 0.3302)
							(mid -0.402042 0.402042)
							(end -0.3302 0.4318)
						)
						(arc
							(start 0.3302 0.4318)
							(mid 0.402042 0.402042)
							(end 0.4318 0.3302)
						)
						(arc
							(start 0.4318 -0.3302)
							(mid 0.402042 -0.402042)
							(end 0.3302 -0.4318)
						)
					)
					(width 0)
					(fill yes)
				)
			)
		)
		(pad "2" smd custom
			(at 0 0.762)
			(size 0.2159 0.2159)
			(layers "F.Cu" "F.Mask" "F.Paste")
			(net "GND")
			(options
				(clearance outline)
				(anchor circle)
			)
			(primitives
				(gr_poly
					(pts
						(arc
							(start -0.3302 -0.4318)
							(mid -0.402042 -0.402042)
							(end -0.4318 -0.3302)
						)
						(arc
							(start -0.4318 0.3302)
							(mid -0.402042 0.402042)
							(end -0.3302 0.4318)
						)
						(arc
							(start 0.3302 0.4318)
							(mid 0.402042 0.402042)
							(end 0.4318 0.3302)
						)
						(arc
							(start 0.4318 -0.3302)
							(mid 0.402042 -0.402042)
							(end 0.3302 -0.4318)
						)
					)
					(width 0)
					(fill yes)
				)
			)
		)
	)
	(footprint ""
		(layer "F.Cu")
		(at 310.007 -68.5546)
		(property "Reference" "PG55"
			(at 0 0 0)
			(layer "F.SilkS")
			(hide yes)
			(effects
				(font
					(size 1.27 1.27)
				)
			)
		)
		(property "Value" "GAP-CLOSE-PWR-3-GP"
			(at 0.0254 -6.5786 0)
			(unlocked yes)
			(layer "F.Fab")
			(hide yes)
			(effects
				(font
					(size 1.016 1.016)
					(thickness 0.1524)
				)
			)
		)
		(property "Device Type" "GAP-CLOSE-PWR-3"
			(at 0.0254 -8.255 0)
			(unlocked yes)
			(layer "F.Fab")
			(hide yes)
			(effects
				(font
					(size 1.016 1.016)
					(thickness 0.1524)
				)
			)
		)
		(duplicate_pad_numbers_are_jumpers no)
		(fp_rect
			(start -0.7112 0.4572)
			(end 0.7112 -0.4572)
			(stroke
				(width 0)
				(type default)
			)
			(fill no)
			(layer "F.CrtYd")
		)
		(fp_poly
			(pts
				(xy -0.7112 -0.4572) (xy 0.7112 -0.4572) (xy 0.7112 0.4572) (xy -0.7112 0.4572)
			)
			(stroke
				(width 0)
				(type default)
			)
			(fill no)
			(layer "F.Fab")
		)
		(pad "1" smd rect
			(at -0.3048 0)
			(size 0.6604 0.762)
			(layers "F.Cu" "F.Mask" "F.Paste")
			(net "DUT_VDD")
		)
		(pad "2" smd rect
			(at 0.3048 0)
			(size 0.6604 0.762)
			(layers "F.Cu" "F.Mask" "F.Paste")
			(net "P0V9_E")
		)
	)
	(footprint ""
		(layer "F.Cu")
		(at 198.3994 -34.7726 180)
		(property "Reference" "R765"
			(at 0 0 180)
			(layer "F.SilkS")
			(hide yes)
			(effects
				(font
					(size 1.27 1.27)
				)
			)
		)
		(property "Value" "4K7R2F-GP"
			(at 0.064008 -3.993896 180)
			(unlocked yes)
			(layer "F.Fab")
			(hide yes)
			(effects
				(font
					(size 1.016 1.016)
					(thickness 0.1524)
				)
			)
		)
		(property "Device Type" "R402H16"
			(at 0.064008 -5.517896 180)
			(unlocked yes)
			(layer "F.Fab")
			(hide yes)
			(effects
				(font
					(size 1.016 1.016)
					(thickness 0.1524)
				)
			)
		)
		(duplicate_pad_numbers_are_jumpers no)
		(fp_line
			(start 0.508 -0.9398)
			(end -0.508 -0.9398)
			(stroke
				(width 0.1524)
				(type default)
			)
			(layer "F.SilkS")
		)
		(fp_line
			(start -0.508 -0.9398)
			(end -0.508 0.9398)
			(stroke
				(width 0.1524)
				(type default)
			)
			(layer "F.SilkS")
		)
		(fp_rect
			(start -0.508 0.9398)
			(end 0.508 -0.9398)
			(stroke
				(width 0)
				(type default)
			)
			(fill no)
			(layer "F.CrtYd")
		)
		(fp_rect
			(start -0.508 0.9398)
			(end 0.508 -0.9398)
			(stroke
				(width 0)
				(type default)
			)
			(fill no)
			(layer "F.Fab")
		)
		(pad "1" smd custom
			(at 0 -0.4445 180)
			(size 0.1397 0.1397)
			(layers "F.Cu" "F.Mask" "F.Paste")
			(net "U55_A0")
			(options
				(clearance outline)
				(anchor circle)
			)
			(primitives
				(gr_poly
					(pts
						(arc
							(start -0.1778 -0.2794)
							(mid -0.249642 -0.249642)
							(end -0.2794 -0.1778)
						)
						(arc
							(start -0.2794 0.1778)
							(mid -0.249642 0.249642)
							(end -0.1778 0.2794)
						)
						(arc
							(start 0.1778 0.2794)
							(mid 0.249642 0.249642)
							(end 0.2794 0.1778)
						)
						(arc
							(start 0.2794 -0.1778)
							(mid 0.249642 -0.249642)
							(end 0.1778 -0.2794)
						)
					)
					(width 0)
					(fill yes)
				)
			)
		)
		(pad "2" smd custom
			(at 0 0.4445 180)
			(size 0.1397 0.1397)
			(layers "F.Cu" "F.Mask" "F.Paste")
			(net "P3V3_STBY")
			(options
				(clearance outline)
				(anchor circle)
			)
			(primitives
				(gr_poly
					(pts
						(arc
							(start -0.1778 -0.2794)
							(mid -0.249642 -0.249642)
							(end -0.2794 -0.1778)
						)
						(arc
							(start -0.2794 0.1778)
							(mid -0.249642 0.249642)
							(end -0.1778 0.2794)
						)
						(arc
							(start 0.1778 0.2794)
							(mid 0.249642 0.249642)
							(end 0.2794 0.1778)
						)
						(arc
							(start 0.2794 -0.1778)
							(mid 0.249642 -0.249642)
							(end 0.1778 -0.2794)
						)
					)
					(width 0)
					(fill yes)
				)
			)
		)
	)
	(footprint ""
		(layer "F.Cu")
		(at 310.007 -67.0306)
		(property "Reference" "PG37"
			(at 0 0 0)
			(layer "F.SilkS")
			(hide yes)
			(effects
				(font
					(size 1.27 1.27)
				)
			)
		)
		(property "Value" "GAP-CLOSE-PWR-3-GP"
			(at 0.0254 -6.5786 0)
			(unlocked yes)
			(layer "F.Fab")
			(hide yes)
			(effects
				(font
					(size 1.016 1.016)
					(thickness 0.1524)
				)
			)
		)
		(property "Device Type" "GAP-CLOSE-PWR-3"
			(at 0.0254 -8.255 0)
			(unlocked yes)
			(layer "F.Fab")
			(hide yes)
			(effects
				(font
					(size 1.016 1.016)
					(thickness 0.1524)
				)
			)
		)
		(duplicate_pad_numbers_are_jumpers no)
		(fp_rect
			(start -0.7112 0.4572)
			(end 0.7112 -0.4572)
			(stroke
				(width 0)
				(type default)
			)
			(fill no)
			(layer "F.CrtYd")
		)
		(fp_poly
			(pts
				(xy -0.7112 -0.4572) (xy 0.7112 -0.4572) (xy 0.7112 0.4572) (xy -0.7112 0.4572)
			)
			(stroke
				(width 0)
				(type default)
			)
			(fill no)
			(layer "F.Fab")
		)
		(pad "1" smd rect
			(at -0.3048 0)
			(size 0.6604 0.762)
			(layers "F.Cu" "F.Mask" "F.Paste")
			(net "DUT_VDD")
		)
		(pad "2" smd rect
			(at 0.3048 0)
			(size 0.6604 0.762)
			(layers "F.Cu" "F.Mask" "F.Paste")
			(net "P0V9_E")
		)
	)
	(footprint ""
		(layer "F.Cu")
		(at 206.60995 -32.418274 90)
		(property "Reference" "R2979"
			(at 0 0 90)
			(layer "F.SilkS")
			(hide yes)
			(effects
				(font
					(size 1.27 1.27)
				)
			)
		)
		(property "Value" "0R2J-2-GP"
			(at 0.064008 -3.993896 90)
			(unlocked yes)
			(layer "F.Fab")
			(hide yes)
			(effects
				(font
					(size 1.016 1.016)
					(thickness 0.1524)
				)
			)
		)
		(property "Device Type" "R402H16"
			(at 0.064008 -5.517896 90)
			(unlocked yes)
			(layer "F.Fab")
			(hide yes)
			(effects
				(font
					(size 1.016 1.016)
					(thickness 0.1524)
				)
			)
		)
		(duplicate_pad_numbers_are_jumpers no)
		(fp_line
			(start 0.508 -0.9398)
			(end -0.508 -0.9398)
			(stroke
				(width 0.1524)
				(type default)
			)
			(layer "F.SilkS")
		)
		(fp_line
			(start -0.508 -0.9398)
			(end -0.508 0.9398)
			(stroke
				(width 0.1524)
				(type default)
			)
			(layer "F.SilkS")
		)
		(fp_rect
			(start -0.508 0.9398)
			(end 0.508 -0.9398)
			(stroke
				(width 0)
				(type default)
			)
			(fill no)
			(layer "F.CrtYd")
		)
		(fp_rect
			(start -0.508 0.9398)
			(end 0.508 -0.9398)
			(stroke
				(width 0)
				(type default)
			)
			(fill no)
			(layer "F.Fab")
		)
		(pad "1" smd custom
			(at 0 -0.4445 90)
			(size 0.1397 0.1397)
			(layers "F.Cu" "F.Mask" "F.Paste")
			(net "U55_SDA")
			(options
				(clearance outline)
				(anchor circle)
			)
			(primitives
				(gr_poly
					(pts
						(arc
							(start -0.1778 -0.2794)
							(mid -0.249642 -0.249642)
							(end -0.2794 -0.1778)
						)
						(arc
							(start -0.2794 0.1778)
							(mid -0.249642 0.249642)
							(end -0.1778 0.2794)
						)
						(arc
							(start 0.1778 0.2794)
							(mid 0.249642 0.249642)
							(end 0.2794 0.1778)
						)
						(arc
							(start 0.2794 -0.1778)
							(mid 0.249642 -0.249642)
							(end 0.1778 -0.2794)
						)
					)
					(width 0)
					(fill yes)
				)
			)
		)
		(pad "2" smd custom
			(at 0 0.4445 90)
			(size 0.1397 0.1397)
			(layers "F.Cu" "F.Mask" "F.Paste")
			(net "BMC_I2C11_MINI5_SDA_S")
			(options
				(clearance outline)
				(anchor circle)
			)
			(primitives
				(gr_poly
					(pts
						(arc
							(start -0.1778 -0.2794)
							(mid -0.249642 -0.249642)
							(end -0.2794 -0.1778)
						)
						(arc
							(start -0.2794 0.1778)
							(mid -0.249642 0.249642)
							(end -0.1778 0.2794)
						)
						(arc
							(start 0.1778 0.2794)
							(mid 0.249642 0.249642)
							(end 0.2794 0.1778)
						)
						(arc
							(start 0.2794 -0.1778)
							(mid 0.249642 -0.249642)
							(end 0.1778 -0.2794)
						)
					)
					(width 0)
					(fill yes)
				)
			)
		)
	)
	(footprint ""
		(layer "F.Cu")
		(at 49.17694 -147.03552)
		(property "Reference" "TP320"
			(at 0 0 0)
			(layer "F.SilkS")
			(hide yes)
			(effects
				(font
					(size 1.27 1.27)
				)
			)
		)
		(property "Value" "TPAD28-2-GP"
			(at -0.0127 -1.6637 0)
			(unlocked yes)
			(layer "F.Fab")
			(hide yes)
			(effects
				(font
					(size 1.016 1.016)
					(thickness 0.1524)
				)
			)
		)
		(property "Device Type" "TPAD28"
			(at -0.0127 -3.1877 0)
			(unlocked yes)
			(layer "F.Fab")
			(hide yes)
			(effects
				(font
					(size 1.016 1.016)
					(thickness 0.1524)
				)
			)
		)
		(duplicate_pad_numbers_are_jumpers no)
		(fp_poly
			(pts
				(arc
					(start 0.3556 0)
					(mid -0.3556 0)
					(end 0.3556 0)
				)
			)
			(stroke
				(width 0)
				(type default)
			)
			(fill no)
			(layer "F.CrtYd")
		)
		(fp_poly
			(pts
				(arc
					(start 0.6096 0)
					(mid -0.6096 0)
					(end 0.6096 0)
				)
			)
			(stroke
				(width 0)
				(type default)
			)
			(fill no)
			(layer "F.Fab")
		)
		(pad "1" smd circle
			(at 0 0)
			(size 0.7112 0.7112)
			(layers "F.Cu" "F.Mask" "F.Paste")
			(net "TP_GPIOO2")
		)
	)
	(footprint ""
		(layer "F.Cu")
		(at 57.1246 -28.2194)
		(property "Reference" "R569"
			(at 0 0 0)
			(layer "F.SilkS")
			(hide yes)
			(effects
				(font
					(size 1.27 1.27)
				)
			)
		)
		(property "Value" "4K7R2F-GP"
			(at 0.064008 -3.993896 0)
			(unlocked yes)
			(layer "F.Fab")
			(hide yes)
			(effects
				(font
					(size 1.016 1.016)
					(thickness 0.1524)
				)
			)
		)
		(property "Device Type" "R402H16"
			(at 0.064008 -5.517896 0)
			(unlocked yes)
			(layer "F.Fab")
			(hide yes)
			(effects
				(font
					(size 1.016 1.016)
					(thickness 0.1524)
				)
			)
		)
		(duplicate_pad_numbers_are_jumpers no)
		(fp_line
			(start -0.508 -0.9398)
			(end -0.508 0.9398)
			(stroke
				(width 0.1524)
				(type default)
			)
			(layer "F.SilkS")
		)
		(fp_line
			(start 0.508 -0.9398)
			(end -0.508 -0.9398)
			(stroke
				(width 0.1524)
				(type default)
			)
			(layer "F.SilkS")
		)
		(fp_rect
			(start -0.508 0.9398)
			(end 0.508 -0.9398)
			(stroke
				(width 0)
				(type default)
			)
			(fill no)
			(layer "F.CrtYd")
		)
		(fp_rect
			(start -0.508 0.9398)
			(end 0.508 -0.9398)
			(stroke
				(width 0)
				(type default)
			)
			(fill no)
			(layer "F.Fab")
		)
		(pad "1" smd custom
			(at 0 -0.4445)
			(size 0.1397 0.1397)
			(layers "F.Cu" "F.Mask" "F.Paste")
			(net "P3V3_STBY")
			(options
				(clearance outline)
				(anchor circle)
			)
			(primitives
				(gr_poly
					(pts
						(arc
							(start -0.1778 -0.2794)
							(mid -0.249642 -0.249642)
							(end -0.2794 -0.1778)
						)
						(arc
							(start -0.2794 0.1778)
							(mid -0.249642 0.249642)
							(end -0.1778 0.2794)
						)
						(arc
							(start 0.1778 0.2794)
							(mid 0.249642 0.249642)
							(end 0.2794 0.1778)
						)
						(arc
							(start 0.2794 -0.1778)
							(mid 0.249642 -0.249642)
							(end 0.1778 -0.2794)
						)
					)
					(width 0)
					(fill yes)
				)
			)
		)
		(pad "2" smd custom
			(at 0 0.4445)
			(size 0.1397 0.1397)
			(layers "F.Cu" "F.Mask" "F.Paste")
			(net "TRAY_RESET_N")
			(options
				(clearance outline)
				(anchor circle)
			)
			(primitives
				(gr_poly
					(pts
						(arc
							(start -0.1778 -0.2794)
							(mid -0.249642 -0.249642)
							(end -0.2794 -0.1778)
						)
						(arc
							(start -0.2794 0.1778)
							(mid -0.249642 0.249642)
							(end -0.1778 0.2794)
						)
						(arc
							(start 0.1778 0.2794)
							(mid 0.249642 0.249642)
							(end 0.2794 0.1778)
						)
						(arc
							(start 0.2794 -0.1778)
							(mid 0.249642 -0.249642)
							(end 0.1778 -0.2794)
						)
					)
					(width 0)
					(fill yes)
				)
			)
		)
	)
	(footprint ""
		(layer "F.Cu")
		(at 273.843496 -10.046716 -90)
		(property "Reference" "R2910"
			(at 0 0 270)
			(layer "F.SilkS")
			(hide yes)
			(effects
				(font
					(size 1.27 1.27)
				)
			)
		)
		(property "Value" "0R2J-2-GP"
			(at 0.064008 -3.993896 270)
			(unlocked yes)
			(layer "F.Fab")
			(hide yes)
			(effects
				(font
					(size 1.016 1.016)
					(thickness 0.1524)
				)
			)
		)
		(property "Device Type" "R402H16"
			(at 0.064008 -5.517896 270)
			(unlocked yes)
			(layer "F.Fab")
			(hide yes)
			(effects
				(font
					(size 1.016 1.016)
					(thickness 0.1524)
				)
			)
		)
		(duplicate_pad_numbers_are_jumpers no)
		(fp_line
			(start -0.508 -0.9398)
			(end -0.508 0.9398)
			(stroke
				(width 0.1524)
				(type default)
			)
			(layer "F.SilkS")
		)
		(fp_line
			(start 0.508 -0.9398)
			(end -0.508 -0.9398)
			(stroke
				(width 0.1524)
				(type default)
			)
			(layer "F.SilkS")
		)
		(fp_rect
			(start -0.508 0.9398)
			(end 0.508 -0.9398)
			(stroke
				(width 0)
				(type default)
			)
			(fill no)
			(layer "F.CrtYd")
		)
		(fp_rect
			(start -0.508 0.9398)
			(end 0.508 -0.9398)
			(stroke
				(width 0)
				(type default)
			)
			(fill no)
			(layer "F.Fab")
		)
		(pad "1" smd custom
			(at 0 -0.4445 270)
			(size 0.1397 0.1397)
			(layers "F.Cu" "F.Mask" "F.Paste")
			(net "CBL_PRSNT_N_5")
			(options
				(clearance outline)
				(anchor circle)
			)
			(primitives
				(gr_poly
					(pts
						(arc
							(start -0.1778 -0.2794)
							(mid -0.249642 -0.249642)
							(end -0.2794 -0.1778)
						)
						(arc
							(start -0.2794 0.1778)
							(mid -0.249642 0.249642)
							(end -0.1778 0.2794)
						)
						(arc
							(start 0.1778 0.2794)
							(mid 0.249642 0.249642)
							(end 0.2794 0.1778)
						)
						(arc
							(start 0.2794 -0.1778)
							(mid 0.249642 -0.249642)
							(end 0.1778 -0.2794)
						)
					)
					(width 0)
					(fill yes)
				)
			)
		)
		(pad "2" smd custom
			(at 0 0.4445 270)
			(size 0.1397 0.1397)
			(layers "F.Cu" "F.Mask" "F.Paste")
			(net "8644_SDA_R_5")
			(options
				(clearance outline)
				(anchor circle)
			)
			(primitives
				(gr_poly
					(pts
						(arc
							(start -0.1778 -0.2794)
							(mid -0.249642 -0.249642)
							(end -0.2794 -0.1778)
						)
						(arc
							(start -0.2794 0.1778)
							(mid -0.249642 0.249642)
							(end -0.1778 0.2794)
						)
						(arc
							(start 0.1778 0.2794)
							(mid 0.249642 0.249642)
							(end 0.2794 0.1778)
						)
						(arc
							(start 0.2794 -0.1778)
							(mid 0.249642 -0.249642)
							(end 0.1778 -0.2794)
						)
					)
					(width 0)
					(fill yes)
				)
			)
		)
	)
	(footprint ""
		(layer "F.Cu")
		(at 38.862 -56.896)
		(property "Reference" "U194"
			(at 0 0 0)
			(layer "F.SilkS")
			(hide yes)
			(effects
				(font
					(size 1.27 1.27)
				)
			)
		)
		(property "Value" "TPS2065DBVT-GP"
			(at 0 -5.1308 0)
			(unlocked yes)
			(layer "F.Fab")
			(hide yes)
			(effects
				(font
					(size 1.016 1.016)
					(thickness 0.1524)
				)
			)
		)
		(property "Device Type" "SOT-23-5H58"
			(at 0 -6.7564 0)
			(unlocked yes)
			(layer "F.Fab")
			(hide yes)
			(effects
				(font
					(size 1.016 1.016)
					(thickness 0.1524)
				)
			)
		)
		(duplicate_pad_numbers_are_jumpers no)
		(fp_line
			(start -1.778 -2.286)
			(end -1.778 2.286)
			(stroke
				(width 0.1524)
				(type default)
			)
			(layer "F.SilkS")
		)
		(fp_line
			(start -1.778 2.286)
			(end -0.254 2.286)
			(stroke
				(width 0.1524)
				(type default)
			)
			(layer "F.SilkS")
		)
		(fp_line
			(start -1.778 2.286)
			(end 1.778 2.286)
			(stroke
				(width 0.1524)
				(type default)
			)
			(layer "F.SilkS")
		)
		(fp_line
			(start -1.7272 2.2352)
			(end -1.7272 0.762)
			(stroke
				(width 0.3302)
				(type default)
			)
			(layer "F.SilkS")
		)
		(fp_line
			(start -0.7112 2.2352)
			(end -1.7272 2.2352)
			(stroke
				(width 0.3302)
				(type default)
			)
			(layer "F.SilkS")
		)
		(fp_line
			(start -0.254 2.286)
			(end 1.778 2.286)
			(stroke
				(width 0.1524)
				(type default)
			)
			(layer "F.SilkS")
		)
		(fp_line
			(start 1.778 -2.286)
			(end -1.778 -2.286)
			(stroke
				(width 0.1524)
				(type default)
			)
			(layer "F.SilkS")
		)
		(fp_line
			(start 1.778 2.286)
			(end 1.778 -2.286)
			(stroke
				(width 0.1524)
				(type default)
			)
			(layer "F.SilkS")
		)
		(fp_poly
			(pts
				(xy -0.9652 2.4384) (xy -1.3208 2.794) (xy -0.6096 2.794)
			)
			(stroke
				(width 0)
				(type default)
			)
			(fill yes)
			(layer "F.SilkS")
		)
		(fp_rect
			(start -1.778 2.286)
			(end 1.778 -2.286)
			(stroke
				(width 0)
				(type default)
			)
			(fill no)
			(layer "F.CrtYd")
		)
		(fp_rect
			(start -1.778 2.286)
			(end 1.778 -2.286)
			(stroke
				(width 0)
				(type default)
			)
			(fill no)
			(layer "F.Fab")
		)
		(pad "1" smd rect
			(at -0.94996 1.143)
			(size 0.508 1.524)
			(layers "F.Cu" "F.Mask" "F.Paste")
			(net "P5V_USB")
		)
		(pad "2" smd rect
			(at 0 1.143)
			(size 0.508 1.524)
			(layers "F.Cu" "F.Mask" "F.Paste")
			(net "GND")
		)
		(pad "3" smd rect
			(at 0.94996 1.143)
			(size 0.508 1.524)
			(layers "F.Cu" "F.Mask" "F.Paste")
			(net "USB_OC#")
		)
		(pad "4" smd rect
			(at 0.94996 -1.143)
			(size 0.508 1.524)
			(layers "F.Cu" "F.Mask" "F.Paste")
			(net "USB5V_EN")
		)
		(pad "5" smd rect
			(at -0.94996 -1.143)
			(size 0.508 1.524)
			(layers "F.Cu" "F.Mask" "F.Paste")
			(net "P5V_USB_BP1_F")
		)
	)
	(footprint ""
		(layer "F.Cu")
		(at 322.453 -99.568)
		(property "Reference" "R593"
			(at 0 0 0)
			(layer "F.SilkS")
			(hide yes)
			(effects
				(font
					(size 1.27 1.27)
				)
			)
		)
		(property "Value" "10KR2F-2-GP"
			(at 0.064008 -3.993896 0)
			(unlocked yes)
			(layer "F.Fab")
			(hide yes)
			(effects
				(font
					(size 1.016 1.016)
					(thickness 0.1524)
				)
			)
		)
		(property "Device Type" "R402H16"
			(at 0.064008 -5.517896 0)
			(unlocked yes)
			(layer "F.Fab")
			(hide yes)
			(effects
				(font
					(size 1.016 1.016)
					(thickness 0.1524)
				)
			)
		)
		(duplicate_pad_numbers_are_jumpers no)
		(fp_line
			(start -0.508 -0.9398)
			(end -0.508 0.9398)
			(stroke
				(width 0.1524)
				(type default)
			)
			(layer "F.SilkS")
		)
		(fp_line
			(start 0.508 -0.9398)
			(end -0.508 -0.9398)
			(stroke
				(width 0.1524)
				(type default)
			)
			(layer "F.SilkS")
		)
		(fp_rect
			(start -0.508 0.9398)
			(end 0.508 -0.9398)
			(stroke
				(width 0)
				(type default)
			)
			(fill no)
			(layer "F.CrtYd")
		)
		(fp_rect
			(start -0.508 0.9398)
			(end 0.508 -0.9398)
			(stroke
				(width 0)
				(type default)
			)
			(fill no)
			(layer "F.Fab")
		)
		(pad "1" smd custom
			(at 0 -0.4445)
			(size 0.1397 0.1397)
			(layers "F.Cu" "F.Mask" "F.Paste")
			(net "P3V3_STBY")
			(options
				(clearance outline)
				(anchor circle)
			)
			(primitives
				(gr_poly
					(pts
						(arc
							(start -0.1778 -0.2794)
							(mid -0.249642 -0.249642)
							(end -0.2794 -0.1778)
						)
						(arc
							(start -0.2794 0.1778)
							(mid -0.249642 0.249642)
							(end -0.1778 0.2794)
						)
						(arc
							(start 0.1778 0.2794)
							(mid 0.249642 0.249642)
							(end 0.2794 0.1778)
						)
						(arc
							(start 0.2794 -0.1778)
							(mid 0.249642 -0.249642)
							(end 0.1778 -0.2794)
						)
					)
					(width 0)
					(fill yes)
				)
			)
		)
		(pad "2" smd custom
			(at 0 0.4445)
			(size 0.1397 0.1397)
			(layers "F.Cu" "F.Mask" "F.Paste")
			(net "IOEXP_PMC1_AD0")
			(options
				(clearance outline)
				(anchor circle)
			)
			(primitives
				(gr_poly
					(pts
						(arc
							(start -0.1778 -0.2794)
							(mid -0.249642 -0.249642)
							(end -0.2794 -0.1778)
						)
						(arc
							(start -0.2794 0.1778)
							(mid -0.249642 0.249642)
							(end -0.1778 0.2794)
						)
						(arc
							(start 0.1778 0.2794)
							(mid 0.249642 0.249642)
							(end 0.2794 0.1778)
						)
						(arc
							(start 0.2794 -0.1778)
							(mid 0.249642 -0.249642)
							(end 0.1778 -0.2794)
						)
					)
					(width 0)
					(fill yes)
				)
			)
		)
	)
	(footprint ""
		(layer "F.Cu")
		(at 57.3786 -26.3144 180)
		(property "Reference" "R736"
			(at 0 0 180)
			(layer "F.SilkS")
			(hide yes)
			(effects
				(font
					(size 1.27 1.27)
				)
			)
		)
		(property "Value" "0R2J-2-GP"
			(at 0.064008 -3.993896 180)
			(unlocked yes)
			(layer "F.Fab")
			(hide yes)
			(effects
				(font
					(size 1.016 1.016)
					(thickness 0.1524)
				)
			)
		)
		(property "Device Type" "R402H16"
			(at 0.064008 -5.517896 180)
			(unlocked yes)
			(layer "F.Fab")
			(hide yes)
			(effects
				(font
					(size 1.016 1.016)
					(thickness 0.1524)
				)
			)
		)
		(duplicate_pad_numbers_are_jumpers no)
		(fp_line
			(start 0.508 -0.9398)
			(end -0.508 -0.9398)
			(stroke
				(width 0.1524)
				(type default)
			)
			(layer "F.SilkS")
		)
		(fp_line
			(start -0.508 -0.9398)
			(end -0.508 0.9398)
			(stroke
				(width 0.1524)
				(type default)
			)
			(layer "F.SilkS")
		)
		(fp_rect
			(start -0.508 0.9398)
			(end 0.508 -0.9398)
			(stroke
				(width 0)
				(type default)
			)
			(fill no)
			(layer "F.CrtYd")
		)
		(fp_rect
			(start -0.508 0.9398)
			(end 0.508 -0.9398)
			(stroke
				(width 0)
				(type default)
			)
			(fill no)
			(layer "F.Fab")
		)
		(pad "1" smd custom
			(at 0 -0.4445 180)
			(size 0.1397 0.1397)
			(layers "F.Cu" "F.Mask" "F.Paste")
			(net "IPMB_DAT")
			(options
				(clearance outline)
				(anchor circle)
			)
			(primitives
				(gr_poly
					(pts
						(arc
							(start -0.1778 -0.2794)
							(mid -0.249642 -0.249642)
							(end -0.2794 -0.1778)
						)
						(arc
							(start -0.2794 0.1778)
							(mid -0.249642 0.249642)
							(end -0.1778 0.2794)
						)
						(arc
							(start 0.1778 0.2794)
							(mid 0.249642 0.249642)
							(end 0.2794 0.1778)
						)
						(arc
							(start 0.2794 -0.1778)
							(mid 0.249642 -0.249642)
							(end 0.1778 -0.2794)
						)
					)
					(width 0)
					(fill yes)
				)
			)
		)
		(pad "2" smd custom
			(at 0 0.4445 180)
			(size 0.1397 0.1397)
			(layers "F.Cu" "F.Mask" "F.Paste")
			(net "BMC_I2C14_MINI8_SDA_S")
			(options
				(clearance outline)
				(anchor circle)
			)
			(primitives
				(gr_poly
					(pts
						(arc
							(start -0.1778 -0.2794)
							(mid -0.249642 -0.249642)
							(end -0.2794 -0.1778)
						)
						(arc
							(start -0.2794 0.1778)
							(mid -0.249642 0.249642)
							(end -0.1778 0.2794)
						)
						(arc
							(start 0.1778 0.2794)
							(mid 0.249642 0.249642)
							(end 0.2794 0.1778)
						)
						(arc
							(start 0.2794 -0.1778)
							(mid 0.249642 -0.249642)
							(end 0.1778 -0.2794)
						)
					)
					(width 0)
					(fill yes)
				)
			)
		)
	)
	(footprint ""
		(layer "F.Cu")
		(at 119.80164 -36.324032 90)
		(property "Reference" "R621"
			(at 0 0 90)
			(layer "F.SilkS")
			(hide yes)
			(effects
				(font
					(size 1.27 1.27)
				)
			)
		)
		(property "Value" "0R2J-2-GP"
			(at 0.064008 -3.993896 90)
			(unlocked yes)
			(layer "F.Fab")
			(hide yes)
			(effects
				(font
					(size 1.016 1.016)
					(thickness 0.1524)
				)
			)
		)
		(property "Device Type" "R402H16"
			(at 0.064008 -5.51815 90)
			(unlocked yes)
			(layer "F.Fab")
			(hide yes)
			(effects
				(font
					(size 1.016 1.016)
					(thickness 0.1524)
				)
			)
		)
		(duplicate_pad_numbers_are_jumpers no)
		(fp_line
			(start 0.508 -0.940054)
			(end -0.508 -0.9398)
			(stroke
				(width 0.1524)
				(type default)
			)
			(layer "F.SilkS")
		)
		(fp_line
			(start -0.508 -0.9398)
			(end -0.508 0.939546)
			(stroke
				(width 0.1524)
				(type default)
			)
			(layer "F.SilkS")
		)
		(fp_rect
			(start -0.508 0.939546)
			(end 0.508 -0.940054)
			(stroke
				(width 0)
				(type default)
			)
			(fill no)
			(layer "F.CrtYd")
		)
		(fp_rect
			(start -0.508 0.939546)
			(end 0.508 -0.940054)
			(stroke
				(width 0)
				(type default)
			)
			(fill no)
			(layer "F.Fab")
		)
		(pad "1" smd custom
			(at 0 -0.4445 90)
			(size 0.1397 0.1397)
			(layers "F.Cu" "F.Mask" "F.Paste")
			(net "UPLINK2_R")
			(options
				(clearance outline)
				(anchor circle)
			)
			(primitives
				(gr_poly
					(pts
						(arc
							(start -0.1778 -0.2794)
							(mid -0.249642 -0.249642)
							(end -0.2794 -0.1778)
						)
						(arc
							(start -0.2794 0.1778)
							(mid -0.249642 0.249642)
							(end -0.1778 0.2794)
						)
						(arc
							(start 0.1778 0.2794)
							(mid 0.249642 0.249642)
							(end 0.2794 0.1778)
						)
						(arc
							(start 0.2794 -0.1778)
							(mid 0.249642 -0.249642)
							(end 0.1778 -0.2794)
						)
					)
					(width 0)
					(fill yes)
				)
			)
		)
		(pad "2" smd custom
			(at 0 0.4445 90)
			(size 0.1397 0.1397)
			(layers "F.Cu" "F.Mask" "F.Paste")
			(net "UPLINK2")
			(options
				(clearance outline)
				(anchor circle)
			)
			(primitives
				(gr_poly
					(pts
						(arc
							(start -0.1778 -0.2794)
							(mid -0.249642 -0.249642)
							(end -0.2794 -0.1778)
						)
						(arc
							(start -0.2794 0.1778)
							(mid -0.249642 0.249642)
							(end -0.1778 0.2794)
						)
						(arc
							(start 0.1778 0.2794)
							(mid 0.249642 0.249642)
							(end 0.2794 0.1778)
						)
						(arc
							(start 0.2794 -0.1778)
							(mid 0.249642 -0.249642)
							(end 0.1778 -0.2794)
						)
					)
					(width 0)
					(fill yes)
				)
			)
		)
	)
	(footprint ""
		(layer "F.Cu")
		(at 149.008084 -212.420454 180)
		(property "Reference" "C313"
			(at 0 0 180)
			(layer "F.SilkS")
			(hide yes)
			(effects
				(font
					(size 1.27 1.27)
				)
			)
		)
		(property "Value" "SCD22U10V2KX-1GP"
			(at 1.1811 -2.7051 180)
			(unlocked yes)
			(layer "F.Fab")
			(hide yes)
			(effects
				(font
					(size 1.016 1.016)
					(thickness 0.1524)
				)
			)
		)
		(property "Device Type" "C402H22"
			(at 1.1811 -4.2291 180)
			(unlocked yes)
			(layer "F.Fab")
			(hide yes)
			(effects
				(font
					(size 1.016 1.016)
					(thickness 0.1524)
				)
			)
		)
		(duplicate_pad_numbers_are_jumpers no)
		(fp_rect
			(start -0.4318 0.9525)
			(end 0.4318 -0.9525)
			(stroke
				(width 0)
				(type default)
			)
			(fill no)
			(layer "F.CrtYd")
		)
		(fp_rect
			(start -0.4318 0.9525)
			(end 0.4318 -0.9525)
			(stroke
				(width 0)
				(type default)
			)
			(fill no)
			(layer "F.Fab")
		)
		(pad "1" smd custom
			(at 0 -0.4445 180)
			(size 0.1524 0.1524)
			(layers "F.Cu" "F.Mask" "F.Paste")
			(net "PCIE_TX_CAP_N56")
			(options
				(clearance outline)
				(anchor circle)
			)
			(primitives
				(gr_poly
					(pts
						(arc
							(start 0.3048 -0.2032)
							(mid 0.275042 -0.275042)
							(end 0.2032 -0.3048)
						)
						(arc
							(start -0.2032 -0.3048)
							(mid -0.275042 -0.275042)
							(end -0.3048 -0.2032)
						)
						(arc
							(start -0.3048 0.2032)
							(mid -0.275042 0.275042)
							(end -0.2032 0.3048)
						)
						(arc
							(start 0.2032 0.3048)
							(mid 0.275042 0.275042)
							(end 0.3048 0.2032)
						)
					)
					(width 0)
					(fill yes)
				)
			)
		)
		(pad "2" smd custom
			(at 0 0.4445 180)
			(size 0.1524 0.1524)
			(layers "F.Cu" "F.Mask" "F.Paste")
			(net "PCIE_TX_N56")
			(options
				(clearance outline)
				(anchor circle)
			)
			(primitives
				(gr_poly
					(pts
						(arc
							(start 0.3048 -0.2032)
							(mid 0.275042 -0.275042)
							(end 0.2032 -0.3048)
						)
						(arc
							(start -0.2032 -0.3048)
							(mid -0.275042 -0.275042)
							(end -0.3048 -0.2032)
						)
						(arc
							(start -0.3048 0.2032)
							(mid -0.275042 0.275042)
							(end -0.2032 0.3048)
						)
						(arc
							(start 0.2032 0.3048)
							(mid 0.275042 0.275042)
							(end 0.3048 0.2032)
						)
					)
					(width 0)
					(fill yes)
				)
			)
		)
	)
	(footprint ""
		(layer "F.Cu")
		(at 53.721 -131.445 -90)
		(property "Reference" "C190"
			(at 0 0 270)
			(layer "F.SilkS")
			(hide yes)
			(effects
				(font
					(size 1.27 1.27)
				)
			)
		)
		(property "Value" "SCD1U16V2KX-3GP"
			(at 1.1811 -2.7051 270)
			(unlocked yes)
			(layer "F.Fab")
			(hide yes)
			(effects
				(font
					(size 1.016 1.016)
					(thickness 0.1524)
				)
			)
		)
		(property "Device Type" "C402H22"
			(at 1.1811 -4.2291 270)
			(unlocked yes)
			(layer "F.Fab")
			(hide yes)
			(effects
				(font
					(size 1.016 1.016)
					(thickness 0.1524)
				)
			)
		)
		(duplicate_pad_numbers_are_jumpers no)
		(fp_rect
			(start -0.4318 0.9525)
			(end 0.4318 -0.9525)
			(stroke
				(width 0)
				(type default)
			)
			(fill no)
			(layer "F.CrtYd")
		)
		(fp_rect
			(start -0.4318 0.9525)
			(end 0.4318 -0.9525)
			(stroke
				(width 0)
				(type default)
			)
			(fill no)
			(layer "F.Fab")
		)
		(pad "1" smd custom
			(at 0 -0.4445 270)
			(size 0.1524 0.1524)
			(layers "F.Cu" "F.Mask" "F.Paste")
			(net "GND")
			(options
				(clearance outline)
				(anchor circle)
			)
			(primitives
				(gr_poly
					(pts
						(arc
							(start 0.3048 -0.2032)
							(mid 0.275042 -0.275042)
							(end 0.2032 -0.3048)
						)
						(arc
							(start -0.2032 -0.3048)
							(mid -0.275042 -0.275042)
							(end -0.3048 -0.2032)
						)
						(arc
							(start -0.3048 0.2032)
							(mid -0.275042 0.275042)
							(end -0.2032 0.3048)
						)
						(arc
							(start 0.2032 0.3048)
							(mid 0.275042 0.275042)
							(end 0.3048 0.2032)
						)
					)
					(width 0)
					(fill yes)
				)
			)
		)
		(pad "2" smd custom
			(at 0 0.4445 270)
			(size 0.1524 0.1524)
			(layers "F.Cu" "F.Mask" "F.Paste")
			(net "ADCVREFFN")
			(options
				(clearance outline)
				(anchor circle)
			)
			(primitives
				(gr_poly
					(pts
						(arc
							(start 0.3048 -0.2032)
							(mid 0.275042 -0.275042)
							(end 0.2032 -0.3048)
						)
						(arc
							(start -0.2032 -0.3048)
							(mid -0.275042 -0.275042)
							(end -0.3048 -0.2032)
						)
						(arc
							(start -0.3048 0.2032)
							(mid -0.275042 0.275042)
							(end -0.2032 0.3048)
						)
						(arc
							(start 0.2032 0.3048)
							(mid 0.275042 0.275042)
							(end 0.3048 0.2032)
						)
					)
					(width 0)
					(fill yes)
				)
			)
		)
	)
	(footprint ""
		(layer "F.Cu")
		(at 13.5128 -120.904 180)
		(property "Reference" "R601"
			(at 0 0 180)
			(layer "F.SilkS")
			(hide yes)
			(effects
				(font
					(size 1.27 1.27)
				)
			)
		)
		(property "Value" "4K7R2F-GP"
			(at 0.064008 -3.993896 180)
			(unlocked yes)
			(layer "F.Fab")
			(hide yes)
			(effects
				(font
					(size 1.016 1.016)
					(thickness 0.1524)
				)
			)
		)
		(property "Device Type" "R402H16"
			(at 0.064008 -5.517896 180)
			(unlocked yes)
			(layer "F.Fab")
			(hide yes)
			(effects
				(font
					(size 1.016 1.016)
					(thickness 0.1524)
				)
			)
		)
		(duplicate_pad_numbers_are_jumpers no)
		(fp_line
			(start 0.508 -0.9398)
			(end -0.508 -0.9398)
			(stroke
				(width 0.1524)
				(type default)
			)
			(layer "F.SilkS")
		)
		(fp_line
			(start -0.508 -0.9398)
			(end -0.508 0.9398)
			(stroke
				(width 0.1524)
				(type default)
			)
			(layer "F.SilkS")
		)
		(fp_rect
			(start -0.508 0.9398)
			(end 0.508 -0.9398)
			(stroke
				(width 0)
				(type default)
			)
			(fill no)
			(layer "F.CrtYd")
		)
		(fp_rect
			(start -0.508 0.9398)
			(end 0.508 -0.9398)
			(stroke
				(width 0)
				(type default)
			)
			(fill no)
			(layer "F.Fab")
		)
		(pad "1" smd custom
			(at 0 -0.4445 180)
			(size 0.1397 0.1397)
			(layers "F.Cu" "F.Mask" "F.Paste")
			(net "BMC_I2C1_MINI1_SCL_S")
			(options
				(clearance outline)
				(anchor circle)
			)
			(primitives
				(gr_poly
					(pts
						(arc
							(start -0.1778 -0.2794)
							(mid -0.249642 -0.249642)
							(end -0.2794 -0.1778)
						)
						(arc
							(start -0.2794 0.1778)
							(mid -0.249642 0.249642)
							(end -0.1778 0.2794)
						)
						(arc
							(start 0.1778 0.2794)
							(mid 0.249642 0.249642)
							(end 0.2794 0.1778)
						)
						(arc
							(start 0.2794 -0.1778)
							(mid 0.249642 -0.249642)
							(end 0.1778 -0.2794)
						)
					)
					(width 0)
					(fill yes)
				)
			)
		)
		(pad "2" smd custom
			(at 0 0.4445 180)
			(size 0.1397 0.1397)
			(layers "F.Cu" "F.Mask" "F.Paste")
			(net "P3V3_STBY")
			(options
				(clearance outline)
				(anchor circle)
			)
			(primitives
				(gr_poly
					(pts
						(arc
							(start -0.1778 -0.2794)
							(mid -0.249642 -0.249642)
							(end -0.2794 -0.1778)
						)
						(arc
							(start -0.2794 0.1778)
							(mid -0.249642 0.249642)
							(end -0.1778 0.2794)
						)
						(arc
							(start 0.1778 0.2794)
							(mid 0.249642 0.249642)
							(end 0.2794 0.1778)
						)
						(arc
							(start 0.2794 -0.1778)
							(mid 0.249642 -0.249642)
							(end 0.1778 -0.2794)
						)
					)
					(width 0)
					(fill yes)
				)
			)
		)
	)
	(footprint ""
		(layer "F.Cu")
		(at 65.4812 -154.0256 90)
		(property "Reference" "PC70"
			(at 0 0 90)
			(layer "F.SilkS")
			(hide yes)
			(effects
				(font
					(size 1.27 1.27)
				)
			)
		)
		(property "Value" "SC4D7U16V5KX-1-GP"
			(at -0.0762 -6.1214 90)
			(unlocked yes)
			(layer "F.Fab")
			(hide yes)
			(effects
				(font
					(size 1.016 1.016)
					(thickness 0.1524)
				)
			)
		)
		(property "Device Type" "C805H56"
			(at -0.0762 -8.1534 90)
			(unlocked yes)
			(layer "F.Fab")
			(hide yes)
			(effects
				(font
					(size 1.016 1.016)
					(thickness 0.1524)
				)
			)
		)
		(duplicate_pad_numbers_are_jumpers no)
		(fp_line
			(start 0.635 0)
			(end -0.635 0)
			(stroke
				(width 0.508)
				(type default)
			)
			(layer "F.SilkS")
		)
		(fp_rect
			(start -0.9652 1.778)
			(end 0.9652 -1.778)
			(stroke
				(width 0)
				(type default)
			)
			(fill no)
			(layer "F.CrtYd")
		)
		(fp_poly
			(pts
				(xy -0.9652 -1.778) (xy 0.9652 -1.778) (xy 0.9652 1.778) (xy -0.9652 1.778)
			)
			(stroke
				(width 0)
				(type default)
			)
			(fill no)
			(layer "F.Fab")
		)
		(pad "1" smd rect
			(at 0 -0.9652 90)
			(size 1.397 1.143)
			(layers "F.Cu" "F.Mask" "F.Paste")
			(net "P1V53_PWR")
		)
		(pad "2" smd rect
			(at 0 0.9652 90)
			(size 1.397 1.143)
			(layers "F.Cu" "F.Mask" "F.Paste")
			(net "GND")
		)
	)
	(footprint ""
		(layer "F.Cu")
		(at 6.4262 -188.1886)
		(property "Reference" "PR9007"
			(at 0 0 0)
			(layer "F.SilkS")
			(hide yes)
			(effects
				(font
					(size 1.27 1.27)
				)
			)
		)
		(property "Value" "0R2J-2-GP"
			(at 0.064008 -3.993896 0)
			(unlocked yes)
			(layer "F.Fab")
			(hide yes)
			(effects
				(font
					(size 1.016 1.016)
					(thickness 0.1524)
				)
			)
		)
		(property "Device Type" "R402H16"
			(at 0.064008 -5.517896 0)
			(unlocked yes)
			(layer "F.Fab")
			(hide yes)
			(effects
				(font
					(size 1.016 1.016)
					(thickness 0.1524)
				)
			)
		)
		(duplicate_pad_numbers_are_jumpers no)
		(fp_line
			(start -0.508 -0.9398)
			(end -0.508 0.9398)
			(stroke
				(width 0.1524)
				(type default)
			)
			(layer "F.SilkS")
		)
		(fp_line
			(start 0.508 -0.9398)
			(end -0.508 -0.9398)
			(stroke
				(width 0.1524)
				(type default)
			)
			(layer "F.SilkS")
		)
		(fp_rect
			(start -0.508 0.9398)
			(end 0.508 -0.9398)
			(stroke
				(width 0)
				(type default)
			)
			(fill no)
			(layer "F.CrtYd")
		)
		(fp_rect
			(start -0.508 0.9398)
			(end 0.508 -0.9398)
			(stroke
				(width 0)
				(type default)
			)
			(fill no)
			(layer "F.Fab")
		)
		(pad "1" smd custom
			(at 0 -0.4445)
			(size 0.1397 0.1397)
			(layers "F.Cu" "F.Mask" "F.Paste")
			(net "MB0_HS_ENABLE")
			(options
				(clearance outline)
				(anchor circle)
			)
			(primitives
				(gr_poly
					(pts
						(arc
							(start -0.1778 -0.2794)
							(mid -0.249642 -0.249642)
							(end -0.2794 -0.1778)
						)
						(arc
							(start -0.2794 0.1778)
							(mid -0.249642 0.249642)
							(end -0.1778 0.2794)
						)
						(arc
							(start 0.1778 0.2794)
							(mid 0.249642 0.249642)
							(end 0.2794 0.1778)
						)
						(arc
							(start 0.2794 -0.1778)
							(mid 0.249642 -0.249642)
							(end 0.1778 -0.2794)
						)
					)
					(width 0)
					(fill yes)
				)
			)
		)
		(pad "2" smd custom
			(at 0 0.4445)
			(size 0.1397 0.1397)
			(layers "F.Cu" "F.Mask" "F.Paste")
			(net "Q95_D")
			(options
				(clearance outline)
				(anchor circle)
			)
			(primitives
				(gr_poly
					(pts
						(arc
							(start -0.1778 -0.2794)
							(mid -0.249642 -0.249642)
							(end -0.2794 -0.1778)
						)
						(arc
							(start -0.2794 0.1778)
							(mid -0.249642 0.249642)
							(end -0.1778 0.2794)
						)
						(arc
							(start 0.1778 0.2794)
							(mid 0.249642 0.249642)
							(end 0.2794 0.1778)
						)
						(arc
							(start 0.2794 -0.1778)
							(mid 0.249642 -0.249642)
							(end 0.1778 -0.2794)
						)
					)
					(width 0)
					(fill yes)
				)
			)
		)
	)
	(footprint ""
		(layer "F.Cu")
		(at 273.843496 -8.903716 -90)
		(property "Reference" "R2901"
			(at 0 0 270)
			(layer "F.SilkS")
			(hide yes)
			(effects
				(font
					(size 1.27 1.27)
				)
			)
		)
		(property "Value" "0R2J-2-GP"
			(at 0.064008 -3.993896 270)
			(unlocked yes)
			(layer "F.Fab")
			(hide yes)
			(effects
				(font
					(size 1.016 1.016)
					(thickness 0.1524)
				)
			)
		)
		(property "Device Type" "R402H16"
			(at 0.064008 -5.517896 270)
			(unlocked yes)
			(layer "F.Fab")
			(hide yes)
			(effects
				(font
					(size 1.016 1.016)
					(thickness 0.1524)
				)
			)
		)
		(duplicate_pad_numbers_are_jumpers no)
		(fp_line
			(start -0.508 -0.9398)
			(end -0.508 0.9398)
			(stroke
				(width 0.1524)
				(type default)
			)
			(layer "F.SilkS")
		)
		(fp_line
			(start 0.508 -0.9398)
			(end -0.508 -0.9398)
			(stroke
				(width 0.1524)
				(type default)
			)
			(layer "F.SilkS")
		)
		(fp_rect
			(start -0.508 0.9398)
			(end 0.508 -0.9398)
			(stroke
				(width 0)
				(type default)
			)
			(fill no)
			(layer "F.CrtYd")
		)
		(fp_rect
			(start -0.508 0.9398)
			(end 0.508 -0.9398)
			(stroke
				(width 0)
				(type default)
			)
			(fill no)
			(layer "F.Fab")
		)
		(pad "1" smd custom
			(at 0 -0.4445 270)
			(size 0.1397 0.1397)
			(layers "F.Cu" "F.Mask" "F.Paste")
			(net "BMC_I2C11_MINI5_SDA")
			(options
				(clearance outline)
				(anchor circle)
			)
			(primitives
				(gr_poly
					(pts
						(arc
							(start -0.1778 -0.2794)
							(mid -0.249642 -0.249642)
							(end -0.2794 -0.1778)
						)
						(arc
							(start -0.2794 0.1778)
							(mid -0.249642 0.249642)
							(end -0.1778 0.2794)
						)
						(arc
							(start 0.1778 0.2794)
							(mid 0.249642 0.249642)
							(end 0.2794 0.1778)
						)
						(arc
							(start 0.2794 -0.1778)
							(mid 0.249642 -0.249642)
							(end 0.1778 -0.2794)
						)
					)
					(width 0)
					(fill yes)
				)
			)
		)
		(pad "2" smd custom
			(at 0 0.4445 270)
			(size 0.1397 0.1397)
			(layers "F.Cu" "F.Mask" "F.Paste")
			(net "8644_SDA_R_5")
			(options
				(clearance outline)
				(anchor circle)
			)
			(primitives
				(gr_poly
					(pts
						(arc
							(start -0.1778 -0.2794)
							(mid -0.249642 -0.249642)
							(end -0.2794 -0.1778)
						)
						(arc
							(start -0.2794 0.1778)
							(mid -0.249642 0.249642)
							(end -0.1778 0.2794)
						)
						(arc
							(start 0.1778 0.2794)
							(mid 0.249642 0.249642)
							(end 0.2794 0.1778)
						)
						(arc
							(start 0.2794 -0.1778)
							(mid 0.249642 -0.249642)
							(end 0.1778 -0.2794)
						)
					)
					(width 0)
					(fill yes)
				)
			)
		)
	)
	(footprint ""
		(layer "F.Cu")
		(at 53.721 -118.11 -90)
		(property "Reference" "R460"
			(at 0 0 270)
			(layer "F.SilkS")
			(hide yes)
			(effects
				(font
					(size 1.27 1.27)
				)
			)
		)
		(property "Value" "0R2J-2-GP"
			(at 0.064008 -3.993896 270)
			(unlocked yes)
			(layer "F.Fab")
			(hide yes)
			(effects
				(font
					(size 1.016 1.016)
					(thickness 0.1524)
				)
			)
		)
		(property "Device Type" "R402H16"
			(at 0.064008 -5.517896 270)
			(unlocked yes)
			(layer "F.Fab")
			(hide yes)
			(effects
				(font
					(size 1.016 1.016)
					(thickness 0.1524)
				)
			)
		)
		(duplicate_pad_numbers_are_jumpers no)
		(fp_line
			(start -0.508 -0.9398)
			(end -0.508 0.9398)
			(stroke
				(width 0.1524)
				(type default)
			)
			(layer "F.SilkS")
		)
		(fp_line
			(start 0.508 -0.9398)
			(end -0.508 -0.9398)
			(stroke
				(width 0.1524)
				(type default)
			)
			(layer "F.SilkS")
		)
		(fp_rect
			(start -0.508 0.9398)
			(end 0.508 -0.9398)
			(stroke
				(width 0)
				(type default)
			)
			(fill no)
			(layer "F.CrtYd")
		)
		(fp_rect
			(start -0.508 0.9398)
			(end 0.508 -0.9398)
			(stroke
				(width 0)
				(type default)
			)
			(fill no)
			(layer "F.Fab")
		)
		(pad "1" smd custom
			(at 0 -0.4445 270)
			(size 0.1397 0.1397)
			(layers "F.Cu" "F.Mask" "F.Paste")
			(net "BMC_I2C7_B_DPB_SDA")
			(options
				(clearance outline)
				(anchor circle)
			)
			(primitives
				(gr_poly
					(pts
						(arc
							(start -0.1778 -0.2794)
							(mid -0.249642 -0.249642)
							(end -0.2794 -0.1778)
						)
						(arc
							(start -0.2794 0.1778)
							(mid -0.249642 0.249642)
							(end -0.1778 0.2794)
						)
						(arc
							(start 0.1778 0.2794)
							(mid 0.249642 0.249642)
							(end 0.2794 0.1778)
						)
						(arc
							(start 0.2794 -0.1778)
							(mid 0.249642 -0.249642)
							(end 0.1778 -0.2794)
						)
					)
					(width 0)
					(fill yes)
				)
			)
		)
		(pad "2" smd custom
			(at 0 0.4445 270)
			(size 0.1397 0.1397)
			(layers "F.Cu" "F.Mask" "F.Paste")
			(net "BMC0_SMB7_DAT")
			(options
				(clearance outline)
				(anchor circle)
			)
			(primitives
				(gr_poly
					(pts
						(arc
							(start -0.1778 -0.2794)
							(mid -0.249642 -0.249642)
							(end -0.2794 -0.1778)
						)
						(arc
							(start -0.2794 0.1778)
							(mid -0.249642 0.249642)
							(end -0.1778 0.2794)
						)
						(arc
							(start 0.1778 0.2794)
							(mid 0.249642 0.249642)
							(end 0.2794 0.1778)
						)
						(arc
							(start 0.2794 -0.1778)
							(mid 0.249642 -0.249642)
							(end 0.1778 -0.2794)
						)
					)
					(width 0)
					(fill yes)
				)
			)
		)
	)
	(footprint ""
		(layer "F.Cu")
		(at 52.578 -178.816 90)
		(property "Reference" "C710"
			(at 0 0 90)
			(layer "F.SilkS")
			(hide yes)
			(effects
				(font
					(size 1.27 1.27)
				)
			)
		)
		(property "Value" "SC220P50V3JN-GP"
			(at 0 -2.8194 90)
			(unlocked yes)
			(layer "F.Fab")
			(hide yes)
			(effects
				(font
					(size 1.016 1.016)
					(thickness 0.1524)
				)
			)
		)
		(property "Device Type" "C603H36"
			(at 0 -4.3434 90)
			(unlocked yes)
			(layer "F.Fab")
			(hide yes)
			(effects
				(font
					(size 1.016 1.016)
					(thickness 0.1524)
				)
			)
		)
		(duplicate_pad_numbers_are_jumpers no)
		(fp_line
			(start 0.508 0)
			(end -0.508 0)
			(stroke
				(width 0.2032)
				(type default)
			)
			(layer "F.SilkS")
		)
		(fp_rect
			(start -0.5842 1.3335)
			(end 0.5842 -1.3335)
			(stroke
				(width 0)
				(type default)
			)
			(fill no)
			(layer "F.CrtYd")
		)
		(fp_rect
			(start -0.5842 1.3335)
			(end 0.5842 -1.3335)
			(stroke
				(width 0)
				(type default)
			)
			(fill no)
			(layer "F.Fab")
		)
		(pad "1" smd custom
			(at 0 -0.762 90)
			(size 0.2159 0.2159)
			(layers "F.Cu" "F.Mask" "F.Paste")
			(net "BMC_I2C8_CLKBUF1_SCL_R")
			(options
				(clearance outline)
				(anchor circle)
			)
			(primitives
				(gr_poly
					(pts
						(arc
							(start -0.3302 -0.4318)
							(mid -0.402042 -0.402042)
							(end -0.4318 -0.3302)
						)
						(arc
							(start -0.4318 0.3302)
							(mid -0.402042 0.402042)
							(end -0.3302 0.4318)
						)
						(arc
							(start 0.3302 0.4318)
							(mid 0.402042 0.402042)
							(end 0.4318 0.3302)
						)
						(arc
							(start 0.4318 -0.3302)
							(mid 0.402042 -0.402042)
							(end 0.3302 -0.4318)
						)
					)
					(width 0)
					(fill yes)
				)
			)
		)
		(pad "2" smd custom
			(at 0 0.762 90)
			(size 0.2159 0.2159)
			(layers "F.Cu" "F.Mask" "F.Paste")
			(net "GND")
			(options
				(clearance outline)
				(anchor circle)
			)
			(primitives
				(gr_poly
					(pts
						(arc
							(start -0.3302 -0.4318)
							(mid -0.402042 -0.402042)
							(end -0.4318 -0.3302)
						)
						(arc
							(start -0.4318 0.3302)
							(mid -0.402042 0.402042)
							(end -0.3302 0.4318)
						)
						(arc
							(start 0.3302 0.4318)
							(mid 0.402042 0.402042)
							(end 0.4318 0.3302)
						)
						(arc
							(start 0.4318 -0.3302)
							(mid 0.402042 -0.402042)
							(end 0.3302 -0.4318)
						)
					)
					(width 0)
					(fill yes)
				)
			)
		)
	)
	(footprint ""
		(layer "F.Cu")
		(at 173.808136 -212.420454 180)
		(property "Reference" "C139"
			(at 0 0 180)
			(layer "F.SilkS")
			(hide yes)
			(effects
				(font
					(size 1.27 1.27)
				)
			)
		)
		(property "Value" "SCD22U10V2KX-1GP"
			(at 1.1811 -2.7051 180)
			(unlocked yes)
			(layer "F.Fab")
			(hide yes)
			(effects
				(font
					(size 1.016 1.016)
					(thickness 0.1524)
				)
			)
		)
		(property "Device Type" "C402H22"
			(at 1.1811 -4.2291 180)
			(unlocked yes)
			(layer "F.Fab")
			(hide yes)
			(effects
				(font
					(size 1.016 1.016)
					(thickness 0.1524)
				)
			)
		)
		(duplicate_pad_numbers_are_jumpers no)
		(fp_rect
			(start -0.4318 0.9525)
			(end 0.4318 -0.9525)
			(stroke
				(width 0)
				(type default)
			)
			(fill no)
			(layer "F.CrtYd")
		)
		(fp_rect
			(start -0.4318 0.9525)
			(end 0.4318 -0.9525)
			(stroke
				(width 0)
				(type default)
			)
			(fill no)
			(layer "F.Fab")
		)
		(pad "1" smd custom
			(at 0 -0.4445 180)
			(size 0.1524 0.1524)
			(layers "F.Cu" "F.Mask" "F.Paste")
			(net "PCIE_TX_CAP_N49")
			(options
				(clearance outline)
				(anchor circle)
			)
			(primitives
				(gr_poly
					(pts
						(arc
							(start 0.3048 -0.2032)
							(mid 0.275042 -0.275042)
							(end 0.2032 -0.3048)
						)
						(arc
							(start -0.2032 -0.3048)
							(mid -0.275042 -0.275042)
							(end -0.3048 -0.2032)
						)
						(arc
							(start -0.3048 0.2032)
							(mid -0.275042 0.275042)
							(end -0.2032 0.3048)
						)
						(arc
							(start 0.2032 0.3048)
							(mid 0.275042 0.275042)
							(end 0.3048 0.2032)
						)
					)
					(width 0)
					(fill yes)
				)
			)
		)
		(pad "2" smd custom
			(at 0 0.4445 180)
			(size 0.1524 0.1524)
			(layers "F.Cu" "F.Mask" "F.Paste")
			(net "PCIE_TX_N49")
			(options
				(clearance outline)
				(anchor circle)
			)
			(primitives
				(gr_poly
					(pts
						(arc
							(start 0.3048 -0.2032)
							(mid 0.275042 -0.275042)
							(end 0.2032 -0.3048)
						)
						(arc
							(start -0.2032 -0.3048)
							(mid -0.275042 -0.275042)
							(end -0.3048 -0.2032)
						)
						(arc
							(start -0.3048 0.2032)
							(mid -0.275042 0.275042)
							(end -0.2032 0.3048)
						)
						(arc
							(start 0.2032 0.3048)
							(mid 0.275042 0.275042)
							(end 0.3048 0.2032)
						)
					)
					(width 0)
					(fill yes)
				)
			)
		)
	)
	(footprint ""
		(layer "F.Cu")
		(at 229.108 -23.241 180)
		(property "Reference" "R3718"
			(at 0 0 180)
			(layer "F.SilkS")
			(hide yes)
			(effects
				(font
					(size 1.27 1.27)
				)
			)
		)
		(property "Value" "4K7R2F-GP"
			(at 0.064008 -3.993896 180)
			(unlocked yes)
			(layer "F.Fab")
			(hide yes)
			(effects
				(font
					(size 1.016 1.016)
					(thickness 0.1524)
				)
			)
		)
		(property "Device Type" "R402H16"
			(at 0.064008 -5.517896 180)
			(unlocked yes)
			(layer "F.Fab")
			(hide yes)
			(effects
				(font
					(size 1.016 1.016)
					(thickness 0.1524)
				)
			)
		)
		(duplicate_pad_numbers_are_jumpers no)
		(fp_line
			(start 0.508 -0.9398)
			(end -0.508 -0.9398)
			(stroke
				(width 0.1524)
				(type default)
			)
			(layer "F.SilkS")
		)
		(fp_line
			(start -0.508 -0.9398)
			(end -0.508 0.9398)
			(stroke
				(width 0.1524)
				(type default)
			)
			(layer "F.SilkS")
		)
		(fp_rect
			(start -0.508 0.9398)
			(end 0.508 -0.9398)
			(stroke
				(width 0)
				(type default)
			)
			(fill no)
			(layer "F.CrtYd")
		)
		(fp_rect
			(start -0.508 0.9398)
			(end 0.508 -0.9398)
			(stroke
				(width 0)
				(type default)
			)
			(fill no)
			(layer "F.Fab")
		)
		(pad "1" smd custom
			(at 0 -0.4445 180)
			(size 0.1397 0.1397)
			(layers "F.Cu" "F.Mask" "F.Paste")
			(net "HOST2_RST_N_LS")
			(options
				(clearance outline)
				(anchor circle)
			)
			(primitives
				(gr_poly
					(pts
						(arc
							(start -0.1778 -0.2794)
							(mid -0.249642 -0.249642)
							(end -0.2794 -0.1778)
						)
						(arc
							(start -0.2794 0.1778)
							(mid -0.249642 0.249642)
							(end -0.1778 0.2794)
						)
						(arc
							(start 0.1778 0.2794)
							(mid 0.249642 0.249642)
							(end 0.2794 0.1778)
						)
						(arc
							(start 0.2794 -0.1778)
							(mid 0.249642 -0.249642)
							(end 0.1778 -0.2794)
						)
					)
					(width 0)
					(fill yes)
				)
			)
		)
		(pad "2" smd custom
			(at 0 0.4445 180)
			(size 0.1397 0.1397)
			(layers "F.Cu" "F.Mask" "F.Paste")
			(net "GND")
			(options
				(clearance outline)
				(anchor circle)
			)
			(primitives
				(gr_poly
					(pts
						(arc
							(start -0.1778 -0.2794)
							(mid -0.249642 -0.249642)
							(end -0.2794 -0.1778)
						)
						(arc
							(start -0.2794 0.1778)
							(mid -0.249642 0.249642)
							(end -0.1778 0.2794)
						)
						(arc
							(start 0.1778 0.2794)
							(mid 0.249642 0.249642)
							(end 0.2794 0.1778)
						)
						(arc
							(start 0.2794 -0.1778)
							(mid 0.249642 -0.249642)
							(end 0.1778 -0.2794)
						)
					)
					(width 0)
					(fill yes)
				)
			)
		)
	)
	(footprint ""
		(layer "F.Cu")
		(at 158.540704 -33.528)
		(property "Reference" "C398"
			(at 0 0 0)
			(layer "F.SilkS")
			(hide yes)
			(effects
				(font
					(size 1.27 1.27)
				)
			)
		)
		(property "Value" "SCD22U10V2KX-1GP"
			(at 1.1811 -2.7051 0)
			(unlocked yes)
			(layer "F.Fab")
			(hide yes)
			(effects
				(font
					(size 1.016 1.016)
					(thickness 0.1524)
				)
			)
		)
		(property "Device Type" "C402H22"
			(at 1.1811 -4.2291 0)
			(unlocked yes)
			(layer "F.Fab")
			(hide yes)
			(effects
				(font
					(size 1.016 1.016)
					(thickness 0.1524)
				)
			)
		)
		(duplicate_pad_numbers_are_jumpers no)
		(fp_rect
			(start -0.4318 0.9525)
			(end 0.4318 -0.9525)
			(stroke
				(width 0)
				(type default)
			)
			(fill no)
			(layer "F.CrtYd")
		)
		(fp_rect
			(start -0.4318 0.9525)
			(end 0.4318 -0.9525)
			(stroke
				(width 0)
				(type default)
			)
			(fill no)
			(layer "F.Fab")
		)
		(pad "1" smd custom
			(at 0 -0.4445)
			(size 0.1524 0.1524)
			(layers "F.Cu" "F.Mask" "F.Paste")
			(net "PCIE_TX_CAP_P89")
			(options
				(clearance outline)
				(anchor circle)
			)
			(primitives
				(gr_poly
					(pts
						(arc
							(start 0.3048 -0.2032)
							(mid 0.275042 -0.275042)
							(end 0.2032 -0.3048)
						)
						(arc
							(start -0.2032 -0.3048)
							(mid -0.275042 -0.275042)
							(end -0.3048 -0.2032)
						)
						(arc
							(start -0.3048 0.2032)
							(mid -0.275042 0.275042)
							(end -0.2032 0.3048)
						)
						(arc
							(start 0.2032 0.3048)
							(mid 0.275042 0.275042)
							(end 0.3048 0.2032)
						)
					)
					(width 0)
					(fill yes)
				)
			)
		)
		(pad "2" smd custom
			(at 0 0.4445)
			(size 0.1524 0.1524)
			(layers "F.Cu" "F.Mask" "F.Paste")
			(net "PCIE_TX_P89")
			(options
				(clearance outline)
				(anchor circle)
			)
			(primitives
				(gr_poly
					(pts
						(arc
							(start 0.3048 -0.2032)
							(mid 0.275042 -0.275042)
							(end 0.2032 -0.3048)
						)
						(arc
							(start -0.2032 -0.3048)
							(mid -0.275042 -0.275042)
							(end -0.3048 -0.2032)
						)
						(arc
							(start -0.3048 0.2032)
							(mid -0.275042 0.275042)
							(end -0.2032 0.3048)
						)
						(arc
							(start 0.2032 0.3048)
							(mid 0.275042 0.275042)
							(end 0.3048 0.2032)
						)
					)
					(width 0)
					(fill yes)
				)
			)
		)
	)
	(footprint ""
		(layer "F.Cu")
		(at 75.795124 -183.235092)
		(property "Reference" "R7928"
			(at 0 0 0)
			(layer "F.SilkS")
			(hide yes)
			(effects
				(font
					(size 1.27 1.27)
				)
			)
		)
		(property "Value" "0R2J-2-GP"
			(at 0.064008 -3.993896 0)
			(unlocked yes)
			(layer "F.Fab")
			(hide yes)
			(effects
				(font
					(size 1.016 1.016)
					(thickness 0.1524)
				)
			)
		)
		(property "Device Type" "R402H16"
			(at 0.064008 -5.517896 0)
			(unlocked yes)
			(layer "F.Fab")
			(hide yes)
			(effects
				(font
					(size 1.016 1.016)
					(thickness 0.1524)
				)
			)
		)
		(duplicate_pad_numbers_are_jumpers no)
		(fp_line
			(start -0.508 -0.9398)
			(end -0.508 0.9398)
			(stroke
				(width 0.1524)
				(type default)
			)
			(layer "F.SilkS")
		)
		(fp_line
			(start 0.508 -0.9398)
			(end -0.508 -0.9398)
			(stroke
				(width 0.1524)
				(type default)
			)
			(layer "F.SilkS")
		)
		(fp_rect
			(start -0.508 0.9398)
			(end 0.508 -0.9398)
			(stroke
				(width 0)
				(type default)
			)
			(fill no)
			(layer "F.CrtYd")
		)
		(fp_rect
			(start -0.508 0.9398)
			(end 0.508 -0.9398)
			(stroke
				(width 0)
				(type default)
			)
			(fill no)
			(layer "F.Fab")
		)
		(pad "1" smd custom
			(at 0 -0.4445)
			(size 0.1397 0.1397)
			(layers "F.Cu" "F.Mask" "F.Paste")
			(net "SSD_PRSNT#5")
			(options
				(clearance outline)
				(anchor circle)
			)
			(primitives
				(gr_poly
					(pts
						(arc
							(start -0.1778 -0.2794)
							(mid -0.249642 -0.249642)
							(end -0.2794 -0.1778)
						)
						(arc
							(start -0.2794 0.1778)
							(mid -0.249642 0.249642)
							(end -0.1778 0.2794)
						)
						(arc
							(start 0.1778 0.2794)
							(mid 0.249642 0.249642)
							(end 0.2794 0.1778)
						)
						(arc
							(start 0.2794 -0.1778)
							(mid 0.249642 -0.249642)
							(end 0.1778 -0.2794)
						)
					)
					(width 0)
					(fill yes)
				)
			)
		)
		(pad "2" smd custom
			(at 0 0.4445)
			(size 0.1397 0.1397)
			(layers "F.Cu" "F.Mask" "F.Paste")
			(net "SSD_PRSNT#5_R")
			(options
				(clearance outline)
				(anchor circle)
			)
			(primitives
				(gr_poly
					(pts
						(arc
							(start -0.1778 -0.2794)
							(mid -0.249642 -0.249642)
							(end -0.2794 -0.1778)
						)
						(arc
							(start -0.2794 0.1778)
							(mid -0.249642 0.249642)
							(end -0.1778 0.2794)
						)
						(arc
							(start 0.1778 0.2794)
							(mid 0.249642 0.249642)
							(end 0.2794 0.1778)
						)
						(arc
							(start 0.2794 -0.1778)
							(mid 0.249642 -0.249642)
							(end 0.1778 -0.2794)
						)
					)
					(width 0)
					(fill yes)
				)
			)
		)
	)
	(footprint ""
		(layer "F.Cu")
		(at 31.623 -51.689 -90)
		(property "Reference" "TC11"
			(at 0 0 270)
			(layer "F.SilkS")
			(hide yes)
			(effects
				(font
					(size 1.27 1.27)
				)
			)
		)
		(property "Value" "SC10U16V5KX-1-GP"
			(at -0.0762 -6.1214 270)
			(unlocked yes)
			(layer "F.Fab")
			(hide yes)
			(effects
				(font
					(size 1.016 1.016)
					(thickness 0.1524)
				)
			)
		)
		(property "Device Type" "C805H54"
			(at -0.0762 -8.1534 270)
			(unlocked yes)
			(layer "F.Fab")
			(hide yes)
			(effects
				(font
					(size 1.016 1.016)
					(thickness 0.1524)
				)
			)
		)
		(duplicate_pad_numbers_are_jumpers no)
		(fp_line
			(start 0.635 0)
			(end -0.635 0)
			(stroke
				(width 0.508)
				(type default)
			)
			(layer "F.SilkS")
		)
		(fp_rect
			(start -0.9652 1.778)
			(end 0.9652 -1.778)
			(stroke
				(width 0)
				(type default)
			)
			(fill no)
			(layer "F.CrtYd")
		)
		(fp_poly
			(pts
				(xy -0.9652 -1.778) (xy 0.9652 -1.778) (xy 0.9652 1.778) (xy -0.9652 1.778)
			)
			(stroke
				(width 0)
				(type default)
			)
			(fill no)
			(layer "F.Fab")
		)
		(pad "1" smd rect
			(at 0 -0.9652 270)
			(size 1.397 1.143)
			(layers "F.Cu" "F.Mask" "F.Paste")
			(net "P5V_USB")
		)
		(pad "2" smd rect
			(at 0 0.9652 270)
			(size 1.397 1.143)
			(layers "F.Cu" "F.Mask" "F.Paste")
			(net "GND")
		)
	)
	(footprint ""
		(layer "F.Cu")
		(at 53.303678 -34.1122 90)
		(property "Reference" "Q42"
			(at 0 0 90)
			(layer "F.SilkS")
			(hide yes)
			(effects
				(font
					(size 1.27 1.27)
				)
			)
		)
		(property "Value" "2N7002K-1-GP"
			(at 0.127 -8.9662 90)
			(unlocked yes)
			(layer "F.Fab")
			(hide yes)
			(effects
				(font
					(size 1.016 1.016)
					(thickness 0.1524)
				)
			)
		)
		(property "Device Type" "SOT23DGS2D4H44"
			(at 0.127 -10.4902 90)
			(unlocked yes)
			(layer "F.Fab")
			(hide yes)
			(effects
				(font
					(size 1.016 1.016)
					(thickness 0.1524)
				)
			)
		)
		(duplicate_pad_numbers_are_jumpers no)
		(fp_line
			(start 1.651 -1.778)
			(end -1.651 -1.778)
			(stroke
				(width 0.1524)
				(type default)
			)
			(layer "F.SilkS")
		)
		(fp_line
			(start -1.651 -1.778)
			(end -1.651 1.778)
			(stroke
				(width 0.1524)
				(type default)
			)
			(layer "F.SilkS")
		)
		(fp_line
			(start 1.651 1.778)
			(end 1.651 -1.778)
			(stroke
				(width 0.1524)
				(type default)
			)
			(layer "F.SilkS")
		)
		(fp_line
			(start -1.651 1.778)
			(end 1.651 1.778)
			(stroke
				(width 0.1524)
				(type default)
			)
			(layer "F.SilkS")
		)
		(fp_poly
			(pts
				(xy -1.778 1.941322) (xy -1.778 -1.817878) (xy 1.778 -1.817878) (xy 1.778 1.941322)
			)
			(stroke
				(width 0)
				(type default)
			)
			(fill no)
			(layer "F.CrtYd")
		)
		(fp_poly
			(pts
				(xy -1.778 1.8796) (xy -1.778 -1.8796) (xy 1.778 -1.8796) (xy 1.778 1.8796)
			)
			(stroke
				(width 0)
				(type default)
			)
			(fill no)
			(layer "F.Fab")
		)
		(pad "D" smd custom
			(at 0 -0.9525 90)
			(size 0.1905 0.1905)
			(layers "F.Cu" "F.Mask" "F.Paste")
			(net "Q42_D")
			(options
				(clearance outline)
				(anchor circle)
			)
			(primitives
				(gr_poly
					(pts
						(arc
							(start -0.1778 0.5715)
							(mid -0.321484 0.511984)
							(end -0.381 0.3683)
						)
						(arc
							(start -0.381 -0.3683)
							(mid -0.321484 -0.511984)
							(end -0.1778 -0.5715)
						)
						(arc
							(start 0.1778 -0.5715)
							(mid 0.321484 -0.511984)
							(end 0.381 -0.3683)
						)
						(arc
							(start 0.381 0.3683)
							(mid 0.321484 0.511984)
							(end 0.1778 0.5715)
						)
					)
					(width 0)
					(fill yes)
				)
			)
		)
		(pad "G" smd custom
			(at -0.98425 0.9525 90)
			(size 0.1905 0.1905)
			(layers "F.Cu" "F.Mask" "F.Paste")
			(net "P3V3_STBY_PG")
			(options
				(clearance outline)
				(anchor circle)
			)
			(primitives
				(gr_poly
					(pts
						(arc
							(start -0.1778 0.5715)
							(mid -0.321484 0.511984)
							(end -0.381 0.3683)
						)
						(arc
							(start -0.381 -0.3683)
							(mid -0.321484 -0.511984)
							(end -0.1778 -0.5715)
						)
						(arc
							(start 0.1778 -0.5715)
							(mid 0.321484 -0.511984)
							(end 0.381 -0.3683)
						)
						(arc
							(start 0.381 0.3683)
							(mid 0.321484 0.511984)
							(end 0.1778 0.5715)
						)
					)
					(width 0)
					(fill yes)
				)
			)
		)
		(pad "S" smd custom
			(at 0.98425 0.9525 90)
			(size 0.1905 0.1905)
			(layers "F.Cu" "F.Mask" "F.Paste")
			(net "GND")
			(options
				(clearance outline)
				(anchor circle)
			)
			(primitives
				(gr_poly
					(pts
						(arc
							(start -0.1778 0.5715)
							(mid -0.321484 0.511984)
							(end -0.381 0.3683)
						)
						(arc
							(start -0.381 -0.3683)
							(mid -0.321484 -0.511984)
							(end -0.1778 -0.5715)
						)
						(arc
							(start 0.1778 -0.5715)
							(mid 0.321484 -0.511984)
							(end 0.381 -0.3683)
						)
						(arc
							(start 0.381 0.3683)
							(mid 0.321484 0.511984)
							(end 0.1778 0.5715)
						)
					)
					(width 0)
					(fill yes)
				)
			)
		)
	)
	(footprint ""
		(layer "F.Cu")
		(at 187.21832 -27.79014 90)
		(property "Reference" "R632"
			(at 0 0 90)
			(layer "F.SilkS")
			(hide yes)
			(effects
				(font
					(size 1.27 1.27)
				)
			)
		)
		(property "Value" "0R2J-2-GP"
			(at 0.064008 -3.993896 90)
			(unlocked yes)
			(layer "F.Fab")
			(hide yes)
			(effects
				(font
					(size 1.016 1.016)
					(thickness 0.1524)
				)
			)
		)
		(property "Device Type" "R402H16"
			(at 0.064008 -5.517896 90)
			(unlocked yes)
			(layer "F.Fab")
			(hide yes)
			(effects
				(font
					(size 1.016 1.016)
					(thickness 0.1524)
				)
			)
		)
		(duplicate_pad_numbers_are_jumpers no)
		(fp_line
			(start 0.508 -0.9398)
			(end -0.508 -0.9398)
			(stroke
				(width 0.1524)
				(type default)
			)
			(layer "F.SilkS")
		)
		(fp_line
			(start -0.508 -0.9398)
			(end -0.508 0.9398)
			(stroke
				(width 0.1524)
				(type default)
			)
			(layer "F.SilkS")
		)
		(fp_rect
			(start -0.508 0.9398)
			(end 0.508 -0.9398)
			(stroke
				(width 0)
				(type default)
			)
			(fill no)
			(layer "F.CrtYd")
		)
		(fp_rect
			(start -0.508 0.9398)
			(end 0.508 -0.9398)
			(stroke
				(width 0)
				(type default)
			)
			(fill no)
			(layer "F.Fab")
		)
		(pad "1" smd custom
			(at 0 -0.4445 90)
			(size 0.1397 0.1397)
			(layers "F.Cu" "F.Mask" "F.Paste")
			(net "8644_USB_DP4")
			(options
				(clearance outline)
				(anchor circle)
			)
			(primitives
				(gr_poly
					(pts
						(arc
							(start -0.1778 -0.2794)
							(mid -0.249642 -0.249642)
							(end -0.2794 -0.1778)
						)
						(arc
							(start -0.2794 0.1778)
							(mid -0.249642 0.249642)
							(end -0.1778 0.2794)
						)
						(arc
							(start 0.1778 0.2794)
							(mid 0.249642 0.249642)
							(end 0.2794 0.1778)
						)
						(arc
							(start 0.2794 -0.1778)
							(mid 0.249642 -0.249642)
							(end 0.1778 -0.2794)
						)
					)
					(width 0)
					(fill yes)
				)
			)
		)
		(pad "2" smd custom
			(at 0 0.4445 90)
			(size 0.1397 0.1397)
			(layers "F.Cu" "F.Mask" "F.Paste")
			(net "P3V3_STBY")
			(options
				(clearance outline)
				(anchor circle)
			)
			(primitives
				(gr_poly
					(pts
						(arc
							(start -0.1778 -0.2794)
							(mid -0.249642 -0.249642)
							(end -0.2794 -0.1778)
						)
						(arc
							(start -0.2794 0.1778)
							(mid -0.249642 0.249642)
							(end -0.1778 0.2794)
						)
						(arc
							(start 0.1778 0.2794)
							(mid 0.249642 0.249642)
							(end 0.2794 0.1778)
						)
						(arc
							(start 0.2794 -0.1778)
							(mid 0.249642 -0.249642)
							(end 0.1778 -0.2794)
						)
					)
					(width 0)
					(fill yes)
				)
			)
		)
	)
	(footprint ""
		(layer "F.Cu")
		(at 162.052 -33.528)
		(property "Reference" "C401"
			(at 0 0 0)
			(layer "F.SilkS")
			(hide yes)
			(effects
				(font
					(size 1.27 1.27)
				)
			)
		)
		(property "Value" "SCD22U10V2KX-1GP"
			(at 1.1811 -2.7051 0)
			(unlocked yes)
			(layer "F.Fab")
			(hide yes)
			(effects
				(font
					(size 1.016 1.016)
					(thickness 0.1524)
				)
			)
		)
		(property "Device Type" "C402H22"
			(at 1.1811 -4.2291 0)
			(unlocked yes)
			(layer "F.Fab")
			(hide yes)
			(effects
				(font
					(size 1.016 1.016)
					(thickness 0.1524)
				)
			)
		)
		(duplicate_pad_numbers_are_jumpers no)
		(fp_rect
			(start -0.4318 0.9525)
			(end 0.4318 -0.9525)
			(stroke
				(width 0)
				(type default)
			)
			(fill no)
			(layer "F.CrtYd")
		)
		(fp_rect
			(start -0.4318 0.9525)
			(end 0.4318 -0.9525)
			(stroke
				(width 0)
				(type default)
			)
			(fill no)
			(layer "F.Fab")
		)
		(pad "1" smd custom
			(at 0 -0.4445)
			(size 0.1524 0.1524)
			(layers "F.Cu" "F.Mask" "F.Paste")
			(net "PCIE_TX_CAP_N90")
			(options
				(clearance outline)
				(anchor circle)
			)
			(primitives
				(gr_poly
					(pts
						(arc
							(start 0.3048 -0.2032)
							(mid 0.275042 -0.275042)
							(end 0.2032 -0.3048)
						)
						(arc
							(start -0.2032 -0.3048)
							(mid -0.275042 -0.275042)
							(end -0.3048 -0.2032)
						)
						(arc
							(start -0.3048 0.2032)
							(mid -0.275042 0.275042)
							(end -0.2032 0.3048)
						)
						(arc
							(start 0.2032 0.3048)
							(mid 0.275042 0.275042)
							(end 0.3048 0.2032)
						)
					)
					(width 0)
					(fill yes)
				)
			)
		)
		(pad "2" smd custom
			(at 0 0.4445)
			(size 0.1524 0.1524)
			(layers "F.Cu" "F.Mask" "F.Paste")
			(net "PCIE_TX_N90")
			(options
				(clearance outline)
				(anchor circle)
			)
			(primitives
				(gr_poly
					(pts
						(arc
							(start 0.3048 -0.2032)
							(mid 0.275042 -0.275042)
							(end 0.2032 -0.3048)
						)
						(arc
							(start -0.2032 -0.3048)
							(mid -0.275042 -0.275042)
							(end -0.3048 -0.2032)
						)
						(arc
							(start -0.3048 0.2032)
							(mid -0.275042 0.275042)
							(end -0.2032 0.3048)
						)
						(arc
							(start 0.2032 0.3048)
							(mid 0.275042 0.275042)
							(end 0.3048 0.2032)
						)
					)
					(width 0)
					(fill yes)
				)
			)
		)
	)
	(footprint ""
		(layer "F.Cu")
		(at 22.479 -164.084 -90)
		(property "Reference" "R510"
			(at 0 0 270)
			(layer "F.SilkS")
			(hide yes)
			(effects
				(font
					(size 1.27 1.27)
				)
			)
		)
		(property "Value" "0R2J-2-GP"
			(at 0.064008 -3.993896 270)
			(unlocked yes)
			(layer "F.Fab")
			(hide yes)
			(effects
				(font
					(size 1.016 1.016)
					(thickness 0.1524)
				)
			)
		)
		(property "Device Type" "R402H16"
			(at 0.064008 -5.517896 270)
			(unlocked yes)
			(layer "F.Fab")
			(hide yes)
			(effects
				(font
					(size 1.016 1.016)
					(thickness 0.1524)
				)
			)
		)
		(duplicate_pad_numbers_are_jumpers no)
		(fp_line
			(start -0.508 -0.9398)
			(end -0.508 0.9398)
			(stroke
				(width 0.1524)
				(type default)
			)
			(layer "F.SilkS")
		)
		(fp_line
			(start 0.508 -0.9398)
			(end -0.508 -0.9398)
			(stroke
				(width 0.1524)
				(type default)
			)
			(layer "F.SilkS")
		)
		(fp_rect
			(start -0.508 0.9398)
			(end 0.508 -0.9398)
			(stroke
				(width 0)
				(type default)
			)
			(fill no)
			(layer "F.CrtYd")
		)
		(fp_rect
			(start -0.508 0.9398)
			(end 0.508 -0.9398)
			(stroke
				(width 0)
				(type default)
			)
			(fill no)
			(layer "F.Fab")
		)
		(pad "1" smd custom
			(at 0 -0.4445 270)
			(size 0.1397 0.1397)
			(layers "F.Cu" "F.Mask" "F.Paste")
			(net "BMC_RESET#_DDR3")
			(options
				(clearance outline)
				(anchor circle)
			)
			(primitives
				(gr_poly
					(pts
						(arc
							(start -0.1778 -0.2794)
							(mid -0.249642 -0.249642)
							(end -0.2794 -0.1778)
						)
						(arc
							(start -0.2794 0.1778)
							(mid -0.249642 0.249642)
							(end -0.1778 0.2794)
						)
						(arc
							(start 0.1778 0.2794)
							(mid 0.249642 0.249642)
							(end 0.2794 0.1778)
						)
						(arc
							(start 0.2794 -0.1778)
							(mid 0.249642 -0.249642)
							(end 0.1778 -0.2794)
						)
					)
					(width 0)
					(fill yes)
				)
			)
		)
		(pad "2" smd custom
			(at 0 0.4445 270)
			(size 0.1397 0.1397)
			(layers "F.Cu" "F.Mask" "F.Paste")
			(net "GPIOB1")
			(options
				(clearance outline)
				(anchor circle)
			)
			(primitives
				(gr_poly
					(pts
						(arc
							(start -0.1778 -0.2794)
							(mid -0.249642 -0.249642)
							(end -0.2794 -0.1778)
						)
						(arc
							(start -0.2794 0.1778)
							(mid -0.249642 0.249642)
							(end -0.1778 0.2794)
						)
						(arc
							(start 0.1778 0.2794)
							(mid 0.249642 0.249642)
							(end 0.2794 0.1778)
						)
						(arc
							(start 0.2794 -0.1778)
							(mid 0.249642 -0.249642)
							(end 0.1778 -0.2794)
						)
					)
					(width 0)
					(fill yes)
				)
			)
		)
	)
	(footprint ""
		(layer "F.Cu")
		(at 72.747124 -183.235092)
		(property "Reference" "R7937"
			(at 0 0 0)
			(layer "F.SilkS")
			(hide yes)
			(effects
				(font
					(size 1.27 1.27)
				)
			)
		)
		(property "Value" "0R2J-2-GP"
			(at 0.064008 -3.993896 0)
			(unlocked yes)
			(layer "F.Fab")
			(hide yes)
			(effects
				(font
					(size 1.016 1.016)
					(thickness 0.1524)
				)
			)
		)
		(property "Device Type" "R402H16"
			(at 0.064008 -5.517896 0)
			(unlocked yes)
			(layer "F.Fab")
			(hide yes)
			(effects
				(font
					(size 1.016 1.016)
					(thickness 0.1524)
				)
			)
		)
		(duplicate_pad_numbers_are_jumpers no)
		(fp_line
			(start -0.508 -0.9398)
			(end -0.508 0.9398)
			(stroke
				(width 0.1524)
				(type default)
			)
			(layer "F.SilkS")
		)
		(fp_line
			(start 0.508 -0.9398)
			(end -0.508 -0.9398)
			(stroke
				(width 0.1524)
				(type default)
			)
			(layer "F.SilkS")
		)
		(fp_rect
			(start -0.508 0.9398)
			(end 0.508 -0.9398)
			(stroke
				(width 0)
				(type default)
			)
			(fill no)
			(layer "F.CrtYd")
		)
		(fp_rect
			(start -0.508 0.9398)
			(end 0.508 -0.9398)
			(stroke
				(width 0)
				(type default)
			)
			(fill no)
			(layer "F.Fab")
		)
		(pad "1" smd custom
			(at 0 -0.4445)
			(size 0.1397 0.1397)
			(layers "F.Cu" "F.Mask" "F.Paste")
			(net "SSD_ATNLED#0")
			(options
				(clearance outline)
				(anchor circle)
			)
			(primitives
				(gr_poly
					(pts
						(arc
							(start -0.1778 -0.2794)
							(mid -0.249642 -0.249642)
							(end -0.2794 -0.1778)
						)
						(arc
							(start -0.2794 0.1778)
							(mid -0.249642 0.249642)
							(end -0.1778 0.2794)
						)
						(arc
							(start 0.1778 0.2794)
							(mid 0.249642 0.249642)
							(end 0.2794 0.1778)
						)
						(arc
							(start 0.2794 -0.1778)
							(mid 0.249642 -0.249642)
							(end 0.1778 -0.2794)
						)
					)
					(width 0)
					(fill yes)
				)
			)
		)
		(pad "2" smd custom
			(at 0 0.4445)
			(size 0.1397 0.1397)
			(layers "F.Cu" "F.Mask" "F.Paste")
			(net "SSD_ATNLED#0_R")
			(options
				(clearance outline)
				(anchor circle)
			)
			(primitives
				(gr_poly
					(pts
						(arc
							(start -0.1778 -0.2794)
							(mid -0.249642 -0.249642)
							(end -0.2794 -0.1778)
						)
						(arc
							(start -0.2794 0.1778)
							(mid -0.249642 0.249642)
							(end -0.1778 0.2794)
						)
						(arc
							(start 0.1778 0.2794)
							(mid 0.249642 0.249642)
							(end 0.2794 0.1778)
						)
						(arc
							(start 0.2794 -0.1778)
							(mid 0.249642 -0.249642)
							(end 0.1778 -0.2794)
						)
					)
					(width 0)
					(fill yes)
				)
			)
		)
	)
	(footprint ""
		(layer "F.Cu")
		(at 42.164 -205.359 -90)
		(property "Reference" "R878"
			(at 0 0 270)
			(layer "F.SilkS")
			(hide yes)
			(effects
				(font
					(size 1.27 1.27)
				)
			)
		)
		(property "Value" "4K7R2J-2-GP"
			(at 0.064008 -3.993896 270)
			(unlocked yes)
			(layer "F.Fab")
			(hide yes)
			(effects
				(font
					(size 1.016 1.016)
					(thickness 0.1524)
				)
			)
		)
		(property "Device Type" "R402H16"
			(at 0.064008 -5.517896 270)
			(unlocked yes)
			(layer "F.Fab")
			(hide yes)
			(effects
				(font
					(size 1.016 1.016)
					(thickness 0.1524)
				)
			)
		)
		(duplicate_pad_numbers_are_jumpers no)
		(fp_line
			(start -0.508 -0.9398)
			(end -0.508 0.9398)
			(stroke
				(width 0.1524)
				(type default)
			)
			(layer "F.SilkS")
		)
		(fp_line
			(start 0.508 -0.9398)
			(end -0.508 -0.9398)
			(stroke
				(width 0.1524)
				(type default)
			)
			(layer "F.SilkS")
		)
		(fp_rect
			(start -0.508 0.9398)
			(end 0.508 -0.9398)
			(stroke
				(width 0)
				(type default)
			)
			(fill no)
			(layer "F.CrtYd")
		)
		(fp_rect
			(start -0.508 0.9398)
			(end 0.508 -0.9398)
			(stroke
				(width 0)
				(type default)
			)
			(fill no)
			(layer "F.Fab")
		)
		(pad "1" smd custom
			(at 0 -0.4445 270)
			(size 0.1397 0.1397)
			(layers "F.Cu" "F.Mask" "F.Paste")
			(net "P3V3_STBY")
			(options
				(clearance outline)
				(anchor circle)
			)
			(primitives
				(gr_poly
					(pts
						(arc
							(start -0.1778 -0.2794)
							(mid -0.249642 -0.249642)
							(end -0.2794 -0.1778)
						)
						(arc
							(start -0.2794 0.1778)
							(mid -0.249642 0.249642)
							(end -0.1778 0.2794)
						)
						(arc
							(start 0.1778 0.2794)
							(mid 0.249642 0.249642)
							(end 0.2794 0.1778)
						)
						(arc
							(start 0.2794 -0.1778)
							(mid 0.249642 -0.249642)
							(end 0.1778 -0.2794)
						)
					)
					(width 0)
					(fill yes)
				)
			)
		)
		(pad "2" smd custom
			(at 0 0.4445 270)
			(size 0.1397 0.1397)
			(layers "F.Cu" "F.Mask" "F.Paste")
			(net "BUF_I2C6_C_FCB_SCL_R")
			(options
				(clearance outline)
				(anchor circle)
			)
			(primitives
				(gr_poly
					(pts
						(arc
							(start -0.1778 -0.2794)
							(mid -0.249642 -0.249642)
							(end -0.2794 -0.1778)
						)
						(arc
							(start -0.2794 0.1778)
							(mid -0.249642 0.249642)
							(end -0.1778 0.2794)
						)
						(arc
							(start 0.1778 0.2794)
							(mid 0.249642 0.249642)
							(end 0.2794 0.1778)
						)
						(arc
							(start 0.2794 -0.1778)
							(mid 0.249642 -0.249642)
							(end 0.1778 -0.2794)
						)
					)
					(width 0)
					(fill yes)
				)
			)
		)
	)
	(footprint ""
		(layer "F.Cu")
		(at 19.76247 -91.624658 90)
		(property "Reference" "R2941"
			(at 0 0 90)
			(layer "F.SilkS")
			(hide yes)
			(effects
				(font
					(size 1.27 1.27)
				)
			)
		)
		(property "Value" "10KR2F-2-GP"
			(at 0.064008 -3.993896 90)
			(unlocked yes)
			(layer "F.Fab")
			(hide yes)
			(effects
				(font
					(size 1.016 1.016)
					(thickness 0.1524)
				)
			)
		)
		(property "Device Type" "R402H16"
			(at 0.064008 -5.517896 90)
			(unlocked yes)
			(layer "F.Fab")
			(hide yes)
			(effects
				(font
					(size 1.016 1.016)
					(thickness 0.1524)
				)
			)
		)
		(duplicate_pad_numbers_are_jumpers no)
		(fp_line
			(start 0.508 -0.9398)
			(end -0.508 -0.9398)
			(stroke
				(width 0.1524)
				(type default)
			)
			(layer "F.SilkS")
		)
		(fp_line
			(start -0.508 -0.9398)
			(end -0.508 0.9398)
			(stroke
				(width 0.1524)
				(type default)
			)
			(layer "F.SilkS")
		)
		(fp_rect
			(start -0.508 0.9398)
			(end 0.508 -0.9398)
			(stroke
				(width 0)
				(type default)
			)
			(fill no)
			(layer "F.CrtYd")
		)
		(fp_rect
			(start -0.508 0.9398)
			(end 0.508 -0.9398)
			(stroke
				(width 0)
				(type default)
			)
			(fill no)
			(layer "F.Fab")
		)
		(pad "1" smd custom
			(at 0 -0.4445 90)
			(size 0.1397 0.1397)
			(layers "F.Cu" "F.Mask" "F.Paste")
			(net "P3V3_STBY")
			(options
				(clearance outline)
				(anchor circle)
			)
			(primitives
				(gr_poly
					(pts
						(arc
							(start -0.1778 -0.2794)
							(mid -0.249642 -0.249642)
							(end -0.2794 -0.1778)
						)
						(arc
							(start -0.2794 0.1778)
							(mid -0.249642 0.249642)
							(end -0.1778 0.2794)
						)
						(arc
							(start 0.1778 0.2794)
							(mid 0.249642 0.249642)
							(end 0.2794 0.1778)
						)
						(arc
							(start 0.2794 -0.1778)
							(mid 0.249642 -0.249642)
							(end 0.1778 -0.2794)
						)
					)
					(width 0)
					(fill yes)
				)
			)
		)
		(pad "2" smd custom
			(at 0 0.4445 90)
			(size 0.1397 0.1397)
			(layers "F.Cu" "F.Mask" "F.Paste")
			(net "FM_TPM_PRES_RST_N")
			(options
				(clearance outline)
				(anchor circle)
			)
			(primitives
				(gr_poly
					(pts
						(arc
							(start -0.1778 -0.2794)
							(mid -0.249642 -0.249642)
							(end -0.2794 -0.1778)
						)
						(arc
							(start -0.2794 0.1778)
							(mid -0.249642 0.249642)
							(end -0.1778 0.2794)
						)
						(arc
							(start 0.1778 0.2794)
							(mid 0.249642 0.249642)
							(end 0.2794 0.1778)
						)
						(arc
							(start 0.2794 -0.1778)
							(mid 0.249642 -0.249642)
							(end 0.1778 -0.2794)
						)
					)
					(width 0)
					(fill yes)
				)
			)
		)
	)
	(footprint ""
		(layer "F.Cu")
		(at 50.292 -135.763)
		(property "Reference" "TP162"
			(at 0 0 0)
			(layer "F.SilkS")
			(hide yes)
			(effects
				(font
					(size 1.27 1.27)
				)
			)
		)
		(property "Value" "TPAD28-2-GP"
			(at -0.0127 -1.6637 0)
			(unlocked yes)
			(layer "F.Fab")
			(hide yes)
			(effects
				(font
					(size 1.016 1.016)
					(thickness 0.1524)
				)
			)
		)
		(property "Device Type" "TPAD28"
			(at -0.0127 -3.1877 0)
			(unlocked yes)
			(layer "F.Fab")
			(hide yes)
			(effects
				(font
					(size 1.016 1.016)
					(thickness 0.1524)
				)
			)
		)
		(duplicate_pad_numbers_are_jumpers no)
		(fp_poly
			(pts
				(arc
					(start 0.3556 0)
					(mid -0.3556 0)
					(end 0.3556 0)
				)
			)
			(stroke
				(width 0)
				(type default)
			)
			(fill no)
			(layer "F.CrtYd")
		)
		(fp_poly
			(pts
				(arc
					(start 0.6096 0)
					(mid -0.6096 0)
					(end 0.6096 0)
				)
			)
			(stroke
				(width 0)
				(type default)
			)
			(fill no)
			(layer "F.Fab")
		)
		(pad "1" smd circle
			(at 0 0)
			(size 0.7112 0.7112)
			(layers "F.Cu" "F.Mask" "F.Paste")
			(net "TP_BMC_GPIOJ7")
		)
	)
	(footprint ""
		(layer "F.Cu")
		(at 162.687 -95.9104 180)
		(property "Reference" "R3108"
			(at 0 0 180)
			(layer "F.SilkS")
			(hide yes)
			(effects
				(font
					(size 1.27 1.27)
				)
			)
		)
		(property "Value" "27R2F-GP"
			(at 0.064008 -3.993896 180)
			(unlocked yes)
			(layer "F.Fab")
			(hide yes)
			(effects
				(font
					(size 1.016 1.016)
					(thickness 0.1524)
				)
			)
		)
		(property "Device Type" "R402H16"
			(at 0.064008 -5.517896 180)
			(unlocked yes)
			(layer "F.Fab")
			(hide yes)
			(effects
				(font
					(size 1.016 1.016)
					(thickness 0.1524)
				)
			)
		)
		(duplicate_pad_numbers_are_jumpers no)
		(fp_line
			(start 0.508 -0.9398)
			(end -0.508 -0.9398)
			(stroke
				(width 0.1524)
				(type default)
			)
			(layer "F.SilkS")
		)
		(fp_line
			(start -0.508 -0.9398)
			(end -0.508 0.9398)
			(stroke
				(width 0.1524)
				(type default)
			)
			(layer "F.SilkS")
		)
		(fp_rect
			(start -0.508 0.9398)
			(end 0.508 -0.9398)
			(stroke
				(width 0)
				(type default)
			)
			(fill no)
			(layer "F.CrtYd")
		)
		(fp_rect
			(start -0.508 0.9398)
			(end 0.508 -0.9398)
			(stroke
				(width 0)
				(type default)
			)
			(fill no)
			(layer "F.Fab")
		)
		(pad "1" smd custom
			(at 0 -0.4445 180)
			(size 0.1397 0.1397)
			(layers "F.Cu" "F.Mask" "F.Paste")
			(net "CLKGEN_P3_R")
			(options
				(clearance outline)
				(anchor circle)
			)
			(primitives
				(gr_poly
					(pts
						(arc
							(start -0.1778 -0.2794)
							(mid -0.249642 -0.249642)
							(end -0.2794 -0.1778)
						)
						(arc
							(start -0.2794 0.1778)
							(mid -0.249642 0.249642)
							(end -0.1778 0.2794)
						)
						(arc
							(start 0.1778 0.2794)
							(mid 0.249642 0.249642)
							(end 0.2794 0.1778)
						)
						(arc
							(start 0.2794 -0.1778)
							(mid 0.249642 -0.249642)
							(end 0.1778 -0.2794)
						)
					)
					(width 0)
					(fill yes)
				)
			)
		)
		(pad "2" smd custom
			(at 0 0.4445 180)
			(size 0.1397 0.1397)
			(layers "F.Cu" "F.Mask" "F.Paste")
			(net "CLKGEN_P3")
			(options
				(clearance outline)
				(anchor circle)
			)
			(primitives
				(gr_poly
					(pts
						(arc
							(start -0.1778 -0.2794)
							(mid -0.249642 -0.249642)
							(end -0.2794 -0.1778)
						)
						(arc
							(start -0.2794 0.1778)
							(mid -0.249642 0.249642)
							(end -0.1778 0.2794)
						)
						(arc
							(start 0.1778 0.2794)
							(mid 0.249642 0.249642)
							(end 0.2794 0.1778)
						)
						(arc
							(start 0.2794 -0.1778)
							(mid 0.249642 -0.249642)
							(end 0.1778 -0.2794)
						)
					)
					(width 0)
					(fill yes)
				)
			)
		)
	)
	(footprint ""
		(layer "F.Cu")
		(at 50.423572 -57.303924 180)
		(property "Reference" "U44"
			(at 0 0 180)
			(layer "F.SilkS")
			(hide yes)
			(effects
				(font
					(size 1.27 1.27)
				)
			)
		)
		(property "Value" "W25Q80DVSSIG-1-GP"
			(at 0 -13.1572 180)
			(unlocked yes)
			(layer "F.Fab")
			(hide yes)
			(effects
				(font
					(size 1.016 1.016)
					(thickness 0.1524)
				)
			)
		)
		(property "Device Type" "SOIC8-1H86"
			(at 0 -14.6812 180)
			(unlocked yes)
			(layer "F.Fab")
			(hide yes)
			(effects
				(font
					(size 1.016 1.016)
					(thickness 0.1524)
				)
			)
		)
		(duplicate_pad_numbers_are_jumpers no)
		(fp_line
			(start 2.1336 2.3876)
			(end -3.048 2.3876)
			(stroke
				(width 0.1524)
				(type default)
			)
			(layer "F.SilkS")
		)
		(fp_line
			(start 2.1336 -2.3876)
			(end 2.1336 2.3876)
			(stroke
				(width 0.1524)
				(type default)
			)
			(layer "F.SilkS")
		)
		(fp_line
			(start 2.1336 -2.3876)
			(end -3.2258 -2.3876)
			(stroke
				(width 0.1524)
				(type default)
			)
			(layer "F.SilkS")
		)
		(fp_line
			(start -2.3114 0)
			(end -3.2258 0.9144)
			(stroke
				(width 0.1524)
				(type default)
			)
			(layer "F.SilkS")
		)
		(fp_line
			(start -2.3114 0)
			(end -3.2258 -0.9144)
			(stroke
				(width 0.1524)
				(type default)
			)
			(layer "F.SilkS")
		)
		(fp_line
			(start -3.048 4.572)
			(end -3.048 2.3876)
			(stroke
				(width 0.508)
				(type default)
			)
			(layer "F.SilkS")
		)
		(fp_line
			(start -3.2258 -2.3876)
			(end -3.2258 4.572)
			(stroke
				(width 0.1524)
				(type default)
			)
			(layer "F.SilkS")
		)
		(fp_poly
			(pts
				(xy -2.2352 2.3876) (xy 2.1336 2.3876) (xy 2.1336 -2.3876) (xy -2.2352 -2.3876)
			)
			(stroke
				(width 0)
				(type default)
			)
			(fill yes)
			(layer "F.SilkS")
		)
		(fp_poly
			(pts
				(xy -3.302 4.826) (xy 3.302 4.826) (xy 3.302 -4.826) (xy -3.302 -4.826)
			)
			(stroke
				(width 0)
				(type default)
			)
			(fill no)
			(layer "F.CrtYd")
		)
		(fp_poly
			(pts
				(xy -3.302 -4.826) (xy 3.302 -4.826) (xy 3.302 4.826) (xy -3.302 4.826)
			)
			(stroke
				(width 0)
				(type default)
			)
			(fill no)
			(layer "F.Fab")
		)
		(pad "1" smd rect
			(at -1.905 3.4925 180)
			(size 0.635 1.651)
			(layers "F.Cu" "F.Mask" "F.Paste")
			(net "NVM_CS_N_R")
		)
		(pad "2" smd rect
			(at -0.635 3.4925 180)
			(size 0.635 1.651)
			(layers "F.Cu" "F.Mask" "F.Paste")
			(net "NVM_SO_R")
		)
		(pad "3" smd rect
			(at 0.635 3.4925 180)
			(size 0.635 1.651)
			(layers "F.Cu" "F.Mask" "F.Paste")
			(net "U44_WP_N")
		)
		(pad "4" smd rect
			(at 1.905 3.4925 180)
			(size 0.635 1.651)
			(layers "F.Cu" "F.Mask" "F.Paste")
			(net "GND")
		)
		(pad "5" smd rect
			(at 1.905 -3.4925 180)
			(size 0.635 1.651)
			(layers "F.Cu" "F.Mask" "F.Paste")
			(net "NVM_SI_R")
		)
		(pad "6" smd rect
			(at 0.635 -3.4925 180)
			(size 0.635 1.651)
			(layers "F.Cu" "F.Mask" "F.Paste")
			(net "NVM_SK_R")
		)
		(pad "7" smd rect
			(at -0.635 -3.4925 180)
			(size 0.635 1.651)
			(layers "F.Cu" "F.Mask" "F.Paste")
			(net "U44_HOLD_N")
		)
		(pad "8" smd rect
			(at -1.905 -3.4925 180)
			(size 0.635 1.651)
			(layers "F.Cu" "F.Mask" "F.Paste")
			(net "P3V3_STBY")
		)
	)
	(footprint ""
		(layer "F.Cu")
		(at 333.40802 -212.420454 180)
		(property "Reference" "C61"
			(at 0 0 180)
			(layer "F.SilkS")
			(hide yes)
			(effects
				(font
					(size 1.27 1.27)
				)
			)
		)
		(property "Value" "SCD22U10V2KX-1GP"
			(at 1.1811 -2.7051 180)
			(unlocked yes)
			(layer "F.Fab")
			(hide yes)
			(effects
				(font
					(size 1.016 1.016)
					(thickness 0.1524)
				)
			)
		)
		(property "Device Type" "C402H22"
			(at 1.1811 -4.2291 180)
			(unlocked yes)
			(layer "F.Fab")
			(hide yes)
			(effects
				(font
					(size 1.016 1.016)
					(thickness 0.1524)
				)
			)
		)
		(duplicate_pad_numbers_are_jumpers no)
		(fp_rect
			(start -0.4318 0.9525)
			(end 0.4318 -0.9525)
			(stroke
				(width 0)
				(type default)
			)
			(fill no)
			(layer "F.CrtYd")
		)
		(fp_rect
			(start -0.4318 0.9525)
			(end 0.4318 -0.9525)
			(stroke
				(width 0)
				(type default)
			)
			(fill no)
			(layer "F.Fab")
		)
		(pad "1" smd custom
			(at 0 -0.4445 180)
			(size 0.1524 0.1524)
			(layers "F.Cu" "F.Mask" "F.Paste")
			(net "PCIE_TX_CAP_N19")
			(options
				(clearance outline)
				(anchor circle)
			)
			(primitives
				(gr_poly
					(pts
						(arc
							(start 0.3048 -0.2032)
							(mid 0.275042 -0.275042)
							(end 0.2032 -0.3048)
						)
						(arc
							(start -0.2032 -0.3048)
							(mid -0.275042 -0.275042)
							(end -0.3048 -0.2032)
						)
						(arc
							(start -0.3048 0.2032)
							(mid -0.275042 0.275042)
							(end -0.2032 0.3048)
						)
						(arc
							(start 0.2032 0.3048)
							(mid 0.275042 0.275042)
							(end 0.3048 0.2032)
						)
					)
					(width 0)
					(fill yes)
				)
			)
		)
		(pad "2" smd custom
			(at 0 0.4445 180)
			(size 0.1524 0.1524)
			(layers "F.Cu" "F.Mask" "F.Paste")
			(net "PCIE_TX_N19")
			(options
				(clearance outline)
				(anchor circle)
			)
			(primitives
				(gr_poly
					(pts
						(arc
							(start 0.3048 -0.2032)
							(mid 0.275042 -0.275042)
							(end 0.2032 -0.3048)
						)
						(arc
							(start -0.2032 -0.3048)
							(mid -0.275042 -0.275042)
							(end -0.3048 -0.2032)
						)
						(arc
							(start -0.3048 0.2032)
							(mid -0.275042 0.275042)
							(end -0.2032 0.3048)
						)
						(arc
							(start 0.2032 0.3048)
							(mid 0.275042 0.275042)
							(end 0.3048 0.2032)
						)
					)
					(width 0)
					(fill yes)
				)
			)
		)
	)
	(footprint ""
		(layer "F.Cu")
		(at 241.681 -23.241 180)
		(property "Reference" "R785"
			(at 0 0 180)
			(layer "F.SilkS")
			(hide yes)
			(effects
				(font
					(size 1.27 1.27)
				)
			)
		)
		(property "Value" "4K7R2F-GP"
			(at 0.064008 -3.993896 180)
			(unlocked yes)
			(layer "F.Fab")
			(hide yes)
			(effects
				(font
					(size 1.016 1.016)
					(thickness 0.1524)
				)
			)
		)
		(property "Device Type" "R402H16"
			(at 0.064008 -5.517896 180)
			(unlocked yes)
			(layer "F.Fab")
			(hide yes)
			(effects
				(font
					(size 1.016 1.016)
					(thickness 0.1524)
				)
			)
		)
		(duplicate_pad_numbers_are_jumpers no)
		(fp_line
			(start 0.508 -0.9398)
			(end -0.508 -0.9398)
			(stroke
				(width 0.1524)
				(type default)
			)
			(layer "F.SilkS")
		)
		(fp_line
			(start -0.508 -0.9398)
			(end -0.508 0.9398)
			(stroke
				(width 0.1524)
				(type default)
			)
			(layer "F.SilkS")
		)
		(fp_rect
			(start -0.508 0.9398)
			(end 0.508 -0.9398)
			(stroke
				(width 0)
				(type default)
			)
			(fill no)
			(layer "F.CrtYd")
		)
		(fp_rect
			(start -0.508 0.9398)
			(end 0.508 -0.9398)
			(stroke
				(width 0)
				(type default)
			)
			(fill no)
			(layer "F.Fab")
		)
		(pad "1" smd custom
			(at 0 -0.4445 180)
			(size 0.1397 0.1397)
			(layers "F.Cu" "F.Mask" "F.Paste")
			(net "BOOTSTRAP5")
			(options
				(clearance outline)
				(anchor circle)
			)
			(primitives
				(gr_poly
					(pts
						(arc
							(start -0.1778 -0.2794)
							(mid -0.249642 -0.249642)
							(end -0.2794 -0.1778)
						)
						(arc
							(start -0.2794 0.1778)
							(mid -0.249642 0.249642)
							(end -0.1778 0.2794)
						)
						(arc
							(start 0.1778 0.2794)
							(mid 0.249642 0.249642)
							(end 0.2794 0.1778)
						)
						(arc
							(start 0.2794 -0.1778)
							(mid 0.249642 -0.249642)
							(end 0.1778 -0.2794)
						)
					)
					(width 0)
					(fill yes)
				)
			)
		)
		(pad "2" smd custom
			(at 0 0.4445 180)
			(size 0.1397 0.1397)
			(layers "F.Cu" "F.Mask" "F.Paste")
			(net "BOOTSTRAP_R_5")
			(options
				(clearance outline)
				(anchor circle)
			)
			(primitives
				(gr_poly
					(pts
						(arc
							(start -0.1778 -0.2794)
							(mid -0.249642 -0.249642)
							(end -0.2794 -0.1778)
						)
						(arc
							(start -0.2794 0.1778)
							(mid -0.249642 0.249642)
							(end -0.1778 0.2794)
						)
						(arc
							(start 0.1778 0.2794)
							(mid 0.249642 0.249642)
							(end 0.2794 0.1778)
						)
						(arc
							(start 0.2794 -0.1778)
							(mid 0.249642 -0.249642)
							(end 0.1778 -0.2794)
						)
					)
					(width 0)
					(fill yes)
				)
			)
		)
	)
	(footprint ""
		(layer "F.Cu")
		(at 335.153 -187.198)
		(property "Reference" "TP169"
			(at 0 0 0)
			(layer "F.SilkS")
			(hide yes)
			(effects
				(font
					(size 1.27 1.27)
				)
			)
		)
		(property "Value" "TPAD28-2-GP"
			(at -0.0127 -1.6637 0)
			(unlocked yes)
			(layer "F.Fab")
			(hide yes)
			(effects
				(font
					(size 1.016 1.016)
					(thickness 0.1524)
				)
			)
		)
		(property "Device Type" "TPAD28"
			(at -0.0127 -3.1877 0)
			(unlocked yes)
			(layer "F.Fab")
			(hide yes)
			(effects
				(font
					(size 1.016 1.016)
					(thickness 0.1524)
				)
			)
		)
		(duplicate_pad_numbers_are_jumpers no)
		(fp_poly
			(pts
				(arc
					(start 0.3556 0)
					(mid -0.3556 0)
					(end 0.3556 0)
				)
			)
			(stroke
				(width 0)
				(type default)
			)
			(fill no)
			(layer "F.CrtYd")
		)
		(fp_poly
			(pts
				(arc
					(start 0.6096 0)
					(mid -0.6096 0)
					(end 0.6096 0)
				)
			)
			(stroke
				(width 0)
				(type default)
			)
			(fill no)
			(layer "F.Fab")
		)
		(pad "1" smd circle
			(at 0 0)
			(size 0.7112 0.7112)
			(layers "F.Cu" "F.Mask" "F.Paste")
			(net "IOEXP4_GPIO12")
		)
	)
	(footprint ""
		(layer "F.Cu")
		(at 29.591 -192.024 90)
		(property "Reference" "R2114"
			(at 0 0 90)
			(layer "F.SilkS")
			(hide yes)
			(effects
				(font
					(size 1.27 1.27)
				)
			)
		)
		(property "Value" "0R2J-2-GP"
			(at 0.064008 -3.993896 90)
			(unlocked yes)
			(layer "F.Fab")
			(hide yes)
			(effects
				(font
					(size 1.016 1.016)
					(thickness 0.1524)
				)
			)
		)
		(property "Device Type" "R402H16"
			(at 0.064008 -5.517896 90)
			(unlocked yes)
			(layer "F.Fab")
			(hide yes)
			(effects
				(font
					(size 1.016 1.016)
					(thickness 0.1524)
				)
			)
		)
		(duplicate_pad_numbers_are_jumpers no)
		(fp_line
			(start 0.508 -0.9398)
			(end -0.508 -0.9398)
			(stroke
				(width 0.1524)
				(type default)
			)
			(layer "F.SilkS")
		)
		(fp_line
			(start -0.508 -0.9398)
			(end -0.508 0.9398)
			(stroke
				(width 0.1524)
				(type default)
			)
			(layer "F.SilkS")
		)
		(fp_rect
			(start -0.508 0.9398)
			(end 0.508 -0.9398)
			(stroke
				(width 0)
				(type default)
			)
			(fill no)
			(layer "F.CrtYd")
		)
		(fp_rect
			(start -0.508 0.9398)
			(end 0.508 -0.9398)
			(stroke
				(width 0)
				(type default)
			)
			(fill no)
			(layer "F.Fab")
		)
		(pad "1" smd custom
			(at 0 -0.4445 90)
			(size 0.1397 0.1397)
			(layers "F.Cu" "F.Mask" "F.Paste")
			(net "MB0_CM_GATE")
			(options
				(clearance outline)
				(anchor circle)
			)
			(primitives
				(gr_poly
					(pts
						(arc
							(start -0.1778 -0.2794)
							(mid -0.249642 -0.249642)
							(end -0.2794 -0.1778)
						)
						(arc
							(start -0.2794 0.1778)
							(mid -0.249642 0.249642)
							(end -0.1778 0.2794)
						)
						(arc
							(start 0.1778 0.2794)
							(mid 0.249642 0.249642)
							(end 0.2794 0.1778)
						)
						(arc
							(start 0.2794 -0.1778)
							(mid 0.249642 -0.249642)
							(end 0.1778 -0.2794)
						)
					)
					(width 0)
					(fill yes)
				)
			)
		)
		(pad "2" smd custom
			(at 0 0.4445 90)
			(size 0.1397 0.1397)
			(layers "F.Cu" "F.Mask" "F.Paste")
			(net "MB0_CM_GATE_R")
			(options
				(clearance outline)
				(anchor circle)
			)
			(primitives
				(gr_poly
					(pts
						(arc
							(start -0.1778 -0.2794)
							(mid -0.249642 -0.249642)
							(end -0.2794 -0.1778)
						)
						(arc
							(start -0.2794 0.1778)
							(mid -0.249642 0.249642)
							(end -0.1778 0.2794)
						)
						(arc
							(start 0.1778 0.2794)
							(mid 0.249642 0.249642)
							(end 0.2794 0.1778)
						)
						(arc
							(start 0.2794 -0.1778)
							(mid 0.249642 -0.249642)
							(end 0.1778 -0.2794)
						)
					)
					(width 0)
					(fill yes)
				)
			)
		)
	)
	(footprint ""
		(layer "F.Cu")
		(at 36.195254 -104.427274 90)
		(property "Reference" "R33"
			(at 0 0 90)
			(layer "F.SilkS")
			(hide yes)
			(effects
				(font
					(size 1.27 1.27)
				)
			)
		)
		(property "Value" "0R3J-0-U-GP"
			(at -0.0254 -2.5146 90)
			(unlocked yes)
			(layer "F.Fab")
			(hide yes)
			(effects
				(font
					(size 1.016 1.016)
					(thickness 0.1524)
				)
			)
		)
		(property "Device Type" "R603H22"
			(at -0.0254 -4.0386 90)
			(unlocked yes)
			(layer "F.Fab")
			(hide yes)
			(effects
				(font
					(size 1.016 1.016)
					(thickness 0.1524)
				)
			)
		)
		(duplicate_pad_numbers_are_jumpers no)
		(fp_line
			(start 0.2032 0)
			(end 0.4826 0)
			(stroke
				(width 0.2032)
				(type default)
			)
			(layer "F.SilkS")
		)
		(fp_line
			(start -0.4826 0)
			(end -0.2032 0)
			(stroke
				(width 0.2032)
				(type default)
			)
			(layer "F.SilkS")
		)
		(fp_rect
			(start -0.5842 1.3335)
			(end 0.5842 -1.3335)
			(stroke
				(width 0)
				(type default)
			)
			(fill no)
			(layer "F.CrtYd")
		)
		(fp_rect
			(start -0.5842 1.3335)
			(end 0.5842 -1.3335)
			(stroke
				(width 0)
				(type default)
			)
			(fill no)
			(layer "F.Fab")
		)
		(pad "1" smd custom
			(at 0 -0.762 90)
			(size 0.2159 0.2159)
			(layers "F.Cu" "F.Mask" "F.Paste")
			(net "P3V3_I2C_MUX")
			(options
				(clearance outline)
				(anchor circle)
			)
			(primitives
				(gr_poly
					(pts
						(arc
							(start -0.3302 -0.4318)
							(mid -0.402042 -0.402042)
							(end -0.4318 -0.3302)
						)
						(arc
							(start -0.4318 0.3302)
							(mid -0.402042 0.402042)
							(end -0.3302 0.4318)
						)
						(arc
							(start 0.3302 0.4318)
							(mid 0.402042 0.402042)
							(end 0.4318 0.3302)
						)
						(arc
							(start 0.4318 -0.3302)
							(mid 0.402042 -0.402042)
							(end 0.3302 -0.4318)
						)
					)
					(width 0)
					(fill yes)
				)
			)
		)
		(pad "2" smd custom
			(at 0 0.762 90)
			(size 0.2159 0.2159)
			(layers "F.Cu" "F.Mask" "F.Paste")
			(net "P3V3_STBY")
			(options
				(clearance outline)
				(anchor circle)
			)
			(primitives
				(gr_poly
					(pts
						(arc
							(start -0.3302 -0.4318)
							(mid -0.402042 -0.402042)
							(end -0.4318 -0.3302)
						)
						(arc
							(start -0.4318 0.3302)
							(mid -0.402042 0.402042)
							(end -0.3302 0.4318)
						)
						(arc
							(start 0.3302 0.4318)
							(mid 0.402042 0.402042)
							(end 0.4318 0.3302)
						)
						(arc
							(start 0.4318 -0.3302)
							(mid 0.402042 -0.402042)
							(end 0.3302 -0.4318)
						)
					)
					(width 0)
					(fill yes)
				)
			)
		)
	)
	(footprint ""
		(layer "F.Cu")
		(at 178.1048 -68.453 180)
		(property "Reference" "PG20"
			(at 0 0 180)
			(layer "F.SilkS")
			(hide yes)
			(effects
				(font
					(size 1.27 1.27)
				)
			)
		)
		(property "Value" "GAP-CLOSE-PWR-3-GP"
			(at 0.0254 -6.5786 180)
			(unlocked yes)
			(layer "F.Fab")
			(hide yes)
			(effects
				(font
					(size 1.016 1.016)
					(thickness 0.1524)
				)
			)
		)
		(property "Device Type" "GAP-CLOSE-PWR-3"
			(at 0.0254 -8.255 180)
			(unlocked yes)
			(layer "F.Fab")
			(hide yes)
			(effects
				(font
					(size 1.016 1.016)
					(thickness 0.1524)
				)
			)
		)
		(duplicate_pad_numbers_are_jumpers no)
		(fp_rect
			(start -0.7112 0.4572)
			(end 0.7112 -0.4572)
			(stroke
				(width 0)
				(type default)
			)
			(fill no)
			(layer "F.CrtYd")
		)
		(fp_poly
			(pts
				(xy -0.7112 -0.4572) (xy 0.7112 -0.4572) (xy 0.7112 0.4572) (xy -0.7112 0.4572)
			)
			(stroke
				(width 0)
				(type default)
			)
			(fill no)
			(layer "F.Fab")
		)
		(pad "1" smd rect
			(at -0.3048 0 180)
			(size 0.6604 0.762)
			(layers "F.Cu" "F.Mask" "F.Paste")
			(net "DUT_AVD_PCIE")
		)
		(pad "2" smd rect
			(at 0.3048 0 180)
			(size 0.6604 0.762)
			(layers "F.Cu" "F.Mask" "F.Paste")
			(net "P0V9")
		)
	)
	(footprint ""
		(layer "F.Cu")
		(at 19.177 -147.828 90)
		(property "Reference" "R334"
			(at 0 0 90)
			(layer "F.SilkS")
			(hide yes)
			(effects
				(font
					(size 1.27 1.27)
				)
			)
		)
		(property "Value" "47KR2F-GP"
			(at 0.064008 -3.993896 90)
			(unlocked yes)
			(layer "F.Fab")
			(hide yes)
			(effects
				(font
					(size 1.016 1.016)
					(thickness 0.1524)
				)
			)
		)
		(property "Device Type" "R402H16"
			(at 0.064008 -5.517896 90)
			(unlocked yes)
			(layer "F.Fab")
			(hide yes)
			(effects
				(font
					(size 1.016 1.016)
					(thickness 0.1524)
				)
			)
		)
		(duplicate_pad_numbers_are_jumpers no)
		(fp_line
			(start 0.508 -0.9398)
			(end -0.508 -0.9398)
			(stroke
				(width 0.1524)
				(type default)
			)
			(layer "F.SilkS")
		)
		(fp_line
			(start -0.508 -0.9398)
			(end -0.508 0.9398)
			(stroke
				(width 0.1524)
				(type default)
			)
			(layer "F.SilkS")
		)
		(fp_rect
			(start -0.508 0.9398)
			(end 0.508 -0.9398)
			(stroke
				(width 0)
				(type default)
			)
			(fill no)
			(layer "F.CrtYd")
		)
		(fp_rect
			(start -0.508 0.9398)
			(end 0.508 -0.9398)
			(stroke
				(width 0)
				(type default)
			)
			(fill no)
			(layer "F.Fab")
		)
		(pad "1" smd custom
			(at 0 -0.4445 90)
			(size 0.1397 0.1397)
			(layers "F.Cu" "F.Mask" "F.Paste")
			(net "FM_BMC_RESET_N")
			(options
				(clearance outline)
				(anchor circle)
			)
			(primitives
				(gr_poly
					(pts
						(arc
							(start -0.1778 -0.2794)
							(mid -0.249642 -0.249642)
							(end -0.2794 -0.1778)
						)
						(arc
							(start -0.2794 0.1778)
							(mid -0.249642 0.249642)
							(end -0.1778 0.2794)
						)
						(arc
							(start 0.1778 0.2794)
							(mid 0.249642 0.249642)
							(end 0.2794 0.1778)
						)
						(arc
							(start 0.2794 -0.1778)
							(mid 0.249642 -0.249642)
							(end 0.1778 -0.2794)
						)
					)
					(width 0)
					(fill yes)
				)
			)
		)
		(pad "2" smd custom
			(at 0 0.4445 90)
			(size 0.1397 0.1397)
			(layers "F.Cu" "F.Mask" "F.Paste")
			(net "GND")
			(options
				(clearance outline)
				(anchor circle)
			)
			(primitives
				(gr_poly
					(pts
						(arc
							(start -0.1778 -0.2794)
							(mid -0.249642 -0.249642)
							(end -0.2794 -0.1778)
						)
						(arc
							(start -0.2794 0.1778)
							(mid -0.249642 0.249642)
							(end -0.1778 0.2794)
						)
						(arc
							(start 0.1778 0.2794)
							(mid 0.249642 0.249642)
							(end 0.2794 0.1778)
						)
						(arc
							(start 0.2794 -0.1778)
							(mid 0.249642 -0.249642)
							(end 0.1778 -0.2794)
						)
					)
					(width 0)
					(fill yes)
				)
			)
		)
	)
	(footprint ""
		(layer "F.Cu")
		(at 321.563238 -33.508188 180)
		(property "Reference" "R726"
			(at 0 0 180)
			(layer "F.SilkS")
			(hide yes)
			(effects
				(font
					(size 1.27 1.27)
				)
			)
		)
		(property "Value" "0R2J-2-GP"
			(at 0.064008 -3.993896 180)
			(unlocked yes)
			(layer "F.Fab")
			(hide yes)
			(effects
				(font
					(size 1.016 1.016)
					(thickness 0.1524)
				)
			)
		)
		(property "Device Type" "R402H16"
			(at 0.064008 -5.517896 180)
			(unlocked yes)
			(layer "F.Fab")
			(hide yes)
			(effects
				(font
					(size 1.016 1.016)
					(thickness 0.1524)
				)
			)
		)
		(duplicate_pad_numbers_are_jumpers no)
		(fp_line
			(start 0.508 -0.9398)
			(end -0.508 -0.9398)
			(stroke
				(width 0.1524)
				(type default)
			)
			(layer "F.SilkS")
		)
		(fp_line
			(start -0.508 -0.9398)
			(end -0.508 0.9398)
			(stroke
				(width 0.1524)
				(type default)
			)
			(layer "F.SilkS")
		)
		(fp_rect
			(start -0.508 0.9398)
			(end 0.508 -0.9398)
			(stroke
				(width 0)
				(type default)
			)
			(fill no)
			(layer "F.CrtYd")
		)
		(fp_rect
			(start -0.508 0.9398)
			(end 0.508 -0.9398)
			(stroke
				(width 0)
				(type default)
			)
			(fill no)
			(layer "F.Fab")
		)
		(pad "1" smd custom
			(at 0 -0.4445 180)
			(size 0.1397 0.1397)
			(layers "F.Cu" "F.Mask" "F.Paste")
			(net "8644_USB_DN8")
			(options
				(clearance outline)
				(anchor circle)
			)
			(primitives
				(gr_poly
					(pts
						(arc
							(start -0.1778 -0.2794)
							(mid -0.249642 -0.249642)
							(end -0.2794 -0.1778)
						)
						(arc
							(start -0.2794 0.1778)
							(mid -0.249642 0.249642)
							(end -0.1778 0.2794)
						)
						(arc
							(start 0.1778 0.2794)
							(mid 0.249642 0.249642)
							(end 0.2794 0.1778)
						)
						(arc
							(start 0.2794 -0.1778)
							(mid 0.249642 -0.249642)
							(end 0.1778 -0.2794)
						)
					)
					(width 0)
					(fill yes)
				)
			)
		)
		(pad "2" smd custom
			(at 0 0.4445 180)
			(size 0.1397 0.1397)
			(layers "F.Cu" "F.Mask" "F.Paste")
			(net "P3V3_STBY")
			(options
				(clearance outline)
				(anchor circle)
			)
			(primitives
				(gr_poly
					(pts
						(arc
							(start -0.1778 -0.2794)
							(mid -0.249642 -0.249642)
							(end -0.2794 -0.1778)
						)
						(arc
							(start -0.2794 0.1778)
							(mid -0.249642 0.249642)
							(end -0.1778 0.2794)
						)
						(arc
							(start 0.1778 0.2794)
							(mid 0.249642 0.249642)
							(end 0.2794 0.1778)
						)
						(arc
							(start 0.2794 -0.1778)
							(mid 0.249642 -0.249642)
							(end 0.1778 -0.2794)
						)
					)
					(width 0)
					(fill yes)
				)
			)
		)
	)
	(footprint ""
		(layer "F.Cu")
		(at 203.02474 -6.691122 90)
		(property "Reference" "R3"
			(at 0 0 90)
			(layer "F.SilkS")
			(hide yes)
			(effects
				(font
					(size 1.27 1.27)
				)
			)
		)
		(property "Value" "0R2J-2-GP"
			(at 0.064008 -3.993896 90)
			(unlocked yes)
			(layer "F.Fab")
			(hide yes)
			(effects
				(font
					(size 1.016 1.016)
					(thickness 0.1524)
				)
			)
		)
		(property "Device Type" "R402H16"
			(at 0.064008 -5.517896 90)
			(unlocked yes)
			(layer "F.Fab")
			(hide yes)
			(effects
				(font
					(size 1.016 1.016)
					(thickness 0.1524)
				)
			)
		)
		(duplicate_pad_numbers_are_jumpers no)
		(fp_line
			(start 0.508 -0.9398)
			(end -0.508 -0.9398)
			(stroke
				(width 0.1524)
				(type default)
			)
			(layer "F.SilkS")
		)
		(fp_line
			(start -0.508 -0.9398)
			(end -0.508 0.9398)
			(stroke
				(width 0.1524)
				(type default)
			)
			(layer "F.SilkS")
		)
		(fp_rect
			(start -0.508 0.9398)
			(end 0.508 -0.9398)
			(stroke
				(width 0)
				(type default)
			)
			(fill no)
			(layer "F.CrtYd")
		)
		(fp_rect
			(start -0.508 0.9398)
			(end 0.508 -0.9398)
			(stroke
				(width 0)
				(type default)
			)
			(fill no)
			(layer "F.Fab")
		)
		(pad "1" smd custom
			(at 0 -0.4445 90)
			(size 0.1397 0.1397)
			(layers "F.Cu" "F.Mask" "F.Paste")
			(net "BOOT_RECOVERY#_R")
			(options
				(clearance outline)
				(anchor circle)
			)
			(primitives
				(gr_poly
					(pts
						(arc
							(start -0.1778 -0.2794)
							(mid -0.249642 -0.249642)
							(end -0.2794 -0.1778)
						)
						(arc
							(start -0.2794 0.1778)
							(mid -0.249642 0.249642)
							(end -0.1778 0.2794)
						)
						(arc
							(start 0.1778 0.2794)
							(mid 0.249642 0.249642)
							(end 0.2794 0.1778)
						)
						(arc
							(start 0.2794 -0.1778)
							(mid 0.249642 -0.249642)
							(end 0.1778 -0.2794)
						)
					)
					(width 0)
					(fill yes)
				)
			)
		)
		(pad "2" smd custom
			(at 0 0.4445 90)
			(size 0.1397 0.1397)
			(layers "F.Cu" "F.Mask" "F.Paste")
			(net "BOOT_RECOVERY#")
			(options
				(clearance outline)
				(anchor circle)
			)
			(primitives
				(gr_poly
					(pts
						(arc
							(start -0.1778 -0.2794)
							(mid -0.249642 -0.249642)
							(end -0.2794 -0.1778)
						)
						(arc
							(start -0.2794 0.1778)
							(mid -0.249642 0.249642)
							(end -0.1778 0.2794)
						)
						(arc
							(start 0.1778 0.2794)
							(mid 0.249642 0.249642)
							(end 0.2794 0.1778)
						)
						(arc
							(start 0.2794 -0.1778)
							(mid 0.249642 -0.249642)
							(end 0.1778 -0.2794)
						)
					)
					(width 0)
					(fill yes)
				)
			)
		)
	)
	(footprint ""
		(layer "F.Cu")
		(at 250.549918 -4.721098 90)
		(property "Reference" "R3603"
			(at 0 0 90)
			(layer "F.SilkS")
			(hide yes)
			(effects
				(font
					(size 1.27 1.27)
				)
			)
		)
		(property "Value" "10KR2F-2-GP"
			(at 0.064008 -3.993896 90)
			(unlocked yes)
			(layer "F.Fab")
			(hide yes)
			(effects
				(font
					(size 1.016 1.016)
					(thickness 0.1524)
				)
			)
		)
		(property "Device Type" "R402H16"
			(at 0.064008 -5.517896 90)
			(unlocked yes)
			(layer "F.Fab")
			(hide yes)
			(effects
				(font
					(size 1.016 1.016)
					(thickness 0.1524)
				)
			)
		)
		(duplicate_pad_numbers_are_jumpers no)
		(fp_line
			(start 0.508 -0.9398)
			(end -0.508 -0.9398)
			(stroke
				(width 0.1524)
				(type default)
			)
			(layer "F.SilkS")
		)
		(fp_line
			(start -0.508 -0.9398)
			(end -0.508 0.9398)
			(stroke
				(width 0.1524)
				(type default)
			)
			(layer "F.SilkS")
		)
		(fp_rect
			(start -0.508 0.9398)
			(end 0.508 -0.9398)
			(stroke
				(width 0)
				(type default)
			)
			(fill no)
			(layer "F.CrtYd")
		)
		(fp_rect
			(start -0.508 0.9398)
			(end 0.508 -0.9398)
			(stroke
				(width 0)
				(type default)
			)
			(fill no)
			(layer "F.Fab")
		)
		(pad "1" smd custom
			(at 0 -0.4445 90)
			(size 0.1397 0.1397)
			(layers "F.Cu" "F.Mask" "F.Paste")
			(net "P3V3_STBY")
			(options
				(clearance outline)
				(anchor circle)
			)
			(primitives
				(gr_poly
					(pts
						(arc
							(start -0.1778 -0.2794)
							(mid -0.249642 -0.249642)
							(end -0.2794 -0.1778)
						)
						(arc
							(start -0.2794 0.1778)
							(mid -0.249642 0.249642)
							(end -0.1778 0.2794)
						)
						(arc
							(start 0.1778 0.2794)
							(mid 0.249642 0.249642)
							(end 0.2794 0.1778)
						)
						(arc
							(start 0.2794 -0.1778)
							(mid 0.249642 -0.249642)
							(end 0.1778 -0.2794)
						)
					)
					(width 0)
					(fill yes)
				)
			)
		)
		(pad "2" smd custom
			(at 0 0.4445 90)
			(size 0.1397 0.1397)
			(layers "F.Cu" "F.Mask" "F.Paste")
			(net "MAX6654_ALERT#")
			(options
				(clearance outline)
				(anchor circle)
			)
			(primitives
				(gr_poly
					(pts
						(arc
							(start -0.1778 -0.2794)
							(mid -0.249642 -0.249642)
							(end -0.2794 -0.1778)
						)
						(arc
							(start -0.2794 0.1778)
							(mid -0.249642 0.249642)
							(end -0.1778 0.2794)
						)
						(arc
							(start 0.1778 0.2794)
							(mid 0.249642 0.249642)
							(end 0.2794 0.1778)
						)
						(arc
							(start 0.2794 -0.1778)
							(mid 0.249642 -0.249642)
							(end 0.1778 -0.2794)
						)
					)
					(width 0)
					(fill yes)
				)
			)
		)
	)
	(footprint ""
		(layer "F.Cu")
		(at 327.007982 -212.420454 180)
		(property "Reference" "C63"
			(at 0 0 180)
			(layer "F.SilkS")
			(hide yes)
			(effects
				(font
					(size 1.27 1.27)
				)
			)
		)
		(property "Value" "SCD22U10V2KX-1GP"
			(at 1.1811 -2.7051 180)
			(unlocked yes)
			(layer "F.Fab")
			(hide yes)
			(effects
				(font
					(size 1.016 1.016)
					(thickness 0.1524)
				)
			)
		)
		(property "Device Type" "C402H22"
			(at 1.1811 -4.2291 180)
			(unlocked yes)
			(layer "F.Fab")
			(hide yes)
			(effects
				(font
					(size 1.016 1.016)
					(thickness 0.1524)
				)
			)
		)
		(duplicate_pad_numbers_are_jumpers no)
		(fp_rect
			(start -0.4318 0.9525)
			(end 0.4318 -0.9525)
			(stroke
				(width 0)
				(type default)
			)
			(fill no)
			(layer "F.CrtYd")
		)
		(fp_rect
			(start -0.4318 0.9525)
			(end 0.4318 -0.9525)
			(stroke
				(width 0)
				(type default)
			)
			(fill no)
			(layer "F.Fab")
		)
		(pad "1" smd custom
			(at 0 -0.4445 180)
			(size 0.1524 0.1524)
			(layers "F.Cu" "F.Mask" "F.Paste")
			(net "PCIE_TX_CAP_N20")
			(options
				(clearance outline)
				(anchor circle)
			)
			(primitives
				(gr_poly
					(pts
						(arc
							(start 0.3048 -0.2032)
							(mid 0.275042 -0.275042)
							(end 0.2032 -0.3048)
						)
						(arc
							(start -0.2032 -0.3048)
							(mid -0.275042 -0.275042)
							(end -0.3048 -0.2032)
						)
						(arc
							(start -0.3048 0.2032)
							(mid -0.275042 0.275042)
							(end -0.2032 0.3048)
						)
						(arc
							(start 0.2032 0.3048)
							(mid 0.275042 0.275042)
							(end 0.3048 0.2032)
						)
					)
					(width 0)
					(fill yes)
				)
			)
		)
		(pad "2" smd custom
			(at 0 0.4445 180)
			(size 0.1524 0.1524)
			(layers "F.Cu" "F.Mask" "F.Paste")
			(net "PCIE_TX_N20")
			(options
				(clearance outline)
				(anchor circle)
			)
			(primitives
				(gr_poly
					(pts
						(arc
							(start 0.3048 -0.2032)
							(mid 0.275042 -0.275042)
							(end 0.2032 -0.3048)
						)
						(arc
							(start -0.2032 -0.3048)
							(mid -0.275042 -0.275042)
							(end -0.3048 -0.2032)
						)
						(arc
							(start -0.3048 0.2032)
							(mid -0.275042 0.275042)
							(end -0.2032 0.3048)
						)
						(arc
							(start 0.2032 0.3048)
							(mid 0.275042 0.275042)
							(end 0.3048 0.2032)
						)
					)
					(width 0)
					(fill yes)
				)
			)
		)
	)
	(footprint ""
		(layer "F.Cu")
		(at 152.111202 -67.083432 90)
		(property "Reference" "PC192"
			(at 0 0 90)
			(layer "F.SilkS")
			(hide yes)
			(effects
				(font
					(size 1.27 1.27)
				)
			)
		)
		(property "Value" "SC10U25V5KX-GP"
			(at -0.0762 -6.1214 90)
			(unlocked yes)
			(layer "F.Fab")
			(hide yes)
			(effects
				(font
					(size 1.016 1.016)
					(thickness 0.1524)
				)
			)
		)
		(property "Device Type" "C805H56"
			(at -0.0762 -8.1534 90)
			(unlocked yes)
			(layer "F.Fab")
			(hide yes)
			(effects
				(font
					(size 1.016 1.016)
					(thickness 0.1524)
				)
			)
		)
		(duplicate_pad_numbers_are_jumpers no)
		(fp_line
			(start 0.635 0)
			(end -0.635 0)
			(stroke
				(width 0.508)
				(type default)
			)
			(layer "F.SilkS")
		)
		(fp_rect
			(start -0.9652 1.778)
			(end 0.9652 -1.778)
			(stroke
				(width 0)
				(type default)
			)
			(fill no)
			(layer "F.CrtYd")
		)
		(fp_poly
			(pts
				(xy -0.9652 -1.778) (xy 0.9652 -1.778) (xy 0.9652 1.778) (xy -0.9652 1.778)
			)
			(stroke
				(width 0)
				(type default)
			)
			(fill no)
			(layer "F.Fab")
		)
		(pad "1" smd rect
			(at 0 -0.9652 90)
			(size 1.397 1.143)
			(layers "F.Cu" "F.Mask" "F.Paste")
			(net "P0V9_VIN")
		)
		(pad "2" smd rect
			(at 0 0.9652 90)
			(size 1.397 1.143)
			(layers "F.Cu" "F.Mask" "F.Paste")
			(net "GND")
		)
	)
	(footprint ""
		(layer "F.Cu")
		(at 32.814006 -83.803744 180)
		(property "Reference" "R734"
			(at 0 0 180)
			(layer "F.SilkS")
			(hide yes)
			(effects
				(font
					(size 1.27 1.27)
				)
			)
		)
		(property "Value" "47R6F-GP"
			(at -0.0508 -4.8514 180)
			(unlocked yes)
			(layer "F.Fab")
			(hide yes)
			(effects
				(font
					(size 1.016 1.016)
					(thickness 0.1524)
				)
			)
		)
		(property "Device Type" "R1206H26"
			(at 0 -6.3754 180)
			(unlocked yes)
			(layer "F.Fab")
			(hide yes)
			(effects
				(font
					(size 1.016 1.016)
					(thickness 0.1524)
				)
			)
		)
		(duplicate_pad_numbers_are_jumpers no)
		(fp_line
			(start 1.016 2.2352)
			(end -1.016 2.2352)
			(stroke
				(width 0.1524)
				(type default)
			)
			(layer "F.SilkS")
		)
		(fp_line
			(start 1.016 -2.2352)
			(end 1.016 2.2352)
			(stroke
				(width 0.1524)
				(type default)
			)
			(layer "F.SilkS")
		)
		(fp_line
			(start -1.016 2.2352)
			(end -1.016 -2.2352)
			(stroke
				(width 0.1524)
				(type default)
			)
			(layer "F.SilkS")
		)
		(fp_line
			(start -1.016 -2.2352)
			(end 1.016 -2.2352)
			(stroke
				(width 0.1524)
				(type default)
			)
			(layer "F.SilkS")
		)
		(fp_rect
			(start -1.0922 2.3114)
			(end 1.0922 -2.3114)
			(stroke
				(width 0)
				(type default)
			)
			(fill no)
			(layer "F.CrtYd")
		)
		(fp_poly
			(pts
				(xy -1.0922 -2.3114) (xy 1.0922 -2.3114) (xy 1.0922 2.3114) (xy -1.0922 2.3114)
			)
			(stroke
				(width 0)
				(type default)
			)
			(fill no)
			(layer "F.Fab")
		)
		(pad "1" smd rect
			(at 0 -1.397 180)
			(size 1.651 1.27)
			(layers "F.Cu" "F.Mask" "F.Paste")
			(net "P5V_STBY")
		)
		(pad "2" smd rect
			(at 0 1.397 180)
			(size 1.651 1.27)
			(layers "F.Cu" "F.Mask" "F.Paste")
			(net "Q46_D")
		)
	)
	(footprint ""
		(layer "F.Cu")
		(at 156.2354 -92.329 180)
		(property "Reference" "R712"
			(at 0 0 180)
			(layer "F.SilkS")
			(hide yes)
			(effects
				(font
					(size 1.27 1.27)
				)
			)
		)
		(property "Value" "1MR2F-GP"
			(at 0.064008 -3.993896 180)
			(unlocked yes)
			(layer "F.Fab")
			(hide yes)
			(effects
				(font
					(size 1.016 1.016)
					(thickness 0.1524)
				)
			)
		)
		(property "Device Type" "R402H16"
			(at 0.064008 -5.517896 180)
			(unlocked yes)
			(layer "F.Fab")
			(hide yes)
			(effects
				(font
					(size 1.016 1.016)
					(thickness 0.1524)
				)
			)
		)
		(duplicate_pad_numbers_are_jumpers no)
		(fp_line
			(start 0.508 -0.9398)
			(end -0.508 -0.9398)
			(stroke
				(width 0.1524)
				(type default)
			)
			(layer "F.SilkS")
		)
		(fp_line
			(start -0.508 -0.9398)
			(end -0.508 0.9398)
			(stroke
				(width 0.1524)
				(type default)
			)
			(layer "F.SilkS")
		)
		(fp_rect
			(start -0.508 0.9398)
			(end 0.508 -0.9398)
			(stroke
				(width 0)
				(type default)
			)
			(fill no)
			(layer "F.CrtYd")
		)
		(fp_rect
			(start -0.508 0.9398)
			(end 0.508 -0.9398)
			(stroke
				(width 0)
				(type default)
			)
			(fill no)
			(layer "F.Fab")
		)
		(pad "1" smd custom
			(at 0 -0.4445 180)
			(size 0.1397 0.1397)
			(layers "F.Cu" "F.Mask" "F.Paste")
			(net "XTAL_X2_CLKGEN")
			(options
				(clearance outline)
				(anchor circle)
			)
			(primitives
				(gr_poly
					(pts
						(arc
							(start -0.1778 -0.2794)
							(mid -0.249642 -0.249642)
							(end -0.2794 -0.1778)
						)
						(arc
							(start -0.2794 0.1778)
							(mid -0.249642 0.249642)
							(end -0.1778 0.2794)
						)
						(arc
							(start 0.1778 0.2794)
							(mid 0.249642 0.249642)
							(end 0.2794 0.1778)
						)
						(arc
							(start 0.2794 -0.1778)
							(mid 0.249642 -0.249642)
							(end 0.1778 -0.2794)
						)
					)
					(width 0)
					(fill yes)
				)
			)
		)
		(pad "2" smd custom
			(at 0 0.4445 180)
			(size 0.1397 0.1397)
			(layers "F.Cu" "F.Mask" "F.Paste")
			(net "XTAL_X1")
			(options
				(clearance outline)
				(anchor circle)
			)
			(primitives
				(gr_poly
					(pts
						(arc
							(start -0.1778 -0.2794)
							(mid -0.249642 -0.249642)
							(end -0.2794 -0.1778)
						)
						(arc
							(start -0.2794 0.1778)
							(mid -0.249642 0.249642)
							(end -0.1778 0.2794)
						)
						(arc
							(start 0.1778 0.2794)
							(mid 0.249642 0.249642)
							(end 0.2794 0.1778)
						)
						(arc
							(start 0.2794 -0.1778)
							(mid 0.249642 -0.249642)
							(end 0.1778 -0.2794)
						)
					)
					(width 0)
					(fill yes)
				)
			)
		)
	)
	(footprint ""
		(layer "F.Cu")
		(at 309.992014 -212.420454 180)
		(property "Reference" "C72"
			(at 0 0 180)
			(layer "F.SilkS")
			(hide yes)
			(effects
				(font
					(size 1.27 1.27)
				)
			)
		)
		(property "Value" "SCD22U10V2KX-1GP"
			(at 1.1811 -2.7051 180)
			(unlocked yes)
			(layer "F.Fab")
			(hide yes)
			(effects
				(font
					(size 1.016 1.016)
					(thickness 0.1524)
				)
			)
		)
		(property "Device Type" "C402H22"
			(at 1.1811 -4.2291 180)
			(unlocked yes)
			(layer "F.Fab")
			(hide yes)
			(effects
				(font
					(size 1.016 1.016)
					(thickness 0.1524)
				)
			)
		)
		(duplicate_pad_numbers_are_jumpers no)
		(fp_rect
			(start -0.4318 0.9525)
			(end 0.4318 -0.9525)
			(stroke
				(width 0)
				(type default)
			)
			(fill no)
			(layer "F.CrtYd")
		)
		(fp_rect
			(start -0.4318 0.9525)
			(end 0.4318 -0.9525)
			(stroke
				(width 0)
				(type default)
			)
			(fill no)
			(layer "F.Fab")
		)
		(pad "1" smd custom
			(at 0 -0.4445 180)
			(size 0.1524 0.1524)
			(layers "F.Cu" "F.Mask" "F.Paste")
			(net "PCIE_TX_CAP_P25")
			(options
				(clearance outline)
				(anchor circle)
			)
			(primitives
				(gr_poly
					(pts
						(arc
							(start 0.3048 -0.2032)
							(mid 0.275042 -0.275042)
							(end 0.2032 -0.3048)
						)
						(arc
							(start -0.2032 -0.3048)
							(mid -0.275042 -0.275042)
							(end -0.3048 -0.2032)
						)
						(arc
							(start -0.3048 0.2032)
							(mid -0.275042 0.275042)
							(end -0.2032 0.3048)
						)
						(arc
							(start 0.2032 0.3048)
							(mid 0.275042 0.275042)
							(end 0.3048 0.2032)
						)
					)
					(width 0)
					(fill yes)
				)
			)
		)
		(pad "2" smd custom
			(at 0 0.4445 180)
			(size 0.1524 0.1524)
			(layers "F.Cu" "F.Mask" "F.Paste")
			(net "PCIE_TX_P25")
			(options
				(clearance outline)
				(anchor circle)
			)
			(primitives
				(gr_poly
					(pts
						(arc
							(start 0.3048 -0.2032)
							(mid 0.275042 -0.275042)
							(end 0.2032 -0.3048)
						)
						(arc
							(start -0.2032 -0.3048)
							(mid -0.275042 -0.275042)
							(end -0.3048 -0.2032)
						)
						(arc
							(start -0.3048 0.2032)
							(mid -0.275042 0.275042)
							(end -0.2032 0.3048)
						)
						(arc
							(start 0.2032 0.3048)
							(mid 0.275042 0.275042)
							(end 0.3048 0.2032)
						)
					)
					(width 0)
					(fill yes)
				)
			)
		)
	)
	(footprint ""
		(layer "F.Cu")
		(at 46.9138 -186.5376 180)
		(property "Reference" "R872"
			(at 0 0 180)
			(layer "F.SilkS")
			(hide yes)
			(effects
				(font
					(size 1.27 1.27)
				)
			)
		)
		(property "Value" "10KR2F-2-GP"
			(at 0.064008 -3.993896 180)
			(unlocked yes)
			(layer "F.Fab")
			(hide yes)
			(effects
				(font
					(size 1.016 1.016)
					(thickness 0.1524)
				)
			)
		)
		(property "Device Type" "R402H16"
			(at 0.064008 -5.517896 180)
			(unlocked yes)
			(layer "F.Fab")
			(hide yes)
			(effects
				(font
					(size 1.016 1.016)
					(thickness 0.1524)
				)
			)
		)
		(duplicate_pad_numbers_are_jumpers no)
		(fp_line
			(start 0.508 -0.9398)
			(end -0.508 -0.9398)
			(stroke
				(width 0.1524)
				(type default)
			)
			(layer "F.SilkS")
		)
		(fp_line
			(start -0.508 -0.9398)
			(end -0.508 0.9398)
			(stroke
				(width 0.1524)
				(type default)
			)
			(layer "F.SilkS")
		)
		(fp_rect
			(start -0.508 0.9398)
			(end 0.508 -0.9398)
			(stroke
				(width 0)
				(type default)
			)
			(fill no)
			(layer "F.CrtYd")
		)
		(fp_rect
			(start -0.508 0.9398)
			(end 0.508 -0.9398)
			(stroke
				(width 0)
				(type default)
			)
			(fill no)
			(layer "F.Fab")
		)
		(pad "1" smd custom
			(at 0 -0.4445 180)
			(size 0.1397 0.1397)
			(layers "F.Cu" "F.Mask" "F.Paste")
			(net "P3V3_STBY")
			(options
				(clearance outline)
				(anchor circle)
			)
			(primitives
				(gr_poly
					(pts
						(arc
							(start -0.1778 -0.2794)
							(mid -0.249642 -0.249642)
							(end -0.2794 -0.1778)
						)
						(arc
							(start -0.2794 0.1778)
							(mid -0.249642 0.249642)
							(end -0.1778 0.2794)
						)
						(arc
							(start 0.1778 0.2794)
							(mid 0.249642 0.249642)
							(end 0.2794 0.1778)
						)
						(arc
							(start 0.2794 -0.1778)
							(mid 0.249642 -0.249642)
							(end 0.1778 -0.2794)
						)
					)
					(width 0)
					(fill yes)
				)
			)
		)
		(pad "2" smd custom
			(at 0 0.4445 180)
			(size 0.1397 0.1397)
			(layers "F.Cu" "F.Mask" "F.Paste")
			(net "I2C9_BUFF_EN")
			(options
				(clearance outline)
				(anchor circle)
			)
			(primitives
				(gr_poly
					(pts
						(arc
							(start -0.1778 -0.2794)
							(mid -0.249642 -0.249642)
							(end -0.2794 -0.1778)
						)
						(arc
							(start -0.2794 0.1778)
							(mid -0.249642 0.249642)
							(end -0.1778 0.2794)
						)
						(arc
							(start 0.1778 0.2794)
							(mid 0.249642 0.249642)
							(end 0.2794 0.1778)
						)
						(arc
							(start 0.2794 -0.1778)
							(mid 0.249642 -0.249642)
							(end 0.1778 -0.2794)
						)
					)
					(width 0)
					(fill yes)
				)
			)
		)
	)
	(footprint ""
		(layer "F.Cu")
		(at 166.116 -88.5444 90)
		(property "Reference" "R3104"
			(at 0 0 90)
			(layer "F.SilkS")
			(hide yes)
			(effects
				(font
					(size 1.27 1.27)
				)
			)
		)
		(property "Value" "27R2F-GP"
			(at 0.064008 -3.993896 90)
			(unlocked yes)
			(layer "F.Fab")
			(hide yes)
			(effects
				(font
					(size 1.016 1.016)
					(thickness 0.1524)
				)
			)
		)
		(property "Device Type" "R402H16"
			(at 0.064008 -5.517896 90)
			(unlocked yes)
			(layer "F.Fab")
			(hide yes)
			(effects
				(font
					(size 1.016 1.016)
					(thickness 0.1524)
				)
			)
		)
		(duplicate_pad_numbers_are_jumpers no)
		(fp_line
			(start 0.508 -0.9398)
			(end -0.508 -0.9398)
			(stroke
				(width 0.1524)
				(type default)
			)
			(layer "F.SilkS")
		)
		(fp_line
			(start -0.508 -0.9398)
			(end -0.508 0.9398)
			(stroke
				(width 0.1524)
				(type default)
			)
			(layer "F.SilkS")
		)
		(fp_rect
			(start -0.508 0.9398)
			(end 0.508 -0.9398)
			(stroke
				(width 0)
				(type default)
			)
			(fill no)
			(layer "F.CrtYd")
		)
		(fp_rect
			(start -0.508 0.9398)
			(end 0.508 -0.9398)
			(stroke
				(width 0)
				(type default)
			)
			(fill no)
			(layer "F.Fab")
		)
		(pad "1" smd custom
			(at 0 -0.4445 90)
			(size 0.1397 0.1397)
			(layers "F.Cu" "F.Mask" "F.Paste")
			(net "CLKGEN_P1_R")
			(options
				(clearance outline)
				(anchor circle)
			)
			(primitives
				(gr_poly
					(pts
						(arc
							(start -0.1778 -0.2794)
							(mid -0.249642 -0.249642)
							(end -0.2794 -0.1778)
						)
						(arc
							(start -0.2794 0.1778)
							(mid -0.249642 0.249642)
							(end -0.1778 0.2794)
						)
						(arc
							(start 0.1778 0.2794)
							(mid 0.249642 0.249642)
							(end 0.2794 0.1778)
						)
						(arc
							(start 0.2794 -0.1778)
							(mid 0.249642 -0.249642)
							(end 0.1778 -0.2794)
						)
					)
					(width 0)
					(fill yes)
				)
			)
		)
		(pad "2" smd custom
			(at 0 0.4445 90)
			(size 0.1397 0.1397)
			(layers "F.Cu" "F.Mask" "F.Paste")
			(net "I210_REFCLK_D_P")
			(options
				(clearance outline)
				(anchor circle)
			)
			(primitives
				(gr_poly
					(pts
						(arc
							(start -0.1778 -0.2794)
							(mid -0.249642 -0.249642)
							(end -0.2794 -0.1778)
						)
						(arc
							(start -0.2794 0.1778)
							(mid -0.249642 0.249642)
							(end -0.1778 0.2794)
						)
						(arc
							(start 0.1778 0.2794)
							(mid 0.249642 0.249642)
							(end 0.2794 0.1778)
						)
						(arc
							(start 0.2794 -0.1778)
							(mid 0.249642 -0.249642)
							(end 0.1778 -0.2794)
						)
					)
					(width 0)
					(fill yes)
				)
			)
		)
	)
	(footprint ""
		(layer "F.Cu")
		(at 21.336 -145.415 180)
		(property "Reference" "C195"
			(at 0 0 180)
			(layer "F.SilkS")
			(hide yes)
			(effects
				(font
					(size 1.27 1.27)
				)
			)
		)
		(property "Value" "SCD1U16V2KX-3GP"
			(at 1.1811 -2.7051 180)
			(unlocked yes)
			(layer "F.Fab")
			(hide yes)
			(effects
				(font
					(size 1.016 1.016)
					(thickness 0.1524)
				)
			)
		)
		(property "Device Type" "C402H22"
			(at 1.1811 -4.2291 180)
			(unlocked yes)
			(layer "F.Fab")
			(hide yes)
			(effects
				(font
					(size 1.016 1.016)
					(thickness 0.1524)
				)
			)
		)
		(duplicate_pad_numbers_are_jumpers no)
		(fp_rect
			(start -0.4318 0.9525)
			(end 0.4318 -0.9525)
			(stroke
				(width 0)
				(type default)
			)
			(fill no)
			(layer "F.CrtYd")
		)
		(fp_rect
			(start -0.4318 0.9525)
			(end 0.4318 -0.9525)
			(stroke
				(width 0)
				(type default)
			)
			(fill no)
			(layer "F.Fab")
		)
		(pad "1" smd custom
			(at 0 -0.4445 180)
			(size 0.1524 0.1524)
			(layers "F.Cu" "F.Mask" "F.Paste")
			(net "MPLLAV33")
			(options
				(clearance outline)
				(anchor circle)
			)
			(primitives
				(gr_poly
					(pts
						(arc
							(start 0.3048 -0.2032)
							(mid 0.275042 -0.275042)
							(end 0.2032 -0.3048)
						)
						(arc
							(start -0.2032 -0.3048)
							(mid -0.275042 -0.275042)
							(end -0.3048 -0.2032)
						)
						(arc
							(start -0.3048 0.2032)
							(mid -0.275042 0.275042)
							(end -0.2032 0.3048)
						)
						(arc
							(start 0.2032 0.3048)
							(mid 0.275042 0.275042)
							(end 0.3048 0.2032)
						)
					)
					(width 0)
					(fill yes)
				)
			)
		)
		(pad "2" smd custom
			(at 0 0.4445 180)
			(size 0.1524 0.1524)
			(layers "F.Cu" "F.Mask" "F.Paste")
			(net "GND")
			(options
				(clearance outline)
				(anchor circle)
			)
			(primitives
				(gr_poly
					(pts
						(arc
							(start 0.3048 -0.2032)
							(mid 0.275042 -0.275042)
							(end 0.2032 -0.3048)
						)
						(arc
							(start -0.2032 -0.3048)
							(mid -0.275042 -0.275042)
							(end -0.3048 -0.2032)
						)
						(arc
							(start -0.3048 0.2032)
							(mid -0.275042 0.275042)
							(end -0.2032 0.3048)
						)
						(arc
							(start 0.2032 0.3048)
							(mid 0.275042 0.275042)
							(end 0.3048 0.2032)
						)
					)
					(width 0)
					(fill yes)
				)
			)
		)
	)
	(footprint ""
		(layer "F.Cu")
		(at 270.599916 -17.500092 90)
		(property "Reference" "LED22"
			(at 0 0 90)
			(layer "F.SilkS")
			(hide yes)
			(effects
				(font
					(size 1.27 1.27)
				)
			)
		)
		(property "Value" "LED-YG-51-GP"
			(at -2.6924 -1.4224 90)
			(unlocked yes)
			(layer "F.Fab")
			(hide yes)
			(effects
				(font
					(size 1.016 1.016)
					(thickness 0.1524)
				)
			)
		)
		(property "Device Type" "LED1608AKH40"
			(at -2.6924 -2.9464 90)
			(unlocked yes)
			(layer "F.Fab")
			(hide yes)
			(effects
				(font
					(size 1.016 1.016)
					(thickness 0.1524)
				)
			)
		)
		(duplicate_pad_numbers_are_jumpers no)
		(fp_line
			(start 0.6604 -1.3716)
			(end 0.6604 1.3716)
			(stroke
				(width 0.1524)
				(type default)
			)
			(layer "F.SilkS")
		)
		(fp_line
			(start -0.6604 -1.3716)
			(end 0.6604 -1.3716)
			(stroke
				(width 0.1524)
				(type default)
			)
			(layer "F.SilkS")
		)
		(fp_line
			(start 0.6604 1.3716)
			(end -0.6604 1.3716)
			(stroke
				(width 0.1524)
				(type default)
			)
			(layer "F.SilkS")
		)
		(fp_line
			(start -0.6604 1.3716)
			(end -0.6604 -1.3716)
			(stroke
				(width 0.1524)
				(type default)
			)
			(layer "F.SilkS")
		)
		(fp_line
			(start -0.5969 1.5494)
			(end 0.5842 1.5494)
			(stroke
				(width 0.508)
				(type default)
			)
			(layer "F.SilkS")
		)
		(fp_line
			(start 0.7493 1.651)
			(end 0.7493 1.1811)
			(stroke
				(width 0.3302)
				(type default)
			)
			(layer "F.SilkS")
		)
		(fp_line
			(start -0.7493 1.651)
			(end -0.7493 1.1811)
			(stroke
				(width 0.3302)
				(type default)
			)
			(layer "F.SilkS")
		)
		(fp_rect
			(start -0.6223 1.3335)
			(end 0.6223 -1.3335)
			(stroke
				(width 0)
				(type default)
			)
			(fill no)
			(layer "F.CrtYd")
		)
		(fp_rect
			(start -0.6223 1.3335)
			(end 0.6223 -1.3335)
			(stroke
				(width 0)
				(type default)
			)
			(fill no)
			(layer "F.Fab")
		)
		(pad "A" smd custom
			(at 0 -0.762 90)
			(size 0.2159 0.2159)
			(layers "F.Cu" "F.Mask" "F.Paste")
			(net "LED_R_13")
			(options
				(clearance outline)
				(anchor circle)
			)
			(primitives
				(gr_poly
					(pts
						(arc
							(start -0.3302 -0.4318)
							(mid -0.402042 -0.402042)
							(end -0.4318 -0.3302)
						)
						(arc
							(start -0.4318 0.3302)
							(mid -0.402042 0.402042)
							(end -0.3302 0.4318)
						)
						(arc
							(start 0.3302 0.4318)
							(mid 0.402042 0.402042)
							(end 0.4318 0.3302)
						)
						(arc
							(start 0.4318 -0.3302)
							(mid 0.402042 -0.402042)
							(end 0.3302 -0.4318)
						)
					)
					(width 0)
					(fill yes)
				)
			)
		)
		(pad "K" smd custom
			(at 0 0.762 90)
			(size 0.2159 0.2159)
			(layers "F.Cu" "F.Mask" "F.Paste")
			(net "LED_Q_13")
			(options
				(clearance outline)
				(anchor circle)
			)
			(primitives
				(gr_poly
					(pts
						(arc
							(start -0.3302 -0.4318)
							(mid -0.402042 -0.402042)
							(end -0.4318 -0.3302)
						)
						(arc
							(start -0.4318 0.3302)
							(mid -0.402042 0.402042)
							(end -0.3302 0.4318)
						)
						(arc
							(start 0.3302 0.4318)
							(mid 0.402042 0.402042)
							(end 0.4318 0.3302)
						)
						(arc
							(start 0.4318 -0.3302)
							(mid 0.402042 -0.402042)
							(end 0.3302 -0.4318)
						)
					)
					(width 0)
					(fill yes)
				)
			)
		)
	)
	(footprint ""
		(layer "F.Cu")
		(at 228.732588 -3.801364 180)
		(property "Reference" "C249"
			(at 0 0 180)
			(layer "F.SilkS")
			(hide yes)
			(effects
				(font
					(size 1.27 1.27)
				)
			)
		)
		(property "Value" "SCD1U16V2KX-3GP"
			(at 1.1811 -2.7051 180)
			(unlocked yes)
			(layer "F.Fab")
			(hide yes)
			(effects
				(font
					(size 1.016 1.016)
					(thickness 0.1524)
				)
			)
		)
		(property "Device Type" "C402H22"
			(at 1.1811 -4.2291 180)
			(unlocked yes)
			(layer "F.Fab")
			(hide yes)
			(effects
				(font
					(size 1.016 1.016)
					(thickness 0.1524)
				)
			)
		)
		(duplicate_pad_numbers_are_jumpers no)
		(fp_rect
			(start -0.4318 0.9525)
			(end 0.4318 -0.9525)
			(stroke
				(width 0)
				(type default)
			)
			(fill no)
			(layer "F.CrtYd")
		)
		(fp_rect
			(start -0.4318 0.9525)
			(end 0.4318 -0.9525)
			(stroke
				(width 0)
				(type default)
			)
			(fill no)
			(layer "F.Fab")
		)
		(pad "1" smd custom
			(at 0 -0.4445 180)
			(size 0.1524 0.1524)
			(layers "F.Cu" "F.Mask" "F.Paste")
			(net "P5V_STBY")
			(options
				(clearance outline)
				(anchor circle)
			)
			(primitives
				(gr_poly
					(pts
						(arc
							(start 0.3048 -0.2032)
							(mid 0.275042 -0.275042)
							(end 0.2032 -0.3048)
						)
						(arc
							(start -0.2032 -0.3048)
							(mid -0.275042 -0.275042)
							(end -0.3048 -0.2032)
						)
						(arc
							(start -0.3048 0.2032)
							(mid -0.275042 0.275042)
							(end -0.2032 0.3048)
						)
						(arc
							(start 0.2032 0.3048)
							(mid 0.275042 0.275042)
							(end 0.3048 0.2032)
						)
					)
					(width 0)
					(fill yes)
				)
			)
		)
		(pad "2" smd custom
			(at 0 0.4445 180)
			(size 0.1524 0.1524)
			(layers "F.Cu" "F.Mask" "F.Paste")
			(net "GND")
			(options
				(clearance outline)
				(anchor circle)
			)
			(primitives
				(gr_poly
					(pts
						(arc
							(start 0.3048 -0.2032)
							(mid 0.275042 -0.275042)
							(end 0.2032 -0.3048)
						)
						(arc
							(start -0.2032 -0.3048)
							(mid -0.275042 -0.275042)
							(end -0.3048 -0.2032)
						)
						(arc
							(start -0.3048 0.2032)
							(mid -0.275042 0.275042)
							(end -0.2032 0.3048)
						)
						(arc
							(start 0.2032 0.3048)
							(mid 0.275042 0.275042)
							(end 0.3048 0.2032)
						)
					)
					(width 0)
					(fill yes)
				)
			)
		)
	)
	(footprint ""
		(layer "F.Cu")
		(at 336.608166 -212.420454 180)
		(property "Reference" "C59"
			(at 0 0 180)
			(layer "F.SilkS")
			(hide yes)
			(effects
				(font
					(size 1.27 1.27)
				)
			)
		)
		(property "Value" "SCD22U10V2KX-1GP"
			(at 1.1811 -2.7051 180)
			(unlocked yes)
			(layer "F.Fab")
			(hide yes)
			(effects
				(font
					(size 1.016 1.016)
					(thickness 0.1524)
				)
			)
		)
		(property "Device Type" "C402H22"
			(at 1.1811 -4.2291 180)
			(unlocked yes)
			(layer "F.Fab")
			(hide yes)
			(effects
				(font
					(size 1.016 1.016)
					(thickness 0.1524)
				)
			)
		)
		(duplicate_pad_numbers_are_jumpers no)
		(fp_rect
			(start -0.4318 0.9525)
			(end 0.4318 -0.9525)
			(stroke
				(width 0)
				(type default)
			)
			(fill no)
			(layer "F.CrtYd")
		)
		(fp_rect
			(start -0.4318 0.9525)
			(end 0.4318 -0.9525)
			(stroke
				(width 0)
				(type default)
			)
			(fill no)
			(layer "F.Fab")
		)
		(pad "1" smd custom
			(at 0 -0.4445 180)
			(size 0.1524 0.1524)
			(layers "F.Cu" "F.Mask" "F.Paste")
			(net "PCIE_TX_CAP_N18")
			(options
				(clearance outline)
				(anchor circle)
			)
			(primitives
				(gr_poly
					(pts
						(arc
							(start 0.3048 -0.2032)
							(mid 0.275042 -0.275042)
							(end 0.2032 -0.3048)
						)
						(arc
							(start -0.2032 -0.3048)
							(mid -0.275042 -0.275042)
							(end -0.3048 -0.2032)
						)
						(arc
							(start -0.3048 0.2032)
							(mid -0.275042 0.275042)
							(end -0.2032 0.3048)
						)
						(arc
							(start 0.2032 0.3048)
							(mid 0.275042 0.275042)
							(end 0.3048 0.2032)
						)
					)
					(width 0)
					(fill yes)
				)
			)
		)
		(pad "2" smd custom
			(at 0 0.4445 180)
			(size 0.1524 0.1524)
			(layers "F.Cu" "F.Mask" "F.Paste")
			(net "PCIE_TX_N18")
			(options
				(clearance outline)
				(anchor circle)
			)
			(primitives
				(gr_poly
					(pts
						(arc
							(start 0.3048 -0.2032)
							(mid 0.275042 -0.275042)
							(end 0.2032 -0.3048)
						)
						(arc
							(start -0.2032 -0.3048)
							(mid -0.275042 -0.275042)
							(end -0.3048 -0.2032)
						)
						(arc
							(start -0.3048 0.2032)
							(mid -0.275042 0.275042)
							(end -0.2032 0.3048)
						)
						(arc
							(start 0.2032 0.3048)
							(mid 0.275042 0.275042)
							(end 0.3048 0.2032)
						)
					)
					(width 0)
					(fill yes)
				)
			)
		)
	)
	(footprint ""
		(layer "F.Cu")
		(at 57.4548 -145.837148)
		(property "Reference" "R418"
			(at 0 0 0)
			(layer "F.SilkS")
			(hide yes)
			(effects
				(font
					(size 1.27 1.27)
				)
			)
		)
		(property "Value" "10KR2F-2-GP"
			(at 0.064008 -3.993896 0)
			(unlocked yes)
			(layer "F.Fab")
			(hide yes)
			(effects
				(font
					(size 1.016 1.016)
					(thickness 0.1524)
				)
			)
		)
		(property "Device Type" "R402H16"
			(at 0.064008 -5.517896 0)
			(unlocked yes)
			(layer "F.Fab")
			(hide yes)
			(effects
				(font
					(size 1.016 1.016)
					(thickness 0.1524)
				)
			)
		)
		(duplicate_pad_numbers_are_jumpers no)
		(fp_line
			(start -0.508 -0.9398)
			(end -0.508 0.9398)
			(stroke
				(width 0.1524)
				(type default)
			)
			(layer "F.SilkS")
		)
		(fp_line
			(start 0.508 -0.9398)
			(end -0.508 -0.9398)
			(stroke
				(width 0.1524)
				(type default)
			)
			(layer "F.SilkS")
		)
		(fp_rect
			(start -0.508 0.9398)
			(end 0.508 -0.9398)
			(stroke
				(width 0)
				(type default)
			)
			(fill no)
			(layer "F.CrtYd")
		)
		(fp_rect
			(start -0.508 0.9398)
			(end 0.508 -0.9398)
			(stroke
				(width 0)
				(type default)
			)
			(fill no)
			(layer "F.Fab")
		)
		(pad "1" smd custom
			(at 0 -0.4445)
			(size 0.1397 0.1397)
			(layers "F.Cu" "F.Mask" "F.Paste")
			(net "P3V3_STBY")
			(options
				(clearance outline)
				(anchor circle)
			)
			(primitives
				(gr_poly
					(pts
						(arc
							(start -0.1778 -0.2794)
							(mid -0.249642 -0.249642)
							(end -0.2794 -0.1778)
						)
						(arc
							(start -0.2794 0.1778)
							(mid -0.249642 0.249642)
							(end -0.1778 0.2794)
						)
						(arc
							(start 0.1778 0.2794)
							(mid 0.249642 0.249642)
							(end 0.2794 0.1778)
						)
						(arc
							(start 0.2794 -0.1778)
							(mid 0.249642 -0.249642)
							(end 0.1778 -0.2794)
						)
					)
					(width 0)
					(fill yes)
				)
			)
		)
		(pad "2" smd custom
			(at 0 0.4445)
			(size 0.1397 0.1397)
			(layers "F.Cu" "F.Mask" "F.Paste")
			(net "BMC_I210_PERST_N")
			(options
				(clearance outline)
				(anchor circle)
			)
			(primitives
				(gr_poly
					(pts
						(arc
							(start -0.1778 -0.2794)
							(mid -0.249642 -0.249642)
							(end -0.2794 -0.1778)
						)
						(arc
							(start -0.2794 0.1778)
							(mid -0.249642 0.249642)
							(end -0.1778 0.2794)
						)
						(arc
							(start 0.1778 0.2794)
							(mid 0.249642 0.249642)
							(end 0.2794 0.1778)
						)
						(arc
							(start 0.2794 -0.1778)
							(mid 0.249642 -0.249642)
							(end 0.1778 -0.2794)
						)
					)
					(width 0)
					(fill yes)
				)
			)
		)
	)
	(footprint ""
		(layer "F.Cu")
		(at 13.8684 -82.1436 180)
		(property "Reference" "C638"
			(at 0 0 180)
			(layer "F.SilkS")
			(hide yes)
			(effects
				(font
					(size 1.27 1.27)
				)
			)
		)
		(property "Value" "SCD1U16V2KX-3GP"
			(at 1.1811 -2.7051 180)
			(unlocked yes)
			(layer "F.Fab")
			(hide yes)
			(effects
				(font
					(size 1.016 1.016)
					(thickness 0.1524)
				)
			)
		)
		(property "Device Type" "C402H22"
			(at 1.1811 -4.2291 180)
			(unlocked yes)
			(layer "F.Fab")
			(hide yes)
			(effects
				(font
					(size 1.016 1.016)
					(thickness 0.1524)
				)
			)
		)
		(duplicate_pad_numbers_are_jumpers no)
		(fp_rect
			(start -0.4318 0.9525)
			(end 0.4318 -0.9525)
			(stroke
				(width 0)
				(type default)
			)
			(fill no)
			(layer "F.CrtYd")
		)
		(fp_rect
			(start -0.4318 0.9525)
			(end 0.4318 -0.9525)
			(stroke
				(width 0)
				(type default)
			)
			(fill no)
			(layer "F.Fab")
		)
		(pad "1" smd custom
			(at 0 -0.4445 180)
			(size 0.1524 0.1524)
			(layers "F.Cu" "F.Mask" "F.Paste")
			(net "P0V9_I210")
			(options
				(clearance outline)
				(anchor circle)
			)
			(primitives
				(gr_poly
					(pts
						(arc
							(start 0.3048 -0.2032)
							(mid 0.275042 -0.275042)
							(end 0.2032 -0.3048)
						)
						(arc
							(start -0.2032 -0.3048)
							(mid -0.275042 -0.275042)
							(end -0.3048 -0.2032)
						)
						(arc
							(start -0.3048 0.2032)
							(mid -0.275042 0.275042)
							(end -0.2032 0.3048)
						)
						(arc
							(start 0.2032 0.3048)
							(mid 0.275042 0.275042)
							(end 0.3048 0.2032)
						)
					)
					(width 0)
					(fill yes)
				)
			)
		)
		(pad "2" smd custom
			(at 0 0.4445 180)
			(size 0.1524 0.1524)
			(layers "F.Cu" "F.Mask" "F.Paste")
			(net "GND")
			(options
				(clearance outline)
				(anchor circle)
			)
			(primitives
				(gr_poly
					(pts
						(arc
							(start 0.3048 -0.2032)
							(mid 0.275042 -0.275042)
							(end 0.2032 -0.3048)
						)
						(arc
							(start -0.2032 -0.3048)
							(mid -0.275042 -0.275042)
							(end -0.3048 -0.2032)
						)
						(arc
							(start -0.3048 0.2032)
							(mid -0.275042 0.275042)
							(end -0.2032 0.3048)
						)
						(arc
							(start 0.2032 0.3048)
							(mid 0.275042 0.275042)
							(end 0.3048 0.2032)
						)
					)
					(width 0)
					(fill yes)
				)
			)
		)
	)
	(footprint ""
		(layer "F.Cu")
		(at 125.3998 -95.0722 180)
		(property "Reference" "R428"
			(at 0 0 180)
			(layer "F.SilkS")
			(hide yes)
			(effects
				(font
					(size 1.27 1.27)
				)
			)
		)
		(property "Value" "10KR2F-2-GP"
			(at 0.064008 -3.993896 180)
			(unlocked yes)
			(layer "F.Fab")
			(hide yes)
			(effects
				(font
					(size 1.016 1.016)
					(thickness 0.1524)
				)
			)
		)
		(property "Device Type" "R402H16"
			(at 0.064008 -5.517896 180)
			(unlocked yes)
			(layer "F.Fab")
			(hide yes)
			(effects
				(font
					(size 1.016 1.016)
					(thickness 0.1524)
				)
			)
		)
		(duplicate_pad_numbers_are_jumpers no)
		(fp_line
			(start 0.508 -0.9398)
			(end -0.508 -0.9398)
			(stroke
				(width 0.1524)
				(type default)
			)
			(layer "F.SilkS")
		)
		(fp_line
			(start -0.508 -0.9398)
			(end -0.508 0.9398)
			(stroke
				(width 0.1524)
				(type default)
			)
			(layer "F.SilkS")
		)
		(fp_rect
			(start -0.508 0.9398)
			(end 0.508 -0.9398)
			(stroke
				(width 0)
				(type default)
			)
			(fill no)
			(layer "F.CrtYd")
		)
		(fp_rect
			(start -0.508 0.9398)
			(end 0.508 -0.9398)
			(stroke
				(width 0)
				(type default)
			)
			(fill no)
			(layer "F.Fab")
		)
		(pad "1" smd custom
			(at 0 -0.4445 180)
			(size 0.1397 0.1397)
			(layers "F.Cu" "F.Mask" "F.Paste")
			(net "P3V3_STBY")
			(options
				(clearance outline)
				(anchor circle)
			)
			(primitives
				(gr_poly
					(pts
						(arc
							(start -0.1778 -0.2794)
							(mid -0.249642 -0.249642)
							(end -0.2794 -0.1778)
						)
						(arc
							(start -0.2794 0.1778)
							(mid -0.249642 0.249642)
							(end -0.1778 0.2794)
						)
						(arc
							(start 0.1778 0.2794)
							(mid 0.249642 0.249642)
							(end 0.2794 0.1778)
						)
						(arc
							(start 0.2794 -0.1778)
							(mid 0.249642 -0.249642)
							(end 0.1778 -0.2794)
						)
					)
					(width 0)
					(fill yes)
				)
			)
		)
		(pad "2" smd custom
			(at 0 0.4445 180)
			(size 0.1397 0.1397)
			(layers "F.Cu" "F.Mask" "F.Paste")
			(net "I2C10_BUFF_EN")
			(options
				(clearance outline)
				(anchor circle)
			)
			(primitives
				(gr_poly
					(pts
						(arc
							(start -0.1778 -0.2794)
							(mid -0.249642 -0.249642)
							(end -0.2794 -0.1778)
						)
						(arc
							(start -0.2794 0.1778)
							(mid -0.249642 0.249642)
							(end -0.1778 0.2794)
						)
						(arc
							(start 0.1778 0.2794)
							(mid 0.249642 0.249642)
							(end 0.2794 0.1778)
						)
						(arc
							(start 0.2794 -0.1778)
							(mid 0.249642 -0.249642)
							(end 0.1778 -0.2794)
						)
					)
					(width 0)
					(fill yes)
				)
			)
		)
	)
	(footprint ""
		(layer "F.Cu")
		(at 88.9 -43.1546)
		(property "Reference" "PG7"
			(at 0 0 0)
			(layer "F.SilkS")
			(hide yes)
			(effects
				(font
					(size 1.27 1.27)
				)
			)
		)
		(property "Value" "GAP-CLOSE-PWR-3-GP"
			(at 0.0254 -6.5786 0)
			(unlocked yes)
			(layer "F.Fab")
			(hide yes)
			(effects
				(font
					(size 1.016 1.016)
					(thickness 0.1524)
				)
			)
		)
		(property "Device Type" "GAP-CLOSE-PWR-3"
			(at 0.0254 -8.255 0)
			(unlocked yes)
			(layer "F.Fab")
			(hide yes)
			(effects
				(font
					(size 1.016 1.016)
					(thickness 0.1524)
				)
			)
		)
		(duplicate_pad_numbers_are_jumpers no)
		(fp_rect
			(start -0.7112 0.4572)
			(end 0.7112 -0.4572)
			(stroke
				(width 0)
				(type default)
			)
			(fill no)
			(layer "F.CrtYd")
		)
		(fp_poly
			(pts
				(xy -0.7112 -0.4572) (xy 0.7112 -0.4572) (xy 0.7112 0.4572) (xy -0.7112 0.4572)
			)
			(stroke
				(width 0)
				(type default)
			)
			(fill no)
			(layer "F.Fab")
		)
		(pad "1" smd rect
			(at -0.3048 0)
			(size 0.6604 0.762)
			(layers "F.Cu" "F.Mask" "F.Paste")
			(net "P3V3_PWR")
		)
		(pad "2" smd rect
			(at 0.3048 0)
			(size 0.6604 0.762)
			(layers "F.Cu" "F.Mask" "F.Paste")
			(net "P3V3_STBY")
		)
	)
	(footprint ""
		(layer "F.Cu")
		(at 200.060052 -30.607 -90)
		(property "Reference" "U55"
			(at 0 0 270)
			(layer "F.SilkS")
			(hide yes)
			(effects
				(font
					(size 1.27 1.27)
				)
			)
		)
		(property "Value" "TCA9554PWR-GP"
			(at 0.127 -12.573 270)
			(unlocked yes)
			(layer "F.Fab")
			(hide yes)
			(effects
				(font
					(size 1.016 1.016)
					(thickness 0.1524)
				)
			)
		)
		(property "Device Type" "TSOIC16H48"
			(at 0.1016 -14.5796 270)
			(unlocked yes)
			(layer "F.Fab")
			(hide yes)
			(effects
				(font
					(size 1.016 1.016)
					(thickness 0.1524)
				)
			)
		)
		(duplicate_pad_numbers_are_jumpers no)
		(fp_line
			(start -2.921 3.81)
			(end -2.921 1.778)
			(stroke
				(width 0.508)
				(type default)
			)
			(layer "F.SilkS")
		)
		(fp_line
			(start 2.3622 1.778)
			(end -2.921 1.778)
			(stroke
				(width 0.1524)
				(type default)
			)
			(layer "F.SilkS")
		)
		(fp_line
			(start -2.54 0)
			(end -3.0988 0.5588)
			(stroke
				(width 0.1524)
				(type default)
			)
			(layer "F.SilkS")
		)
		(fp_line
			(start -2.54 0)
			(end -3.0988 -0.5588)
			(stroke
				(width 0.1524)
				(type default)
			)
			(layer "F.SilkS")
		)
		(fp_line
			(start -3.0988 -1.778)
			(end -3.0988 1.778)
			(stroke
				(width 0.1524)
				(type default)
			)
			(layer "F.SilkS")
		)
		(fp_line
			(start -3.0988 -1.778)
			(end 2.3622 -1.778)
			(stroke
				(width 0.1524)
				(type default)
			)
			(layer "F.SilkS")
		)
		(fp_line
			(start 2.3622 -1.778)
			(end 2.3622 1.778)
			(stroke
				(width 0.1524)
				(type default)
			)
			(layer "F.SilkS")
		)
		(fp_poly
			(pts
				(xy -2.4638 -1.778) (xy -2.4638 1.778) (xy 2.3622 1.778) (xy 2.3622 -1.778)
			)
			(stroke
				(width 0)
				(type default)
			)
			(fill yes)
			(layer "F.SilkS")
		)
		(fp_rect
			(start -3.175 4.064)
			(end 3.175 -4.064)
			(stroke
				(width 0)
				(type default)
			)
			(fill no)
			(layer "F.CrtYd")
		)
		(fp_poly
			(pts
				(xy -3.175 -4.064) (xy 3.175 -4.064) (xy 3.175 4.064) (xy -3.175 4.064)
			)
			(stroke
				(width 0)
				(type default)
			)
			(fill no)
			(layer "F.Fab")
		)
		(pad "1" smd rect
			(at -2.27584 2.8194 270)
			(size 0.3556 1.524)
			(layers "F.Cu" "F.Mask" "F.Paste")
			(net "U55_A0")
		)
		(pad "2" smd rect
			(at -1.6256 2.8194 270)
			(size 0.3556 1.524)
			(layers "F.Cu" "F.Mask" "F.Paste")
			(net "U55_A1")
		)
		(pad "3" smd rect
			(at -0.97536 2.8194 270)
			(size 0.3556 1.524)
			(layers "F.Cu" "F.Mask" "F.Paste")
			(net "U55_A2")
		)
		(pad "4" smd rect
			(at -0.32512 2.8194 270)
			(size 0.3556 1.524)
			(layers "F.Cu" "F.Mask" "F.Paste")
			(net "U55_P0")
		)
		(pad "5" smd rect
			(at 0.32512 2.8194 270)
			(size 0.3556 1.524)
			(layers "F.Cu" "F.Mask" "F.Paste")
			(net "Net_41")
		)
		(pad "6" smd rect
			(at 0.97536 2.8194 270)
			(size 0.3556 1.524)
			(layers "F.Cu" "F.Mask" "F.Paste")
			(net "Net_42")
		)
		(pad "7" smd rect
			(at 1.6256 2.8194 270)
			(size 0.3556 1.524)
			(layers "F.Cu" "F.Mask" "F.Paste")
			(net "Net_43")
		)
		(pad "8" smd rect
			(at 2.27584 2.8194 270)
			(size 0.3556 1.524)
			(layers "F.Cu" "F.Mask" "F.Paste")
			(net "GND")
		)
		(pad "9" smd rect
			(at 2.27584 -2.8194 270)
			(size 0.3556 1.524)
			(layers "F.Cu" "F.Mask" "F.Paste")
			(net "Net_44")
		)
		(pad "10" smd rect
			(at 1.6256 -2.8194 270)
			(size 0.3556 1.524)
			(layers "F.Cu" "F.Mask" "F.Paste")
			(net "Net_65")
		)
		(pad "11" smd rect
			(at 0.97536 -2.8194 270)
			(size 0.3556 1.524)
			(layers "F.Cu" "F.Mask" "F.Paste")
			(net "Net_66")
		)
		(pad "12" smd rect
			(at 0.32512 -2.8194 270)
			(size 0.3556 1.524)
			(layers "F.Cu" "F.Mask" "F.Paste")
			(net "Net_67")
		)
		(pad "13" smd rect
			(at -0.32512 -2.8194 270)
			(size 0.3556 1.524)
			(layers "F.Cu" "F.Mask" "F.Paste")
			(net "U55_INT_N")
		)
		(pad "14" smd rect
			(at -0.97536 -2.8194 270)
			(size 0.3556 1.524)
			(layers "F.Cu" "F.Mask" "F.Paste")
			(net "U55_SCL")
		)
		(pad "15" smd rect
			(at -1.6256 -2.8194 270)
			(size 0.3556 1.524)
			(layers "F.Cu" "F.Mask" "F.Paste")
			(net "U55_SDA")
		)
		(pad "16" smd rect
			(at -2.27584 -2.8194 270)
			(size 0.3556 1.524)
			(layers "F.Cu" "F.Mask" "F.Paste")
			(net "P3V3_STBY")
		)
	)
	(footprint ""
		(layer "F.Cu")
		(at 21.00326 -99.73691 90)
		(property "Reference" "R2947"
			(at 0 0 90)
			(layer "F.SilkS")
			(hide yes)
			(effects
				(font
					(size 1.27 1.27)
				)
			)
		)
		(property "Value" "10KR2F-2-GP"
			(at 0.064008 -3.993896 90)
			(unlocked yes)
			(layer "F.Fab")
			(hide yes)
			(effects
				(font
					(size 1.016 1.016)
					(thickness 0.1524)
				)
			)
		)
		(property "Device Type" "R402H16"
			(at 0.064008 -5.517896 90)
			(unlocked yes)
			(layer "F.Fab")
			(hide yes)
			(effects
				(font
					(size 1.016 1.016)
					(thickness 0.1524)
				)
			)
		)
		(duplicate_pad_numbers_are_jumpers no)
		(fp_line
			(start 0.508 -0.9398)
			(end -0.508 -0.9398)
			(stroke
				(width 0.1524)
				(type default)
			)
			(layer "F.SilkS")
		)
		(fp_line
			(start -0.508 -0.9398)
			(end -0.508 0.9398)
			(stroke
				(width 0.1524)
				(type default)
			)
			(layer "F.SilkS")
		)
		(fp_rect
			(start -0.508 0.9398)
			(end 0.508 -0.9398)
			(stroke
				(width 0)
				(type default)
			)
			(fill no)
			(layer "F.CrtYd")
		)
		(fp_rect
			(start -0.508 0.9398)
			(end 0.508 -0.9398)
			(stroke
				(width 0)
				(type default)
			)
			(fill no)
			(layer "F.Fab")
		)
		(pad "1" smd custom
			(at 0 -0.4445 90)
			(size 0.1397 0.1397)
			(layers "F.Cu" "F.Mask" "F.Paste")
			(net "P3V3_STBY")
			(options
				(clearance outline)
				(anchor circle)
			)
			(primitives
				(gr_poly
					(pts
						(arc
							(start -0.1778 -0.2794)
							(mid -0.249642 -0.249642)
							(end -0.2794 -0.1778)
						)
						(arc
							(start -0.2794 0.1778)
							(mid -0.249642 0.249642)
							(end -0.1778 0.2794)
						)
						(arc
							(start 0.1778 0.2794)
							(mid 0.249642 0.249642)
							(end 0.2794 0.1778)
						)
						(arc
							(start 0.2794 -0.1778)
							(mid 0.249642 -0.249642)
							(end 0.1778 -0.2794)
						)
					)
					(width 0)
					(fill yes)
				)
			)
		)
		(pad "2" smd custom
			(at 0 0.4445 90)
			(size 0.1397 0.1397)
			(layers "F.Cu" "F.Mask" "F.Paste")
			(net "FM_TPM_PRES_N")
			(options
				(clearance outline)
				(anchor circle)
			)
			(primitives
				(gr_poly
					(pts
						(arc
							(start -0.1778 -0.2794)
							(mid -0.249642 -0.249642)
							(end -0.2794 -0.1778)
						)
						(arc
							(start -0.2794 0.1778)
							(mid -0.249642 0.249642)
							(end -0.1778 0.2794)
						)
						(arc
							(start 0.1778 0.2794)
							(mid 0.249642 0.249642)
							(end 0.2794 0.1778)
						)
						(arc
							(start 0.2794 -0.1778)
							(mid 0.249642 -0.249642)
							(end 0.1778 -0.2794)
						)
					)
					(width 0)
					(fill yes)
				)
			)
		)
	)
	(footprint ""
		(layer "F.Cu")
		(at 142.374874 -90.95232)
		(property "Reference" "PU6"
			(at 0 0 0)
			(layer "F.SilkS")
			(hide yes)
			(effects
				(font
					(size 1.27 1.27)
				)
			)
		)
		(property "Value" "TPS74801DRCR-1-GP-U"
			(at -3.5306 1.3208 0)
			(unlocked yes)
			(layer "F.Fab")
			(hide yes)
			(effects
				(font
					(size 1.016 1.016)
					(thickness 0.1524)
				)
			)
		)
		(property "Device Type" "DFN10G3-G315175H40"
			(at -3.5306 -0.2032 0)
			(unlocked yes)
			(layer "F.Fab")
			(hide yes)
			(effects
				(font
					(size 1.016 1.016)
					(thickness 0.1524)
				)
			)
		)
		(duplicate_pad_numbers_are_jumpers no)
		(fp_line
			(start -2.3876 -2.5146)
			(end -2.3876 -1.7526)
			(stroke
				(width 0.1524)
				(type default)
			)
			(layer "F.SilkS")
		)
		(fp_line
			(start -2.3876 1.7526)
			(end -2.3876 2.5146)
			(stroke
				(width 0.1524)
				(type default)
			)
			(layer "F.SilkS")
		)
		(fp_line
			(start -2.3876 2.5146)
			(end -1.6256 2.5146)
			(stroke
				(width 0.1524)
				(type default)
			)
			(layer "F.SilkS")
		)
		(fp_line
			(start -1.6256 -2.5146)
			(end -2.3876 -2.5146)
			(stroke
				(width 0.1524)
				(type default)
			)
			(layer "F.SilkS")
		)
		(fp_line
			(start -0.9906 -2.794)
			(end -0.9906 -2.286)
			(stroke
				(width 0.1524)
				(type default)
			)
			(layer "F.SilkS")
		)
		(fp_line
			(start 0.9906 2.286)
			(end 0.9906 3.048)
			(stroke
				(width 0.1524)
				(type default)
			)
			(layer "F.SilkS")
		)
		(fp_line
			(start 1.6256 2.5146)
			(end 2.3876 2.5146)
			(stroke
				(width 0.1524)
				(type default)
			)
			(layer "F.SilkS")
		)
		(fp_line
			(start 2.3876 2.5146)
			(end 2.3876 1.7526)
			(stroke
				(width 0.1524)
				(type default)
			)
			(layer "F.SilkS")
		)
		(fp_poly
			(pts
				(xy 1.6256 -2.5146) (xy 2.3876 -2.5146) (xy 2.3876 -1.7526)
			)
			(stroke
				(width 0)
				(type default)
			)
			(fill yes)
			(layer "F.SilkS")
		)
		(fp_rect
			(start -1.4986 1.4986)
			(end 1.4986 -1.4986)
			(stroke
				(width 0)
				(type default)
			)
			(fill no)
			(layer "F.CrtYd")
		)
		(fp_poly
			(pts
				(xy -2.3876 2.5146) (xy -2.3876 0.00254) (xy -1.4986 0.00254) (xy -1.4986 1.4986) (xy 1.4986 1.4986)
				(xy 1.4986 -1.4986) (xy -1.4986 -1.4986) (xy -1.4986 -0.00254) (xy -2.3876 -0.00254) (xy -2.3876 -2.5146)
				(xy 2.3876 -2.5146) (xy 2.3876 2.5146)
			)
			(stroke
				(width 0)
				(type default)
			)
			(fill no)
			(layer "F.CrtYd")
		)
		(fp_rect
			(start -2.3876 2.5146)
			(end 2.3876 -2.5146)
			(stroke
				(width 0)
				(type default)
			)
			(fill no)
			(layer "F.Fab")
		)
		(pad "1" smd rect
			(at 0.99949 -1.5494)
			(size 0.3048 0.9144)
			(layers "F.Cu" "F.Mask" "F.Paste")
			(net "VR_P1V8_STBY_IN")
		)
		(pad "2" smd rect
			(at 0.50038 -1.5494)
			(size 0.3048 0.9144)
			(layers "F.Cu" "F.Mask" "F.Paste")
			(net "VR_P1V8_STBY_IN")
		)
		(pad "3" smd rect
			(at 0 -1.5494)
			(size 0.3048 0.9144)
			(layers "F.Cu" "F.Mask" "F.Paste")
			(net "PWRGD_P1V8_STBY")
		)
		(pad "4" smd rect
			(at -0.50038 -1.5494)
			(size 0.3048 0.9144)
			(layers "F.Cu" "F.Mask" "F.Paste")
			(net "VR_P1V8_STBY_BIAS")
		)
		(pad "5" smd rect
			(at -0.99949 -1.5494)
			(size 0.3048 0.9144)
			(layers "F.Cu" "F.Mask" "F.Paste")
			(net "VR_P1V8_STBY_EN_R")
		)
		(pad "6" smd rect
			(at -0.99949 1.5494)
			(size 0.3048 0.9144)
			(layers "F.Cu" "F.Mask" "F.Paste")
			(net "GND")
		)
		(pad "7" smd rect
			(at -0.50038 1.5494)
			(size 0.3048 0.9144)
			(layers "F.Cu" "F.Mask" "F.Paste")
			(net "VR_P1V8_STBY_SS_C")
		)
		(pad "8" smd rect
			(at 0 1.5494)
			(size 0.3048 0.9144)
			(layers "F.Cu" "F.Mask" "F.Paste")
			(net "VR_P1V8_STBY_FB")
		)
		(pad "9" smd rect
			(at 0.50038 1.5494)
			(size 0.3048 0.9144)
			(layers "F.Cu" "F.Mask" "F.Paste")
			(net "P1V8_PWR")
		)
		(pad "10" smd rect
			(at 0.99949 1.5494)
			(size 0.3048 0.9144)
			(layers "F.Cu" "F.Mask" "F.Paste")
			(net "P1V8_PWR")
		)
		(pad "11" smd custom
			(at 0 0)
			(size 0.4318 0.4318)
			(layers "F.Cu" "F.Mask" "F.Paste")
			(net "GND")
			(options
				(clearance outline)
				(anchor circle)
			)
			(primitives
				(gr_poly
					(pts
						(xy -1.2446 0.8636) (xy -1.2446 0.3937) (xy -1.8796 0.3937) (xy -1.8796 0.1143) (xy -1.2446 0.1143)
						(xy -1.2446 -0.1143) (xy -1.8796 -0.1143) (xy -1.8796 -0.3937) (xy -1.2446 -0.3937) (xy -1.2446 -0.8636)
						(xy 1.2446 -0.8636) (xy 1.2446 -0.3937) (xy 1.8796 -0.3937) (xy 1.8796 -0.1143) (xy 1.2446 -0.1143)
						(xy 1.2446 0.1143) (xy 1.8796 0.1143) (xy 1.8796 0.3937) (xy 1.2446 0.3937) (xy 1.2446 0.8636)
					)
					(width 0)
					(fill yes)
				)
			)
		)
	)
	(footprint ""
		(layer "F.Cu")
		(at 131.470146 -59.750198 180)
		(property "Reference" "R616"
			(at 0 0 180)
			(layer "F.SilkS")
			(hide yes)
			(effects
				(font
					(size 1.27 1.27)
				)
			)
		)
		(property "Value" "100KR2F-L1-GP"
			(at 0.064008 -3.993896 180)
			(unlocked yes)
			(layer "F.Fab")
			(hide yes)
			(effects
				(font
					(size 1.016 1.016)
					(thickness 0.1524)
				)
			)
		)
		(property "Device Type" "R402H16"
			(at 0.064008 -5.517896 180)
			(unlocked yes)
			(layer "F.Fab")
			(hide yes)
			(effects
				(font
					(size 1.016 1.016)
					(thickness 0.1524)
				)
			)
		)
		(duplicate_pad_numbers_are_jumpers no)
		(fp_line
			(start 0.508 -0.9398)
			(end -0.508 -0.9398)
			(stroke
				(width 0.1524)
				(type default)
			)
			(layer "F.SilkS")
		)
		(fp_line
			(start -0.508 -0.9398)
			(end -0.508 0.9398)
			(stroke
				(width 0.1524)
				(type default)
			)
			(layer "F.SilkS")
		)
		(fp_rect
			(start -0.508 0.9398)
			(end 0.508 -0.9398)
			(stroke
				(width 0)
				(type default)
			)
			(fill no)
			(layer "F.CrtYd")
		)
		(fp_rect
			(start -0.508 0.9398)
			(end 0.508 -0.9398)
			(stroke
				(width 0)
				(type default)
			)
			(fill no)
			(layer "F.Fab")
		)
		(pad "1" smd custom
			(at 0 -0.4445 180)
			(size 0.1397 0.1397)
			(layers "F.Cu" "F.Mask" "F.Paste")
			(net "DUT_VDDO")
			(options
				(clearance outline)
				(anchor circle)
			)
			(primitives
				(gr_poly
					(pts
						(arc
							(start -0.1778 -0.2794)
							(mid -0.249642 -0.249642)
							(end -0.2794 -0.1778)
						)
						(arc
							(start -0.2794 0.1778)
							(mid -0.249642 0.249642)
							(end -0.1778 0.2794)
						)
						(arc
							(start 0.1778 0.2794)
							(mid 0.249642 0.249642)
							(end 0.2794 0.1778)
						)
						(arc
							(start 0.2794 -0.1778)
							(mid 0.249642 -0.249642)
							(end 0.1778 -0.2794)
						)
					)
					(width 0)
					(fill yes)
				)
			)
		)
		(pad "2" smd custom
			(at 0 0.4445 180)
			(size 0.1397 0.1397)
			(layers "F.Cu" "F.Mask" "F.Paste")
			(net "SPI_CSB0_0")
			(options
				(clearance outline)
				(anchor circle)
			)
			(primitives
				(gr_poly
					(pts
						(arc
							(start -0.1778 -0.2794)
							(mid -0.249642 -0.249642)
							(end -0.2794 -0.1778)
						)
						(arc
							(start -0.2794 0.1778)
							(mid -0.249642 0.249642)
							(end -0.1778 0.2794)
						)
						(arc
							(start 0.1778 0.2794)
							(mid 0.249642 0.249642)
							(end 0.2794 0.1778)
						)
						(arc
							(start 0.2794 -0.1778)
							(mid 0.249642 -0.249642)
							(end 0.1778 -0.2794)
						)
					)
					(width 0)
					(fill yes)
				)
			)
		)
	)
	(footprint ""
		(layer "F.Cu")
		(at 322.707 -86.487 180)
		(property "Reference" "R559"
			(at 0 0 180)
			(layer "F.SilkS")
			(hide yes)
			(effects
				(font
					(size 1.27 1.27)
				)
			)
		)
		(property "Value" "10KR2F-2-GP"
			(at 0.064008 -3.993896 180)
			(unlocked yes)
			(layer "F.Fab")
			(hide yes)
			(effects
				(font
					(size 1.016 1.016)
					(thickness 0.1524)
				)
			)
		)
		(property "Device Type" "R402H16"
			(at 0.064008 -5.517896 180)
			(unlocked yes)
			(layer "F.Fab")
			(hide yes)
			(effects
				(font
					(size 1.016 1.016)
					(thickness 0.1524)
				)
			)
		)
		(duplicate_pad_numbers_are_jumpers no)
		(fp_line
			(start 0.508 -0.9398)
			(end -0.508 -0.9398)
			(stroke
				(width 0.1524)
				(type default)
			)
			(layer "F.SilkS")
		)
		(fp_line
			(start -0.508 -0.9398)
			(end -0.508 0.9398)
			(stroke
				(width 0.1524)
				(type default)
			)
			(layer "F.SilkS")
		)
		(fp_rect
			(start -0.508 0.9398)
			(end 0.508 -0.9398)
			(stroke
				(width 0)
				(type default)
			)
			(fill no)
			(layer "F.CrtYd")
		)
		(fp_rect
			(start -0.508 0.9398)
			(end 0.508 -0.9398)
			(stroke
				(width 0)
				(type default)
			)
			(fill no)
			(layer "F.Fab")
		)
		(pad "1" smd custom
			(at 0 -0.4445 180)
			(size 0.1397 0.1397)
			(layers "F.Cu" "F.Mask" "F.Paste")
			(net "P3V3_STBY")
			(options
				(clearance outline)
				(anchor circle)
			)
			(primitives
				(gr_poly
					(pts
						(arc
							(start -0.1778 -0.2794)
							(mid -0.249642 -0.249642)
							(end -0.2794 -0.1778)
						)
						(arc
							(start -0.2794 0.1778)
							(mid -0.249642 0.249642)
							(end -0.1778 0.2794)
						)
						(arc
							(start 0.1778 0.2794)
							(mid 0.249642 0.249642)
							(end 0.2794 0.1778)
						)
						(arc
							(start 0.2794 -0.1778)
							(mid 0.249642 -0.249642)
							(end 0.1778 -0.2794)
						)
					)
					(width 0)
					(fill yes)
				)
			)
		)
		(pad "2" smd custom
			(at 0 0.4445 180)
			(size 0.1397 0.1397)
			(layers "F.Cu" "F.Mask" "F.Paste")
			(net "IOEXP_PMC1_AD2")
			(options
				(clearance outline)
				(anchor circle)
			)
			(primitives
				(gr_poly
					(pts
						(arc
							(start -0.1778 -0.2794)
							(mid -0.249642 -0.249642)
							(end -0.2794 -0.1778)
						)
						(arc
							(start -0.2794 0.1778)
							(mid -0.249642 0.249642)
							(end -0.1778 0.2794)
						)
						(arc
							(start 0.1778 0.2794)
							(mid 0.249642 0.249642)
							(end 0.2794 0.1778)
						)
						(arc
							(start 0.2794 -0.1778)
							(mid 0.249642 -0.249642)
							(end 0.1778 -0.2794)
						)
					)
					(width 0)
					(fill yes)
				)
			)
		)
	)
	(footprint ""
		(layer "F.Cu")
		(at 335.592166 -212.420454 180)
		(property "Reference" "C58"
			(at 0 0 180)
			(layer "F.SilkS")
			(hide yes)
			(effects
				(font
					(size 1.27 1.27)
				)
			)
		)
		(property "Value" "SCD22U10V2KX-1GP"
			(at 1.1811 -2.7051 180)
			(unlocked yes)
			(layer "F.Fab")
			(hide yes)
			(effects
				(font
					(size 1.016 1.016)
					(thickness 0.1524)
				)
			)
		)
		(property "Device Type" "C402H22"
			(at 1.1811 -4.2291 180)
			(unlocked yes)
			(layer "F.Fab")
			(hide yes)
			(effects
				(font
					(size 1.016 1.016)
					(thickness 0.1524)
				)
			)
		)
		(duplicate_pad_numbers_are_jumpers no)
		(fp_rect
			(start -0.4318 0.9525)
			(end 0.4318 -0.9525)
			(stroke
				(width 0)
				(type default)
			)
			(fill no)
			(layer "F.CrtYd")
		)
		(fp_rect
			(start -0.4318 0.9525)
			(end 0.4318 -0.9525)
			(stroke
				(width 0)
				(type default)
			)
			(fill no)
			(layer "F.Fab")
		)
		(pad "1" smd custom
			(at 0 -0.4445 180)
			(size 0.1524 0.1524)
			(layers "F.Cu" "F.Mask" "F.Paste")
			(net "PCIE_TX_CAP_P18")
			(options
				(clearance outline)
				(anchor circle)
			)
			(primitives
				(gr_poly
					(pts
						(arc
							(start 0.3048 -0.2032)
							(mid 0.275042 -0.275042)
							(end 0.2032 -0.3048)
						)
						(arc
							(start -0.2032 -0.3048)
							(mid -0.275042 -0.275042)
							(end -0.3048 -0.2032)
						)
						(arc
							(start -0.3048 0.2032)
							(mid -0.275042 0.275042)
							(end -0.2032 0.3048)
						)
						(arc
							(start 0.2032 0.3048)
							(mid 0.275042 0.275042)
							(end 0.3048 0.2032)
						)
					)
					(width 0)
					(fill yes)
				)
			)
		)
		(pad "2" smd custom
			(at 0 0.4445 180)
			(size 0.1524 0.1524)
			(layers "F.Cu" "F.Mask" "F.Paste")
			(net "PCIE_TX_P18")
			(options
				(clearance outline)
				(anchor circle)
			)
			(primitives
				(gr_poly
					(pts
						(arc
							(start 0.3048 -0.2032)
							(mid 0.275042 -0.275042)
							(end 0.2032 -0.3048)
						)
						(arc
							(start -0.2032 -0.3048)
							(mid -0.275042 -0.275042)
							(end -0.3048 -0.2032)
						)
						(arc
							(start -0.3048 0.2032)
							(mid -0.275042 0.275042)
							(end -0.2032 0.3048)
						)
						(arc
							(start 0.2032 0.3048)
							(mid 0.275042 0.275042)
							(end 0.3048 0.2032)
						)
					)
					(width 0)
					(fill yes)
				)
			)
		)
	)
	(footprint ""
		(layer "F.Cu")
		(at 316.983872 -35.859466 90)
		(property "Reference" "R218"
			(at 0 0 90)
			(layer "F.SilkS")
			(hide yes)
			(effects
				(font
					(size 1.27 1.27)
				)
			)
		)
		(property "Value" "4K7R2F-GP"
			(at 0.064008 -3.993896 90)
			(unlocked yes)
			(layer "F.Fab")
			(hide yes)
			(effects
				(font
					(size 1.016 1.016)
					(thickness 0.1524)
				)
			)
		)
		(property "Device Type" "R402H16"
			(at 0.064008 -5.517896 90)
			(unlocked yes)
			(layer "F.Fab")
			(hide yes)
			(effects
				(font
					(size 1.016 1.016)
					(thickness 0.1524)
				)
			)
		)
		(duplicate_pad_numbers_are_jumpers no)
		(fp_line
			(start 0.508 -0.9398)
			(end -0.508 -0.9398)
			(stroke
				(width 0.1524)
				(type default)
			)
			(layer "F.SilkS")
		)
		(fp_line
			(start -0.508 -0.9398)
			(end -0.508 0.9398)
			(stroke
				(width 0.1524)
				(type default)
			)
			(layer "F.SilkS")
		)
		(fp_rect
			(start -0.508 0.9398)
			(end 0.508 -0.9398)
			(stroke
				(width 0)
				(type default)
			)
			(fill no)
			(layer "F.CrtYd")
		)
		(fp_rect
			(start -0.508 0.9398)
			(end 0.508 -0.9398)
			(stroke
				(width 0)
				(type default)
			)
			(fill no)
			(layer "F.Fab")
		)
		(pad "1" smd custom
			(at 0 -0.4445 90)
			(size 0.1397 0.1397)
			(layers "F.Cu" "F.Mask" "F.Paste")
			(net "CLK_P_8_R")
			(options
				(clearance outline)
				(anchor circle)
			)
			(primitives
				(gr_poly
					(pts
						(arc
							(start -0.1778 -0.2794)
							(mid -0.249642 -0.249642)
							(end -0.2794 -0.1778)
						)
						(arc
							(start -0.2794 0.1778)
							(mid -0.249642 0.249642)
							(end -0.1778 0.2794)
						)
						(arc
							(start 0.1778 0.2794)
							(mid 0.249642 0.249642)
							(end 0.2794 0.1778)
						)
						(arc
							(start 0.2794 -0.1778)
							(mid 0.249642 -0.249642)
							(end 0.1778 -0.2794)
						)
					)
					(width 0)
					(fill yes)
				)
			)
		)
		(pad "2" smd custom
			(at 0 0.4445 90)
			(size 0.1397 0.1397)
			(layers "F.Cu" "F.Mask" "F.Paste")
			(net "GND")
			(options
				(clearance outline)
				(anchor circle)
			)
			(primitives
				(gr_poly
					(pts
						(arc
							(start -0.1778 -0.2794)
							(mid -0.249642 -0.249642)
							(end -0.2794 -0.1778)
						)
						(arc
							(start -0.2794 0.1778)
							(mid -0.249642 0.249642)
							(end -0.1778 0.2794)
						)
						(arc
							(start 0.1778 0.2794)
							(mid 0.249642 0.249642)
							(end 0.2794 0.1778)
						)
						(arc
							(start 0.2794 -0.1778)
							(mid 0.249642 -0.249642)
							(end 0.1778 -0.2794)
						)
					)
					(width 0)
					(fill yes)
				)
			)
		)
	)
	(footprint ""
		(layer "F.Cu")
		(at 39.538148 -68.890642 90)
		(property "Reference" "PG2"
			(at 0 0 90)
			(layer "F.SilkS")
			(hide yes)
			(effects
				(font
					(size 1.27 1.27)
				)
			)
		)
		(property "Value" "GAP-CLOSE-PWR-3-GP"
			(at 0.0254 -6.5786 90)
			(unlocked yes)
			(layer "F.Fab")
			(hide yes)
			(effects
				(font
					(size 1.016 1.016)
					(thickness 0.1524)
				)
			)
		)
		(property "Device Type" "GAP-CLOSE-PWR-3"
			(at 0.0254 -8.255 90)
			(unlocked yes)
			(layer "F.Fab")
			(hide yes)
			(effects
				(font
					(size 1.016 1.016)
					(thickness 0.1524)
				)
			)
		)
		(duplicate_pad_numbers_are_jumpers no)
		(fp_rect
			(start -0.7112 0.4572)
			(end 0.7112 -0.4572)
			(stroke
				(width 0)
				(type default)
			)
			(fill no)
			(layer "F.CrtYd")
		)
		(fp_poly
			(pts
				(xy -0.7112 -0.4572) (xy 0.7112 -0.4572) (xy 0.7112 0.4572) (xy -0.7112 0.4572)
			)
			(stroke
				(width 0)
				(type default)
			)
			(fill no)
			(layer "F.Fab")
		)
		(pad "1" smd rect
			(at -0.3048 0 90)
			(size 0.6604 0.762)
			(layers "F.Cu" "F.Mask" "F.Paste")
			(net "P5V_STBY")
		)
		(pad "2" smd rect
			(at 0.3048 0 90)
			(size 0.6604 0.762)
			(layers "F.Cu" "F.Mask" "F.Paste")
			(net "P5V_STBY_LR")
		)
	)
	(footprint ""
		(layer "F.Cu")
		(at 87.122 -46.609 180)
		(property "Reference" "PC39"
			(at 0 0 180)
			(layer "F.SilkS")
			(hide yes)
			(effects
				(font
					(size 1.27 1.27)
				)
			)
		)
		(property "Value" "SC10U6D3V5KX-4GP"
			(at -0.0762 -6.1214 180)
			(unlocked yes)
			(layer "F.Fab")
			(hide yes)
			(effects
				(font
					(size 1.016 1.016)
					(thickness 0.1524)
				)
			)
		)
		(property "Device Type" "C805H58"
			(at -0.0762 -8.1534 180)
			(unlocked yes)
			(layer "F.Fab")
			(hide yes)
			(effects
				(font
					(size 1.016 1.016)
					(thickness 0.1524)
				)
			)
		)
		(duplicate_pad_numbers_are_jumpers no)
		(fp_line
			(start 0.635 0)
			(end -0.635 0)
			(stroke
				(width 0.508)
				(type default)
			)
			(layer "F.SilkS")
		)
		(fp_rect
			(start -0.9652 1.778)
			(end 0.9652 -1.778)
			(stroke
				(width 0)
				(type default)
			)
			(fill no)
			(layer "F.CrtYd")
		)
		(fp_poly
			(pts
				(xy -0.9652 -1.778) (xy 0.9652 -1.778) (xy 0.9652 1.778) (xy -0.9652 1.778)
			)
			(stroke
				(width 0)
				(type default)
			)
			(fill no)
			(layer "F.Fab")
		)
		(pad "1" smd rect
			(at 0 -0.9652 180)
			(size 1.397 1.143)
			(layers "F.Cu" "F.Mask" "F.Paste")
			(net "P3V3_PWR")
		)
		(pad "2" smd rect
			(at 0 0.9652 180)
			(size 1.397 1.143)
			(layers "F.Cu" "F.Mask" "F.Paste")
			(net "GND")
		)
	)
	(footprint ""
		(layer "F.Cu")
		(at 24.186642 -99.238816)
		(property "Reference" "C43"
			(at 0 0 0)
			(layer "F.SilkS")
			(hide yes)
			(effects
				(font
					(size 1.27 1.27)
				)
			)
		)
		(property "Value" "SCD1U16V2KX-L-GP"
			(at 1.1811 -2.7051 0)
			(unlocked yes)
			(layer "F.Fab")
			(hide yes)
			(effects
				(font
					(size 1.016 1.016)
					(thickness 0.1524)
				)
			)
		)
		(property "Device Type" "C402H22"
			(at 1.1811 -4.2291 0)
			(unlocked yes)
			(layer "F.Fab")
			(hide yes)
			(effects
				(font
					(size 1.016 1.016)
					(thickness 0.1524)
				)
			)
		)
		(duplicate_pad_numbers_are_jumpers no)
		(fp_rect
			(start -0.4318 0.9525)
			(end 0.4318 -0.9525)
			(stroke
				(width 0)
				(type default)
			)
			(fill no)
			(layer "F.CrtYd")
		)
		(fp_rect
			(start -0.4318 0.9525)
			(end 0.4318 -0.9525)
			(stroke
				(width 0)
				(type default)
			)
			(fill no)
			(layer "F.Fab")
		)
		(pad "1" smd custom
			(at 0 -0.4445)
			(size 0.1524 0.1524)
			(layers "F.Cu" "F.Mask" "F.Paste")
			(net "P5V_STBY")
			(options
				(clearance outline)
				(anchor circle)
			)
			(primitives
				(gr_poly
					(pts
						(arc
							(start 0.3048 -0.2032)
							(mid 0.275042 -0.275042)
							(end 0.2032 -0.3048)
						)
						(arc
							(start -0.2032 -0.3048)
							(mid -0.275042 -0.275042)
							(end -0.3048 -0.2032)
						)
						(arc
							(start -0.3048 0.2032)
							(mid -0.275042 0.275042)
							(end -0.2032 0.3048)
						)
						(arc
							(start 0.2032 0.3048)
							(mid 0.275042 0.275042)
							(end 0.3048 0.2032)
						)
					)
					(width 0)
					(fill yes)
				)
			)
		)
		(pad "2" smd custom
			(at 0 0.4445)
			(size 0.1524 0.1524)
			(layers "F.Cu" "F.Mask" "F.Paste")
			(net "GND")
			(options
				(clearance outline)
				(anchor circle)
			)
			(primitives
				(gr_poly
					(pts
						(arc
							(start 0.3048 -0.2032)
							(mid 0.275042 -0.275042)
							(end 0.2032 -0.3048)
						)
						(arc
							(start -0.2032 -0.3048)
							(mid -0.275042 -0.275042)
							(end -0.3048 -0.2032)
						)
						(arc
							(start -0.3048 0.2032)
							(mid -0.275042 0.275042)
							(end -0.2032 0.3048)
						)
						(arc
							(start 0.2032 0.3048)
							(mid 0.275042 0.275042)
							(end 0.3048 0.2032)
						)
					)
					(width 0)
					(fill yes)
				)
			)
		)
	)
	(footprint ""
		(layer "F.Cu")
		(at 230.251 -23.241 180)
		(property "Reference" "R3717"
			(at 0 0 180)
			(layer "F.SilkS")
			(hide yes)
			(effects
				(font
					(size 1.27 1.27)
				)
			)
		)
		(property "Value" "4K7R2F-GP"
			(at 0.064008 -3.993896 180)
			(unlocked yes)
			(layer "F.Fab")
			(hide yes)
			(effects
				(font
					(size 1.016 1.016)
					(thickness 0.1524)
				)
			)
		)
		(property "Device Type" "R402H16"
			(at 0.064008 -5.517896 180)
			(unlocked yes)
			(layer "F.Fab")
			(hide yes)
			(effects
				(font
					(size 1.016 1.016)
					(thickness 0.1524)
				)
			)
		)
		(duplicate_pad_numbers_are_jumpers no)
		(fp_line
			(start 0.508 -0.9398)
			(end -0.508 -0.9398)
			(stroke
				(width 0.1524)
				(type default)
			)
			(layer "F.SilkS")
		)
		(fp_line
			(start -0.508 -0.9398)
			(end -0.508 0.9398)
			(stroke
				(width 0.1524)
				(type default)
			)
			(layer "F.SilkS")
		)
		(fp_rect
			(start -0.508 0.9398)
			(end 0.508 -0.9398)
			(stroke
				(width 0)
				(type default)
			)
			(fill no)
			(layer "F.CrtYd")
		)
		(fp_rect
			(start -0.508 0.9398)
			(end 0.508 -0.9398)
			(stroke
				(width 0)
				(type default)
			)
			(fill no)
			(layer "F.Fab")
		)
		(pad "1" smd custom
			(at 0 -0.4445 180)
			(size 0.1397 0.1397)
			(layers "F.Cu" "F.Mask" "F.Paste")
			(net "HOST1_RST_N_LS")
			(options
				(clearance outline)
				(anchor circle)
			)
			(primitives
				(gr_poly
					(pts
						(arc
							(start -0.1778 -0.2794)
							(mid -0.249642 -0.249642)
							(end -0.2794 -0.1778)
						)
						(arc
							(start -0.2794 0.1778)
							(mid -0.249642 0.249642)
							(end -0.1778 0.2794)
						)
						(arc
							(start 0.1778 0.2794)
							(mid 0.249642 0.249642)
							(end 0.2794 0.1778)
						)
						(arc
							(start 0.2794 -0.1778)
							(mid 0.249642 -0.249642)
							(end 0.1778 -0.2794)
						)
					)
					(width 0)
					(fill yes)
				)
			)
		)
		(pad "2" smd custom
			(at 0 0.4445 180)
			(size 0.1397 0.1397)
			(layers "F.Cu" "F.Mask" "F.Paste")
			(net "GND")
			(options
				(clearance outline)
				(anchor circle)
			)
			(primitives
				(gr_poly
					(pts
						(arc
							(start -0.1778 -0.2794)
							(mid -0.249642 -0.249642)
							(end -0.2794 -0.1778)
						)
						(arc
							(start -0.2794 0.1778)
							(mid -0.249642 0.249642)
							(end -0.1778 0.2794)
						)
						(arc
							(start 0.1778 0.2794)
							(mid 0.249642 0.249642)
							(end 0.2794 0.1778)
						)
						(arc
							(start 0.2794 -0.1778)
							(mid 0.249642 -0.249642)
							(end 0.1778 -0.2794)
						)
					)
					(width 0)
					(fill yes)
				)
			)
		)
	)
	(footprint ""
		(layer "F.Cu")
		(at 151.511 -33.528)
		(property "Reference" "C388"
			(at 0 0 0)
			(layer "F.SilkS")
			(hide yes)
			(effects
				(font
					(size 1.27 1.27)
				)
			)
		)
		(property "Value" "SCD22U10V2KX-1GP"
			(at 1.1811 -2.7051 0)
			(unlocked yes)
			(layer "F.Fab")
			(hide yes)
			(effects
				(font
					(size 1.016 1.016)
					(thickness 0.1524)
				)
			)
		)
		(property "Device Type" "C402H22"
			(at 1.1811 -4.2291 0)
			(unlocked yes)
			(layer "F.Fab")
			(hide yes)
			(effects
				(font
					(size 1.016 1.016)
					(thickness 0.1524)
				)
			)
		)
		(duplicate_pad_numbers_are_jumpers no)
		(fp_rect
			(start -0.4318 0.9525)
			(end 0.4318 -0.9525)
			(stroke
				(width 0)
				(type default)
			)
			(fill no)
			(layer "F.CrtYd")
		)
		(fp_rect
			(start -0.4318 0.9525)
			(end 0.4318 -0.9525)
			(stroke
				(width 0)
				(type default)
			)
			(fill no)
			(layer "F.Fab")
		)
		(pad "1" smd custom
			(at 0 -0.4445)
			(size 0.1524 0.1524)
			(layers "F.Cu" "F.Mask" "F.Paste")
			(net "PCIE_TX_CAP_N84")
			(options
				(clearance outline)
				(anchor circle)
			)
			(primitives
				(gr_poly
					(pts
						(arc
							(start 0.3048 -0.2032)
							(mid 0.275042 -0.275042)
							(end 0.2032 -0.3048)
						)
						(arc
							(start -0.2032 -0.3048)
							(mid -0.275042 -0.275042)
							(end -0.3048 -0.2032)
						)
						(arc
							(start -0.3048 0.2032)
							(mid -0.275042 0.275042)
							(end -0.2032 0.3048)
						)
						(arc
							(start 0.2032 0.3048)
							(mid 0.275042 0.275042)
							(end 0.3048 0.2032)
						)
					)
					(width 0)
					(fill yes)
				)
			)
		)
		(pad "2" smd custom
			(at 0 0.4445)
			(size 0.1524 0.1524)
			(layers "F.Cu" "F.Mask" "F.Paste")
			(net "PCIE_TX_N84")
			(options
				(clearance outline)
				(anchor circle)
			)
			(primitives
				(gr_poly
					(pts
						(arc
							(start 0.3048 -0.2032)
							(mid 0.275042 -0.275042)
							(end 0.2032 -0.3048)
						)
						(arc
							(start -0.2032 -0.3048)
							(mid -0.275042 -0.275042)
							(end -0.3048 -0.2032)
						)
						(arc
							(start -0.3048 0.2032)
							(mid -0.275042 0.275042)
							(end -0.2032 0.3048)
						)
						(arc
							(start 0.2032 0.3048)
							(mid 0.275042 0.275042)
							(end 0.3048 0.2032)
						)
					)
					(width 0)
					(fill yes)
				)
			)
		)
	)
	(footprint ""
		(layer "F.Cu")
		(at 320.608198 -212.420454 180)
		(property "Reference" "C66"
			(at 0 0 180)
			(layer "F.SilkS")
			(hide yes)
			(effects
				(font
					(size 1.27 1.27)
				)
			)
		)
		(property "Value" "SCD22U10V2KX-1GP"
			(at 1.1811 -2.7051 180)
			(unlocked yes)
			(layer "F.Fab")
			(hide yes)
			(effects
				(font
					(size 1.016 1.016)
					(thickness 0.1524)
				)
			)
		)
		(property "Device Type" "C402H22"
			(at 1.1811 -4.2291 180)
			(unlocked yes)
			(layer "F.Fab")
			(hide yes)
			(effects
				(font
					(size 1.016 1.016)
					(thickness 0.1524)
				)
			)
		)
		(duplicate_pad_numbers_are_jumpers no)
		(fp_rect
			(start -0.4318 0.9525)
			(end 0.4318 -0.9525)
			(stroke
				(width 0)
				(type default)
			)
			(fill no)
			(layer "F.CrtYd")
		)
		(fp_rect
			(start -0.4318 0.9525)
			(end 0.4318 -0.9525)
			(stroke
				(width 0)
				(type default)
			)
			(fill no)
			(layer "F.Fab")
		)
		(pad "1" smd custom
			(at 0 -0.4445 180)
			(size 0.1524 0.1524)
			(layers "F.Cu" "F.Mask" "F.Paste")
			(net "PCIE_TX_CAP_N22")
			(options
				(clearance outline)
				(anchor circle)
			)
			(primitives
				(gr_poly
					(pts
						(arc
							(start 0.3048 -0.2032)
							(mid 0.275042 -0.275042)
							(end 0.2032 -0.3048)
						)
						(arc
							(start -0.2032 -0.3048)
							(mid -0.275042 -0.275042)
							(end -0.3048 -0.2032)
						)
						(arc
							(start -0.3048 0.2032)
							(mid -0.275042 0.275042)
							(end -0.2032 0.3048)
						)
						(arc
							(start 0.2032 0.3048)
							(mid 0.275042 0.275042)
							(end 0.3048 0.2032)
						)
					)
					(width 0)
					(fill yes)
				)
			)
		)
		(pad "2" smd custom
			(at 0 0.4445 180)
			(size 0.1524 0.1524)
			(layers "F.Cu" "F.Mask" "F.Paste")
			(net "PCIE_TX_N22")
			(options
				(clearance outline)
				(anchor circle)
			)
			(primitives
				(gr_poly
					(pts
						(arc
							(start 0.3048 -0.2032)
							(mid 0.275042 -0.275042)
							(end 0.2032 -0.3048)
						)
						(arc
							(start -0.2032 -0.3048)
							(mid -0.275042 -0.275042)
							(end -0.3048 -0.2032)
						)
						(arc
							(start -0.3048 0.2032)
							(mid -0.275042 0.275042)
							(end -0.2032 0.3048)
						)
						(arc
							(start 0.2032 0.3048)
							(mid 0.275042 0.275042)
							(end 0.3048 0.2032)
						)
					)
					(width 0)
					(fill yes)
				)
			)
		)
	)
	(footprint ""
		(layer "F.Cu")
		(at 125.599952 -1.999996 90)
		(property "Reference" "LED11"
			(at 0 0 90)
			(layer "F.SilkS")
			(hide yes)
			(effects
				(font
					(size 1.27 1.27)
				)
			)
		)
		(property "Value" "LED-YG-51-GP"
			(at -2.6924 -1.4224 90)
			(unlocked yes)
			(layer "F.Fab")
			(hide yes)
			(effects
				(font
					(size 1.016 1.016)
					(thickness 0.1524)
				)
			)
		)
		(property "Device Type" "LED1608AKH40"
			(at -2.6924 -2.9464 90)
			(unlocked yes)
			(layer "F.Fab")
			(hide yes)
			(effects
				(font
					(size 1.016 1.016)
					(thickness 0.1524)
				)
			)
		)
		(duplicate_pad_numbers_are_jumpers no)
		(fp_line
			(start 0.6604 -1.3716)
			(end 0.6604 1.3716)
			(stroke
				(width 0.1524)
				(type default)
			)
			(layer "F.SilkS")
		)
		(fp_line
			(start -0.6604 -1.3716)
			(end 0.6604 -1.3716)
			(stroke
				(width 0.1524)
				(type default)
			)
			(layer "F.SilkS")
		)
		(fp_line
			(start 0.6604 1.3716)
			(end -0.6604 1.3716)
			(stroke
				(width 0.1524)
				(type default)
			)
			(layer "F.SilkS")
		)
		(fp_line
			(start -0.6604 1.3716)
			(end -0.6604 -1.3716)
			(stroke
				(width 0.1524)
				(type default)
			)
			(layer "F.SilkS")
		)
		(fp_line
			(start -0.5969 1.5494)
			(end 0.5842 1.5494)
			(stroke
				(width 0.508)
				(type default)
			)
			(layer "F.SilkS")
		)
		(fp_line
			(start 0.7493 1.651)
			(end 0.7493 1.1811)
			(stroke
				(width 0.3302)
				(type default)
			)
			(layer "F.SilkS")
		)
		(fp_line
			(start -0.7493 1.651)
			(end -0.7493 1.1811)
			(stroke
				(width 0.3302)
				(type default)
			)
			(layer "F.SilkS")
		)
		(fp_rect
			(start -0.6223 1.3335)
			(end 0.6223 -1.3335)
			(stroke
				(width 0)
				(type default)
			)
			(fill no)
			(layer "F.CrtYd")
		)
		(fp_rect
			(start -0.6223 1.3335)
			(end 0.6223 -1.3335)
			(stroke
				(width 0)
				(type default)
			)
			(fill no)
			(layer "F.Fab")
		)
		(pad "A" smd custom
			(at 0 -0.762 90)
			(size 0.2159 0.2159)
			(layers "F.Cu" "F.Mask" "F.Paste")
			(net "LED_R_4")
			(options
				(clearance outline)
				(anchor circle)
			)
			(primitives
				(gr_poly
					(pts
						(arc
							(start -0.3302 -0.4318)
							(mid -0.402042 -0.402042)
							(end -0.4318 -0.3302)
						)
						(arc
							(start -0.4318 0.3302)
							(mid -0.402042 0.402042)
							(end -0.3302 0.4318)
						)
						(arc
							(start 0.3302 0.4318)
							(mid 0.402042 0.402042)
							(end 0.4318 0.3302)
						)
						(arc
							(start 0.4318 -0.3302)
							(mid 0.402042 -0.402042)
							(end 0.3302 -0.4318)
						)
					)
					(width 0)
					(fill yes)
				)
			)
		)
		(pad "K" smd custom
			(at 0 0.762 90)
			(size 0.2159 0.2159)
			(layers "F.Cu" "F.Mask" "F.Paste")
			(net "LED_Q_4")
			(options
				(clearance outline)
				(anchor circle)
			)
			(primitives
				(gr_poly
					(pts
						(arc
							(start -0.3302 -0.4318)
							(mid -0.402042 -0.402042)
							(end -0.4318 -0.3302)
						)
						(arc
							(start -0.4318 0.3302)
							(mid -0.402042 0.402042)
							(end -0.3302 0.4318)
						)
						(arc
							(start 0.3302 0.4318)
							(mid 0.402042 0.402042)
							(end 0.4318 0.3302)
						)
						(arc
							(start 0.4318 -0.3302)
							(mid 0.402042 -0.402042)
							(end 0.3302 -0.4318)
						)
					)
					(width 0)
					(fill yes)
				)
			)
		)
	)
	(footprint ""
		(layer "F.Cu")
		(at 323.56171 -33.482788)
		(property "Reference" "C48"
			(at 0 0 0)
			(layer "F.SilkS")
			(hide yes)
			(effects
				(font
					(size 1.27 1.27)
				)
			)
		)
		(property "Value" "SCD22U10V2KX-1GP"
			(at 1.1811 -2.7051 0)
			(unlocked yes)
			(layer "F.Fab")
			(hide yes)
			(effects
				(font
					(size 1.016 1.016)
					(thickness 0.1524)
				)
			)
		)
		(property "Device Type" "C402H22"
			(at 1.1811 -4.2291 0)
			(unlocked yes)
			(layer "F.Fab")
			(hide yes)
			(effects
				(font
					(size 1.016 1.016)
					(thickness 0.1524)
				)
			)
		)
		(duplicate_pad_numbers_are_jumpers no)
		(fp_rect
			(start -0.4318 0.9525)
			(end 0.4318 -0.9525)
			(stroke
				(width 0)
				(type default)
			)
			(fill no)
			(layer "F.CrtYd")
		)
		(fp_rect
			(start -0.4318 0.9525)
			(end 0.4318 -0.9525)
			(stroke
				(width 0)
				(type default)
			)
			(fill no)
			(layer "F.Fab")
		)
		(pad "1" smd custom
			(at 0 -0.4445)
			(size 0.1524 0.1524)
			(layers "F.Cu" "F.Mask" "F.Paste")
			(net "PCIE_TX_CAP_P13")
			(options
				(clearance outline)
				(anchor circle)
			)
			(primitives
				(gr_poly
					(pts
						(arc
							(start 0.3048 -0.2032)
							(mid 0.275042 -0.275042)
							(end 0.2032 -0.3048)
						)
						(arc
							(start -0.2032 -0.3048)
							(mid -0.275042 -0.275042)
							(end -0.3048 -0.2032)
						)
						(arc
							(start -0.3048 0.2032)
							(mid -0.275042 0.275042)
							(end -0.2032 0.3048)
						)
						(arc
							(start 0.2032 0.3048)
							(mid 0.275042 0.275042)
							(end 0.3048 0.2032)
						)
					)
					(width 0)
					(fill yes)
				)
			)
		)
		(pad "2" smd custom
			(at 0 0.4445)
			(size 0.1524 0.1524)
			(layers "F.Cu" "F.Mask" "F.Paste")
			(net "PCIE_TX_P13")
			(options
				(clearance outline)
				(anchor circle)
			)
			(primitives
				(gr_poly
					(pts
						(arc
							(start 0.3048 -0.2032)
							(mid 0.275042 -0.275042)
							(end 0.2032 -0.3048)
						)
						(arc
							(start -0.2032 -0.3048)
							(mid -0.275042 -0.275042)
							(end -0.3048 -0.2032)
						)
						(arc
							(start -0.3048 0.2032)
							(mid -0.275042 0.275042)
							(end -0.2032 0.3048)
						)
						(arc
							(start 0.2032 0.3048)
							(mid 0.275042 0.275042)
							(end 0.3048 0.2032)
						)
					)
					(width 0)
					(fill yes)
				)
			)
		)
	)
	(footprint ""
		(layer "F.Cu")
		(at 41.148 -201.549 90)
		(property "Reference" "U30"
			(at 0 0 90)
			(layer "F.SilkS")
			(hide yes)
			(effects
				(font
					(size 1.27 1.27)
				)
			)
		)
		(property "Value" "PCA9511ADP-T-GP"
			(at 0 -13.1572 90)
			(unlocked yes)
			(layer "F.Fab")
			(hide yes)
			(effects
				(font
					(size 1.016 1.016)
					(thickness 0.1524)
				)
			)
		)
		(property "Device Type" "SSOIC8-2H44"
			(at 0 -15.1892 90)
			(unlocked yes)
			(layer "F.Fab")
			(hide yes)
			(effects
				(font
					(size 1.016 1.016)
					(thickness 0.1524)
				)
			)
		)
		(duplicate_pad_numbers_are_jumpers no)
		(fp_line
			(start 1.0922 -1.016)
			(end 1.0922 1.016)
			(stroke
				(width 0.1524)
				(type default)
			)
			(layer "F.SilkS")
		)
		(fp_line
			(start -1.9304 -1.016)
			(end 1.0922 -1.016)
			(stroke
				(width 0.1524)
				(type default)
			)
			(layer "F.SilkS")
		)
		(fp_line
			(start -1.524 0)
			(end -1.9304 -0.4064)
			(stroke
				(width 0.1524)
				(type default)
			)
			(layer "F.SilkS")
		)
		(fp_line
			(start -1.524 0)
			(end -1.9304 0.4064)
			(stroke
				(width 0.1524)
				(type default)
			)
			(layer "F.SilkS")
		)
		(fp_line
			(start 1.0922 1.016)
			(end -1.9304 1.016)
			(stroke
				(width 0.1524)
				(type default)
			)
			(layer "F.SilkS")
		)
		(fp_line
			(start -1.9304 1.016)
			(end -1.9304 -1.016)
			(stroke
				(width 0.1524)
				(type default)
			)
			(layer "F.SilkS")
		)
		(fp_line
			(start -1.7018 1.0414)
			(end -1.7018 2.9718)
			(stroke
				(width 0.635)
				(type default)
			)
			(layer "F.SilkS")
		)
		(fp_poly
			(pts
				(xy -1.1938 -1.016) (xy 1.0922 -1.016) (xy 1.0922 1.016) (xy -1.1938 1.016)
			)
			(stroke
				(width 0)
				(type default)
			)
			(fill yes)
			(layer "F.SilkS")
		)
		(fp_rect
			(start -2.0066 3.3401)
			(end 2.0066 -3.3401)
			(stroke
				(width 0)
				(type default)
			)
			(fill no)
			(layer "F.CrtYd")
		)
		(fp_poly
			(pts
				(xy -2.0066 -3.3401) (xy 2.0066 -3.3401) (xy 2.0066 3.3401) (xy -2.0066 3.3401)
			)
			(stroke
				(width 0)
				(type default)
			)
			(fill no)
			(layer "F.Fab")
		)
		(pad "1" smd rect
			(at -0.97536 2.0701 90)
			(size 0.4064 1.524)
			(layers "F.Cu" "F.Mask" "F.Paste")
			(net "I2C6_BUFF_EN")
		)
		(pad "2" smd rect
			(at -0.32512 2.0701 90)
			(size 0.4064 1.524)
			(layers "F.Cu" "F.Mask" "F.Paste")
			(net "BMC_I2C6_C_FCB_SCL_R")
		)
		(pad "3" smd rect
			(at 0.32512 2.0701 90)
			(size 0.4064 1.524)
			(layers "F.Cu" "F.Mask" "F.Paste")
			(net "BUF_I2C6_C_FCB_SCL_R")
		)
		(pad "4" smd rect
			(at 0.97536 2.0701 90)
			(size 0.4064 1.524)
			(layers "F.Cu" "F.Mask" "F.Paste")
			(net "GND")
		)
		(pad "5" smd rect
			(at 0.97536 -2.0701 90)
			(size 0.4064 1.524)
			(layers "F.Cu" "F.Mask" "F.Paste")
			(net "I2C6_BUF_READY")
		)
		(pad "6" smd rect
			(at 0.32512 -2.0701 90)
			(size 0.4064 1.524)
			(layers "F.Cu" "F.Mask" "F.Paste")
			(net "BUF_I2C6_C_FCB_SDA_R")
		)
		(pad "7" smd rect
			(at -0.32512 -2.0701 90)
			(size 0.4064 1.524)
			(layers "F.Cu" "F.Mask" "F.Paste")
			(net "BMC_I2C6_C_FCB_SDA_R")
		)
		(pad "8" smd rect
			(at -0.97536 -2.0701 90)
			(size 0.4064 1.524)
			(layers "F.Cu" "F.Mask" "F.Paste")
			(net "P3V3_STBY")
		)
	)
	(footprint ""
		(layer "F.Cu")
		(at 14.5288 -173.9138 180)
		(property "Reference" "R664"
			(at 0 0 180)
			(layer "F.SilkS")
			(hide yes)
			(effects
				(font
					(size 1.27 1.27)
				)
			)
		)
		(property "Value" "27KR2F-L-GP"
			(at 0.064008 -3.993896 180)
			(unlocked yes)
			(layer "F.Fab")
			(hide yes)
			(effects
				(font
					(size 1.016 1.016)
					(thickness 0.1524)
				)
			)
		)
		(property "Device Type" "R402H16"
			(at 0.064008 -5.517896 180)
			(unlocked yes)
			(layer "F.Fab")
			(hide yes)
			(effects
				(font
					(size 1.016 1.016)
					(thickness 0.1524)
				)
			)
		)
		(duplicate_pad_numbers_are_jumpers no)
		(fp_line
			(start 0.508 -0.9398)
			(end -0.508 -0.9398)
			(stroke
				(width 0.1524)
				(type default)
			)
			(layer "F.SilkS")
		)
		(fp_line
			(start -0.508 -0.9398)
			(end -0.508 0.9398)
			(stroke
				(width 0.1524)
				(type default)
			)
			(layer "F.SilkS")
		)
		(fp_rect
			(start -0.508 0.9398)
			(end 0.508 -0.9398)
			(stroke
				(width 0)
				(type default)
			)
			(fill no)
			(layer "F.CrtYd")
		)
		(fp_rect
			(start -0.508 0.9398)
			(end 0.508 -0.9398)
			(stroke
				(width 0)
				(type default)
			)
			(fill no)
			(layer "F.Fab")
		)
		(pad "1" smd custom
			(at 0 -0.4445 180)
			(size 0.1397 0.1397)
			(layers "F.Cu" "F.Mask" "F.Paste")
			(net "P12V_PCIE")
			(options
				(clearance outline)
				(anchor circle)
			)
			(primitives
				(gr_poly
					(pts
						(arc
							(start -0.1778 -0.2794)
							(mid -0.249642 -0.249642)
							(end -0.2794 -0.1778)
						)
						(arc
							(start -0.2794 0.1778)
							(mid -0.249642 0.249642)
							(end -0.1778 0.2794)
						)
						(arc
							(start 0.1778 0.2794)
							(mid 0.249642 0.249642)
							(end 0.2794 0.1778)
						)
						(arc
							(start 0.2794 -0.1778)
							(mid 0.249642 -0.249642)
							(end 0.1778 -0.2794)
						)
					)
					(width 0)
					(fill yes)
				)
			)
		)
		(pad "2" smd custom
			(at 0 0.4445 180)
			(size 0.1397 0.1397)
			(layers "F.Cu" "F.Mask" "F.Paste")
			(net "TRAY_MBP_CTRL_EN_N")
			(options
				(clearance outline)
				(anchor circle)
			)
			(primitives
				(gr_poly
					(pts
						(arc
							(start -0.1778 -0.2794)
							(mid -0.249642 -0.249642)
							(end -0.2794 -0.1778)
						)
						(arc
							(start -0.2794 0.1778)
							(mid -0.249642 0.249642)
							(end -0.1778 0.2794)
						)
						(arc
							(start 0.1778 0.2794)
							(mid 0.249642 0.249642)
							(end 0.2794 0.1778)
						)
						(arc
							(start 0.2794 -0.1778)
							(mid 0.249642 -0.249642)
							(end 0.1778 -0.2794)
						)
					)
					(width 0)
					(fill yes)
				)
			)
		)
	)
	(footprint ""
		(layer "F.Cu")
		(at 261.112 -26.289 180)
		(property "Reference" "R745"
			(at 0 0 180)
			(layer "F.SilkS")
			(hide yes)
			(effects
				(font
					(size 1.27 1.27)
				)
			)
		)
		(property "Value" "4K7R2F-GP"
			(at 0.064008 -3.993896 180)
			(unlocked yes)
			(layer "F.Fab")
			(hide yes)
			(effects
				(font
					(size 1.016 1.016)
					(thickness 0.1524)
				)
			)
		)
		(property "Device Type" "R402H16"
			(at 0.064008 -5.517896 180)
			(unlocked yes)
			(layer "F.Fab")
			(hide yes)
			(effects
				(font
					(size 1.016 1.016)
					(thickness 0.1524)
				)
			)
		)
		(duplicate_pad_numbers_are_jumpers no)
		(fp_line
			(start 0.508 -0.9398)
			(end -0.508 -0.9398)
			(stroke
				(width 0.1524)
				(type default)
			)
			(layer "F.SilkS")
		)
		(fp_line
			(start -0.508 -0.9398)
			(end -0.508 0.9398)
			(stroke
				(width 0.1524)
				(type default)
			)
			(layer "F.SilkS")
		)
		(fp_rect
			(start -0.508 0.9398)
			(end 0.508 -0.9398)
			(stroke
				(width 0)
				(type default)
			)
			(fill no)
			(layer "F.CrtYd")
		)
		(fp_rect
			(start -0.508 0.9398)
			(end 0.508 -0.9398)
			(stroke
				(width 0)
				(type default)
			)
			(fill no)
			(layer "F.Fab")
		)
		(pad "1" smd custom
			(at 0 -0.4445 180)
			(size 0.1397 0.1397)
			(layers "F.Cu" "F.Mask" "F.Paste")
			(net "P3V3_GPIO")
			(options
				(clearance outline)
				(anchor circle)
			)
			(primitives
				(gr_poly
					(pts
						(arc
							(start -0.1778 -0.2794)
							(mid -0.249642 -0.249642)
							(end -0.2794 -0.1778)
						)
						(arc
							(start -0.2794 0.1778)
							(mid -0.249642 0.249642)
							(end -0.1778 0.2794)
						)
						(arc
							(start 0.1778 0.2794)
							(mid 0.249642 0.249642)
							(end 0.2794 0.1778)
						)
						(arc
							(start 0.2794 -0.1778)
							(mid 0.249642 -0.249642)
							(end 0.1778 -0.2794)
						)
					)
					(width 0)
					(fill yes)
				)
			)
		)
		(pad "2" smd custom
			(at 0 0.4445 180)
			(size 0.1397 0.1397)
			(layers "F.Cu" "F.Mask" "F.Paste")
			(net "IOEXP_INT#_4")
			(options
				(clearance outline)
				(anchor circle)
			)
			(primitives
				(gr_poly
					(pts
						(arc
							(start -0.1778 -0.2794)
							(mid -0.249642 -0.249642)
							(end -0.2794 -0.1778)
						)
						(arc
							(start -0.2794 0.1778)
							(mid -0.249642 0.249642)
							(end -0.1778 0.2794)
						)
						(arc
							(start 0.1778 0.2794)
							(mid 0.249642 0.249642)
							(end 0.2794 0.1778)
						)
						(arc
							(start 0.2794 -0.1778)
							(mid 0.249642 -0.249642)
							(end 0.1778 -0.2794)
						)
					)
					(width 0)
					(fill yes)
				)
			)
		)
	)
	(footprint ""
		(layer "F.Cu")
		(at 265.599926 -17.500092 90)
		(property "Reference" "LED21"
			(at 0 0 90)
			(layer "F.SilkS")
			(hide yes)
			(effects
				(font
					(size 1.27 1.27)
				)
			)
		)
		(property "Value" "LED-YG-51-GP"
			(at -2.6924 -1.4224 90)
			(unlocked yes)
			(layer "F.Fab")
			(hide yes)
			(effects
				(font
					(size 1.016 1.016)
					(thickness 0.1524)
				)
			)
		)
		(property "Device Type" "LED1608AKH40"
			(at -2.6924 -2.9464 90)
			(unlocked yes)
			(layer "F.Fab")
			(hide yes)
			(effects
				(font
					(size 1.016 1.016)
					(thickness 0.1524)
				)
			)
		)
		(duplicate_pad_numbers_are_jumpers no)
		(fp_line
			(start 0.6604 -1.3716)
			(end 0.6604 1.3716)
			(stroke
				(width 0.1524)
				(type default)
			)
			(layer "F.SilkS")
		)
		(fp_line
			(start -0.6604 -1.3716)
			(end 0.6604 -1.3716)
			(stroke
				(width 0.1524)
				(type default)
			)
			(layer "F.SilkS")
		)
		(fp_line
			(start 0.6604 1.3716)
			(end -0.6604 1.3716)
			(stroke
				(width 0.1524)
				(type default)
			)
			(layer "F.SilkS")
		)
		(fp_line
			(start -0.6604 1.3716)
			(end -0.6604 -1.3716)
			(stroke
				(width 0.1524)
				(type default)
			)
			(layer "F.SilkS")
		)
		(fp_line
			(start -0.5969 1.5494)
			(end 0.5842 1.5494)
			(stroke
				(width 0.508)
				(type default)
			)
			(layer "F.SilkS")
		)
		(fp_line
			(start 0.7493 1.651)
			(end 0.7493 1.1811)
			(stroke
				(width 0.3302)
				(type default)
			)
			(layer "F.SilkS")
		)
		(fp_line
			(start -0.7493 1.651)
			(end -0.7493 1.1811)
			(stroke
				(width 0.3302)
				(type default)
			)
			(layer "F.SilkS")
		)
		(fp_rect
			(start -0.6223 1.3335)
			(end 0.6223 -1.3335)
			(stroke
				(width 0)
				(type default)
			)
			(fill no)
			(layer "F.CrtYd")
		)
		(fp_rect
			(start -0.6223 1.3335)
			(end 0.6223 -1.3335)
			(stroke
				(width 0)
				(type default)
			)
			(fill no)
			(layer "F.Fab")
		)
		(pad "A" smd custom
			(at 0 -0.762 90)
			(size 0.2159 0.2159)
			(layers "F.Cu" "F.Mask" "F.Paste")
			(net "LED_R_12")
			(options
				(clearance outline)
				(anchor circle)
			)
			(primitives
				(gr_poly
					(pts
						(arc
							(start -0.3302 -0.4318)
							(mid -0.402042 -0.402042)
							(end -0.4318 -0.3302)
						)
						(arc
							(start -0.4318 0.3302)
							(mid -0.402042 0.402042)
							(end -0.3302 0.4318)
						)
						(arc
							(start 0.3302 0.4318)
							(mid 0.402042 0.402042)
							(end 0.4318 0.3302)
						)
						(arc
							(start 0.4318 -0.3302)
							(mid 0.402042 -0.402042)
							(end 0.3302 -0.4318)
						)
					)
					(width 0)
					(fill yes)
				)
			)
		)
		(pad "K" smd custom
			(at 0 0.762 90)
			(size 0.2159 0.2159)
			(layers "F.Cu" "F.Mask" "F.Paste")
			(net "LED_Q_12")
			(options
				(clearance outline)
				(anchor circle)
			)
			(primitives
				(gr_poly
					(pts
						(arc
							(start -0.3302 -0.4318)
							(mid -0.402042 -0.402042)
							(end -0.4318 -0.3302)
						)
						(arc
							(start -0.4318 0.3302)
							(mid -0.402042 0.402042)
							(end -0.3302 0.4318)
						)
						(arc
							(start 0.3302 0.4318)
							(mid 0.402042 0.402042)
							(end 0.4318 0.3302)
						)
						(arc
							(start 0.4318 -0.3302)
							(mid 0.402042 -0.402042)
							(end 0.3302 -0.4318)
						)
					)
					(width 0)
					(fill yes)
				)
			)
		)
	)
	(footprint ""
		(layer "F.Cu")
		(at 53.721 -133.477 -90)
		(property "Reference" "R319"
			(at 0 0 270)
			(layer "F.SilkS")
			(hide yes)
			(effects
				(font
					(size 1.27 1.27)
				)
			)
		)
		(property "Value" "0R2J-2-GP"
			(at 0.064008 -3.993896 270)
			(unlocked yes)
			(layer "F.Fab")
			(hide yes)
			(effects
				(font
					(size 1.016 1.016)
					(thickness 0.1524)
				)
			)
		)
		(property "Device Type" "R402H16"
			(at 0.064008 -5.517896 270)
			(unlocked yes)
			(layer "F.Fab")
			(hide yes)
			(effects
				(font
					(size 1.016 1.016)
					(thickness 0.1524)
				)
			)
		)
		(duplicate_pad_numbers_are_jumpers no)
		(fp_line
			(start -0.508 -0.9398)
			(end -0.508 0.9398)
			(stroke
				(width 0.1524)
				(type default)
			)
			(layer "F.SilkS")
		)
		(fp_line
			(start 0.508 -0.9398)
			(end -0.508 -0.9398)
			(stroke
				(width 0.1524)
				(type default)
			)
			(layer "F.SilkS")
		)
		(fp_rect
			(start -0.508 0.9398)
			(end 0.508 -0.9398)
			(stroke
				(width 0)
				(type default)
			)
			(fill no)
			(layer "F.CrtYd")
		)
		(fp_rect
			(start -0.508 0.9398)
			(end 0.508 -0.9398)
			(stroke
				(width 0)
				(type default)
			)
			(fill no)
			(layer "F.Fab")
		)
		(pad "1" smd custom
			(at 0 -0.4445 270)
			(size 0.1397 0.1397)
			(layers "F.Cu" "F.Mask" "F.Paste")
			(net "ADC_P1V8_STBY")
			(options
				(clearance outline)
				(anchor circle)
			)
			(primitives
				(gr_poly
					(pts
						(arc
							(start -0.1778 -0.2794)
							(mid -0.249642 -0.249642)
							(end -0.2794 -0.1778)
						)
						(arc
							(start -0.2794 0.1778)
							(mid -0.249642 0.249642)
							(end -0.1778 0.2794)
						)
						(arc
							(start 0.1778 0.2794)
							(mid 0.249642 0.249642)
							(end 0.2794 0.1778)
						)
						(arc
							(start 0.2794 -0.1778)
							(mid 0.249642 -0.249642)
							(end 0.1778 -0.2794)
						)
					)
					(width 0)
					(fill yes)
				)
			)
		)
		(pad "2" smd custom
			(at 0 0.4445 270)
			(size 0.1397 0.1397)
			(layers "F.Cu" "F.Mask" "F.Paste")
			(net "ADC_P1V8_STBY_BMC")
			(options
				(clearance outline)
				(anchor circle)
			)
			(primitives
				(gr_poly
					(pts
						(arc
							(start -0.1778 -0.2794)
							(mid -0.249642 -0.249642)
							(end -0.2794 -0.1778)
						)
						(arc
							(start -0.2794 0.1778)
							(mid -0.249642 0.249642)
							(end -0.1778 0.2794)
						)
						(arc
							(start 0.1778 0.2794)
							(mid 0.249642 0.249642)
							(end 0.2794 0.1778)
						)
						(arc
							(start 0.2794 -0.1778)
							(mid 0.249642 -0.249642)
							(end 0.1778 -0.2794)
						)
					)
					(width 0)
					(fill yes)
				)
			)
		)
	)
	(footprint ""
		(layer "F.Cu")
		(at 147.992084 -212.420454 180)
		(property "Reference" "C273"
			(at 0 0 180)
			(layer "F.SilkS")
			(hide yes)
			(effects
				(font
					(size 1.27 1.27)
				)
			)
		)
		(property "Value" "SCD22U10V2KX-1GP"
			(at 1.1811 -2.7051 180)
			(unlocked yes)
			(layer "F.Fab")
			(hide yes)
			(effects
				(font
					(size 1.016 1.016)
					(thickness 0.1524)
				)
			)
		)
		(property "Device Type" "C402H22"
			(at 1.1811 -4.2291 180)
			(unlocked yes)
			(layer "F.Fab")
			(hide yes)
			(effects
				(font
					(size 1.016 1.016)
					(thickness 0.1524)
				)
			)
		)
		(duplicate_pad_numbers_are_jumpers no)
		(fp_rect
			(start -0.4318 0.9525)
			(end 0.4318 -0.9525)
			(stroke
				(width 0)
				(type default)
			)
			(fill no)
			(layer "F.CrtYd")
		)
		(fp_rect
			(start -0.4318 0.9525)
			(end 0.4318 -0.9525)
			(stroke
				(width 0)
				(type default)
			)
			(fill no)
			(layer "F.Fab")
		)
		(pad "1" smd custom
			(at 0 -0.4445 180)
			(size 0.1524 0.1524)
			(layers "F.Cu" "F.Mask" "F.Paste")
			(net "PCIE_TX_CAP_P56")
			(options
				(clearance outline)
				(anchor circle)
			)
			(primitives
				(gr_poly
					(pts
						(arc
							(start 0.3048 -0.2032)
							(mid 0.275042 -0.275042)
							(end 0.2032 -0.3048)
						)
						(arc
							(start -0.2032 -0.3048)
							(mid -0.275042 -0.275042)
							(end -0.3048 -0.2032)
						)
						(arc
							(start -0.3048 0.2032)
							(mid -0.275042 0.275042)
							(end -0.2032 0.3048)
						)
						(arc
							(start 0.2032 0.3048)
							(mid 0.275042 0.275042)
							(end 0.3048 0.2032)
						)
					)
					(width 0)
					(fill yes)
				)
			)
		)
		(pad "2" smd custom
			(at 0 0.4445 180)
			(size 0.1524 0.1524)
			(layers "F.Cu" "F.Mask" "F.Paste")
			(net "PCIE_TX_P56")
			(options
				(clearance outline)
				(anchor circle)
			)
			(primitives
				(gr_poly
					(pts
						(arc
							(start 0.3048 -0.2032)
							(mid 0.275042 -0.275042)
							(end 0.2032 -0.3048)
						)
						(arc
							(start -0.2032 -0.3048)
							(mid -0.275042 -0.275042)
							(end -0.3048 -0.2032)
						)
						(arc
							(start -0.3048 0.2032)
							(mid -0.275042 0.275042)
							(end -0.2032 0.3048)
						)
						(arc
							(start 0.2032 0.3048)
							(mid 0.275042 0.275042)
							(end 0.3048 0.2032)
						)
					)
					(width 0)
					(fill yes)
				)
			)
		)
	)
	(footprint ""
		(layer "F.Cu")
		(at 36.068 -115.57)
		(property "Reference" "R630"
			(at 0 0 0)
			(layer "F.SilkS")
			(hide yes)
			(effects
				(font
					(size 1.27 1.27)
				)
			)
		)
		(property "Value" "0R2J-2-GP"
			(at 0.064008 -3.993896 0)
			(unlocked yes)
			(layer "F.Fab")
			(hide yes)
			(effects
				(font
					(size 1.016 1.016)
					(thickness 0.1524)
				)
			)
		)
		(property "Device Type" "R402H16"
			(at 0.064008 -5.517896 0)
			(unlocked yes)
			(layer "F.Fab")
			(hide yes)
			(effects
				(font
					(size 1.016 1.016)
					(thickness 0.1524)
				)
			)
		)
		(duplicate_pad_numbers_are_jumpers no)
		(fp_line
			(start -0.508 -0.9398)
			(end -0.508 0.9398)
			(stroke
				(width 0.1524)
				(type default)
			)
			(layer "F.SilkS")
		)
		(fp_line
			(start 0.508 -0.9398)
			(end -0.508 -0.9398)
			(stroke
				(width 0.1524)
				(type default)
			)
			(layer "F.SilkS")
		)
		(fp_rect
			(start -0.508 0.9398)
			(end 0.508 -0.9398)
			(stroke
				(width 0)
				(type default)
			)
			(fill no)
			(layer "F.CrtYd")
		)
		(fp_rect
			(start -0.508 0.9398)
			(end 0.508 -0.9398)
			(stroke
				(width 0)
				(type default)
			)
			(fill no)
			(layer "F.Fab")
		)
		(pad "1" smd custom
			(at 0 -0.4445)
			(size 0.1397 0.1397)
			(layers "F.Cu" "F.Mask" "F.Paste")
			(net "FM_TPM_PRES_N_R")
			(options
				(clearance outline)
				(anchor circle)
			)
			(primitives
				(gr_poly
					(pts
						(arc
							(start -0.1778 -0.2794)
							(mid -0.249642 -0.249642)
							(end -0.2794 -0.1778)
						)
						(arc
							(start -0.2794 0.1778)
							(mid -0.249642 0.249642)
							(end -0.1778 0.2794)
						)
						(arc
							(start 0.1778 0.2794)
							(mid 0.249642 0.249642)
							(end 0.2794 0.1778)
						)
						(arc
							(start 0.2794 -0.1778)
							(mid 0.249642 -0.249642)
							(end 0.1778 -0.2794)
						)
					)
					(width 0)
					(fill yes)
				)
			)
		)
		(pad "2" smd custom
			(at 0 0.4445)
			(size 0.1397 0.1397)
			(layers "F.Cu" "F.Mask" "F.Paste")
			(net "FM_TPM_PRES_N")
			(options
				(clearance outline)
				(anchor circle)
			)
			(primitives
				(gr_poly
					(pts
						(arc
							(start -0.1778 -0.2794)
							(mid -0.249642 -0.249642)
							(end -0.2794 -0.1778)
						)
						(arc
							(start -0.2794 0.1778)
							(mid -0.249642 0.249642)
							(end -0.1778 0.2794)
						)
						(arc
							(start 0.1778 0.2794)
							(mid 0.249642 0.249642)
							(end 0.2794 0.1778)
						)
						(arc
							(start 0.2794 -0.1778)
							(mid 0.249642 -0.249642)
							(end 0.1778 -0.2794)
						)
					)
					(width 0)
					(fill yes)
				)
			)
		)
	)
	(footprint ""
		(layer "F.Cu")
		(at 313.563 -69.215 180)
		(property "Reference" "PTC4"
			(at 0 0 180)
			(layer "F.SilkS")
			(hide yes)
			(effects
				(font
					(size 1.27 1.27)
				)
			)
		)
		(property "Value" "SE470UF2VDM-GP"
			(at 0 -9.6012 180)
			(unlocked yes)
			(layer "F.Fab")
			(hide yes)
			(effects
				(font
					(size 1.016 1.016)
					(thickness 0.1524)
				)
			)
		)
		(property "Device Type" "CT7343H83"
			(at 0 -11.1252 180)
			(unlocked yes)
			(layer "F.Fab")
			(hide yes)
			(effects
				(font
					(size 1.016 1.016)
					(thickness 0.1524)
				)
			)
		)
		(duplicate_pad_numbers_are_jumpers no)
		(fp_line
			(start 2.286 4.8768)
			(end -2.286 4.8768)
			(stroke
				(width 0.1524)
				(type default)
			)
			(layer "F.SilkS")
		)
		(fp_line
			(start 2.286 2.032)
			(end 2.286 4.8768)
			(stroke
				(width 0.1524)
				(type default)
			)
			(layer "F.SilkS")
		)
		(fp_line
			(start 2.286 -2.032)
			(end 2.286 -4.8768)
			(stroke
				(width 0.1524)
				(type default)
			)
			(layer "F.SilkS")
		)
		(fp_line
			(start 2.286 -4.8768)
			(end -2.286 -4.8768)
			(stroke
				(width 0.1524)
				(type default)
			)
			(layer "F.SilkS")
		)
		(fp_line
			(start 2.1082 -4.699)
			(end -2.1082 -4.699)
			(stroke
				(width 0.508)
				(type default)
			)
			(layer "F.SilkS")
		)
		(fp_line
			(start -2.286 4.8768)
			(end -2.286 2.032)
			(stroke
				(width 0.1524)
				(type default)
			)
			(layer "F.SilkS")
		)
		(fp_line
			(start -2.286 -4.8768)
			(end -2.286 -2.032)
			(stroke
				(width 0.1524)
				(type default)
			)
			(layer "F.SilkS")
		)
		(fp_rect
			(start -2.1463 3.6449)
			(end 2.1463 -3.6449)
			(stroke
				(width 0)
				(type default)
			)
			(fill no)
			(layer "F.CrtYd")
		)
		(fp_poly
			(pts
				(xy -2.54 4.953) (xy -2.54 4.2926) (xy -3.81 4.2926) (xy -3.81 -4.2926) (xy -2.54 -4.2926) (xy -2.54 -4.953)
				(xy 2.54 -4.953) (xy 2.54 -4.2926) (xy 3.81 -4.2926) (xy 3.81 -1.6256) (xy 2.1463 -1.6256) (xy 2.1463 -3.6449)
				(xy -2.1463 -3.6449) (xy -2.1463 3.6449) (xy 2.1463 3.6449) (xy 2.1463 -1.6129) (xy 3.81 -1.6129)
				(xy 3.81 4.2926) (xy 2.54 4.2926) (xy 2.54 4.953)
			)
			(stroke
				(width 0)
				(type default)
			)
			(fill no)
			(layer "F.CrtYd")
		)
		(fp_rect
			(start 2.54 4.2926)
			(end 3.81 -4.2926)
			(stroke
				(width 0)
				(type default)
			)
			(fill no)
			(layer "F.Fab")
		)
		(fp_rect
			(start -2.54 4.953)
			(end 2.54 -4.953)
			(stroke
				(width 0)
				(type default)
			)
			(fill no)
			(layer "F.Fab")
		)
		(fp_rect
			(start -3.81 4.2926)
			(end -2.54 -4.2926)
			(stroke
				(width 0)
				(type default)
			)
			(fill no)
			(layer "F.Fab")
		)
		(pad "1" smd rect
			(at 0 -3.1496 180)
			(size 2.413 2.286)
			(layers "F.Cu" "F.Mask" "F.Paste")
			(net "P0V9_E")
		)
		(pad "2" smd rect
			(at 0 3.1496 180)
			(size 2.413 2.286)
			(layers "F.Cu" "F.Mask" "F.Paste")
			(net "GND")
		)
		(zone
			(layer "F.Cu")
			(hatch none 0.5)
			(connect_pads
				(clearance 0)
			)
			(min_thickness 0.25)
			(keepout
				(tracks allowed)
				(vias not_allowed)
				(pads allowed)
				(copperpour not_allowed)
				(footprints allowed)
			)
			(placement
				(enabled no)
				(sheetname "")
			)
			(fill
				(thermal_gap 0.5)
				(thermal_bridge_width 0.5)
				(island_removal_mode 0)
			)
			(polygon
				(pts
					(xy 312.0517 -67.5259) (xy 312.0517 -64.6176) (xy 315.0743 -64.6176) (xy 315.0743 -67.5132) (xy 315.0743 -67.8434)
					(xy 312.0517 -67.8434)
				)
			)
		)
		(zone
			(layer "F.Cu")
			(hatch none 0.5)
			(connect_pads
				(clearance 0)
			)
			(min_thickness 0.25)
			(keepout
				(tracks allowed)
				(vias not_allowed)
				(pads allowed)
				(copperpour not_allowed)
				(footprints allowed)
			)
			(placement
				(enabled no)
				(sheetname "")
			)
			(fill
				(thermal_gap 0.5)
				(thermal_bridge_width 0.5)
				(island_removal_mode 0)
			)
			(polygon
				(pts
					(xy 315.0743 -73.8124) (xy 312.0517 -73.8124) (xy 312.0517 -70.9168) (xy 312.0517 -70.5866) (xy 315.0743 -70.5866)
					(xy 315.0743 -70.9168)
				)
			)
		)
	)
	(footprint ""
		(layer "F.Cu")
		(at 286.4866 -33.8582 90)
		(property "Reference" "C8"
			(at 0 0 90)
			(layer "F.SilkS")
			(hide yes)
			(effects
				(font
					(size 1.27 1.27)
				)
			)
		)
		(property "Value" "SCD22U10V2KX-1GP"
			(at 1.1811 -2.7051 90)
			(unlocked yes)
			(layer "F.Fab")
			(hide yes)
			(effects
				(font
					(size 1.016 1.016)
					(thickness 0.1524)
				)
			)
		)
		(property "Device Type" "C402H22"
			(at 1.1811 -4.2291 90)
			(unlocked yes)
			(layer "F.Fab")
			(hide yes)
			(effects
				(font
					(size 1.016 1.016)
					(thickness 0.1524)
				)
			)
		)
		(duplicate_pad_numbers_are_jumpers no)
		(fp_rect
			(start -0.4318 0.9525)
			(end 0.4318 -0.9525)
			(stroke
				(width 0)
				(type default)
			)
			(fill no)
			(layer "F.CrtYd")
		)
		(fp_rect
			(start -0.4318 0.9525)
			(end 0.4318 -0.9525)
			(stroke
				(width 0)
				(type default)
			)
			(fill no)
			(layer "F.Fab")
		)
		(pad "1" smd custom
			(at 0 -0.4445 90)
			(size 0.1524 0.1524)
			(layers "F.Cu" "F.Mask" "F.Paste")
			(net "PCIE_TX_CAP_N2")
			(options
				(clearance outline)
				(anchor circle)
			)
			(primitives
				(gr_poly
					(pts
						(arc
							(start 0.3048 -0.2032)
							(mid 0.275042 -0.275042)
							(end 0.2032 -0.3048)
						)
						(arc
							(start -0.2032 -0.3048)
							(mid -0.275042 -0.275042)
							(end -0.3048 -0.2032)
						)
						(arc
							(start -0.3048 0.2032)
							(mid -0.275042 0.275042)
							(end -0.2032 0.3048)
						)
						(arc
							(start 0.2032 0.3048)
							(mid 0.275042 0.275042)
							(end 0.3048 0.2032)
						)
					)
					(width 0)
					(fill yes)
				)
			)
		)
		(pad "2" smd custom
			(at 0 0.4445 90)
			(size 0.1524 0.1524)
			(layers "F.Cu" "F.Mask" "F.Paste")
			(net "PCIE_TX_N2")
			(options
				(clearance outline)
				(anchor circle)
			)
			(primitives
				(gr_poly
					(pts
						(arc
							(start 0.3048 -0.2032)
							(mid 0.275042 -0.275042)
							(end 0.2032 -0.3048)
						)
						(arc
							(start -0.2032 -0.3048)
							(mid -0.275042 -0.275042)
							(end -0.3048 -0.2032)
						)
						(arc
							(start -0.3048 0.2032)
							(mid -0.275042 0.275042)
							(end -0.2032 0.3048)
						)
						(arc
							(start 0.2032 0.3048)
							(mid 0.275042 0.275042)
							(end 0.3048 0.2032)
						)
					)
					(width 0)
					(fill yes)
				)
			)
		)
	)
	(footprint ""
		(layer "F.Cu")
		(at 37.222176 -61.854842 90)
		(property "Reference" "TC15"
			(at 0 0 90)
			(layer "F.SilkS")
			(hide yes)
			(effects
				(font
					(size 1.27 1.27)
				)
			)
		)
		(property "Value" "SC22U25V6KX-GP-U"
			(at -2.860802 -5.279644 90)
			(unlocked yes)
			(layer "F.Fab")
			(hide yes)
			(effects
				(font
					(size 1.016 1.016)
					(thickness 0.1524)
				)
			)
		)
		(property "Device Type" "C1206-TO0D3H75"
			(at -2.860802 -6.803644 90)
			(unlocked yes)
			(layer "F.Fab")
			(hide yes)
			(effects
				(font
					(size 1.016 1.016)
					(thickness 0.1524)
				)
			)
		)
		(duplicate_pad_numbers_are_jumpers no)
		(fp_line
			(start 1.3081 -2.3749)
			(end 1.3081 2.3749)
			(stroke
				(width 0.1524)
				(type default)
			)
			(layer "F.SilkS")
		)
		(fp_line
			(start -1.3081 -2.3749)
			(end 1.3081 -2.3749)
			(stroke
				(width 0.1524)
				(type default)
			)
			(layer "F.SilkS")
		)
		(fp_line
			(start 1.3081 2.3749)
			(end -1.3081 2.3749)
			(stroke
				(width 0.1524)
				(type default)
			)
			(layer "F.SilkS")
		)
		(fp_line
			(start -1.3081 2.3749)
			(end -1.3081 -2.3749)
			(stroke
				(width 0.1524)
				(type default)
			)
			(layer "F.SilkS")
		)
		(fp_rect
			(start -0.8001 1.6002)
			(end 0.8001 -1.6002)
			(stroke
				(width 0)
				(type default)
			)
			(fill no)
			(layer "F.CrtYd")
		)
		(fp_poly
			(pts
				(xy -1.5621 2.4511) (xy -1.5621 1.6002) (xy 0.8001 1.6002) (xy 0.8001 -1.6002) (xy -0.8001 -1.6002)
				(xy -0.8001 1.5875) (xy -1.5621 1.5875) (xy -1.5621 -2.4511) (xy 1.5621 -2.4511) (xy 1.5621 2.4511)
			)
			(stroke
				(width 0)
				(type default)
			)
			(fill no)
			(layer "F.CrtYd")
		)
		(fp_rect
			(start -1.5621 2.4511)
			(end 1.5621 -2.4511)
			(stroke
				(width 0)
				(type default)
			)
			(fill no)
			(layer "F.Fab")
		)
		(pad "1" smd rect
			(at 0 -1.392936 90)
			(size 2.1082 1.4478)
			(layers "F.Cu" "F.Mask" "F.Paste")
			(net "P5V_USB_BP1_F")
		)
		(pad "2" smd rect
			(at 0 1.392936 90)
			(size 2.1082 1.4478)
			(layers "F.Cu" "F.Mask" "F.Paste")
			(net "GND")
		)
	)
	(footprint ""
		(layer "F.Cu")
		(at 212.594444 -41.069514 -90)
		(property "Reference" "C639"
			(at 0 0 270)
			(layer "F.SilkS")
			(hide yes)
			(effects
				(font
					(size 1.27 1.27)
				)
			)
		)
		(property "Value" "SCD22U10V2KX-1GP"
			(at 1.1811 -2.7051 270)
			(unlocked yes)
			(layer "F.Fab")
			(hide yes)
			(effects
				(font
					(size 1.016 1.016)
					(thickness 0.1524)
				)
			)
		)
		(property "Device Type" "C402H22"
			(at 1.1811 -4.2291 270)
			(unlocked yes)
			(layer "F.Fab")
			(hide yes)
			(effects
				(font
					(size 1.016 1.016)
					(thickness 0.1524)
				)
			)
		)
		(duplicate_pad_numbers_are_jumpers no)
		(fp_rect
			(start -0.4318 0.9525)
			(end 0.4318 -0.9525)
			(stroke
				(width 0)
				(type default)
			)
			(fill no)
			(layer "F.CrtYd")
		)
		(fp_rect
			(start -0.4318 0.9525)
			(end 0.4318 -0.9525)
			(stroke
				(width 0)
				(type default)
			)
			(fill no)
			(layer "F.Fab")
		)
		(pad "1" smd custom
			(at 0 -0.4445 270)
			(size 0.1524 0.1524)
			(layers "F.Cu" "F.Mask" "F.Paste")
			(net "PCIE_TX_CAP_N78")
			(options
				(clearance outline)
				(anchor circle)
			)
			(primitives
				(gr_poly
					(pts
						(arc
							(start 0.3048 -0.2032)
							(mid 0.275042 -0.275042)
							(end 0.2032 -0.3048)
						)
						(arc
							(start -0.2032 -0.3048)
							(mid -0.275042 -0.275042)
							(end -0.3048 -0.2032)
						)
						(arc
							(start -0.3048 0.2032)
							(mid -0.275042 0.275042)
							(end -0.2032 0.3048)
						)
						(arc
							(start 0.2032 0.3048)
							(mid 0.275042 0.275042)
							(end 0.3048 0.2032)
						)
					)
					(width 0)
					(fill yes)
				)
			)
		)
		(pad "2" smd custom
			(at 0 0.4445 270)
			(size 0.1524 0.1524)
			(layers "F.Cu" "F.Mask" "F.Paste")
			(net "PCIE_TX_N78")
			(options
				(clearance outline)
				(anchor circle)
			)
			(primitives
				(gr_poly
					(pts
						(arc
							(start 0.3048 -0.2032)
							(mid 0.275042 -0.275042)
							(end 0.2032 -0.3048)
						)
						(arc
							(start -0.2032 -0.3048)
							(mid -0.275042 -0.275042)
							(end -0.3048 -0.2032)
						)
						(arc
							(start -0.3048 0.2032)
							(mid -0.275042 0.275042)
							(end -0.2032 0.3048)
						)
						(arc
							(start 0.2032 0.3048)
							(mid 0.275042 0.275042)
							(end 0.3048 0.2032)
						)
					)
					(width 0)
					(fill yes)
				)
			)
		)
	)
	(footprint ""
		(layer "F.Cu")
		(at 294.997378 -33.694116)
		(property "Reference" "C13"
			(at 0 0 0)
			(layer "F.SilkS")
			(hide yes)
			(effects
				(font
					(size 1.27 1.27)
				)
			)
		)
		(property "Value" "SCD22U10V2KX-1GP"
			(at 1.1811 -2.7051 0)
			(unlocked yes)
			(layer "F.Fab")
			(hide yes)
			(effects
				(font
					(size 1.016 1.016)
					(thickness 0.1524)
				)
			)
		)
		(property "Device Type" "C402H22"
			(at 1.1811 -4.2291 0)
			(unlocked yes)
			(layer "F.Fab")
			(hide yes)
			(effects
				(font
					(size 1.016 1.016)
					(thickness 0.1524)
				)
			)
		)
		(duplicate_pad_numbers_are_jumpers no)
		(fp_rect
			(start -0.4318 0.9525)
			(end 0.4318 -0.9525)
			(stroke
				(width 0)
				(type default)
			)
			(fill no)
			(layer "F.CrtYd")
		)
		(fp_rect
			(start -0.4318 0.9525)
			(end 0.4318 -0.9525)
			(stroke
				(width 0)
				(type default)
			)
			(fill no)
			(layer "F.Fab")
		)
		(pad "1" smd custom
			(at 0 -0.4445)
			(size 0.1524 0.1524)
			(layers "F.Cu" "F.Mask" "F.Paste")
			(net "PCIE_TX_CAP_N4")
			(options
				(clearance outline)
				(anchor circle)
			)
			(primitives
				(gr_poly
					(pts
						(arc
							(start 0.3048 -0.2032)
							(mid 0.275042 -0.275042)
							(end 0.2032 -0.3048)
						)
						(arc
							(start -0.2032 -0.3048)
							(mid -0.275042 -0.275042)
							(end -0.3048 -0.2032)
						)
						(arc
							(start -0.3048 0.2032)
							(mid -0.275042 0.275042)
							(end -0.2032 0.3048)
						)
						(arc
							(start 0.2032 0.3048)
							(mid 0.275042 0.275042)
							(end 0.3048 0.2032)
						)
					)
					(width 0)
					(fill yes)
				)
			)
		)
		(pad "2" smd custom
			(at 0 0.4445)
			(size 0.1524 0.1524)
			(layers "F.Cu" "F.Mask" "F.Paste")
			(net "PCIE_TX_N4")
			(options
				(clearance outline)
				(anchor circle)
			)
			(primitives
				(gr_poly
					(pts
						(arc
							(start 0.3048 -0.2032)
							(mid 0.275042 -0.275042)
							(end 0.2032 -0.3048)
						)
						(arc
							(start -0.2032 -0.3048)
							(mid -0.275042 -0.275042)
							(end -0.3048 -0.2032)
						)
						(arc
							(start -0.3048 0.2032)
							(mid -0.275042 0.275042)
							(end -0.2032 0.3048)
						)
						(arc
							(start 0.2032 0.3048)
							(mid 0.275042 0.275042)
							(end 0.3048 0.2032)
						)
					)
					(width 0)
					(fill yes)
				)
			)
		)
	)
	(footprint ""
		(layer "F.Cu")
		(at 51.181 -147.447 -90)
		(property "Reference" "C326"
			(at 0 0 270)
			(layer "F.SilkS")
			(hide yes)
			(effects
				(font
					(size 1.27 1.27)
				)
			)
		)
		(property "Value" "SCD1U16V2KX-3GP"
			(at 1.1811 -2.7051 270)
			(unlocked yes)
			(layer "F.Fab")
			(hide yes)
			(effects
				(font
					(size 1.016 1.016)
					(thickness 0.1524)
				)
			)
		)
		(property "Device Type" "C402H22"
			(at 1.1811 -4.2291 270)
			(unlocked yes)
			(layer "F.Fab")
			(hide yes)
			(effects
				(font
					(size 1.016 1.016)
					(thickness 0.1524)
				)
			)
		)
		(duplicate_pad_numbers_are_jumpers no)
		(fp_rect
			(start -0.4318 0.9525)
			(end 0.4318 -0.9525)
			(stroke
				(width 0)
				(type default)
			)
			(fill no)
			(layer "F.CrtYd")
		)
		(fp_rect
			(start -0.4318 0.9525)
			(end 0.4318 -0.9525)
			(stroke
				(width 0)
				(type default)
			)
			(fill no)
			(layer "F.Fab")
		)
		(pad "1" smd custom
			(at 0 -0.4445 270)
			(size 0.1524 0.1524)
			(layers "F.Cu" "F.Mask" "F.Paste")
			(net "P3V3_STBY")
			(options
				(clearance outline)
				(anchor circle)
			)
			(primitives
				(gr_poly
					(pts
						(arc
							(start 0.3048 -0.2032)
							(mid 0.275042 -0.275042)
							(end 0.2032 -0.3048)
						)
						(arc
							(start -0.2032 -0.3048)
							(mid -0.275042 -0.275042)
							(end -0.3048 -0.2032)
						)
						(arc
							(start -0.3048 0.2032)
							(mid -0.275042 0.275042)
							(end -0.2032 0.3048)
						)
						(arc
							(start 0.2032 0.3048)
							(mid 0.275042 0.275042)
							(end 0.3048 0.2032)
						)
					)
					(width 0)
					(fill yes)
				)
			)
		)
		(pad "2" smd custom
			(at 0 0.4445 270)
			(size 0.1524 0.1524)
			(layers "F.Cu" "F.Mask" "F.Paste")
			(net "GND")
			(options
				(clearance outline)
				(anchor circle)
			)
			(primitives
				(gr_poly
					(pts
						(arc
							(start 0.3048 -0.2032)
							(mid 0.275042 -0.275042)
							(end 0.2032 -0.3048)
						)
						(arc
							(start -0.2032 -0.3048)
							(mid -0.275042 -0.275042)
							(end -0.3048 -0.2032)
						)
						(arc
							(start -0.3048 0.2032)
							(mid -0.275042 0.275042)
							(end -0.2032 0.3048)
						)
						(arc
							(start 0.2032 0.3048)
							(mid 0.275042 0.275042)
							(end 0.3048 0.2032)
						)
					)
					(width 0)
					(fill yes)
				)
			)
		)
	)
	(footprint ""
		(layer "F.Cu")
		(at 129.159 -208.8896 180)
		(property "Reference" "R7955"
			(at 0 0 180)
			(layer "F.SilkS")
			(hide yes)
			(effects
				(font
					(size 1.27 1.27)
				)
			)
		)
		(property "Value" "0R2J-2-GP"
			(at 0.064008 -3.993896 180)
			(unlocked yes)
			(layer "F.Fab")
			(hide yes)
			(effects
				(font
					(size 1.016 1.016)
					(thickness 0.1524)
				)
			)
		)
		(property "Device Type" "R402H16"
			(at 0.064008 -5.517896 180)
			(unlocked yes)
			(layer "F.Fab")
			(hide yes)
			(effects
				(font
					(size 1.016 1.016)
					(thickness 0.1524)
				)
			)
		)
		(duplicate_pad_numbers_are_jumpers no)
		(fp_line
			(start 0.508 -0.9398)
			(end -0.508 -0.9398)
			(stroke
				(width 0.1524)
				(type default)
			)
			(layer "F.SilkS")
		)
		(fp_line
			(start -0.508 -0.9398)
			(end -0.508 0.9398)
			(stroke
				(width 0.1524)
				(type default)
			)
			(layer "F.SilkS")
		)
		(fp_rect
			(start -0.508 0.9398)
			(end 0.508 -0.9398)
			(stroke
				(width 0)
				(type default)
			)
			(fill no)
			(layer "F.CrtYd")
		)
		(fp_rect
			(start -0.508 0.9398)
			(end 0.508 -0.9398)
			(stroke
				(width 0)
				(type default)
			)
			(fill no)
			(layer "F.Fab")
		)
		(pad "1" smd custom
			(at 0 -0.4445 180)
			(size 0.1397 0.1397)
			(layers "F.Cu" "F.Mask" "F.Paste")
			(net "SSD_PWREN7")
			(options
				(clearance outline)
				(anchor circle)
			)
			(primitives
				(gr_poly
					(pts
						(arc
							(start -0.1778 -0.2794)
							(mid -0.249642 -0.249642)
							(end -0.2794 -0.1778)
						)
						(arc
							(start -0.2794 0.1778)
							(mid -0.249642 0.249642)
							(end -0.1778 0.2794)
						)
						(arc
							(start 0.1778 0.2794)
							(mid 0.249642 0.249642)
							(end 0.2794 0.1778)
						)
						(arc
							(start 0.2794 -0.1778)
							(mid 0.249642 -0.249642)
							(end 0.1778 -0.2794)
						)
					)
					(width 0)
					(fill yes)
				)
			)
		)
		(pad "2" smd custom
			(at 0 0.4445 180)
			(size 0.1397 0.1397)
			(layers "F.Cu" "F.Mask" "F.Paste")
			(net "SSD_PWREN7_R")
			(options
				(clearance outline)
				(anchor circle)
			)
			(primitives
				(gr_poly
					(pts
						(arc
							(start -0.1778 -0.2794)
							(mid -0.249642 -0.249642)
							(end -0.2794 -0.1778)
						)
						(arc
							(start -0.2794 0.1778)
							(mid -0.249642 0.249642)
							(end -0.1778 0.2794)
						)
						(arc
							(start 0.1778 0.2794)
							(mid 0.249642 0.249642)
							(end 0.2794 0.1778)
						)
						(arc
							(start 0.2794 -0.1778)
							(mid 0.249642 -0.249642)
							(end 0.1778 -0.2794)
						)
					)
					(width 0)
					(fill yes)
				)
			)
		)
	)
	(footprint ""
		(layer "F.Cu")
		(at 246.7356 -13.3604 180)
		(property "Reference" "C464"
			(at 0 0 180)
			(layer "F.SilkS")
			(hide yes)
			(effects
				(font
					(size 1.27 1.27)
				)
			)
		)
		(property "Value" "SC4D7U16V5KX-1-GP"
			(at -0.0762 -6.1214 180)
			(unlocked yes)
			(layer "F.Fab")
			(hide yes)
			(effects
				(font
					(size 1.016 1.016)
					(thickness 0.1524)
				)
			)
		)
		(property "Device Type" "C805H56"
			(at -0.0762 -8.1534 180)
			(unlocked yes)
			(layer "F.Fab")
			(hide yes)
			(effects
				(font
					(size 1.016 1.016)
					(thickness 0.1524)
				)
			)
		)
		(duplicate_pad_numbers_are_jumpers no)
		(fp_line
			(start 0.635 0)
			(end -0.635 0)
			(stroke
				(width 0.508)
				(type default)
			)
			(layer "F.SilkS")
		)
		(fp_rect
			(start -0.9652 1.778)
			(end 0.9652 -1.778)
			(stroke
				(width 0)
				(type default)
			)
			(fill no)
			(layer "F.CrtYd")
		)
		(fp_poly
			(pts
				(xy -0.9652 -1.778) (xy 0.9652 -1.778) (xy 0.9652 1.778) (xy -0.9652 1.778)
			)
			(stroke
				(width 0)
				(type default)
			)
			(fill no)
			(layer "F.Fab")
		)
		(pad "1" smd rect
			(at 0 -0.9652 180)
			(size 1.397 1.143)
			(layers "F.Cu" "F.Mask" "F.Paste")
			(net "DUT_VDDO")
		)
		(pad "2" smd rect
			(at 0 0.9652 180)
			(size 1.397 1.143)
			(layers "F.Cu" "F.Mask" "F.Paste")
			(net "GND")
		)
	)
	(footprint ""
		(layer "F.Cu")
		(at 18.864326 -151.43988)
		(property "Reference" "U25"
			(at 0 0 0)
			(layer "F.SilkS")
			(hide yes)
			(effects
				(font
					(size 1.27 1.27)
				)
			)
		)
		(property "Value" "SN74LVC1G07DCKRG4-2-GP"
			(at -2.3368 -8.6868 0)
			(unlocked yes)
			(layer "F.Fab")
			(hide yes)
			(effects
				(font
					(size 1.016 1.016)
					(thickness 0.1524)
				)
			)
		)
		(property "Device Type" "SC70-5H44"
			(at -2.3114 -10.414 0)
			(unlocked yes)
			(layer "F.Fab")
			(hide yes)
			(effects
				(font
					(size 1.016 1.016)
					(thickness 0.1524)
				)
			)
		)
		(duplicate_pad_numbers_are_jumpers no)
		(fp_line
			(start -1.27 -1.7018)
			(end 1.27 -1.7018)
			(stroke
				(width 0.1524)
				(type default)
			)
			(layer "F.SilkS")
		)
		(fp_line
			(start -1.27 1.7018)
			(end -1.27 -1.7018)
			(stroke
				(width 0.1524)
				(type default)
			)
			(layer "F.SilkS")
		)
		(fp_line
			(start 0.6604 -1.8034)
			(end 1.3843 -1.8034)
			(stroke
				(width 0.3302)
				(type default)
			)
			(layer "F.SilkS")
		)
		(fp_line
			(start 1.27 -1.7018)
			(end 1.27 1.7018)
			(stroke
				(width 0.1524)
				(type default)
			)
			(layer "F.SilkS")
		)
		(fp_line
			(start 1.27 1.7018)
			(end -1.27 1.7018)
			(stroke
				(width 0.1524)
				(type default)
			)
			(layer "F.SilkS")
		)
		(fp_line
			(start 1.3843 -1.8034)
			(end 1.3843 -1.1176)
			(stroke
				(width 0.3302)
				(type default)
			)
			(layer "F.SilkS")
		)
		(fp_rect
			(start -1.524 1.9558)
			(end 1.524 -1.9558)
			(stroke
				(width 0)
				(type default)
			)
			(fill no)
			(layer "F.CrtYd")
		)
		(fp_poly
			(pts
				(xy -1.524 -1.9558) (xy 1.524 -1.9558) (xy 1.524 1.9558) (xy -1.524 1.9558)
			)
			(stroke
				(width 0)
				(type default)
			)
			(fill no)
			(layer "F.Fab")
		)
		(pad "1" smd rect
			(at 0.65024 -0.8255)
			(size 0.4064 1.2192)
			(layers "F.Cu" "F.Mask" "F.Paste")
			(net "Net_2089")
		)
		(pad "2" smd rect
			(at 0 -0.8255)
			(size 0.4064 1.2192)
			(layers "F.Cu" "F.Mask" "F.Paste")
			(net "FM_BMC_RESET_N")
		)
		(pad "3" smd rect
			(at -0.65024 -0.8255)
			(size 0.4064 1.2192)
			(layers "F.Cu" "F.Mask" "F.Paste")
			(net "GND")
		)
		(pad "4" smd rect
			(at -0.65024 0.8255)
			(size 0.4064 1.2192)
			(layers "F.Cu" "F.Mask" "F.Paste")
			(net "RST_BMC_DDR3_R_N")
		)
		(pad "5" smd rect
			(at 0.65024 0.8255)
			(size 0.4064 1.2192)
			(layers "F.Cu" "F.Mask" "F.Paste")
			(net "P3V3_STBY")
		)
	)
	(footprint ""
		(layer "F.Cu")
		(at 65.913 -33.782 180)
		(property "Reference" "PG3"
			(at 0 0 180)
			(layer "F.SilkS")
			(hide yes)
			(effects
				(font
					(size 1.27 1.27)
				)
			)
		)
		(property "Value" "COPPER-CLOSE-GP-U"
			(at 0.0762 -2.8702 180)
			(unlocked yes)
			(layer "F.Fab")
			(hide yes)
			(effects
				(font
					(size 1.016 1.016)
					(thickness 0.1524)
				)
			)
		)
		(property "Device Type" "CON2C-U"
			(at 0.0762 -4.3942 180)
			(unlocked yes)
			(layer "F.Fab")
			(hide yes)
			(effects
				(font
					(size 1.016 1.016)
					(thickness 0.1524)
				)
			)
		)
		(duplicate_pad_numbers_are_jumpers no)
		(fp_rect
			(start -0.9398 0.9652)
			(end 0.9398 -0.9652)
			(stroke
				(width 0)
				(type default)
			)
			(fill no)
			(layer "F.CrtYd")
		)
		(fp_rect
			(start -0.9398 0.9652)
			(end 0.9398 -0.9652)
			(stroke
				(width 0)
				(type default)
			)
			(fill no)
			(layer "F.Fab")
		)
		(pad "1" smd custom
			(at 0 -0.5334 180)
			(size 0.17145 0.17145)
			(layers "F.Cu" "F.Mask" "F.Paste")
			(net "AGND_P3V3_STBY")
			(options
				(clearance outline)
				(anchor circle)
			)
			(primitives
				(gr_poly
					(pts
						(xy -0.127 0.3429) (xy -0.127 0.1651) (xy -0.635 -0.3429) (xy 0.635 -0.3429) (xy 0.127 0.1651)
						(xy 0.127 0.3429)
					)
					(width 0)
					(fill yes)
				)
			)
		)
		(pad "2" smd custom
			(at 0 0.5334 180)
			(size 0.17145 0.17145)
			(layers "F.Cu" "F.Mask" "F.Paste")
			(net "GND")
			(options
				(clearance outline)
				(anchor circle)
			)
			(primitives
				(gr_poly
					(pts
						(xy -0.635 0.3429) (xy -0.127 -0.1651) (xy -0.127 -0.3429) (xy 0.127 -0.3429) (xy 0.127 -0.1651)
						(xy 0.635 0.3429)
					)
					(width 0)
					(fill yes)
				)
			)
		)
	)
	(footprint ""
		(layer "F.Cu")
		(at 69.699124 -183.235092 180)
		(property "Reference" "R517"
			(at 0 0 180)
			(layer "F.SilkS")
			(hide yes)
			(effects
				(font
					(size 1.27 1.27)
				)
			)
		)
		(property "Value" "10KR2F-2-GP"
			(at 0.064008 -3.993896 180)
			(unlocked yes)
			(layer "F.Fab")
			(hide yes)
			(effects
				(font
					(size 1.016 1.016)
					(thickness 0.1524)
				)
			)
		)
		(property "Device Type" "R402H16"
			(at 0.064008 -5.517896 180)
			(unlocked yes)
			(layer "F.Fab")
			(hide yes)
			(effects
				(font
					(size 1.016 1.016)
					(thickness 0.1524)
				)
			)
		)
		(duplicate_pad_numbers_are_jumpers no)
		(fp_line
			(start 0.508 -0.9398)
			(end -0.508 -0.9398)
			(stroke
				(width 0.1524)
				(type default)
			)
			(layer "F.SilkS")
		)
		(fp_line
			(start -0.508 -0.9398)
			(end -0.508 0.9398)
			(stroke
				(width 0.1524)
				(type default)
			)
			(layer "F.SilkS")
		)
		(fp_rect
			(start -0.508 0.9398)
			(end 0.508 -0.9398)
			(stroke
				(width 0)
				(type default)
			)
			(fill no)
			(layer "F.CrtYd")
		)
		(fp_rect
			(start -0.508 0.9398)
			(end 0.508 -0.9398)
			(stroke
				(width 0)
				(type default)
			)
			(fill no)
			(layer "F.Fab")
		)
		(pad "1" smd custom
			(at 0 -0.4445 180)
			(size 0.1397 0.1397)
			(layers "F.Cu" "F.Mask" "F.Paste")
			(net "GND")
			(options
				(clearance outline)
				(anchor circle)
			)
			(primitives
				(gr_poly
					(pts
						(arc
							(start -0.1778 -0.2794)
							(mid -0.249642 -0.249642)
							(end -0.2794 -0.1778)
						)
						(arc
							(start -0.2794 0.1778)
							(mid -0.249642 0.249642)
							(end -0.1778 0.2794)
						)
						(arc
							(start 0.1778 0.2794)
							(mid 0.249642 0.249642)
							(end 0.2794 0.1778)
						)
						(arc
							(start 0.2794 -0.1778)
							(mid 0.249642 -0.249642)
							(end 0.1778 -0.2794)
						)
					)
					(width 0)
					(fill yes)
				)
			)
		)
		(pad "2" smd custom
			(at 0 0.4445 180)
			(size 0.1397 0.1397)
			(layers "F.Cu" "F.Mask" "F.Paste")
			(net "IOEXP1_AD1")
			(options
				(clearance outline)
				(anchor circle)
			)
			(primitives
				(gr_poly
					(pts
						(arc
							(start -0.1778 -0.2794)
							(mid -0.249642 -0.249642)
							(end -0.2794 -0.1778)
						)
						(arc
							(start -0.2794 0.1778)
							(mid -0.249642 0.249642)
							(end -0.1778 0.2794)
						)
						(arc
							(start 0.1778 0.2794)
							(mid 0.249642 0.249642)
							(end 0.2794 0.1778)
						)
						(arc
							(start 0.2794 -0.1778)
							(mid 0.249642 -0.249642)
							(end 0.1778 -0.2794)
						)
					)
					(width 0)
					(fill yes)
				)
			)
		)
	)
	(footprint ""
		(layer "F.Cu")
		(at 215.991948 -212.420454 180)
		(property "Reference" "C109"
			(at 0 0 180)
			(layer "F.SilkS")
			(hide yes)
			(effects
				(font
					(size 1.27 1.27)
				)
			)
		)
		(property "Value" "SCD22U10V2KX-1GP"
			(at 1.1811 -2.7051 180)
			(unlocked yes)
			(layer "F.Fab")
			(hide yes)
			(effects
				(font
					(size 1.016 1.016)
					(thickness 0.1524)
				)
			)
		)
		(property "Device Type" "C402H22"
			(at 1.1811 -4.2291 180)
			(unlocked yes)
			(layer "F.Fab")
			(hide yes)
			(effects
				(font
					(size 1.016 1.016)
					(thickness 0.1524)
				)
			)
		)
		(duplicate_pad_numbers_are_jumpers no)
		(fp_rect
			(start -0.4318 0.9525)
			(end 0.4318 -0.9525)
			(stroke
				(width 0)
				(type default)
			)
			(fill no)
			(layer "F.CrtYd")
		)
		(fp_rect
			(start -0.4318 0.9525)
			(end 0.4318 -0.9525)
			(stroke
				(width 0)
				(type default)
			)
			(fill no)
			(layer "F.Fab")
		)
		(pad "1" smd custom
			(at 0 -0.4445 180)
			(size 0.1524 0.1524)
			(layers "F.Cu" "F.Mask" "F.Paste")
			(net "PCIE_TX_CAP_P38")
			(options
				(clearance outline)
				(anchor circle)
			)
			(primitives
				(gr_poly
					(pts
						(arc
							(start 0.3048 -0.2032)
							(mid 0.275042 -0.275042)
							(end 0.2032 -0.3048)
						)
						(arc
							(start -0.2032 -0.3048)
							(mid -0.275042 -0.275042)
							(end -0.3048 -0.2032)
						)
						(arc
							(start -0.3048 0.2032)
							(mid -0.275042 0.275042)
							(end -0.2032 0.3048)
						)
						(arc
							(start 0.2032 0.3048)
							(mid 0.275042 0.275042)
							(end 0.3048 0.2032)
						)
					)
					(width 0)
					(fill yes)
				)
			)
		)
		(pad "2" smd custom
			(at 0 0.4445 180)
			(size 0.1524 0.1524)
			(layers "F.Cu" "F.Mask" "F.Paste")
			(net "PCIE_TX_P38")
			(options
				(clearance outline)
				(anchor circle)
			)
			(primitives
				(gr_poly
					(pts
						(arc
							(start 0.3048 -0.2032)
							(mid 0.275042 -0.275042)
							(end 0.2032 -0.3048)
						)
						(arc
							(start -0.2032 -0.3048)
							(mid -0.275042 -0.275042)
							(end -0.3048 -0.2032)
						)
						(arc
							(start -0.3048 0.2032)
							(mid -0.275042 0.275042)
							(end -0.2032 0.3048)
						)
						(arc
							(start 0.2032 0.3048)
							(mid 0.275042 0.275042)
							(end 0.3048 0.2032)
						)
					)
					(width 0)
					(fill yes)
				)
			)
		)
	)
	(footprint ""
		(layer "F.Cu")
		(at 253.04242 -11.364976 180)
		(property "Reference" "R3602"
			(at 0 0 180)
			(layer "F.SilkS")
			(hide yes)
			(effects
				(font
					(size 1.27 1.27)
				)
			)
		)
		(property "Value" "1KR2F-3-GP"
			(at 0.064008 -3.993896 180)
			(unlocked yes)
			(layer "F.Fab")
			(hide yes)
			(effects
				(font
					(size 1.016 1.016)
					(thickness 0.1524)
				)
			)
		)
		(property "Device Type" "R402H16"
			(at 0.064008 -5.517896 180)
			(unlocked yes)
			(layer "F.Fab")
			(hide yes)
			(effects
				(font
					(size 1.016 1.016)
					(thickness 0.1524)
				)
			)
		)
		(duplicate_pad_numbers_are_jumpers no)
		(fp_line
			(start 0.508 -0.9398)
			(end -0.508 -0.9398)
			(stroke
				(width 0.1524)
				(type default)
			)
			(layer "F.SilkS")
		)
		(fp_line
			(start -0.508 -0.9398)
			(end -0.508 0.9398)
			(stroke
				(width 0.1524)
				(type default)
			)
			(layer "F.SilkS")
		)
		(fp_rect
			(start -0.508 0.9398)
			(end 0.508 -0.9398)
			(stroke
				(width 0)
				(type default)
			)
			(fill no)
			(layer "F.CrtYd")
		)
		(fp_rect
			(start -0.508 0.9398)
			(end 0.508 -0.9398)
			(stroke
				(width 0)
				(type default)
			)
			(fill no)
			(layer "F.Fab")
		)
		(pad "1" smd custom
			(at 0 -0.4445 180)
			(size 0.1397 0.1397)
			(layers "F.Cu" "F.Mask" "F.Paste")
			(net "MAX6654_ADD1")
			(options
				(clearance outline)
				(anchor circle)
			)
			(primitives
				(gr_poly
					(pts
						(arc
							(start -0.1778 -0.2794)
							(mid -0.249642 -0.249642)
							(end -0.2794 -0.1778)
						)
						(arc
							(start -0.2794 0.1778)
							(mid -0.249642 0.249642)
							(end -0.1778 0.2794)
						)
						(arc
							(start 0.1778 0.2794)
							(mid 0.249642 0.249642)
							(end 0.2794 0.1778)
						)
						(arc
							(start 0.2794 -0.1778)
							(mid 0.249642 -0.249642)
							(end 0.1778 -0.2794)
						)
					)
					(width 0)
					(fill yes)
				)
			)
		)
		(pad "2" smd custom
			(at 0 0.4445 180)
			(size 0.1397 0.1397)
			(layers "F.Cu" "F.Mask" "F.Paste")
			(net "GND")
			(options
				(clearance outline)
				(anchor circle)
			)
			(primitives
				(gr_poly
					(pts
						(arc
							(start -0.1778 -0.2794)
							(mid -0.249642 -0.249642)
							(end -0.2794 -0.1778)
						)
						(arc
							(start -0.2794 0.1778)
							(mid -0.249642 0.249642)
							(end -0.1778 0.2794)
						)
						(arc
							(start 0.1778 0.2794)
							(mid 0.249642 0.249642)
							(end 0.2794 0.1778)
						)
						(arc
							(start 0.2794 -0.1778)
							(mid 0.249642 -0.249642)
							(end 0.1778 -0.2794)
						)
					)
					(width 0)
					(fill yes)
				)
			)
		)
	)
	(footprint ""
		(layer "F.Cu")
		(at 7.874 -106.68)
		(property "Reference" "PC80"
			(at 0 0 0)
			(layer "F.SilkS")
			(hide yes)
			(effects
				(font
					(size 1.27 1.27)
				)
			)
		)
		(property "Value" "SC10U6D3V5KX-4GP"
			(at -0.0762 -6.1214 0)
			(unlocked yes)
			(layer "F.Fab")
			(hide yes)
			(effects
				(font
					(size 1.016 1.016)
					(thickness 0.1524)
				)
			)
		)
		(property "Device Type" "C805H58"
			(at -0.0762 -8.1534 0)
			(unlocked yes)
			(layer "F.Fab")
			(hide yes)
			(effects
				(font
					(size 1.016 1.016)
					(thickness 0.1524)
				)
			)
		)
		(duplicate_pad_numbers_are_jumpers no)
		(fp_line
			(start 0.635 0)
			(end -0.635 0)
			(stroke
				(width 0.508)
				(type default)
			)
			(layer "F.SilkS")
		)
		(fp_rect
			(start -0.9652 1.778)
			(end 0.9652 -1.778)
			(stroke
				(width 0)
				(type default)
			)
			(fill no)
			(layer "F.CrtYd")
		)
		(fp_poly
			(pts
				(xy -0.9652 -1.778) (xy 0.9652 -1.778) (xy 0.9652 1.778) (xy -0.9652 1.778)
			)
			(stroke
				(width 0)
				(type default)
			)
			(fill no)
			(layer "F.Fab")
		)
		(pad "1" smd rect
			(at 0 -0.9652)
			(size 1.397 1.143)
			(layers "F.Cu" "F.Mask" "F.Paste")
			(net "VR_P1V26_STBY_BIAS")
		)
		(pad "2" smd rect
			(at 0 0.9652)
			(size 1.397 1.143)
			(layers "F.Cu" "F.Mask" "F.Paste")
			(net "GND")
		)
	)
	(footprint ""
		(layer "F.Cu")
		(at 235.966 -6.92658 -90)
		(property "Reference" "C322"
			(at 0 0 270)
			(layer "F.SilkS")
			(hide yes)
			(effects
				(font
					(size 1.27 1.27)
				)
			)
		)
		(property "Value" "SCD1U16V2KX-3GP"
			(at 1.1811 -2.7051 270)
			(unlocked yes)
			(layer "F.Fab")
			(hide yes)
			(effects
				(font
					(size 1.016 1.016)
					(thickness 0.1524)
				)
			)
		)
		(property "Device Type" "C402H22"
			(at 1.1811 -4.2291 270)
			(unlocked yes)
			(layer "F.Fab")
			(hide yes)
			(effects
				(font
					(size 1.016 1.016)
					(thickness 0.1524)
				)
			)
		)
		(duplicate_pad_numbers_are_jumpers no)
		(fp_rect
			(start -0.4318 0.9525)
			(end 0.4318 -0.9525)
			(stroke
				(width 0)
				(type default)
			)
			(fill no)
			(layer "F.CrtYd")
		)
		(fp_rect
			(start -0.4318 0.9525)
			(end 0.4318 -0.9525)
			(stroke
				(width 0)
				(type default)
			)
			(fill no)
			(layer "F.Fab")
		)
		(pad "1" smd custom
			(at 0 -0.4445 270)
			(size 0.1524 0.1524)
			(layers "F.Cu" "F.Mask" "F.Paste")
			(net "DP_RST_N")
			(options
				(clearance outline)
				(anchor circle)
			)
			(primitives
				(gr_poly
					(pts
						(arc
							(start 0.3048 -0.2032)
							(mid 0.275042 -0.275042)
							(end 0.2032 -0.3048)
						)
						(arc
							(start -0.2032 -0.3048)
							(mid -0.275042 -0.275042)
							(end -0.3048 -0.2032)
						)
						(arc
							(start -0.3048 0.2032)
							(mid -0.275042 0.275042)
							(end -0.2032 0.3048)
						)
						(arc
							(start 0.2032 0.3048)
							(mid 0.275042 0.275042)
							(end 0.3048 0.2032)
						)
					)
					(width 0)
					(fill yes)
				)
			)
		)
		(pad "2" smd custom
			(at 0 0.4445 270)
			(size 0.1524 0.1524)
			(layers "F.Cu" "F.Mask" "F.Paste")
			(net "GND")
			(options
				(clearance outline)
				(anchor circle)
			)
			(primitives
				(gr_poly
					(pts
						(arc
							(start 0.3048 -0.2032)
							(mid 0.275042 -0.275042)
							(end 0.2032 -0.3048)
						)
						(arc
							(start -0.2032 -0.3048)
							(mid -0.275042 -0.275042)
							(end -0.3048 -0.2032)
						)
						(arc
							(start -0.3048 0.2032)
							(mid -0.275042 0.275042)
							(end -0.2032 0.3048)
						)
						(arc
							(start 0.2032 0.3048)
							(mid 0.275042 0.275042)
							(end 0.3048 0.2032)
						)
					)
					(width 0)
					(fill yes)
				)
			)
		)
	)
	(footprint ""
		(layer "F.Cu")
		(at 87.8586 -185.6486 90)
		(property "Reference" "C4136"
			(at 0 0 90)
			(layer "F.SilkS")
			(hide yes)
			(effects
				(font
					(size 1.27 1.27)
				)
			)
		)
		(property "Value" "SCD1U25V3KX-GP"
			(at 0 -2.8194 90)
			(unlocked yes)
			(layer "F.Fab")
			(hide yes)
			(effects
				(font
					(size 1.016 1.016)
					(thickness 0.1524)
				)
			)
		)
		(property "Device Type" "C603H36"
			(at 0 -4.3434 90)
			(unlocked yes)
			(layer "F.Fab")
			(hide yes)
			(effects
				(font
					(size 1.016 1.016)
					(thickness 0.1524)
				)
			)
		)
		(duplicate_pad_numbers_are_jumpers no)
		(fp_line
			(start 0.508 0)
			(end -0.508 0)
			(stroke
				(width 0.2032)
				(type default)
			)
			(layer "F.SilkS")
		)
		(fp_rect
			(start -0.5842 1.3335)
			(end 0.5842 -1.3335)
			(stroke
				(width 0)
				(type default)
			)
			(fill no)
			(layer "F.CrtYd")
		)
		(fp_rect
			(start -0.5842 1.3335)
			(end 0.5842 -1.3335)
			(stroke
				(width 0)
				(type default)
			)
			(fill no)
			(layer "F.Fab")
		)
		(pad "1" smd custom
			(at 0 -0.762 90)
			(size 0.2159 0.2159)
			(layers "F.Cu" "F.Mask" "F.Paste")
			(net "GND")
			(options
				(clearance outline)
				(anchor circle)
			)
			(primitives
				(gr_poly
					(pts
						(arc
							(start -0.3302 -0.4318)
							(mid -0.402042 -0.402042)
							(end -0.4318 -0.3302)
						)
						(arc
							(start -0.4318 0.3302)
							(mid -0.402042 0.402042)
							(end -0.3302 0.4318)
						)
						(arc
							(start 0.3302 0.4318)
							(mid 0.402042 0.402042)
							(end 0.4318 0.3302)
						)
						(arc
							(start 0.4318 -0.3302)
							(mid 0.402042 -0.402042)
							(end 0.3302 -0.4318)
						)
					)
					(width 0)
					(fill yes)
				)
			)
		)
		(pad "2" smd custom
			(at 0 0.762 90)
			(size 0.2159 0.2159)
			(layers "F.Cu" "F.Mask" "F.Paste")
			(net "SSD_PWREN1_R")
			(options
				(clearance outline)
				(anchor circle)
			)
			(primitives
				(gr_poly
					(pts
						(arc
							(start -0.3302 -0.4318)
							(mid -0.402042 -0.402042)
							(end -0.4318 -0.3302)
						)
						(arc
							(start -0.4318 0.3302)
							(mid -0.402042 0.402042)
							(end -0.3302 0.4318)
						)
						(arc
							(start 0.3302 0.4318)
							(mid 0.402042 0.402042)
							(end 0.4318 0.3302)
						)
						(arc
							(start 0.4318 -0.3302)
							(mid 0.402042 -0.402042)
							(end 0.3302 -0.4318)
						)
					)
					(width 0)
					(fill yes)
				)
			)
		)
	)
	(footprint ""
		(layer "F.Cu")
		(at 205.359 -23.0124 -90)
		(property "Reference" "R835"
			(at 0 0 270)
			(layer "F.SilkS")
			(hide yes)
			(effects
				(font
					(size 1.27 1.27)
				)
			)
		)
		(property "Value" "4K7R2F-GP"
			(at 0.064008 -3.993896 270)
			(unlocked yes)
			(layer "F.Fab")
			(hide yes)
			(effects
				(font
					(size 1.016 1.016)
					(thickness 0.1524)
				)
			)
		)
		(property "Device Type" "R402H16"
			(at 0.064008 -5.517896 270)
			(unlocked yes)
			(layer "F.Fab")
			(hide yes)
			(effects
				(font
					(size 1.016 1.016)
					(thickness 0.1524)
				)
			)
		)
		(duplicate_pad_numbers_are_jumpers no)
		(fp_line
			(start -0.508 -0.9398)
			(end -0.508 0.9398)
			(stroke
				(width 0.1524)
				(type default)
			)
			(layer "F.SilkS")
		)
		(fp_line
			(start 0.508 -0.9398)
			(end -0.508 -0.9398)
			(stroke
				(width 0.1524)
				(type default)
			)
			(layer "F.SilkS")
		)
		(fp_rect
			(start -0.508 0.9398)
			(end 0.508 -0.9398)
			(stroke
				(width 0)
				(type default)
			)
			(fill no)
			(layer "F.CrtYd")
		)
		(fp_rect
			(start -0.508 0.9398)
			(end 0.508 -0.9398)
			(stroke
				(width 0)
				(type default)
			)
			(fill no)
			(layer "F.Fab")
		)
		(pad "1" smd custom
			(at 0 -0.4445 270)
			(size 0.1397 0.1397)
			(layers "F.Cu" "F.Mask" "F.Paste")
			(net "P3V3_STBY")
			(options
				(clearance outline)
				(anchor circle)
			)
			(primitives
				(gr_poly
					(pts
						(arc
							(start -0.1778 -0.2794)
							(mid -0.249642 -0.249642)
							(end -0.2794 -0.1778)
						)
						(arc
							(start -0.2794 0.1778)
							(mid -0.249642 0.249642)
							(end -0.1778 0.2794)
						)
						(arc
							(start 0.1778 0.2794)
							(mid 0.249642 0.249642)
							(end 0.2794 0.1778)
						)
						(arc
							(start 0.2794 -0.1778)
							(mid 0.249642 -0.249642)
							(end 0.1778 -0.2794)
						)
					)
					(width 0)
					(fill yes)
				)
			)
		)
		(pad "2" smd custom
			(at 0 0.4445 270)
			(size 0.1397 0.1397)
			(layers "F.Cu" "F.Mask" "F.Paste")
			(net "U56_INT_N")
			(options
				(clearance outline)
				(anchor circle)
			)
			(primitives
				(gr_poly
					(pts
						(arc
							(start -0.1778 -0.2794)
							(mid -0.249642 -0.249642)
							(end -0.2794 -0.1778)
						)
						(arc
							(start -0.2794 0.1778)
							(mid -0.249642 0.249642)
							(end -0.1778 0.2794)
						)
						(arc
							(start 0.1778 0.2794)
							(mid 0.249642 0.249642)
							(end 0.2794 0.1778)
						)
						(arc
							(start 0.2794 -0.1778)
							(mid 0.249642 -0.249642)
							(end 0.1778 -0.2794)
						)
					)
					(width 0)
					(fill yes)
				)
			)
		)
	)
	(footprint ""
		(layer "F.Cu")
		(at 118.364 -17.0688)
		(property "Reference" "R748"
			(at 0 0 0)
			(layer "F.SilkS")
			(hide yes)
			(effects
				(font
					(size 1.27 1.27)
				)
			)
		)
		(property "Value" "4K7R2F-GP"
			(at 0.064008 -3.993896 0)
			(unlocked yes)
			(layer "F.Fab")
			(hide yes)
			(effects
				(font
					(size 1.016 1.016)
					(thickness 0.1524)
				)
			)
		)
		(property "Device Type" "R402H16"
			(at 0.064008 -5.517896 0)
			(unlocked yes)
			(layer "F.Fab")
			(hide yes)
			(effects
				(font
					(size 1.016 1.016)
					(thickness 0.1524)
				)
			)
		)
		(duplicate_pad_numbers_are_jumpers no)
		(fp_line
			(start -0.508 -0.9398)
			(end -0.508 0.9398)
			(stroke
				(width 0.1524)
				(type default)
			)
			(layer "F.SilkS")
		)
		(fp_line
			(start 0.508 -0.9398)
			(end -0.508 -0.9398)
			(stroke
				(width 0.1524)
				(type default)
			)
			(layer "F.SilkS")
		)
		(fp_rect
			(start -0.508 0.9398)
			(end 0.508 -0.9398)
			(stroke
				(width 0)
				(type default)
			)
			(fill no)
			(layer "F.CrtYd")
		)
		(fp_rect
			(start -0.508 0.9398)
			(end 0.508 -0.9398)
			(stroke
				(width 0)
				(type default)
			)
			(fill no)
			(layer "F.Fab")
		)
		(pad "1" smd custom
			(at 0 -0.4445)
			(size 0.1397 0.1397)
			(layers "F.Cu" "F.Mask" "F.Paste")
			(net "U54_A1")
			(options
				(clearance outline)
				(anchor circle)
			)
			(primitives
				(gr_poly
					(pts
						(arc
							(start -0.1778 -0.2794)
							(mid -0.249642 -0.249642)
							(end -0.2794 -0.1778)
						)
						(arc
							(start -0.2794 0.1778)
							(mid -0.249642 0.249642)
							(end -0.1778 0.2794)
						)
						(arc
							(start 0.1778 0.2794)
							(mid 0.249642 0.249642)
							(end 0.2794 0.1778)
						)
						(arc
							(start 0.2794 -0.1778)
							(mid 0.249642 -0.249642)
							(end 0.1778 -0.2794)
						)
					)
					(width 0)
					(fill yes)
				)
			)
		)
		(pad "2" smd custom
			(at 0 0.4445)
			(size 0.1397 0.1397)
			(layers "F.Cu" "F.Mask" "F.Paste")
			(net "P3V3_STBY")
			(options
				(clearance outline)
				(anchor circle)
			)
			(primitives
				(gr_poly
					(pts
						(arc
							(start -0.1778 -0.2794)
							(mid -0.249642 -0.249642)
							(end -0.2794 -0.1778)
						)
						(arc
							(start -0.2794 0.1778)
							(mid -0.249642 0.249642)
							(end -0.1778 0.2794)
						)
						(arc
							(start 0.1778 0.2794)
							(mid 0.249642 0.249642)
							(end 0.2794 0.1778)
						)
						(arc
							(start 0.2794 -0.1778)
							(mid 0.249642 -0.249642)
							(end 0.1778 -0.2794)
						)
					)
					(width 0)
					(fill yes)
				)
			)
		)
	)
	(footprint ""
		(layer "F.Cu")
		(at 326.771 -86.487)
		(property "Reference" "R4168"
			(at 0 0 0)
			(layer "F.SilkS")
			(hide yes)
			(effects
				(font
					(size 1.27 1.27)
				)
			)
		)
		(property "Value" "4K7R2F-GP"
			(at 0.064008 -3.993896 0)
			(unlocked yes)
			(layer "F.Fab")
			(hide yes)
			(effects
				(font
					(size 1.016 1.016)
					(thickness 0.1524)
				)
			)
		)
		(property "Device Type" "R402H16"
			(at 0.064008 -5.517896 0)
			(unlocked yes)
			(layer "F.Fab")
			(hide yes)
			(effects
				(font
					(size 1.016 1.016)
					(thickness 0.1524)
				)
			)
		)
		(duplicate_pad_numbers_are_jumpers no)
		(fp_line
			(start -0.508 -0.9398)
			(end -0.508 0.9398)
			(stroke
				(width 0.1524)
				(type default)
			)
			(layer "F.SilkS")
		)
		(fp_line
			(start 0.508 -0.9398)
			(end -0.508 -0.9398)
			(stroke
				(width 0.1524)
				(type default)
			)
			(layer "F.SilkS")
		)
		(fp_rect
			(start -0.508 0.9398)
			(end 0.508 -0.9398)
			(stroke
				(width 0)
				(type default)
			)
			(fill no)
			(layer "F.CrtYd")
		)
		(fp_rect
			(start -0.508 0.9398)
			(end 0.508 -0.9398)
			(stroke
				(width 0)
				(type default)
			)
			(fill no)
			(layer "F.Fab")
		)
		(pad "1" smd custom
			(at 0 -0.4445)
			(size 0.1397 0.1397)
			(layers "F.Cu" "F.Mask" "F.Paste")
			(net "UPLINK4")
			(options
				(clearance outline)
				(anchor circle)
			)
			(primitives
				(gr_poly
					(pts
						(arc
							(start -0.1778 -0.2794)
							(mid -0.249642 -0.249642)
							(end -0.2794 -0.1778)
						)
						(arc
							(start -0.2794 0.1778)
							(mid -0.249642 0.249642)
							(end -0.1778 0.2794)
						)
						(arc
							(start 0.1778 0.2794)
							(mid 0.249642 0.249642)
							(end 0.2794 0.1778)
						)
						(arc
							(start 0.2794 -0.1778)
							(mid 0.249642 -0.249642)
							(end 0.1778 -0.2794)
						)
					)
					(width 0)
					(fill yes)
				)
			)
		)
		(pad "2" smd custom
			(at 0 0.4445)
			(size 0.1397 0.1397)
			(layers "F.Cu" "F.Mask" "F.Paste")
			(net "P3V3_STBY")
			(options
				(clearance outline)
				(anchor circle)
			)
			(primitives
				(gr_poly
					(pts
						(arc
							(start -0.1778 -0.2794)
							(mid -0.249642 -0.249642)
							(end -0.2794 -0.1778)
						)
						(arc
							(start -0.2794 0.1778)
							(mid -0.249642 0.249642)
							(end -0.1778 0.2794)
						)
						(arc
							(start 0.1778 0.2794)
							(mid 0.249642 0.249642)
							(end 0.2794 0.1778)
						)
						(arc
							(start 0.2794 -0.1778)
							(mid 0.249642 -0.249642)
							(end 0.1778 -0.2794)
						)
					)
					(width 0)
					(fill yes)
				)
			)
		)
	)
	(footprint ""
		(layer "F.Cu")
		(at 73.406 -32.004 -90)
		(property "Reference" "PR27"
			(at 0 0 270)
			(layer "F.SilkS")
			(hide yes)
			(effects
				(font
					(size 1.27 1.27)
				)
			)
		)
		(property "Value" "10R3F-GP"
			(at -0.0254 -2.5146 270)
			(unlocked yes)
			(layer "F.Fab")
			(hide yes)
			(effects
				(font
					(size 1.016 1.016)
					(thickness 0.1524)
				)
			)
		)
		(property "Device Type" "R603H22"
			(at -0.0254 -4.0386 270)
			(unlocked yes)
			(layer "F.Fab")
			(hide yes)
			(effects
				(font
					(size 1.016 1.016)
					(thickness 0.1524)
				)
			)
		)
		(duplicate_pad_numbers_are_jumpers no)
		(fp_line
			(start -0.4826 0)
			(end -0.2032 0)
			(stroke
				(width 0.2032)
				(type default)
			)
			(layer "F.SilkS")
		)
		(fp_line
			(start 0.2032 0)
			(end 0.4826 0)
			(stroke
				(width 0.2032)
				(type default)
			)
			(layer "F.SilkS")
		)
		(fp_rect
			(start -0.5842 1.3335)
			(end 0.5842 -1.3335)
			(stroke
				(width 0)
				(type default)
			)
			(fill no)
			(layer "F.CrtYd")
		)
		(fp_rect
			(start -0.5842 1.3335)
			(end 0.5842 -1.3335)
			(stroke
				(width 0)
				(type default)
			)
			(fill no)
			(layer "F.Fab")
		)
		(pad "1" smd custom
			(at 0 -0.762 270)
			(size 0.2159 0.2159)
			(layers "F.Cu" "F.Mask" "F.Paste")
			(net "P3V3_PWR")
			(options
				(clearance outline)
				(anchor circle)
			)
			(primitives
				(gr_poly
					(pts
						(arc
							(start -0.3302 -0.4318)
							(mid -0.402042 -0.402042)
							(end -0.4318 -0.3302)
						)
						(arc
							(start -0.4318 0.3302)
							(mid -0.402042 0.402042)
							(end -0.3302 0.4318)
						)
						(arc
							(start 0.3302 0.4318)
							(mid 0.402042 0.402042)
							(end 0.4318 0.3302)
						)
						(arc
							(start 0.4318 -0.3302)
							(mid 0.402042 -0.402042)
							(end 0.3302 -0.4318)
						)
					)
					(width 0)
					(fill yes)
				)
			)
		)
		(pad "2" smd custom
			(at 0 0.762 270)
			(size 0.2159 0.2159)
			(layers "F.Cu" "F.Mask" "F.Paste")
			(net "P3V3_STBY_VFB_R")
			(options
				(clearance outline)
				(anchor circle)
			)
			(primitives
				(gr_poly
					(pts
						(arc
							(start -0.3302 -0.4318)
							(mid -0.402042 -0.402042)
							(end -0.4318 -0.3302)
						)
						(arc
							(start -0.4318 0.3302)
							(mid -0.402042 0.402042)
							(end -0.3302 0.4318)
						)
						(arc
							(start 0.3302 0.4318)
							(mid 0.402042 0.402042)
							(end 0.4318 0.3302)
						)
						(arc
							(start 0.4318 -0.3302)
							(mid 0.402042 -0.402042)
							(end 0.3302 -0.4318)
						)
					)
					(width 0)
					(fill yes)
				)
			)
		)
	)
	(footprint ""
		(layer "F.Cu")
		(at 154.813 -90.267282 180)
		(property "Reference" "C412"
			(at 0 0 180)
			(layer "F.SilkS")
			(hide yes)
			(effects
				(font
					(size 1.27 1.27)
				)
			)
		)
		(property "Value" "SC12P50V2JN-3GP"
			(at 1.1811 -2.7051 180)
			(unlocked yes)
			(layer "F.Fab")
			(hide yes)
			(effects
				(font
					(size 1.016 1.016)
					(thickness 0.1524)
				)
			)
		)
		(property "Device Type" "C402H24"
			(at 1.1811 -4.2291 180)
			(unlocked yes)
			(layer "F.Fab")
			(hide yes)
			(effects
				(font
					(size 1.016 1.016)
					(thickness 0.1524)
				)
			)
		)
		(duplicate_pad_numbers_are_jumpers no)
		(fp_rect
			(start -0.4318 0.9525)
			(end 0.4318 -0.9525)
			(stroke
				(width 0)
				(type default)
			)
			(fill no)
			(layer "F.CrtYd")
		)
		(fp_rect
			(start -0.4318 0.9525)
			(end 0.4318 -0.9525)
			(stroke
				(width 0)
				(type default)
			)
			(fill no)
			(layer "F.Fab")
		)
		(pad "1" smd custom
			(at 0 -0.4445 180)
			(size 0.1524 0.1524)
			(layers "F.Cu" "F.Mask" "F.Paste")
			(net "XTAL_X2")
			(options
				(clearance outline)
				(anchor circle)
			)
			(primitives
				(gr_poly
					(pts
						(arc
							(start 0.3048 -0.2032)
							(mid 0.275042 -0.275042)
							(end 0.2032 -0.3048)
						)
						(arc
							(start -0.2032 -0.3048)
							(mid -0.275042 -0.275042)
							(end -0.3048 -0.2032)
						)
						(arc
							(start -0.3048 0.2032)
							(mid -0.275042 0.275042)
							(end -0.2032 0.3048)
						)
						(arc
							(start 0.2032 0.3048)
							(mid 0.275042 0.275042)
							(end 0.3048 0.2032)
						)
					)
					(width 0)
					(fill yes)
				)
			)
		)
		(pad "2" smd custom
			(at 0 0.4445 180)
			(size 0.1524 0.1524)
			(layers "F.Cu" "F.Mask" "F.Paste")
			(net "GND")
			(options
				(clearance outline)
				(anchor circle)
			)
			(primitives
				(gr_poly
					(pts
						(arc
							(start 0.3048 -0.2032)
							(mid 0.275042 -0.275042)
							(end 0.2032 -0.3048)
						)
						(arc
							(start -0.2032 -0.3048)
							(mid -0.275042 -0.275042)
							(end -0.3048 -0.2032)
						)
						(arc
							(start -0.3048 0.2032)
							(mid -0.275042 0.275042)
							(end -0.2032 0.3048)
						)
						(arc
							(start 0.2032 0.3048)
							(mid 0.275042 0.275042)
							(end 0.3048 0.2032)
						)
					)
					(width 0)
					(fill yes)
				)
			)
		)
	)
	(footprint ""
		(layer "F.Cu")
		(at 153.113232 -53.222398)
		(property "Reference" "PQ19"
			(at 0 0 0)
			(layer "F.SilkS")
			(hide yes)
			(effects
				(font
					(size 1.27 1.27)
				)
			)
		)
		(property "Value" "AO3400-GP-U"
			(at 0.0254 -12.3444 0)
			(unlocked yes)
			(layer "F.Fab")
			(hide yes)
			(effects
				(font
					(size 1.016 1.016)
					(thickness 0.1524)
				)
			)
		)
		(property "Device Type" "SOT23DGS2D8H50"
			(at 0.0254 -14.2494 0)
			(unlocked yes)
			(layer "F.Fab")
			(hide yes)
			(effects
				(font
					(size 1.016 1.016)
					(thickness 0.1524)
				)
			)
		)
		(duplicate_pad_numbers_are_jumpers no)
		(fp_line
			(start -1.7018 -0.254)
			(end 1.7018 -0.254)
			(stroke
				(width 0.1524)
				(type default)
			)
			(layer "F.SilkS")
		)
		(fp_line
			(start -1.7018 0.254)
			(end -1.7018 -0.254)
			(stroke
				(width 0.1524)
				(type default)
			)
			(layer "F.SilkS")
		)
		(fp_line
			(start 1.7018 -0.254)
			(end 1.7018 0.254)
			(stroke
				(width 0.1524)
				(type default)
			)
			(layer "F.SilkS")
		)
		(fp_line
			(start 1.7018 0.254)
			(end -1.7018 0.254)
			(stroke
				(width 0.1524)
				(type default)
			)
			(layer "F.SilkS")
		)
		(fp_rect
			(start -1.778 1.9812)
			(end 1.778 -1.9812)
			(stroke
				(width 0)
				(type default)
			)
			(fill no)
			(layer "F.CrtYd")
		)
		(fp_poly
			(pts
				(xy -1.778 -1.9812) (xy 1.778 -1.9812) (xy 1.778 1.9812) (xy -1.778 1.9812)
			)
			(stroke
				(width 0)
				(type default)
			)
			(fill no)
			(layer "F.Fab")
		)
		(pad "D" smd custom
			(at 0 -1.1176)
			(size 0.254 0.254)
			(layers "F.Cu" "F.Mask" "F.Paste")
			(net "P0V9_VFB_AVS")
			(options
				(clearance outline)
				(anchor circle)
			)
			(primitives
				(gr_poly
					(pts
						(arc
							(start -0.508 -0.4064)
							(mid -0.448484 -0.550084)
							(end -0.3048 -0.6096)
						)
						(arc
							(start 0.3048 -0.6096)
							(mid 0.448484 -0.550084)
							(end 0.508 -0.4064)
						)
						(arc
							(start 0.508 0.4064)
							(mid 0.448484 0.550084)
							(end 0.3048 0.6096)
						)
						(arc
							(start -0.3048 0.6096)
							(mid -0.448484 0.550084)
							(end -0.508 0.4064)
						)
					)
					(width 0)
					(fill yes)
				)
			)
		)
		(pad "G" smd custom
			(at -1.016 1.1176)
			(size 0.254 0.254)
			(layers "F.Cu" "F.Mask" "F.Paste")
			(net "AVS_ENB1_R")
			(options
				(clearance outline)
				(anchor circle)
			)
			(primitives
				(gr_poly
					(pts
						(arc
							(start -0.508 -0.4064)
							(mid -0.448484 -0.550084)
							(end -0.3048 -0.6096)
						)
						(arc
							(start 0.3048 -0.6096)
							(mid 0.448484 -0.550084)
							(end 0.508 -0.4064)
						)
						(arc
							(start 0.508 0.4064)
							(mid 0.448484 0.550084)
							(end 0.3048 0.6096)
						)
						(arc
							(start -0.3048 0.6096)
							(mid -0.448484 0.550084)
							(end -0.508 0.4064)
						)
					)
					(width 0)
					(fill yes)
				)
			)
		)
		(pad "S" smd custom
			(at 1.016 1.1176)
			(size 0.254 0.254)
			(layers "F.Cu" "F.Mask" "F.Paste")
			(net "AGND_P0V9")
			(options
				(clearance outline)
				(anchor circle)
			)
			(primitives
				(gr_poly
					(pts
						(arc
							(start -0.508 -0.4064)
							(mid -0.448484 -0.550084)
							(end -0.3048 -0.6096)
						)
						(arc
							(start 0.3048 -0.6096)
							(mid 0.448484 -0.550084)
							(end 0.508 -0.4064)
						)
						(arc
							(start 0.508 0.4064)
							(mid 0.448484 0.550084)
							(end 0.3048 0.6096)
						)
						(arc
							(start -0.3048 0.6096)
							(mid -0.448484 0.550084)
							(end -0.508 0.4064)
						)
					)
					(width 0)
					(fill yes)
				)
			)
		)
	)
	(footprint ""
		(layer "F.Cu")
		(at 166.116 -94.5134 90)
		(property "Reference" "R88"
			(at 0 0 90)
			(layer "F.SilkS")
			(hide yes)
			(effects
				(font
					(size 1.27 1.27)
				)
			)
		)
		(property "Value" "0R2J-2-GP"
			(at 0.064008 -3.993896 90)
			(unlocked yes)
			(layer "F.Fab")
			(hide yes)
			(effects
				(font
					(size 1.016 1.016)
					(thickness 0.1524)
				)
			)
		)
		(property "Device Type" "R402H16"
			(at 0.064008 -5.517896 90)
			(unlocked yes)
			(layer "F.Fab")
			(hide yes)
			(effects
				(font
					(size 1.016 1.016)
					(thickness 0.1524)
				)
			)
		)
		(duplicate_pad_numbers_are_jumpers no)
		(fp_line
			(start 0.508 -0.9398)
			(end -0.508 -0.9398)
			(stroke
				(width 0.1524)
				(type default)
			)
			(layer "F.SilkS")
		)
		(fp_line
			(start -0.508 -0.9398)
			(end -0.508 0.9398)
			(stroke
				(width 0.1524)
				(type default)
			)
			(layer "F.SilkS")
		)
		(fp_rect
			(start -0.508 0.9398)
			(end 0.508 -0.9398)
			(stroke
				(width 0)
				(type default)
			)
			(fill no)
			(layer "F.CrtYd")
		)
		(fp_rect
			(start -0.508 0.9398)
			(end 0.508 -0.9398)
			(stroke
				(width 0)
				(type default)
			)
			(fill no)
			(layer "F.Fab")
		)
		(pad "1" smd custom
			(at 0 -0.4445 90)
			(size 0.1397 0.1397)
			(layers "F.Cu" "F.Mask" "F.Paste")
			(net "CLKGEN_OE2_R")
			(options
				(clearance outline)
				(anchor circle)
			)
			(primitives
				(gr_poly
					(pts
						(arc
							(start -0.1778 -0.2794)
							(mid -0.249642 -0.249642)
							(end -0.2794 -0.1778)
						)
						(arc
							(start -0.2794 0.1778)
							(mid -0.249642 0.249642)
							(end -0.1778 0.2794)
						)
						(arc
							(start 0.1778 0.2794)
							(mid 0.249642 0.249642)
							(end 0.2794 0.1778)
						)
						(arc
							(start 0.2794 -0.1778)
							(mid 0.249642 -0.249642)
							(end 0.1778 -0.2794)
						)
					)
					(width 0)
					(fill yes)
				)
			)
		)
		(pad "2" smd custom
			(at 0 0.4445 90)
			(size 0.1397 0.1397)
			(layers "F.Cu" "F.Mask" "F.Paste")
			(net "CLKGEN_OE2")
			(options
				(clearance outline)
				(anchor circle)
			)
			(primitives
				(gr_poly
					(pts
						(arc
							(start -0.1778 -0.2794)
							(mid -0.249642 -0.249642)
							(end -0.2794 -0.1778)
						)
						(arc
							(start -0.2794 0.1778)
							(mid -0.249642 0.249642)
							(end -0.1778 0.2794)
						)
						(arc
							(start 0.1778 0.2794)
							(mid 0.249642 0.249642)
							(end 0.2794 0.1778)
						)
						(arc
							(start 0.2794 -0.1778)
							(mid 0.249642 -0.249642)
							(end 0.1778 -0.2794)
						)
					)
					(width 0)
					(fill yes)
				)
			)
		)
	)
	(footprint ""
		(layer "F.Cu")
		(at 169.037 -53.848 -90)
		(property "Reference" "R326"
			(at 0 0 270)
			(layer "F.SilkS")
			(hide yes)
			(effects
				(font
					(size 1.27 1.27)
				)
			)
		)
		(property "Value" "0R2J-2-GP"
			(at 0.064008 -3.993896 270)
			(unlocked yes)
			(layer "F.Fab")
			(hide yes)
			(effects
				(font
					(size 1.016 1.016)
					(thickness 0.1524)
				)
			)
		)
		(property "Device Type" "R402H16"
			(at 0.064008 -5.517896 270)
			(unlocked yes)
			(layer "F.Fab")
			(hide yes)
			(effects
				(font
					(size 1.016 1.016)
					(thickness 0.1524)
				)
			)
		)
		(duplicate_pad_numbers_are_jumpers no)
		(fp_line
			(start -0.508 -0.9398)
			(end -0.508 0.9398)
			(stroke
				(width 0.1524)
				(type default)
			)
			(layer "F.SilkS")
		)
		(fp_line
			(start 0.508 -0.9398)
			(end -0.508 -0.9398)
			(stroke
				(width 0.1524)
				(type default)
			)
			(layer "F.SilkS")
		)
		(fp_rect
			(start -0.508 0.9398)
			(end 0.508 -0.9398)
			(stroke
				(width 0)
				(type default)
			)
			(fill no)
			(layer "F.CrtYd")
		)
		(fp_rect
			(start -0.508 0.9398)
			(end 0.508 -0.9398)
			(stroke
				(width 0)
				(type default)
			)
			(fill no)
			(layer "F.Fab")
		)
		(pad "1" smd custom
			(at 0 -0.4445 270)
			(size 0.1397 0.1397)
			(layers "F.Cu" "F.Mask" "F.Paste")
			(net "VS1_LED_R")
			(options
				(clearance outline)
				(anchor circle)
			)
			(primitives
				(gr_poly
					(pts
						(arc
							(start -0.1778 -0.2794)
							(mid -0.249642 -0.249642)
							(end -0.2794 -0.1778)
						)
						(arc
							(start -0.2794 0.1778)
							(mid -0.249642 0.249642)
							(end -0.1778 0.2794)
						)
						(arc
							(start 0.1778 0.2794)
							(mid 0.249642 0.249642)
							(end 0.2794 0.1778)
						)
						(arc
							(start 0.2794 -0.1778)
							(mid 0.249642 -0.249642)
							(end 0.1778 -0.2794)
						)
					)
					(width 0)
					(fill yes)
				)
			)
		)
		(pad "2" smd custom
			(at 0 0.4445 270)
			(size 0.1397 0.1397)
			(layers "F.Cu" "F.Mask" "F.Paste")
			(net "VS1_LED")
			(options
				(clearance outline)
				(anchor circle)
			)
			(primitives
				(gr_poly
					(pts
						(arc
							(start -0.1778 -0.2794)
							(mid -0.249642 -0.249642)
							(end -0.2794 -0.1778)
						)
						(arc
							(start -0.2794 0.1778)
							(mid -0.249642 0.249642)
							(end -0.1778 0.2794)
						)
						(arc
							(start 0.1778 0.2794)
							(mid 0.249642 0.249642)
							(end 0.2794 0.1778)
						)
						(arc
							(start 0.2794 -0.1778)
							(mid 0.249642 -0.249642)
							(end 0.1778 -0.2794)
						)
					)
					(width 0)
					(fill yes)
				)
			)
		)
	)
	(footprint ""
		(layer "F.Cu")
		(at 24.60244 -125.782578)
		(property "Reference" "R73"
			(at 0 0 0)
			(layer "F.SilkS")
			(hide yes)
			(effects
				(font
					(size 1.27 1.27)
				)
			)
		)
		(property "Value" "33R1J-GP"
			(at -3.3274 -1.3335 0)
			(unlocked yes)
			(layer "F.Fab")
			(hide yes)
			(effects
				(font
					(size 1.016 1.016)
					(thickness 0.1524)
				)
			)
		)
		(property "Device Type" "R0201H12"
			(at -3.3274 -2.8575 0)
			(unlocked yes)
			(layer "F.Fab")
			(hide yes)
			(effects
				(font
					(size 1.016 1.016)
					(thickness 0.1524)
				)
			)
		)
		(duplicate_pad_numbers_are_jumpers no)
		(fp_rect
			(start -0.2794 0.6477)
			(end 0.2794 -0.6477)
			(stroke
				(width 0)
				(type default)
			)
			(fill no)
			(layer "F.CrtYd")
		)
		(fp_rect
			(start -0.2794 0.6477)
			(end 0.2794 -0.6477)
			(stroke
				(width 0)
				(type default)
			)
			(fill no)
			(layer "F.Fab")
		)
		(pad "1" smd custom
			(at 0 -0.2794)
			(size 0.0762 0.0762)
			(layers "F.Cu" "F.Mask" "F.Paste")
			(net "BMC_REFCLK_N")
			(options
				(clearance outline)
				(anchor circle)
			)
			(primitives
				(gr_poly
					(pts
						(arc
							(start 0.1524 -0.127)
							(mid 0.137521 -0.162921)
							(end 0.1016 -0.1778)
						)
						(arc
							(start -0.1016 -0.1778)
							(mid -0.137521 -0.162921)
							(end -0.1524 -0.127)
						)
						(arc
							(start -0.1524 0.127)
							(mid -0.137521 0.162921)
							(end -0.1016 0.1778)
						)
						(arc
							(start 0.1016 0.1778)
							(mid 0.137521 0.162921)
							(end 0.1524 0.127)
						)
					)
					(width 0)
					(fill yes)
				)
			)
		)
		(pad "2" smd custom
			(at 0 0.2794)
			(size 0.0762 0.0762)
			(layers "F.Cu" "F.Mask" "F.Paste")
			(net "BMC_REFCLK_P")
			(options
				(clearance outline)
				(anchor circle)
			)
			(primitives
				(gr_poly
					(pts
						(arc
							(start 0.1524 -0.127)
							(mid 0.137521 -0.162921)
							(end 0.1016 -0.1778)
						)
						(arc
							(start -0.1016 -0.1778)
							(mid -0.137521 -0.162921)
							(end -0.1524 -0.127)
						)
						(arc
							(start -0.1524 0.127)
							(mid -0.137521 0.162921)
							(end -0.1016 0.1778)
						)
						(arc
							(start 0.1016 0.1778)
							(mid 0.137521 0.162921)
							(end 0.1524 0.127)
						)
					)
					(width 0)
					(fill yes)
				)
			)
		)
	)
	(footprint ""
		(layer "F.Cu")
		(at 17.78 -157.48 180)
		(property "Reference" "D1402"
			(at 0 0 180)
			(layer "F.SilkS")
			(hide yes)
			(effects
				(font
					(size 1.27 1.27)
				)
			)
		)
		(property "Value" "RB551V30-GP"
			(at 0 -6.7818 180)
			(unlocked yes)
			(layer "F.Fab")
			(hide yes)
			(effects
				(font
					(size 1.016 1.016)
					(thickness 0.1524)
				)
			)
		)
		(property "Device Type" "SOD323AKH38"
			(at 0 -8.6868 180)
			(unlocked yes)
			(layer "F.Fab")
			(hide yes)
			(effects
				(font
					(size 1.016 1.016)
					(thickness 0.1524)
				)
			)
		)
		(duplicate_pad_numbers_are_jumpers no)
		(fp_line
			(start 0.889 2.159)
			(end -0.889 2.159)
			(stroke
				(width 0.1524)
				(type default)
			)
			(layer "F.SilkS")
		)
		(fp_line
			(start 0.889 -1.9304)
			(end 0.889 2.159)
			(stroke
				(width 0.1524)
				(type default)
			)
			(layer "F.SilkS")
		)
		(fp_line
			(start 0.762 2.0574)
			(end -0.762 2.0574)
			(stroke
				(width 0.508)
				(type default)
			)
			(layer "F.SilkS")
		)
		(fp_line
			(start -0.889 2.159)
			(end -0.889 -1.9304)
			(stroke
				(width 0.1524)
				(type default)
			)
			(layer "F.SilkS")
		)
		(fp_line
			(start -0.889 -1.9304)
			(end 0.889 -1.9304)
			(stroke
				(width 0.1524)
				(type default)
			)
			(layer "F.SilkS")
		)
		(fp_rect
			(start -1.016 2.3114)
			(end 1.016 -2.0066)
			(stroke
				(width 0)
				(type default)
			)
			(fill no)
			(layer "F.CrtYd")
		)
		(fp_poly
			(pts
				(xy -1.016 -2.0066) (xy 1.016 -2.0066) (xy 1.016 2.3114) (xy -1.016 2.3114)
			)
			(stroke
				(width 0)
				(type default)
			)
			(fill no)
			(layer "F.Fab")
		)
		(pad "A" smd rect
			(at 0 -1.143 180)
			(size 0.5588 1.016)
			(layers "F.Cu" "F.Mask" "F.Paste")
			(net "FM_BMC_RESET#_BTN_D")
		)
		(pad "K" smd rect
			(at 0 1.143 180)
			(size 0.5588 1.016)
			(layers "F.Cu" "F.Mask" "F.Paste")
			(net "FM_BMC_RESET#_BTN")
		)
	)
	(footprint ""
		(layer "F.Cu")
		(at 122.143774 -35.131756 180)
		(property "Reference" "R619"
			(at 0 0 180)
			(layer "F.SilkS")
			(hide yes)
			(effects
				(font
					(size 1.27 1.27)
				)
			)
		)
		(property "Value" "0R2J-2-GP"
			(at 0.064008 -3.993896 180)
			(unlocked yes)
			(layer "F.Fab")
			(hide yes)
			(effects
				(font
					(size 1.016 1.016)
					(thickness 0.1524)
				)
			)
		)
		(property "Device Type" "R402H16"
			(at 0.064008 -5.517896 180)
			(unlocked yes)
			(layer "F.Fab")
			(hide yes)
			(effects
				(font
					(size 1.016 1.016)
					(thickness 0.1524)
				)
			)
		)
		(duplicate_pad_numbers_are_jumpers no)
		(fp_line
			(start 0.508 -0.9398)
			(end -0.508 -0.9398)
			(stroke
				(width 0.1524)
				(type default)
			)
			(layer "F.SilkS")
		)
		(fp_line
			(start -0.508 -0.9398)
			(end -0.508 0.9398)
			(stroke
				(width 0.1524)
				(type default)
			)
			(layer "F.SilkS")
		)
		(fp_rect
			(start -0.508 0.9398)
			(end 0.508 -0.9398)
			(stroke
				(width 0)
				(type default)
			)
			(fill no)
			(layer "F.CrtYd")
		)
		(fp_rect
			(start -0.508 0.9398)
			(end 0.508 -0.9398)
			(stroke
				(width 0)
				(type default)
			)
			(fill no)
			(layer "F.Fab")
		)
		(pad "1" smd custom
			(at 0 -0.4445 180)
			(size 0.1397 0.1397)
			(layers "F.Cu" "F.Mask" "F.Paste")
			(net "UPLINK1_R")
			(options
				(clearance outline)
				(anchor circle)
			)
			(primitives
				(gr_poly
					(pts
						(arc
							(start -0.1778 -0.2794)
							(mid -0.249642 -0.249642)
							(end -0.2794 -0.1778)
						)
						(arc
							(start -0.2794 0.1778)
							(mid -0.249642 0.249642)
							(end -0.1778 0.2794)
						)
						(arc
							(start 0.1778 0.2794)
							(mid 0.249642 0.249642)
							(end 0.2794 0.1778)
						)
						(arc
							(start 0.2794 -0.1778)
							(mid 0.249642 -0.249642)
							(end 0.1778 -0.2794)
						)
					)
					(width 0)
					(fill yes)
				)
			)
		)
		(pad "2" smd custom
			(at 0 0.4445 180)
			(size 0.1397 0.1397)
			(layers "F.Cu" "F.Mask" "F.Paste")
			(net "UPLINK1")
			(options
				(clearance outline)
				(anchor circle)
			)
			(primitives
				(gr_poly
					(pts
						(arc
							(start -0.1778 -0.2794)
							(mid -0.249642 -0.249642)
							(end -0.2794 -0.1778)
						)
						(arc
							(start -0.2794 0.1778)
							(mid -0.249642 0.249642)
							(end -0.1778 0.2794)
						)
						(arc
							(start 0.1778 0.2794)
							(mid 0.249642 0.249642)
							(end 0.2794 0.1778)
						)
						(arc
							(start 0.2794 -0.1778)
							(mid 0.249642 -0.249642)
							(end 0.1778 -0.2794)
						)
					)
					(width 0)
					(fill yes)
				)
			)
		)
	)
	(footprint ""
		(layer "F.Cu")
		(at 83.627214 -83.04022 180)
		(property "Reference" "SC1303"
			(at 0 0 180)
			(layer "F.SilkS")
			(hide yes)
			(effects
				(font
					(size 1.27 1.27)
				)
			)
		)
		(property "Value" "SCD1U16V2KX-3GP"
			(at 1.1811 -2.7051 180)
			(unlocked yes)
			(layer "F.Fab")
			(hide yes)
			(effects
				(font
					(size 1.016 1.016)
					(thickness 0.1524)
				)
			)
		)
		(property "Device Type" "C402H22"
			(at 1.1811 -4.2291 180)
			(unlocked yes)
			(layer "F.Fab")
			(hide yes)
			(effects
				(font
					(size 1.016 1.016)
					(thickness 0.1524)
				)
			)
		)
		(duplicate_pad_numbers_are_jumpers no)
		(fp_rect
			(start -0.4318 0.9525)
			(end 0.4318 -0.9525)
			(stroke
				(width 0)
				(type default)
			)
			(fill no)
			(layer "F.CrtYd")
		)
		(fp_rect
			(start -0.4318 0.9525)
			(end 0.4318 -0.9525)
			(stroke
				(width 0)
				(type default)
			)
			(fill no)
			(layer "F.Fab")
		)
		(pad "1" smd custom
			(at 0 -0.4445 180)
			(size 0.1524 0.1524)
			(layers "F.Cu" "F.Mask" "F.Paste")
			(net "P1V8_STBY")
			(options
				(clearance outline)
				(anchor circle)
			)
			(primitives
				(gr_poly
					(pts
						(arc
							(start 0.3048 -0.2032)
							(mid 0.275042 -0.275042)
							(end 0.2032 -0.3048)
						)
						(arc
							(start -0.2032 -0.3048)
							(mid -0.275042 -0.275042)
							(end -0.3048 -0.2032)
						)
						(arc
							(start -0.3048 0.2032)
							(mid -0.275042 0.275042)
							(end -0.2032 0.3048)
						)
						(arc
							(start 0.2032 0.3048)
							(mid 0.275042 0.275042)
							(end 0.3048 0.2032)
						)
					)
					(width 0)
					(fill yes)
				)
			)
		)
		(pad "2" smd custom
			(at 0 0.4445 180)
			(size 0.1524 0.1524)
			(layers "F.Cu" "F.Mask" "F.Paste")
			(net "GND")
			(options
				(clearance outline)
				(anchor circle)
			)
			(primitives
				(gr_poly
					(pts
						(arc
							(start 0.3048 -0.2032)
							(mid 0.275042 -0.275042)
							(end 0.2032 -0.3048)
						)
						(arc
							(start -0.2032 -0.3048)
							(mid -0.275042 -0.275042)
							(end -0.3048 -0.2032)
						)
						(arc
							(start -0.3048 0.2032)
							(mid -0.275042 0.275042)
							(end -0.2032 0.3048)
						)
						(arc
							(start 0.2032 0.3048)
							(mid 0.275042 0.275042)
							(end 0.3048 0.2032)
						)
					)
					(width 0)
					(fill yes)
				)
			)
		)
	)
	(footprint ""
		(layer "F.Cu")
		(at 193.6242 -4.1148)
		(property "Reference" "JP12"
			(at 0 0 0)
			(layer "F.SilkS")
			(hide yes)
			(effects
				(font
					(size 1.27 1.27)
				)
			)
		)
		(property "Value" "PIN-CON3-S-GP"
			(at -5.588 -5.3086 0)
			(unlocked yes)
			(layer "F.Fab")
			(hide yes)
			(effects
				(font
					(size 1.016 1.016)
					(thickness 0.1524)
				)
			)
		)
		(property "Device Type" "21S-91-03GB01"
			(at -5.588 -6.8326 0)
			(unlocked yes)
			(layer "F.Fab")
			(hide yes)
			(effects
				(font
					(size 1.016 1.016)
					(thickness 0.1524)
				)
			)
		)
		(duplicate_pad_numbers_are_jumpers no)
		(fp_line
			(start -4.0132 -1.6256)
			(end -2.7432 -1.6256)
			(stroke
				(width 0.4064)
				(type default)
			)
			(layer "F.SilkS")
		)
		(fp_line
			(start -4.0132 -0.3556)
			(end -4.0132 -1.6256)
			(stroke
				(width 0.4064)
				(type default)
			)
			(layer "F.SilkS")
		)
		(fp_line
			(start -3.8862 -1.4986)
			(end -3.8862 1.4986)
			(stroke
				(width 0.1524)
				(type default)
			)
			(layer "F.SilkS")
		)
		(fp_line
			(start -3.8862 1.4986)
			(end 3.8862 1.4986)
			(stroke
				(width 0.1524)
				(type default)
			)
			(layer "F.SilkS")
		)
		(fp_line
			(start 3.8862 -1.4986)
			(end -3.8862 -1.4986)
			(stroke
				(width 0.1524)
				(type default)
			)
			(layer "F.SilkS")
		)
		(fp_line
			(start 3.8862 1.4986)
			(end 3.8862 -1.4986)
			(stroke
				(width 0.1524)
				(type default)
			)
			(layer "F.SilkS")
		)
		(fp_circle
			(center -2.54 0)
			(end -1.4732 0)
			(stroke
				(width 0.3048)
				(type default)
			)
			(fill no)
			(layer "F.SilkS")
		)
		(fp_circle
			(center 0 0)
			(end 1.0668 0)
			(stroke
				(width 0.3048)
				(type default)
			)
			(fill no)
			(layer "F.SilkS")
		)
		(fp_circle
			(center 2.54 0)
			(end 3.6068 0)
			(stroke
				(width 0.3048)
				(type default)
			)
			(fill no)
			(layer "F.SilkS")
		)
		(fp_rect
			(start -3.6322 1.2446)
			(end 3.6322 -1.2446)
			(stroke
				(width 0)
				(type default)
			)
			(fill no)
			(layer "F.CrtYd")
		)
		(fp_poly
			(pts
				(xy 4.1402 -1.2446) (xy -3.6322 -1.2446) (xy -3.6322 1.2446) (xy 3.6322 1.2446) (xy 3.6322 -1.2319)
				(xy 4.1402 -1.2319) (xy 4.1402 1.7526) (xy -4.1402 1.7526) (xy -4.1402 -1.7526) (xy 4.1402 -1.7526)
			)
			(stroke
				(width 0)
				(type default)
			)
			(fill no)
			(layer "F.CrtYd")
		)
		(fp_rect
			(start -4.1402 1.7526)
			(end 4.1402 -1.7526)
			(stroke
				(width 0)
				(type default)
			)
			(fill no)
			(layer "F.Fab")
		)
		(pad "1" thru_hole circle
			(at -2.54 0)
			(size 1.4224 1.4224)
			(drill 1.016)
			(layers "*.Cu" "*.Mask")
			(remove_unused_layers no)
			(net "WP_DISABLE")
			(clearance 0.1524)
			(thermal_gap 0.1524)
		)
		(pad "2" thru_hole circle
			(at 0 0)
			(size 1.4224 1.4224)
			(drill 1.016)
			(layers "*.Cu" "*.Mask")
			(remove_unused_layers no)
			(net "FLA1_WPN")
			(clearance 0.1524)
			(thermal_gap 0.1524)
		)
		(pad "3" thru_hole circle
			(at 2.54 0)
			(size 1.4224 1.4224)
			(drill 1.016)
			(layers "*.Cu" "*.Mask")
			(remove_unused_layers no)
			(net "WP_ENABLE")
			(clearance 0.1524)
			(thermal_gap 0.1524)
		)
	)
	(footprint ""
		(layer "F.Cu")
		(at 159.807402 -55.272432 90)
		(property "Reference" "PR172"
			(at 0 0 90)
			(layer "F.SilkS")
			(hide yes)
			(effects
				(font
					(size 1.27 1.27)
				)
			)
		)
		(property "Value" "10D7R2F-GP"
			(at 0.064008 -3.993896 90)
			(unlocked yes)
			(layer "F.Fab")
			(hide yes)
			(effects
				(font
					(size 1.016 1.016)
					(thickness 0.1524)
				)
			)
		)
		(property "Device Type" "R402H16"
			(at 0.064008 -5.517896 90)
			(unlocked yes)
			(layer "F.Fab")
			(hide yes)
			(effects
				(font
					(size 1.016 1.016)
					(thickness 0.1524)
				)
			)
		)
		(duplicate_pad_numbers_are_jumpers no)
		(fp_line
			(start 0.508 -0.9398)
			(end -0.508 -0.9398)
			(stroke
				(width 0.1524)
				(type default)
			)
			(layer "F.SilkS")
		)
		(fp_line
			(start -0.508 -0.9398)
			(end -0.508 0.9398)
			(stroke
				(width 0.1524)
				(type default)
			)
			(layer "F.SilkS")
		)
		(fp_rect
			(start -0.508 0.9398)
			(end 0.508 -0.9398)
			(stroke
				(width 0)
				(type default)
			)
			(fill no)
			(layer "F.CrtYd")
		)
		(fp_rect
			(start -0.508 0.9398)
			(end 0.508 -0.9398)
			(stroke
				(width 0)
				(type default)
			)
			(fill no)
			(layer "F.Fab")
		)
		(pad "1" smd custom
			(at 0 -0.4445 90)
			(size 0.1397 0.1397)
			(layers "F.Cu" "F.Mask" "F.Paste")
			(net "P0V9_VFB_R")
			(options
				(clearance outline)
				(anchor circle)
			)
			(primitives
				(gr_poly
					(pts
						(arc
							(start -0.1778 -0.2794)
							(mid -0.249642 -0.249642)
							(end -0.2794 -0.1778)
						)
						(arc
							(start -0.2794 0.1778)
							(mid -0.249642 0.249642)
							(end -0.1778 0.2794)
						)
						(arc
							(start 0.1778 0.2794)
							(mid 0.249642 0.249642)
							(end 0.2794 0.1778)
						)
						(arc
							(start 0.2794 -0.1778)
							(mid 0.249642 -0.249642)
							(end 0.1778 -0.2794)
						)
					)
					(width 0)
					(fill yes)
				)
			)
		)
		(pad "2" smd custom
			(at 0 0.4445 90)
			(size 0.1397 0.1397)
			(layers "F.Cu" "F.Mask" "F.Paste")
			(net "P0V9")
			(options
				(clearance outline)
				(anchor circle)
			)
			(primitives
				(gr_poly
					(pts
						(arc
							(start -0.1778 -0.2794)
							(mid -0.249642 -0.249642)
							(end -0.2794 -0.1778)
						)
						(arc
							(start -0.2794 0.1778)
							(mid -0.249642 0.249642)
							(end -0.1778 0.2794)
						)
						(arc
							(start 0.1778 0.2794)
							(mid 0.249642 0.249642)
							(end 0.2794 0.1778)
						)
						(arc
							(start 0.2794 -0.1778)
							(mid 0.249642 -0.249642)
							(end 0.1778 -0.2794)
						)
					)
					(width 0)
					(fill yes)
				)
			)
		)
	)
	(footprint ""
		(layer "F.Cu")
		(at 201.00798 -212.420454 180)
		(property "Reference" "C116"
			(at 0 0 180)
			(layer "F.SilkS")
			(hide yes)
			(effects
				(font
					(size 1.27 1.27)
				)
			)
		)
		(property "Value" "SCD22U10V2KX-1GP"
			(at 1.1811 -2.7051 180)
			(unlocked yes)
			(layer "F.Fab")
			(hide yes)
			(effects
				(font
					(size 1.016 1.016)
					(thickness 0.1524)
				)
			)
		)
		(property "Device Type" "C402H22"
			(at 1.1811 -4.2291 180)
			(unlocked yes)
			(layer "F.Fab")
			(hide yes)
			(effects
				(font
					(size 1.016 1.016)
					(thickness 0.1524)
				)
			)
		)
		(duplicate_pad_numbers_are_jumpers no)
		(fp_rect
			(start -0.4318 0.9525)
			(end 0.4318 -0.9525)
			(stroke
				(width 0)
				(type default)
			)
			(fill no)
			(layer "F.CrtYd")
		)
		(fp_rect
			(start -0.4318 0.9525)
			(end 0.4318 -0.9525)
			(stroke
				(width 0)
				(type default)
			)
			(fill no)
			(layer "F.Fab")
		)
		(pad "1" smd custom
			(at 0 -0.4445 180)
			(size 0.1524 0.1524)
			(layers "F.Cu" "F.Mask" "F.Paste")
			(net "PCIE_TX_CAP_N42")
			(options
				(clearance outline)
				(anchor circle)
			)
			(primitives
				(gr_poly
					(pts
						(arc
							(start 0.3048 -0.2032)
							(mid 0.275042 -0.275042)
							(end 0.2032 -0.3048)
						)
						(arc
							(start -0.2032 -0.3048)
							(mid -0.275042 -0.275042)
							(end -0.3048 -0.2032)
						)
						(arc
							(start -0.3048 0.2032)
							(mid -0.275042 0.275042)
							(end -0.2032 0.3048)
						)
						(arc
							(start 0.2032 0.3048)
							(mid 0.275042 0.275042)
							(end 0.3048 0.2032)
						)
					)
					(width 0)
					(fill yes)
				)
			)
		)
		(pad "2" smd custom
			(at 0 0.4445 180)
			(size 0.1524 0.1524)
			(layers "F.Cu" "F.Mask" "F.Paste")
			(net "PCIE_TX_N42")
			(options
				(clearance outline)
				(anchor circle)
			)
			(primitives
				(gr_poly
					(pts
						(arc
							(start 0.3048 -0.2032)
							(mid 0.275042 -0.275042)
							(end 0.2032 -0.3048)
						)
						(arc
							(start -0.2032 -0.3048)
							(mid -0.275042 -0.275042)
							(end -0.3048 -0.2032)
						)
						(arc
							(start -0.3048 0.2032)
							(mid -0.275042 0.275042)
							(end -0.2032 0.3048)
						)
						(arc
							(start 0.2032 0.3048)
							(mid 0.275042 0.275042)
							(end 0.3048 0.2032)
						)
					)
					(width 0)
					(fill yes)
				)
			)
		)
	)
	(footprint ""
		(layer "F.Cu")
		(at 166.116 -89.5604 90)
		(property "Reference" "R3105"
			(at 0 0 90)
			(layer "F.SilkS")
			(hide yes)
			(effects
				(font
					(size 1.27 1.27)
				)
			)
		)
		(property "Value" "27R2F-GP"
			(at 0.064008 -3.993896 90)
			(unlocked yes)
			(layer "F.Fab")
			(hide yes)
			(effects
				(font
					(size 1.016 1.016)
					(thickness 0.1524)
				)
			)
		)
		(property "Device Type" "R402H16"
			(at 0.064008 -5.517896 90)
			(unlocked yes)
			(layer "F.Fab")
			(hide yes)
			(effects
				(font
					(size 1.016 1.016)
					(thickness 0.1524)
				)
			)
		)
		(duplicate_pad_numbers_are_jumpers no)
		(fp_line
			(start 0.508 -0.9398)
			(end -0.508 -0.9398)
			(stroke
				(width 0.1524)
				(type default)
			)
			(layer "F.SilkS")
		)
		(fp_line
			(start -0.508 -0.9398)
			(end -0.508 0.9398)
			(stroke
				(width 0.1524)
				(type default)
			)
			(layer "F.SilkS")
		)
		(fp_rect
			(start -0.508 0.9398)
			(end 0.508 -0.9398)
			(stroke
				(width 0)
				(type default)
			)
			(fill no)
			(layer "F.CrtYd")
		)
		(fp_rect
			(start -0.508 0.9398)
			(end 0.508 -0.9398)
			(stroke
				(width 0)
				(type default)
			)
			(fill no)
			(layer "F.Fab")
		)
		(pad "1" smd custom
			(at 0 -0.4445 90)
			(size 0.1397 0.1397)
			(layers "F.Cu" "F.Mask" "F.Paste")
			(net "CLKGEN_N1_R")
			(options
				(clearance outline)
				(anchor circle)
			)
			(primitives
				(gr_poly
					(pts
						(arc
							(start -0.1778 -0.2794)
							(mid -0.249642 -0.249642)
							(end -0.2794 -0.1778)
						)
						(arc
							(start -0.2794 0.1778)
							(mid -0.249642 0.249642)
							(end -0.1778 0.2794)
						)
						(arc
							(start 0.1778 0.2794)
							(mid 0.249642 0.249642)
							(end 0.2794 0.1778)
						)
						(arc
							(start 0.2794 -0.1778)
							(mid 0.249642 -0.249642)
							(end 0.1778 -0.2794)
						)
					)
					(width 0)
					(fill yes)
				)
			)
		)
		(pad "2" smd custom
			(at 0 0.4445 90)
			(size 0.1397 0.1397)
			(layers "F.Cu" "F.Mask" "F.Paste")
			(net "I210_REFCLK_D_N")
			(options
				(clearance outline)
				(anchor circle)
			)
			(primitives
				(gr_poly
					(pts
						(arc
							(start -0.1778 -0.2794)
							(mid -0.249642 -0.249642)
							(end -0.2794 -0.1778)
						)
						(arc
							(start -0.2794 0.1778)
							(mid -0.249642 0.249642)
							(end -0.1778 0.2794)
						)
						(arc
							(start 0.1778 0.2794)
							(mid 0.249642 0.249642)
							(end 0.2794 0.1778)
						)
						(arc
							(start 0.2794 -0.1778)
							(mid 0.249642 -0.249642)
							(end 0.1778 -0.2794)
						)
					)
					(width 0)
					(fill yes)
				)
			)
		)
	)
	(footprint ""
		(layer "F.Cu")
		(at 64.065912 -31.700216 -90)
		(property "Reference" "R739"
			(at 0 0 270)
			(layer "F.SilkS")
			(hide yes)
			(effects
				(font
					(size 1.27 1.27)
				)
			)
		)
		(property "Value" "0R2J-2-GP"
			(at 0.064008 -3.993896 270)
			(unlocked yes)
			(layer "F.Fab")
			(hide yes)
			(effects
				(font
					(size 1.016 1.016)
					(thickness 0.1524)
				)
			)
		)
		(property "Device Type" "R402H16"
			(at 0.064008 -5.517896 270)
			(unlocked yes)
			(layer "F.Fab")
			(hide yes)
			(effects
				(font
					(size 1.016 1.016)
					(thickness 0.1524)
				)
			)
		)
		(duplicate_pad_numbers_are_jumpers no)
		(fp_line
			(start -0.508 -0.9398)
			(end -0.508 0.9398)
			(stroke
				(width 0.1524)
				(type default)
			)
			(layer "F.SilkS")
		)
		(fp_line
			(start 0.508 -0.9398)
			(end -0.508 -0.9398)
			(stroke
				(width 0.1524)
				(type default)
			)
			(layer "F.SilkS")
		)
		(fp_rect
			(start -0.508 0.9398)
			(end 0.508 -0.9398)
			(stroke
				(width 0)
				(type default)
			)
			(fill no)
			(layer "F.CrtYd")
		)
		(fp_rect
			(start -0.508 0.9398)
			(end 0.508 -0.9398)
			(stroke
				(width 0)
				(type default)
			)
			(fill no)
			(layer "F.Fab")
		)
		(pad "1" smd custom
			(at 0 -0.4445 270)
			(size 0.1397 0.1397)
			(layers "F.Cu" "F.Mask" "F.Paste")
			(net "TRAY_MBP_CTRL_EN_N")
			(options
				(clearance outline)
				(anchor circle)
			)
			(primitives
				(gr_poly
					(pts
						(arc
							(start -0.1778 -0.2794)
							(mid -0.249642 -0.249642)
							(end -0.2794 -0.1778)
						)
						(arc
							(start -0.2794 0.1778)
							(mid -0.249642 0.249642)
							(end -0.1778 0.2794)
						)
						(arc
							(start 0.1778 0.2794)
							(mid 0.249642 0.249642)
							(end 0.2794 0.1778)
						)
						(arc
							(start 0.2794 -0.1778)
							(mid 0.249642 -0.249642)
							(end 0.1778 -0.2794)
						)
					)
					(width 0)
					(fill yes)
				)
			)
		)
		(pad "2" smd custom
			(at 0 0.4445 270)
			(size 0.1397 0.1397)
			(layers "F.Cu" "F.Mask" "F.Paste")
			(net "CN2_P23")
			(options
				(clearance outline)
				(anchor circle)
			)
			(primitives
				(gr_poly
					(pts
						(arc
							(start -0.1778 -0.2794)
							(mid -0.249642 -0.249642)
							(end -0.2794 -0.1778)
						)
						(arc
							(start -0.2794 0.1778)
							(mid -0.249642 0.249642)
							(end -0.1778 0.2794)
						)
						(arc
							(start 0.1778 0.2794)
							(mid 0.249642 0.249642)
							(end 0.2794 0.1778)
						)
						(arc
							(start 0.2794 -0.1778)
							(mid 0.249642 -0.249642)
							(end 0.1778 -0.2794)
						)
					)
					(width 0)
					(fill yes)
				)
			)
		)
	)
	(footprint ""
		(layer "F.Cu")
		(at 13.0302 -180.6956)
		(property "Reference" "R2110"
			(at 0 0 0)
			(layer "F.SilkS")
			(hide yes)
			(effects
				(font
					(size 1.27 1.27)
				)
			)
		)
		(property "Value" "1KR2J-1-GP"
			(at 0.064008 -3.993896 0)
			(unlocked yes)
			(layer "F.Fab")
			(hide yes)
			(effects
				(font
					(size 1.016 1.016)
					(thickness 0.1524)
				)
			)
		)
		(property "Device Type" "R402H16"
			(at 0.064008 -5.517896 0)
			(unlocked yes)
			(layer "F.Fab")
			(hide yes)
			(effects
				(font
					(size 1.016 1.016)
					(thickness 0.1524)
				)
			)
		)
		(duplicate_pad_numbers_are_jumpers no)
		(fp_line
			(start -0.508 -0.9398)
			(end -0.508 0.9398)
			(stroke
				(width 0.1524)
				(type default)
			)
			(layer "F.SilkS")
		)
		(fp_line
			(start 0.508 -0.9398)
			(end -0.508 -0.9398)
			(stroke
				(width 0.1524)
				(type default)
			)
			(layer "F.SilkS")
		)
		(fp_rect
			(start -0.508 0.9398)
			(end 0.508 -0.9398)
			(stroke
				(width 0)
				(type default)
			)
			(fill no)
			(layer "F.CrtYd")
		)
		(fp_rect
			(start -0.508 0.9398)
			(end 0.508 -0.9398)
			(stroke
				(width 0)
				(type default)
			)
			(fill no)
			(layer "F.Fab")
		)
		(pad "1" smd custom
			(at 0 -0.4445)
			(size 0.1397 0.1397)
			(layers "F.Cu" "F.Mask" "F.Paste")
			(net "MB0_CM_VOUT_R")
			(options
				(clearance outline)
				(anchor circle)
			)
			(primitives
				(gr_poly
					(pts
						(arc
							(start -0.1778 -0.2794)
							(mid -0.249642 -0.249642)
							(end -0.2794 -0.1778)
						)
						(arc
							(start -0.2794 0.1778)
							(mid -0.249642 0.249642)
							(end -0.1778 0.2794)
						)
						(arc
							(start 0.1778 0.2794)
							(mid 0.249642 0.249642)
							(end 0.2794 0.1778)
						)
						(arc
							(start 0.2794 -0.1778)
							(mid 0.249642 -0.249642)
							(end 0.1778 -0.2794)
						)
					)
					(width 0)
					(fill yes)
				)
			)
		)
		(pad "2" smd custom
			(at 0 0.4445)
			(size 0.1397 0.1397)
			(layers "F.Cu" "F.Mask" "F.Paste")
			(net "P12V")
			(options
				(clearance outline)
				(anchor circle)
			)
			(primitives
				(gr_poly
					(pts
						(arc
							(start -0.1778 -0.2794)
							(mid -0.249642 -0.249642)
							(end -0.2794 -0.1778)
						)
						(arc
							(start -0.2794 0.1778)
							(mid -0.249642 0.249642)
							(end -0.1778 0.2794)
						)
						(arc
							(start 0.1778 0.2794)
							(mid 0.249642 0.249642)
							(end 0.2794 0.1778)
						)
						(arc
							(start 0.2794 -0.1778)
							(mid 0.249642 -0.249642)
							(end 0.1778 -0.2794)
						)
					)
					(width 0)
					(fill yes)
				)
			)
		)
	)
	(footprint ""
		(layer "F.Cu")
		(at 161.163 -33.528)
		(property "Reference" "C400"
			(at 0 0 0)
			(layer "F.SilkS")
			(hide yes)
			(effects
				(font
					(size 1.27 1.27)
				)
			)
		)
		(property "Value" "SCD22U10V2KX-1GP"
			(at 1.1811 -2.7051 0)
			(unlocked yes)
			(layer "F.Fab")
			(hide yes)
			(effects
				(font
					(size 1.016 1.016)
					(thickness 0.1524)
				)
			)
		)
		(property "Device Type" "C402H22"
			(at 1.1811 -4.2291 0)
			(unlocked yes)
			(layer "F.Fab")
			(hide yes)
			(effects
				(font
					(size 1.016 1.016)
					(thickness 0.1524)
				)
			)
		)
		(duplicate_pad_numbers_are_jumpers no)
		(fp_rect
			(start -0.4318 0.9525)
			(end 0.4318 -0.9525)
			(stroke
				(width 0)
				(type default)
			)
			(fill no)
			(layer "F.CrtYd")
		)
		(fp_rect
			(start -0.4318 0.9525)
			(end 0.4318 -0.9525)
			(stroke
				(width 0)
				(type default)
			)
			(fill no)
			(layer "F.Fab")
		)
		(pad "1" smd custom
			(at 0 -0.4445)
			(size 0.1524 0.1524)
			(layers "F.Cu" "F.Mask" "F.Paste")
			(net "PCIE_TX_CAP_P90")
			(options
				(clearance outline)
				(anchor circle)
			)
			(primitives
				(gr_poly
					(pts
						(arc
							(start 0.3048 -0.2032)
							(mid 0.275042 -0.275042)
							(end 0.2032 -0.3048)
						)
						(arc
							(start -0.2032 -0.3048)
							(mid -0.275042 -0.275042)
							(end -0.3048 -0.2032)
						)
						(arc
							(start -0.3048 0.2032)
							(mid -0.275042 0.275042)
							(end -0.2032 0.3048)
						)
						(arc
							(start 0.2032 0.3048)
							(mid 0.275042 0.275042)
							(end 0.3048 0.2032)
						)
					)
					(width 0)
					(fill yes)
				)
			)
		)
		(pad "2" smd custom
			(at 0 0.4445)
			(size 0.1524 0.1524)
			(layers "F.Cu" "F.Mask" "F.Paste")
			(net "PCIE_TX_P90")
			(options
				(clearance outline)
				(anchor circle)
			)
			(primitives
				(gr_poly
					(pts
						(arc
							(start 0.3048 -0.2032)
							(mid 0.275042 -0.275042)
							(end 0.2032 -0.3048)
						)
						(arc
							(start -0.2032 -0.3048)
							(mid -0.275042 -0.275042)
							(end -0.3048 -0.2032)
						)
						(arc
							(start -0.3048 0.2032)
							(mid -0.275042 0.275042)
							(end -0.2032 0.3048)
						)
						(arc
							(start 0.2032 0.3048)
							(mid 0.275042 0.275042)
							(end 0.3048 0.2032)
						)
					)
					(width 0)
					(fill yes)
				)
			)
		)
	)
	(footprint ""
		(layer "F.Cu")
		(at 37.599874 -36.289996)
		(property "Reference" "SKT1"
			(at 0 0 0)
			(layer "F.SilkS")
			(hide yes)
			(effects
				(font
					(size 1.27 1.27)
				)
			)
		)
		(property "Value" "SKT-USB-250-GP"
			(at -10.033 -1.3716 0)
			(unlocked yes)
			(layer "F.Fab")
			(hide yes)
			(effects
				(font
					(size 1.016 1.016)
					(thickness 0.1524)
				)
			)
		)
		(property "Device Type" "67643-3911"
			(at -10.033 -2.8956 0)
			(unlocked yes)
			(layer "F.Fab")
			(hide yes)
			(effects
				(font
					(size 1.016 1.016)
					(thickness 0.1524)
				)
			)
		)
		(duplicate_pad_numbers_are_jumpers no)
		(fp_line
			(start -8.1788 -1.4605)
			(end -7.4549 -1.4605)
			(stroke
				(width 0.1524)
				(type default)
			)
			(layer "F.SilkS")
		)
		(fp_line
			(start -8.1788 1.4605)
			(end -8.1788 -1.4605)
			(stroke
				(width 0.1524)
				(type default)
			)
			(layer "F.SilkS")
		)
		(fp_line
			(start -7.4549 -5.2324)
			(end 7.4549 -5.2324)
			(stroke
				(width 0.1524)
				(type default)
			)
			(layer "F.SilkS")
		)
		(fp_line
			(start -7.4549 -1.4605)
			(end -7.4549 -5.2324)
			(stroke
				(width 0.1524)
				(type default)
			)
			(layer "F.SilkS")
		)
		(fp_line
			(start -7.4549 1.4605)
			(end -8.1788 1.4605)
			(stroke
				(width 0.1524)
				(type default)
			)
			(layer "F.SilkS")
		)
		(fp_line
			(start -7.4549 10.279888)
			(end 7.4549 10.279888)
			(stroke
				(width 0.1524)
				(type default)
			)
			(layer "F.SilkS")
		)
		(fp_line
			(start -7.4549 10.541)
			(end -7.4549 1.4605)
			(stroke
				(width 0.1524)
				(type default)
			)
			(layer "F.SilkS")
		)
		(fp_line
			(start 7.4549 -5.2324)
			(end 7.4549 -1.4605)
			(stroke
				(width 0.1524)
				(type default)
			)
			(layer "F.SilkS")
		)
		(fp_line
			(start 7.4549 -1.4605)
			(end 8.1788 -1.4605)
			(stroke
				(width 0.1524)
				(type default)
			)
			(layer "F.SilkS")
		)
		(fp_line
			(start 7.4549 1.4605)
			(end 7.4549 10.541)
			(stroke
				(width 0.1524)
				(type default)
			)
			(layer "F.SilkS")
		)
		(fp_line
			(start 7.4549 10.541)
			(end -7.4549 10.541)
			(stroke
				(width 0.1524)
				(type default)
			)
			(layer "F.SilkS")
		)
		(fp_line
			(start 8.1788 -1.4605)
			(end 8.1788 1.4605)
			(stroke
				(width 0.1524)
				(type default)
			)
			(layer "F.SilkS")
		)
		(fp_line
			(start 8.1788 1.4605)
			(end 7.4549 1.4605)
			(stroke
				(width 0.1524)
				(type default)
			)
			(layer "F.SilkS")
		)
		(fp_arc
			(start 0 -3.000756)
			(mid 2.041429 -2.709926)
			(end 0 -2.419096)
			(stroke
				(width 0.3048)
				(type default)
			)
			(layer "F.SilkS")
		)
		(fp_arc
			(start 0 -2.419096)
			(mid -2.041429 -2.709926)
			(end 0 -3.000756)
			(stroke
				(width 0.3048)
				(type default)
			)
			(layer "F.SilkS")
		)
		(fp_circle
			(center -6.569964 0)
			(end -4.855464 0)
			(stroke
				(width 0.3048)
				(type default)
			)
			(fill no)
			(layer "F.SilkS")
		)
		(fp_circle
			(center -3.50012 -2.709926)
			(end -2.45872 -2.709926)
			(stroke
				(width 0.3048)
				(type default)
			)
			(fill no)
			(layer "F.SilkS")
		)
		(fp_circle
			(center 3.50012 -2.709926)
			(end 4.54152 -2.709926)
			(stroke
				(width 0.3048)
				(type default)
			)
			(fill no)
			(layer "F.SilkS")
		)
		(fp_circle
			(center 6.569964 0)
			(end 8.284464 0)
			(stroke
				(width 0.3048)
				(type default)
			)
			(fill no)
			(layer "F.SilkS")
		)
		(fp_poly
			(pts
				(xy -7.2009 10.287) (xy -7.2009 0.7493) (xy -7.8486 0.7493) (xy -7.8486 -0.7493) (xy -7.2009 -0.7493)
				(xy -7.2009 -4.9784) (xy 7.2009 -4.9784) (xy 7.2009 -0.7493) (xy 7.8486 -0.7493) (xy 7.8486 0.7493)
				(xy 7.2009 0.7493) (xy 7.2009 10.287)
			)
			(stroke
				(width 0)
				(type default)
			)
			(fill no)
			(layer "F.CrtYd")
		)
		(fp_poly
			(pts
				(xy -7.2009 10.287) (xy -7.2009 0.7493) (xy -7.8486 0.7493) (xy -7.8486 -0.7493) (xy -7.2009 -0.7493)
				(xy -7.2009 -4.9784) (xy 7.2009 -4.9784) (xy 7.2009 -4.4323) (xy 7.7089 -4.4323) (xy 7.7089 -5.4864)
				(xy -7.7089 -5.4864) (xy -7.7089 -1.7145) (xy -8.4328 -1.7145) (xy -8.4328 1.7145) (xy -7.7089 1.7145)
				(xy -7.7089 10.795) (xy 7.7089 10.795) (xy 7.7089 1.7145) (xy 8.4328 1.7145) (xy 8.4328 -1.7145)
				(xy 7.7089 -1.7145) (xy 7.7089 -4.4196) (xy 7.2009 -4.4196) (xy 7.2009 -0.7493) (xy 7.8486 -0.7493)
				(xy 7.8486 0.7493) (xy 7.2009 0.7493) (xy 7.2009 10.287)
			)
			(stroke
				(width 0)
				(type default)
			)
			(fill no)
			(layer "F.CrtYd")
		)
		(fp_poly
			(pts
				(xy -7.7089 10.795) (xy -7.7089 1.7145) (xy -8.4328 1.7145) (xy -8.4328 -1.7145) (xy -7.7089 -1.7145)
				(xy -7.7089 -5.4864) (xy 7.7089 -5.4864) (xy 7.7089 -1.7145) (xy 8.4328 -1.7145) (xy 8.4328 1.7145)
				(xy 7.7089 1.7145) (xy 7.7089 10.795)
			)
			(stroke
				(width 0)
				(type default)
			)
			(fill no)
			(layer "F.Fab")
		)
		(pad "1" thru_hole circle
			(at -3.50012 -2.709926)
			(size 1.3716 1.3716)
			(drill 0.9652)
			(layers "*.Cu" "*.Mask")
			(remove_unused_layers no)
			(net "P5V_USB")
			(clearance 0.1524)
			(thermal_gap 0.1524)
		)
		(pad "2" thru_hole circle
			(at -0.999998 -2.709926)
			(size 1.3716 1.3716)
			(drill 0.9652)
			(layers "*.Cu" "*.Mask")
			(remove_unused_layers no)
			(net "USB_P1_F_DN1")
			(clearance 0.1524)
			(thermal_gap 0.1524)
		)
		(pad "3" thru_hole circle
			(at 0.999998 -2.709926)
			(size 1.3716 1.3716)
			(drill 0.9652)
			(layers "*.Cu" "*.Mask")
			(remove_unused_layers no)
			(net "USB_P1_F_DP1")
			(clearance 0.1524)
			(thermal_gap 0.1524)
		)
		(pad "4" thru_hole circle
			(at 3.50012 -2.709926)
			(size 1.3716 1.3716)
			(drill 0.9652)
			(layers "*.Cu" "*.Mask")
			(remove_unused_layers no)
			(net "GND")
			(clearance 0.1524)
			(thermal_gap 0.1524)
		)
		(pad "5" thru_hole circle
			(at 6.569964 0)
			(size 2.7178 2.7178)
			(drill 2.3114)
			(layers "*.Cu" "*.Mask")
			(remove_unused_layers no)
			(net "AGND_USB")
			(clearance 0.1524)
			(thermal_gap 0.1524)
		)
		(pad "6" thru_hole circle
			(at -6.569964 0)
			(size 2.7178 2.7178)
			(drill 2.3114)
			(layers "*.Cu" "*.Mask")
			(remove_unused_layers no)
			(net "AGND_USB")
			(clearance 0.1524)
			(thermal_gap 0.1524)
		)
	)
	(footprint ""
		(layer "F.Cu")
		(at 62.3062 -161.8996)
		(property "Reference" "PR67"
			(at 0 0 0)
			(layer "F.SilkS")
			(hide yes)
			(effects
				(font
					(size 1.27 1.27)
				)
			)
		)
		(property "Value" "4K75R2F-1-GP"
			(at 0.064008 -3.993896 0)
			(unlocked yes)
			(layer "F.Fab")
			(hide yes)
			(effects
				(font
					(size 1.016 1.016)
					(thickness 0.1524)
				)
			)
		)
		(property "Device Type" "R402H16"
			(at 0.064008 -5.517896 0)
			(unlocked yes)
			(layer "F.Fab")
			(hide yes)
			(effects
				(font
					(size 1.016 1.016)
					(thickness 0.1524)
				)
			)
		)
		(duplicate_pad_numbers_are_jumpers no)
		(fp_line
			(start -0.508 -0.9398)
			(end -0.508 0.9398)
			(stroke
				(width 0.1524)
				(type default)
			)
			(layer "F.SilkS")
		)
		(fp_line
			(start 0.508 -0.9398)
			(end -0.508 -0.9398)
			(stroke
				(width 0.1524)
				(type default)
			)
			(layer "F.SilkS")
		)
		(fp_rect
			(start -0.508 0.9398)
			(end 0.508 -0.9398)
			(stroke
				(width 0)
				(type default)
			)
			(fill no)
			(layer "F.CrtYd")
		)
		(fp_rect
			(start -0.508 0.9398)
			(end 0.508 -0.9398)
			(stroke
				(width 0)
				(type default)
			)
			(fill no)
			(layer "F.Fab")
		)
		(pad "1" smd custom
			(at 0 -0.4445)
			(size 0.1397 0.1397)
			(layers "F.Cu" "F.Mask" "F.Paste")
			(net "VR_P1V538_STBY_FB")
			(options
				(clearance outline)
				(anchor circle)
			)
			(primitives
				(gr_poly
					(pts
						(arc
							(start -0.1778 -0.2794)
							(mid -0.249642 -0.249642)
							(end -0.2794 -0.1778)
						)
						(arc
							(start -0.2794 0.1778)
							(mid -0.249642 0.249642)
							(end -0.1778 0.2794)
						)
						(arc
							(start 0.1778 0.2794)
							(mid 0.249642 0.249642)
							(end 0.2794 0.1778)
						)
						(arc
							(start 0.2794 -0.1778)
							(mid 0.249642 -0.249642)
							(end 0.1778 -0.2794)
						)
					)
					(width 0)
					(fill yes)
				)
			)
		)
		(pad "2" smd custom
			(at 0 0.4445)
			(size 0.1397 0.1397)
			(layers "F.Cu" "F.Mask" "F.Paste")
			(net "GND")
			(options
				(clearance outline)
				(anchor circle)
			)
			(primitives
				(gr_poly
					(pts
						(arc
							(start -0.1778 -0.2794)
							(mid -0.249642 -0.249642)
							(end -0.2794 -0.1778)
						)
						(arc
							(start -0.2794 0.1778)
							(mid -0.249642 0.249642)
							(end -0.1778 0.2794)
						)
						(arc
							(start 0.1778 0.2794)
							(mid 0.249642 0.249642)
							(end 0.2794 0.1778)
						)
						(arc
							(start 0.2794 -0.1778)
							(mid 0.249642 -0.249642)
							(end 0.1778 -0.2794)
						)
					)
					(width 0)
					(fill yes)
				)
			)
		)
	)
	(footprint ""
		(layer "F.Cu")
		(at 31.369 -48.006 -90)
		(property "Reference" "C240"
			(at 0 0 270)
			(layer "F.SilkS")
			(hide yes)
			(effects
				(font
					(size 1.27 1.27)
				)
			)
		)
		(property "Value" "SCD1U16V2JX-1-GP"
			(at 1.1811 -2.7051 270)
			(unlocked yes)
			(layer "F.Fab")
			(hide yes)
			(effects
				(font
					(size 1.016 1.016)
					(thickness 0.1524)
				)
			)
		)
		(property "Device Type" "C402H22"
			(at 1.1811 -4.2291 270)
			(unlocked yes)
			(layer "F.Fab")
			(hide yes)
			(effects
				(font
					(size 1.016 1.016)
					(thickness 0.1524)
				)
			)
		)
		(duplicate_pad_numbers_are_jumpers no)
		(fp_rect
			(start -0.4318 0.9525)
			(end 0.4318 -0.9525)
			(stroke
				(width 0)
				(type default)
			)
			(fill no)
			(layer "F.CrtYd")
		)
		(fp_rect
			(start -0.4318 0.9525)
			(end 0.4318 -0.9525)
			(stroke
				(width 0)
				(type default)
			)
			(fill no)
			(layer "F.Fab")
		)
		(pad "1" smd custom
			(at 0 -0.4445 270)
			(size 0.1524 0.1524)
			(layers "F.Cu" "F.Mask" "F.Paste")
			(net "P5V_USB")
			(options
				(clearance outline)
				(anchor circle)
			)
			(primitives
				(gr_poly
					(pts
						(arc
							(start 0.3048 -0.2032)
							(mid 0.275042 -0.275042)
							(end 0.2032 -0.3048)
						)
						(arc
							(start -0.2032 -0.3048)
							(mid -0.275042 -0.275042)
							(end -0.3048 -0.2032)
						)
						(arc
							(start -0.3048 0.2032)
							(mid -0.275042 0.275042)
							(end -0.2032 0.3048)
						)
						(arc
							(start 0.2032 0.3048)
							(mid 0.275042 0.275042)
							(end 0.3048 0.2032)
						)
					)
					(width 0)
					(fill yes)
				)
			)
		)
		(pad "2" smd custom
			(at 0 0.4445 270)
			(size 0.1524 0.1524)
			(layers "F.Cu" "F.Mask" "F.Paste")
			(net "GND")
			(options
				(clearance outline)
				(anchor circle)
			)
			(primitives
				(gr_poly
					(pts
						(arc
							(start 0.3048 -0.2032)
							(mid 0.275042 -0.275042)
							(end 0.2032 -0.3048)
						)
						(arc
							(start -0.2032 -0.3048)
							(mid -0.275042 -0.275042)
							(end -0.3048 -0.2032)
						)
						(arc
							(start -0.3048 0.2032)
							(mid -0.275042 0.275042)
							(end -0.2032 0.3048)
						)
						(arc
							(start 0.2032 0.3048)
							(mid 0.275042 0.275042)
							(end 0.3048 0.2032)
						)
					)
					(width 0)
					(fill yes)
				)
			)
		)
	)
	(footprint ""
		(layer "F.Cu")
		(at 16.578326 -127.56388 90)
		(property "Reference" "R407"
			(at 0 0 90)
			(layer "F.SilkS")
			(hide yes)
			(effects
				(font
					(size 1.27 1.27)
				)
			)
		)
		(property "Value" "10KR2F-2-GP"
			(at 0.064008 -3.993896 90)
			(unlocked yes)
			(layer "F.Fab")
			(hide yes)
			(effects
				(font
					(size 1.016 1.016)
					(thickness 0.1524)
				)
			)
		)
		(property "Device Type" "R402H16"
			(at 0.064008 -5.517896 90)
			(unlocked yes)
			(layer "F.Fab")
			(hide yes)
			(effects
				(font
					(size 1.016 1.016)
					(thickness 0.1524)
				)
			)
		)
		(duplicate_pad_numbers_are_jumpers no)
		(fp_line
			(start 0.508 -0.9398)
			(end -0.508 -0.9398)
			(stroke
				(width 0.1524)
				(type default)
			)
			(layer "F.SilkS")
		)
		(fp_line
			(start -0.508 -0.9398)
			(end -0.508 0.9398)
			(stroke
				(width 0.1524)
				(type default)
			)
			(layer "F.SilkS")
		)
		(fp_rect
			(start -0.508 0.9398)
			(end 0.508 -0.9398)
			(stroke
				(width 0)
				(type default)
			)
			(fill no)
			(layer "F.CrtYd")
		)
		(fp_rect
			(start -0.508 0.9398)
			(end 0.508 -0.9398)
			(stroke
				(width 0)
				(type default)
			)
			(fill no)
			(layer "F.Fab")
		)
		(pad "1" smd custom
			(at 0 -0.4445 90)
			(size 0.1397 0.1397)
			(layers "F.Cu" "F.Mask" "F.Paste")
			(net "P3V3_STBY")
			(options
				(clearance outline)
				(anchor circle)
			)
			(primitives
				(gr_poly
					(pts
						(arc
							(start -0.1778 -0.2794)
							(mid -0.249642 -0.249642)
							(end -0.2794 -0.1778)
						)
						(arc
							(start -0.2794 0.1778)
							(mid -0.249642 0.249642)
							(end -0.1778 0.2794)
						)
						(arc
							(start 0.1778 0.2794)
							(mid 0.249642 0.249642)
							(end 0.2794 0.1778)
						)
						(arc
							(start 0.2794 -0.1778)
							(mid 0.249642 -0.249642)
							(end 0.1778 -0.2794)
						)
					)
					(width 0)
					(fill yes)
				)
			)
		)
		(pad "2" smd custom
			(at 0 0.4445 90)
			(size 0.1397 0.1397)
			(layers "F.Cu" "F.Mask" "F.Paste")
			(net "PE1_PERST#")
			(options
				(clearance outline)
				(anchor circle)
			)
			(primitives
				(gr_poly
					(pts
						(arc
							(start -0.1778 -0.2794)
							(mid -0.249642 -0.249642)
							(end -0.2794 -0.1778)
						)
						(arc
							(start -0.2794 0.1778)
							(mid -0.249642 0.249642)
							(end -0.1778 0.2794)
						)
						(arc
							(start 0.1778 0.2794)
							(mid 0.249642 0.249642)
							(end 0.2794 0.1778)
						)
						(arc
							(start 0.2794 -0.1778)
							(mid 0.249642 -0.249642)
							(end 0.1778 -0.2794)
						)
					)
					(width 0)
					(fill yes)
				)
			)
		)
	)
	(footprint ""
		(layer "F.Cu")
		(at 229.108 -92.202 90)
		(property "Reference" "R585"
			(at 0 0 90)
			(layer "F.SilkS")
			(hide yes)
			(effects
				(font
					(size 1.27 1.27)
				)
			)
		)
		(property "Value" "4K7R2F-GP"
			(at 0.064008 -3.993896 90)
			(unlocked yes)
			(layer "F.Fab")
			(hide yes)
			(effects
				(font
					(size 1.016 1.016)
					(thickness 0.1524)
				)
			)
		)
		(property "Device Type" "R402H16"
			(at 0.064008 -5.517896 90)
			(unlocked yes)
			(layer "F.Fab")
			(hide yes)
			(effects
				(font
					(size 1.016 1.016)
					(thickness 0.1524)
				)
			)
		)
		(duplicate_pad_numbers_are_jumpers no)
		(fp_line
			(start 0.508 -0.9398)
			(end -0.508 -0.9398)
			(stroke
				(width 0.1524)
				(type default)
			)
			(layer "F.SilkS")
		)
		(fp_line
			(start -0.508 -0.9398)
			(end -0.508 0.9398)
			(stroke
				(width 0.1524)
				(type default)
			)
			(layer "F.SilkS")
		)
		(fp_rect
			(start -0.508 0.9398)
			(end 0.508 -0.9398)
			(stroke
				(width 0)
				(type default)
			)
			(fill no)
			(layer "F.CrtYd")
		)
		(fp_rect
			(start -0.508 0.9398)
			(end 0.508 -0.9398)
			(stroke
				(width 0)
				(type default)
			)
			(fill no)
			(layer "F.Fab")
		)
		(pad "1" smd custom
			(at 0 -0.4445 90)
			(size 0.1397 0.1397)
			(layers "F.Cu" "F.Mask" "F.Paste")
			(net "TEMP_3_A0")
			(options
				(clearance outline)
				(anchor circle)
			)
			(primitives
				(gr_poly
					(pts
						(arc
							(start -0.1778 -0.2794)
							(mid -0.249642 -0.249642)
							(end -0.2794 -0.1778)
						)
						(arc
							(start -0.2794 0.1778)
							(mid -0.249642 0.249642)
							(end -0.1778 0.2794)
						)
						(arc
							(start 0.1778 0.2794)
							(mid 0.249642 0.249642)
							(end 0.2794 0.1778)
						)
						(arc
							(start 0.2794 -0.1778)
							(mid 0.249642 -0.249642)
							(end 0.1778 -0.2794)
						)
					)
					(width 0)
					(fill yes)
				)
			)
		)
		(pad "2" smd custom
			(at 0 0.4445 90)
			(size 0.1397 0.1397)
			(layers "F.Cu" "F.Mask" "F.Paste")
			(net "GND")
			(options
				(clearance outline)
				(anchor circle)
			)
			(primitives
				(gr_poly
					(pts
						(arc
							(start -0.1778 -0.2794)
							(mid -0.249642 -0.249642)
							(end -0.2794 -0.1778)
						)
						(arc
							(start -0.2794 0.1778)
							(mid -0.249642 0.249642)
							(end -0.1778 0.2794)
						)
						(arc
							(start 0.1778 0.2794)
							(mid 0.249642 0.249642)
							(end 0.2794 0.1778)
						)
						(arc
							(start 0.2794 -0.1778)
							(mid 0.249642 -0.249642)
							(end 0.1778 -0.2794)
						)
					)
					(width 0)
					(fill yes)
				)
			)
		)
	)
	(footprint ""
		(layer "F.Cu")
		(at 319.659 -86.487 180)
		(property "Reference" "R527"
			(at 0 0 180)
			(layer "F.SilkS")
			(hide yes)
			(effects
				(font
					(size 1.27 1.27)
				)
			)
		)
		(property "Value" "10KR2F-2-GP"
			(at 0.064008 -3.993896 180)
			(unlocked yes)
			(layer "F.Fab")
			(hide yes)
			(effects
				(font
					(size 1.016 1.016)
					(thickness 0.1524)
				)
			)
		)
		(property "Device Type" "R402H16"
			(at 0.064008 -5.517896 180)
			(unlocked yes)
			(layer "F.Fab")
			(hide yes)
			(effects
				(font
					(size 1.016 1.016)
					(thickness 0.1524)
				)
			)
		)
		(duplicate_pad_numbers_are_jumpers no)
		(fp_line
			(start 0.508 -0.9398)
			(end -0.508 -0.9398)
			(stroke
				(width 0.1524)
				(type default)
			)
			(layer "F.SilkS")
		)
		(fp_line
			(start -0.508 -0.9398)
			(end -0.508 0.9398)
			(stroke
				(width 0.1524)
				(type default)
			)
			(layer "F.SilkS")
		)
		(fp_rect
			(start -0.508 0.9398)
			(end 0.508 -0.9398)
			(stroke
				(width 0)
				(type default)
			)
			(fill no)
			(layer "F.CrtYd")
		)
		(fp_rect
			(start -0.508 0.9398)
			(end 0.508 -0.9398)
			(stroke
				(width 0)
				(type default)
			)
			(fill no)
			(layer "F.Fab")
		)
		(pad "1" smd custom
			(at 0 -0.4445 180)
			(size 0.1397 0.1397)
			(layers "F.Cu" "F.Mask" "F.Paste")
			(net "GND")
			(options
				(clearance outline)
				(anchor circle)
			)
			(primitives
				(gr_poly
					(pts
						(arc
							(start -0.1778 -0.2794)
							(mid -0.249642 -0.249642)
							(end -0.2794 -0.1778)
						)
						(arc
							(start -0.2794 0.1778)
							(mid -0.249642 0.249642)
							(end -0.1778 0.2794)
						)
						(arc
							(start 0.1778 0.2794)
							(mid 0.249642 0.249642)
							(end 0.2794 0.1778)
						)
						(arc
							(start 0.2794 -0.1778)
							(mid 0.249642 -0.249642)
							(end 0.1778 -0.2794)
						)
					)
					(width 0)
					(fill yes)
				)
			)
		)
		(pad "2" smd custom
			(at 0 0.4445 180)
			(size 0.1397 0.1397)
			(layers "F.Cu" "F.Mask" "F.Paste")
			(net "IOEXP_PMC1_AD1")
			(options
				(clearance outline)
				(anchor circle)
			)
			(primitives
				(gr_poly
					(pts
						(arc
							(start -0.1778 -0.2794)
							(mid -0.249642 -0.249642)
							(end -0.2794 -0.1778)
						)
						(arc
							(start -0.2794 0.1778)
							(mid -0.249642 0.249642)
							(end -0.1778 0.2794)
						)
						(arc
							(start 0.1778 0.2794)
							(mid 0.249642 0.249642)
							(end 0.2794 0.1778)
						)
						(arc
							(start 0.2794 -0.1778)
							(mid 0.249642 -0.249642)
							(end 0.1778 -0.2794)
						)
					)
					(width 0)
					(fill yes)
				)
			)
		)
	)
	(footprint ""
		(layer "F.Cu")
		(at 186.0804 -61.595)
		(property "Reference" "C572"
			(at 0 0 0)
			(layer "F.SilkS")
			(hide yes)
			(effects
				(font
					(size 1.27 1.27)
				)
			)
		)
		(property "Value" "SC4D7U16V5KX-1-GP"
			(at -0.0762 -6.1214 0)
			(unlocked yes)
			(layer "F.Fab")
			(hide yes)
			(effects
				(font
					(size 1.016 1.016)
					(thickness 0.1524)
				)
			)
		)
		(property "Device Type" "C805H56"
			(at -0.0762 -8.1534 0)
			(unlocked yes)
			(layer "F.Fab")
			(hide yes)
			(effects
				(font
					(size 1.016 1.016)
					(thickness 0.1524)
				)
			)
		)
		(duplicate_pad_numbers_are_jumpers no)
		(fp_line
			(start 0.635 0)
			(end -0.635 0)
			(stroke
				(width 0.508)
				(type default)
			)
			(layer "F.SilkS")
		)
		(fp_rect
			(start -0.9652 1.778)
			(end 0.9652 -1.778)
			(stroke
				(width 0)
				(type default)
			)
			(fill no)
			(layer "F.CrtYd")
		)
		(fp_poly
			(pts
				(xy -0.9652 -1.778) (xy 0.9652 -1.778) (xy 0.9652 1.778) (xy -0.9652 1.778)
			)
			(stroke
				(width 0)
				(type default)
			)
			(fill no)
			(layer "F.Fab")
		)
		(pad "1" smd rect
			(at 0 -0.9652)
			(size 1.397 1.143)
			(layers "F.Cu" "F.Mask" "F.Paste")
			(net "DUT_AVD_PCIE")
		)
		(pad "2" smd rect
			(at 0 0.9652)
			(size 1.397 1.143)
			(layers "F.Cu" "F.Mask" "F.Paste")
			(net "GND")
		)
	)
	(footprint ""
		(layer "F.Cu")
		(at 230.251 -12.319 90)
		(property "Reference" "C727"
			(at 0 0 90)
			(layer "F.SilkS")
			(hide yes)
			(effects
				(font
					(size 1.27 1.27)
				)
			)
		)
		(property "Value" "SCD1U10V2KX-5GP"
			(at 1.1811 -2.7051 90)
			(unlocked yes)
			(layer "F.Fab")
			(hide yes)
			(effects
				(font
					(size 1.016 1.016)
					(thickness 0.1524)
				)
			)
		)
		(property "Device Type" "C402H22"
			(at 1.1811 -4.2291 90)
			(unlocked yes)
			(layer "F.Fab")
			(hide yes)
			(effects
				(font
					(size 1.016 1.016)
					(thickness 0.1524)
				)
			)
		)
		(duplicate_pad_numbers_are_jumpers no)
		(fp_rect
			(start -0.4318 0.9525)
			(end 0.4318 -0.9525)
			(stroke
				(width 0)
				(type default)
			)
			(fill no)
			(layer "F.CrtYd")
		)
		(fp_rect
			(start -0.4318 0.9525)
			(end 0.4318 -0.9525)
			(stroke
				(width 0)
				(type default)
			)
			(fill no)
			(layer "F.Fab")
		)
		(pad "1" smd custom
			(at 0 -0.4445 90)
			(size 0.1524 0.1524)
			(layers "F.Cu" "F.Mask" "F.Paste")
			(net "P3V3_STBY")
			(options
				(clearance outline)
				(anchor circle)
			)
			(primitives
				(gr_poly
					(pts
						(arc
							(start 0.3048 -0.2032)
							(mid 0.275042 -0.275042)
							(end 0.2032 -0.3048)
						)
						(arc
							(start -0.2032 -0.3048)
							(mid -0.275042 -0.275042)
							(end -0.3048 -0.2032)
						)
						(arc
							(start -0.3048 0.2032)
							(mid -0.275042 0.275042)
							(end -0.2032 0.3048)
						)
						(arc
							(start 0.2032 0.3048)
							(mid 0.275042 0.275042)
							(end 0.3048 0.2032)
						)
					)
					(width 0)
					(fill yes)
				)
			)
		)
		(pad "2" smd custom
			(at 0 0.4445 90)
			(size 0.1524 0.1524)
			(layers "F.Cu" "F.Mask" "F.Paste")
			(net "GND")
			(options
				(clearance outline)
				(anchor circle)
			)
			(primitives
				(gr_poly
					(pts
						(arc
							(start 0.3048 -0.2032)
							(mid 0.275042 -0.275042)
							(end 0.2032 -0.3048)
						)
						(arc
							(start -0.2032 -0.3048)
							(mid -0.275042 -0.275042)
							(end -0.3048 -0.2032)
						)
						(arc
							(start -0.3048 0.2032)
							(mid -0.275042 0.275042)
							(end -0.2032 0.3048)
						)
						(arc
							(start 0.2032 0.3048)
							(mid 0.275042 0.275042)
							(end 0.3048 0.2032)
						)
					)
					(width 0)
					(fill yes)
				)
			)
		)
	)
	(footprint ""
		(layer "F.Cu")
		(at 18.161 -75.6666 -90)
		(property "Reference" "U20"
			(at 0 0 270)
			(layer "F.SilkS")
			(hide yes)
			(effects
				(font
					(size 1.27 1.27)
				)
			)
		)
		(property "Value" "WGI210AT-2-GP"
			(at -7.0358 -7.3787 270)
			(unlocked yes)
			(layer "F.Fab")
			(hide yes)
			(effects
				(font
					(size 1.016 1.016)
					(thickness 0.1524)
				)
			)
		)
		(property "Device Type" "QFN64G9-G3D6H40"
			(at -7.0358 -8.9027 270)
			(unlocked yes)
			(layer "F.Fab")
			(hide yes)
			(effects
				(font
					(size 1.016 1.016)
					(thickness 0.1524)
				)
			)
		)
		(duplicate_pad_numbers_are_jumpers no)
		(fp_line
			(start -5.5118 5.5118)
			(end -4.2418 5.5118)
			(stroke
				(width 0.1524)
				(type default)
			)
			(layer "F.SilkS")
		)
		(fp_line
			(start 4.2418 5.5118)
			(end 5.5118 5.5118)
			(stroke
				(width 0.1524)
				(type default)
			)
			(layer "F.SilkS")
		)
		(fp_line
			(start 5.5118 5.5118)
			(end 5.5118 4.2418)
			(stroke
				(width 0.1524)
				(type default)
			)
			(layer "F.SilkS")
		)
		(fp_line
			(start -2.750058 5.262118)
			(end -2.750058 5.770118)
			(stroke
				(width 0.1524)
				(type default)
			)
			(layer "F.SilkS")
		)
		(fp_line
			(start -0.249936 5.262118)
			(end -0.249936 6.024118)
			(stroke
				(width 0.1524)
				(type default)
			)
			(layer "F.SilkS")
		)
		(fp_line
			(start 2.249932 5.262118)
			(end 2.249932 5.770118)
			(stroke
				(width 0.1524)
				(type default)
			)
			(layer "F.SilkS")
		)
		(fp_line
			(start -5.5118 4.2418)
			(end -5.5118 5.5118)
			(stroke
				(width 0.1524)
				(type default)
			)
			(layer "F.SilkS")
		)
		(fp_line
			(start 5.262118 3.24993)
			(end 6.024118 3.24993)
			(stroke
				(width 0.1524)
				(type default)
			)
			(layer "F.SilkS")
		)
		(fp_line
			(start -5.262118 2.750058)
			(end -6.024118 2.750058)
			(stroke
				(width 0.1524)
				(type default)
			)
			(layer "F.SilkS")
		)
		(fp_line
			(start 5.262118 0.750062)
			(end 5.770118 0.750062)
			(stroke
				(width 0.1524)
				(type default)
			)
			(layer "F.SilkS")
		)
		(fp_line
			(start -5.262118 0.249936)
			(end -5.770118 0.249936)
			(stroke
				(width 0.1524)
				(type default)
			)
			(layer "F.SilkS")
		)
		(fp_line
			(start 5.262118 -1.75006)
			(end 6.024118 -1.75006)
			(stroke
				(width 0.1524)
				(type default)
			)
			(layer "F.SilkS")
		)
		(fp_line
			(start -5.262118 -2.249932)
			(end -6.024118 -2.249932)
			(stroke
				(width 0.1524)
				(type default)
			)
			(layer "F.SilkS")
		)
		(fp_line
			(start -3.24993 -5.262118)
			(end -3.24993 -5.770118)
			(stroke
				(width 0.1524)
				(type default)
			)
			(layer "F.SilkS")
		)
		(fp_line
			(start -0.750062 -5.262118)
			(end -0.750062 -6.024118)
			(stroke
				(width 0.1524)
				(type default)
			)
			(layer "F.SilkS")
		)
		(fp_line
			(start 1.75006 -5.262118)
			(end 1.75006 -5.770118)
			(stroke
				(width 0.1524)
				(type default)
			)
			(layer "F.SilkS")
		)
		(fp_line
			(start -5.5118 -5.5118)
			(end -5.5118 -4.2418)
			(stroke
				(width 0.1524)
				(type default)
			)
			(layer "F.SilkS")
		)
		(fp_line
			(start -4.2418 -5.5118)
			(end -5.5118 -5.5118)
			(stroke
				(width 0.1524)
				(type default)
			)
			(layer "F.SilkS")
		)
		(fp_poly
			(pts
				(xy 5.5118 -5.5118) (xy 4.2418 -5.5118) (xy 5.5118 -4.2418)
			)
			(stroke
				(width 0)
				(type default)
			)
			(fill yes)
			(layer "F.SilkS")
		)
		(fp_rect
			(start -4.4958 4.4958)
			(end 4.4958 -4.4958)
			(stroke
				(width 0)
				(type default)
			)
			(fill no)
			(layer "F.CrtYd")
		)
		(fp_poly
			(pts
				(xy 5.5118 -4.4958) (xy -4.4958 -4.4958) (xy -4.4958 4.4958) (xy 4.4958 4.4958) (xy 4.4958 -4.4831)
				(xy 5.5118 -4.4831) (xy 5.5118 5.5118) (xy -5.5118 5.5118) (xy -5.5118 -5.5118) (xy 5.5118 -5.5118)
			)
			(stroke
				(width 0)
				(type default)
			)
			(fill no)
			(layer "F.CrtYd")
		)
		(fp_rect
			(start -5.5118 5.5118)
			(end 5.5118 -5.5118)
			(stroke
				(width 0)
				(type default)
			)
			(fill no)
			(layer "F.Fab")
		)
		(pad "1" smd rect
			(at 3.750056 -4.423918 270)
			(size 0.3048 0.9144)
			(drill
				(offset 0 -0.127)
			)
			(layers "F.Cu" "F.Mask" "F.Paste")
			(net "LAN_MAIN_PWR_OK")
		)
		(pad "2" smd rect
			(at 3.24993 -4.423918 270)
			(size 0.3048 1.1684)
			(layers "F.Cu" "F.Mask" "F.Paste")
			(net "CLK_50M_RMII_PHY_IN")
		)
		(pad "3" smd rect
			(at 2.750058 -4.423918 270)
			(size 0.3048 1.1684)
			(layers "F.Cu" "F.Mask" "F.Paste")
			(net "RMII_BMC_CRS_DV")
		)
		(pad "4" smd rect
			(at 2.249932 -4.423918 270)
			(size 0.3048 1.1684)
			(layers "F.Cu" "F.Mask" "F.Paste")
			(net "NIC_JTDO")
		)
		(pad "5" smd rect
			(at 1.75006 -4.423918 270)
			(size 0.3048 1.1684)
			(layers "F.Cu" "F.Mask" "F.Paste")
			(net "RMII_PHY_BMC_RXD1_R")
		)
		(pad "6" smd rect
			(at 1.249934 -4.423918 270)
			(size 0.3048 1.1684)
			(layers "F.Cu" "F.Mask" "F.Paste")
			(net "RMII_PHY_BMC_RXD0_R")
		)
		(pad "7" smd rect
			(at 0.750062 -4.423918 270)
			(size 0.3048 1.1684)
			(layers "F.Cu" "F.Mask" "F.Paste")
			(net "RMII_BMC_TX_EN")
		)
		(pad "8" smd rect
			(at 0.249936 -4.423918 270)
			(size 0.3048 1.1684)
			(layers "F.Cu" "F.Mask" "F.Paste")
			(net "RMII_BMC_PHY_TXD1")
		)
		(pad "9" smd rect
			(at -0.249936 -4.423918 270)
			(size 0.3048 1.1684)
			(layers "F.Cu" "F.Mask" "F.Paste")
			(net "RMII_BMC_PHY_TXD0")
		)
		(pad "10" smd rect
			(at -0.750062 -4.423918 270)
			(size 0.3048 1.1684)
			(layers "F.Cu" "F.Mask" "F.Paste")
			(net "P3V3_STBY")
		)
		(pad "11" smd rect
			(at -1.249934 -4.423918 270)
			(size 0.3048 1.1684)
			(layers "F.Cu" "F.Mask" "F.Paste")
			(net "P0V9_I210")
		)
		(pad "12" smd rect
			(at -1.75006 -4.423918 270)
			(size 0.3048 1.1684)
			(layers "F.Cu" "F.Mask" "F.Paste")
			(net "NVM_SI")
		)
		(pad "13" smd rect
			(at -2.249932 -4.423918 270)
			(size 0.3048 1.1684)
			(layers "F.Cu" "F.Mask" "F.Paste")
			(net "NVM_SK")
		)
		(pad "14" smd rect
			(at -2.750058 -4.423918 270)
			(size 0.3048 1.1684)
			(layers "F.Cu" "F.Mask" "F.Paste")
			(net "NVM_SO")
		)
		(pad "15" smd rect
			(at -3.24993 -4.423918 270)
			(size 0.3048 1.1684)
			(layers "F.Cu" "F.Mask" "F.Paste")
			(net "NVM_CS_N")
		)
		(pad "16" smd rect
			(at -3.750056 -4.423918 270)
			(size 0.3048 0.9144)
			(drill
				(offset 0 -0.127)
			)
			(layers "F.Cu" "F.Mask" "F.Paste")
			(net "PHY_WAKE_N")
		)
		(pad "17" smd rect
			(at -4.423918 -3.750056 270)
			(size 0.9144 0.3048)
			(drill
				(offset -0.127 0)
			)
			(layers "F.Cu" "F.Mask" "F.Paste")
			(net "PHY_RESET_N")
		)
		(pad "18" smd rect
			(at -4.423918 -3.24993 270)
			(size 1.1684 0.3048)
			(layers "F.Cu" "F.Mask" "F.Paste")
			(net "NIC_JTMS")
		)
		(pad "19" smd rect
			(at -4.423918 -2.750058 270)
			(size 1.1684 0.3048)
			(layers "F.Cu" "F.Mask" "F.Paste")
			(net "NIC_JTCK")
		)
		(pad "20" smd rect
			(at -4.423918 -2.249932 270)
			(size 1.1684 0.3048)
			(layers "F.Cu" "F.Mask" "F.Paste")
			(net "PCIE_RX_CAP_N78")
		)
		(pad "21" smd rect
			(at -4.423918 -1.75006 270)
			(size 1.1684 0.3048)
			(layers "F.Cu" "F.Mask" "F.Paste")
			(net "PCIE_RX_CAP_P78")
		)
		(pad "22" smd rect
			(at -4.423918 -1.249934 270)
			(size 1.1684 0.3048)
			(layers "F.Cu" "F.Mask" "F.Paste")
			(net "Net_209")
		)
		(pad "23" smd rect
			(at -4.423918 -0.750062 270)
			(size 1.1684 0.3048)
			(layers "F.Cu" "F.Mask" "F.Paste")
			(net "PCIE_TX_N78")
		)
		(pad "24" smd rect
			(at -4.423918 -0.249936 270)
			(size 1.1684 0.3048)
			(layers "F.Cu" "F.Mask" "F.Paste")
			(net "PCIE_TX_P78")
		)
		(pad "25" smd rect
			(at -4.423918 0.249936 270)
			(size 1.1684 0.3048)
			(layers "F.Cu" "F.Mask" "F.Paste")
			(net "I210_REFCLK_D_N")
		)
		(pad "26" smd rect
			(at -4.423918 0.750062 270)
			(size 1.1684 0.3048)
			(layers "F.Cu" "F.Mask" "F.Paste")
			(net "I210_REFCLK_D_P")
		)
		(pad "27" smd rect
			(at -4.423918 1.249934 270)
			(size 1.1684 0.3048)
			(layers "F.Cu" "F.Mask" "F.Paste")
			(net "P3V3_STBY")
		)
		(pad "28" smd rect
			(at -4.423918 1.75006 270)
			(size 1.1684 0.3048)
			(layers "F.Cu" "F.Mask" "F.Paste")
			(net "FM_PCH_LAN1_DISABLE_N")
		)
		(pad "29" smd rect
			(at -4.423918 2.249932 270)
			(size 1.1684 0.3048)
			(layers "F.Cu" "F.Mask" "F.Paste")
			(net "NIC_JTDI")
		)
		(pad "30" smd rect
			(at -4.423918 2.750058 270)
			(size 1.1684 0.3048)
			(layers "F.Cu" "F.Mask" "F.Paste")
			(net "LED_MDI0_LINK_N")
		)
		(pad "31" smd rect
			(at -4.423918 3.24993 270)
			(size 1.1684 0.3048)
			(layers "F.Cu" "F.Mask" "F.Paste")
			(net "LED_MDI0_100M_N")
		)
		(pad "32" smd rect
			(at -4.423918 3.750056 270)
			(size 0.9144 0.3048)
			(drill
				(offset -0.127 0)
			)
			(layers "F.Cu" "F.Mask" "F.Paste")
			(net "P0V9_I210")
		)
		(pad "33" smd rect
			(at -3.750056 4.423918 270)
			(size 0.3048 0.9144)
			(drill
				(offset 0 0.127)
			)
			(layers "F.Cu" "F.Mask" "F.Paste")
			(net "LED_MDI0_1G_N")
		)
		(pad "34" smd rect
			(at -3.24993 4.423918 270)
			(size 0.3048 1.1684)
			(layers "F.Cu" "F.Mask" "F.Paste")
			(net "LAN_SMB_CLK")
		)
		(pad "35" smd rect
			(at -2.750058 4.423918 270)
			(size 0.3048 1.1684)
			(layers "F.Cu" "F.Mask" "F.Paste")
			(net "LAN_SMB_ALERT_N")
		)
		(pad "36" smd rect
			(at -2.249932 4.423918 270)
			(size 0.3048 1.1684)
			(layers "F.Cu" "F.Mask" "F.Paste")
			(net "LAN_SMB_DAT")
		)
		(pad "37" smd rect
			(at -1.75006 4.423918 270)
			(size 0.3048 1.1684)
			(layers "F.Cu" "F.Mask" "F.Paste")
			(net "I210_CBOT")
		)
		(pad "38" smd rect
			(at -1.249934 4.423918 270)
			(size 0.3048 1.1684)
			(layers "F.Cu" "F.Mask" "F.Paste")
			(net "P0V9_I210")
		)
		(pad "39" smd rect
			(at -0.750062 4.423918 270)
			(size 0.3048 1.1684)
			(layers "F.Cu" "F.Mask" "F.Paste")
			(net "P1V5_I210")
		)
		(pad "40" smd rect
			(at -0.249936 4.423918 270)
			(size 0.3048 1.1684)
			(layers "F.Cu" "F.Mask" "F.Paste")
			(net "I210_CTOP")
		)
		(pad "41" smd rect
			(at 0.249936 4.423918 270)
			(size 0.3048 1.1684)
			(layers "F.Cu" "F.Mask" "F.Paste")
			(net "P3V3_STBY")
		)
		(pad "42" smd rect
			(at 0.750062 4.423918 270)
			(size 0.3048 1.1684)
			(layers "F.Cu" "F.Mask" "F.Paste")
			(net "P0V9_I210")
		)
		(pad "43" smd rect
			(at 1.249934 4.423918 270)
			(size 0.3048 1.1684)
			(layers "F.Cu" "F.Mask" "F.Paste")
			(net "NCSI_ARB_IN")
		)
		(pad "44" smd rect
			(at 1.75006 4.423918 270)
			(size 0.3048 1.1684)
			(layers "F.Cu" "F.Mask" "F.Paste")
			(net "NCSI_ARB_OUT")
		)
		(pad "45" smd rect
			(at 2.249932 4.423918 270)
			(size 0.3048 1.1684)
			(layers "F.Cu" "F.Mask" "F.Paste")
			(net "XTAL_OUT_I210")
		)
		(pad "46" smd rect
			(at 2.750058 4.423918 270)
			(size 0.3048 1.1684)
			(layers "F.Cu" "F.Mask" "F.Paste")
			(net "XTAL_IN_I210")
		)
		(pad "47" smd rect
			(at 3.24993 4.423918 270)
			(size 0.3048 1.1684)
			(layers "F.Cu" "F.Mask" "F.Paste")
			(net "P1V5_I210")
		)
		(pad "48" smd rect
			(at 3.750056 4.423918 270)
			(size 0.3048 0.9144)
			(drill
				(offset 0 0.127)
			)
			(layers "F.Cu" "F.Mask" "F.Paste")
			(net "LAN_SE_RSET")
		)
		(pad "49" smd rect
			(at 4.423918 3.750056 270)
			(size 0.9144 0.3048)
			(drill
				(offset 0.127 0)
			)
			(layers "F.Cu" "F.Mask" "F.Paste")
			(net "NIC0_MDI0_N3")
		)
		(pad "50" smd rect
			(at 4.423918 3.24993 270)
			(size 1.1684 0.3048)
			(layers "F.Cu" "F.Mask" "F.Paste")
			(net "NIC0_MDI0_P3")
		)
		(pad "51" smd rect
			(at 4.423918 2.750058 270)
			(size 1.1684 0.3048)
			(layers "F.Cu" "F.Mask" "F.Paste")
			(net "LAN1_51")
		)
		(pad "52" smd rect
			(at 4.423918 2.249932 270)
			(size 1.1684 0.3048)
			(layers "F.Cu" "F.Mask" "F.Paste")
			(net "NIC0_MDI0_N2")
		)
		(pad "53" smd rect
			(at 4.423918 1.75006 270)
			(size 1.1684 0.3048)
			(layers "F.Cu" "F.Mask" "F.Paste")
			(net "NIC0_MDI0_P2")
		)
		(pad "54" smd rect
			(at 4.423918 1.249934 270)
			(size 1.1684 0.3048)
			(layers "F.Cu" "F.Mask" "F.Paste")
			(net "NIC0_MDI0_N1")
		)
		(pad "55" smd rect
			(at 4.423918 0.750062 270)
			(size 1.1684 0.3048)
			(layers "F.Cu" "F.Mask" "F.Paste")
			(net "NIC0_MDI0_P1")
		)
		(pad "56" smd rect
			(at 4.423918 0.249936 270)
			(size 1.1684 0.3048)
			(layers "F.Cu" "F.Mask" "F.Paste")
			(net "LAN1_56")
		)
		(pad "57" smd rect
			(at 4.423918 -0.249936 270)
			(size 1.1684 0.3048)
			(layers "F.Cu" "F.Mask" "F.Paste")
			(net "NIC0_MDI0_N0")
		)
		(pad "58" smd rect
			(at 4.423918 -0.750062 270)
			(size 1.1684 0.3048)
			(layers "F.Cu" "F.Mask" "F.Paste")
			(net "NIC0_MDI0_P0")
		)
		(pad "59" smd rect
			(at 4.423918 -1.249934 270)
			(size 1.1684 0.3048)
			(layers "F.Cu" "F.Mask" "F.Paste")
			(net "P0V9_I210")
		)
		(pad "60" smd rect
			(at 4.423918 -1.75006 270)
			(size 1.1684 0.3048)
			(layers "F.Cu" "F.Mask" "F.Paste")
			(net "TP_SDP3")
		)
		(pad "61" smd rect
			(at 4.423918 -2.249932 270)
			(size 1.1684 0.3048)
			(layers "F.Cu" "F.Mask" "F.Paste")
			(net "PCIE_DIS")
		)
		(pad "62" smd rect
			(at 4.423918 -2.750058 270)
			(size 1.1684 0.3048)
			(layers "F.Cu" "F.Mask" "F.Paste")
			(net "TP_SDP2")
		)
		(pad "63" smd rect
			(at 4.423918 -3.24993 270)
			(size 1.1684 0.3048)
			(layers "F.Cu" "F.Mask" "F.Paste")
			(net "TP_SDP0")
		)
		(pad "64" smd rect
			(at 4.423918 -3.750056 270)
			(size 0.9144 0.3048)
			(drill
				(offset 0.127 0)
			)
			(layers "F.Cu" "F.Mask" "F.Paste")
			(net "P3V3_STBY")
		)
		(pad "65" smd rect
			(at 0 0 270)
			(size 3.6068 3.6068)
			(layers "F.Cu" "F.Mask" "F.Paste")
			(net "GND")
		)
	)
	(footprint ""
		(layer "F.Cu")
		(at 11.9126 -125.0188 180)
		(property "Reference" "R18"
			(at 0 0 180)
			(layer "F.SilkS")
			(hide yes)
			(effects
				(font
					(size 1.27 1.27)
				)
			)
		)
		(property "Value" "0R2J-2-GP"
			(at 0.064008 -3.993896 180)
			(unlocked yes)
			(layer "F.Fab")
			(hide yes)
			(effects
				(font
					(size 1.016 1.016)
					(thickness 0.1524)
				)
			)
		)
		(property "Device Type" "R402H16"
			(at 0.064008 -5.517896 180)
			(unlocked yes)
			(layer "F.Fab")
			(hide yes)
			(effects
				(font
					(size 1.016 1.016)
					(thickness 0.1524)
				)
			)
		)
		(duplicate_pad_numbers_are_jumpers no)
		(fp_line
			(start 0.508 -0.9398)
			(end -0.508 -0.9398)
			(stroke
				(width 0.1524)
				(type default)
			)
			(layer "F.SilkS")
		)
		(fp_line
			(start -0.508 -0.9398)
			(end -0.508 0.9398)
			(stroke
				(width 0.1524)
				(type default)
			)
			(layer "F.SilkS")
		)
		(fp_rect
			(start -0.508 0.9398)
			(end 0.508 -0.9398)
			(stroke
				(width 0)
				(type default)
			)
			(fill no)
			(layer "F.CrtYd")
		)
		(fp_rect
			(start -0.508 0.9398)
			(end 0.508 -0.9398)
			(stroke
				(width 0)
				(type default)
			)
			(fill no)
			(layer "F.Fab")
		)
		(pad "1" smd custom
			(at 0 -0.4445 180)
			(size 0.1397 0.1397)
			(layers "F.Cu" "F.Mask" "F.Paste")
			(net "BMC_I2C2_MINI2_SCL_S")
			(options
				(clearance outline)
				(anchor circle)
			)
			(primitives
				(gr_poly
					(pts
						(arc
							(start -0.1778 -0.2794)
							(mid -0.249642 -0.249642)
							(end -0.2794 -0.1778)
						)
						(arc
							(start -0.2794 0.1778)
							(mid -0.249642 0.249642)
							(end -0.1778 0.2794)
						)
						(arc
							(start 0.1778 0.2794)
							(mid 0.249642 0.249642)
							(end 0.2794 0.1778)
						)
						(arc
							(start 0.2794 -0.1778)
							(mid 0.249642 -0.249642)
							(end 0.1778 -0.2794)
						)
					)
					(width 0)
					(fill yes)
				)
			)
		)
		(pad "2" smd custom
			(at 0 0.4445 180)
			(size 0.1397 0.1397)
			(layers "F.Cu" "F.Mask" "F.Paste")
			(net "BMC_I2C2_MINI2_SCL")
			(options
				(clearance outline)
				(anchor circle)
			)
			(primitives
				(gr_poly
					(pts
						(arc
							(start -0.1778 -0.2794)
							(mid -0.249642 -0.249642)
							(end -0.2794 -0.1778)
						)
						(arc
							(start -0.2794 0.1778)
							(mid -0.249642 0.249642)
							(end -0.1778 0.2794)
						)
						(arc
							(start 0.1778 0.2794)
							(mid 0.249642 0.249642)
							(end 0.2794 0.1778)
						)
						(arc
							(start 0.2794 -0.1778)
							(mid 0.249642 -0.249642)
							(end 0.1778 -0.2794)
						)
					)
					(width 0)
					(fill yes)
				)
			)
		)
	)
	(footprint ""
		(layer "F.Cu")
		(at 210.70824 -26.83002 90)
		(property "Reference" "R839"
			(at 0 0 90)
			(layer "F.SilkS")
			(hide yes)
			(effects
				(font
					(size 1.27 1.27)
				)
			)
		)
		(property "Value" "4K7R2F-GP"
			(at 0.064008 -3.993896 90)
			(unlocked yes)
			(layer "F.Fab")
			(hide yes)
			(effects
				(font
					(size 1.016 1.016)
					(thickness 0.1524)
				)
			)
		)
		(property "Device Type" "R402H16"
			(at 0.064008 -5.517896 90)
			(unlocked yes)
			(layer "F.Fab")
			(hide yes)
			(effects
				(font
					(size 1.016 1.016)
					(thickness 0.1524)
				)
			)
		)
		(duplicate_pad_numbers_are_jumpers no)
		(fp_line
			(start 0.508 -0.9398)
			(end -0.508 -0.9398)
			(stroke
				(width 0.1524)
				(type default)
			)
			(layer "F.SilkS")
		)
		(fp_line
			(start -0.508 -0.9398)
			(end -0.508 0.9398)
			(stroke
				(width 0.1524)
				(type default)
			)
			(layer "F.SilkS")
		)
		(fp_rect
			(start -0.508 0.9398)
			(end 0.508 -0.9398)
			(stroke
				(width 0)
				(type default)
			)
			(fill no)
			(layer "F.CrtYd")
		)
		(fp_rect
			(start -0.508 0.9398)
			(end 0.508 -0.9398)
			(stroke
				(width 0)
				(type default)
			)
			(fill no)
			(layer "F.Fab")
		)
		(pad "1" smd custom
			(at 0 -0.4445 90)
			(size 0.1397 0.1397)
			(layers "F.Cu" "F.Mask" "F.Paste")
			(net "DUT_VDDO")
			(options
				(clearance outline)
				(anchor circle)
			)
			(primitives
				(gr_poly
					(pts
						(arc
							(start -0.1778 -0.2794)
							(mid -0.249642 -0.249642)
							(end -0.2794 -0.1778)
						)
						(arc
							(start -0.2794 0.1778)
							(mid -0.249642 0.249642)
							(end -0.1778 0.2794)
						)
						(arc
							(start 0.1778 0.2794)
							(mid 0.249642 0.249642)
							(end 0.2794 0.1778)
						)
						(arc
							(start 0.2794 -0.1778)
							(mid 0.249642 -0.249642)
							(end 0.1778 -0.2794)
						)
					)
					(width 0)
					(fill yes)
				)
			)
		)
		(pad "2" smd custom
			(at 0 0.4445 90)
			(size 0.1397 0.1397)
			(layers "F.Cu" "F.Mask" "F.Paste")
			(net "DUT_TAP_SEL")
			(options
				(clearance outline)
				(anchor circle)
			)
			(primitives
				(gr_poly
					(pts
						(arc
							(start -0.1778 -0.2794)
							(mid -0.249642 -0.249642)
							(end -0.2794 -0.1778)
						)
						(arc
							(start -0.2794 0.1778)
							(mid -0.249642 0.249642)
							(end -0.1778 0.2794)
						)
						(arc
							(start 0.1778 0.2794)
							(mid 0.249642 0.249642)
							(end 0.2794 0.1778)
						)
						(arc
							(start 0.2794 -0.1778)
							(mid 0.249642 -0.249642)
							(end 0.1778 -0.2794)
						)
					)
					(width 0)
					(fill yes)
				)
			)
		)
	)
	(footprint ""
		(layer "F.Cu")
		(at 204.3684 -26.1112 -90)
		(property "Reference" "C136"
			(at 0 0 270)
			(layer "F.SilkS")
			(hide yes)
			(effects
				(font
					(size 1.27 1.27)
				)
			)
		)
		(property "Value" "SCD1U10V2KX-5GP"
			(at 1.1811 -2.7051 270)
			(unlocked yes)
			(layer "F.Fab")
			(hide yes)
			(effects
				(font
					(size 1.016 1.016)
					(thickness 0.1524)
				)
			)
		)
		(property "Device Type" "C402H22"
			(at 1.1811 -4.2291 270)
			(unlocked yes)
			(layer "F.Fab")
			(hide yes)
			(effects
				(font
					(size 1.016 1.016)
					(thickness 0.1524)
				)
			)
		)
		(duplicate_pad_numbers_are_jumpers no)
		(fp_rect
			(start -0.4318 0.9525)
			(end 0.4318 -0.9525)
			(stroke
				(width 0)
				(type default)
			)
			(fill no)
			(layer "F.CrtYd")
		)
		(fp_rect
			(start -0.4318 0.9525)
			(end 0.4318 -0.9525)
			(stroke
				(width 0)
				(type default)
			)
			(fill no)
			(layer "F.Fab")
		)
		(pad "1" smd custom
			(at 0 -0.4445 270)
			(size 0.1524 0.1524)
			(layers "F.Cu" "F.Mask" "F.Paste")
			(net "P3V3_STBY")
			(options
				(clearance outline)
				(anchor circle)
			)
			(primitives
				(gr_poly
					(pts
						(arc
							(start 0.3048 -0.2032)
							(mid 0.275042 -0.275042)
							(end 0.2032 -0.3048)
						)
						(arc
							(start -0.2032 -0.3048)
							(mid -0.275042 -0.275042)
							(end -0.3048 -0.2032)
						)
						(arc
							(start -0.3048 0.2032)
							(mid -0.275042 0.275042)
							(end -0.2032 0.3048)
						)
						(arc
							(start 0.2032 0.3048)
							(mid 0.275042 0.275042)
							(end 0.3048 0.2032)
						)
					)
					(width 0)
					(fill yes)
				)
			)
		)
		(pad "2" smd custom
			(at 0 0.4445 270)
			(size 0.1524 0.1524)
			(layers "F.Cu" "F.Mask" "F.Paste")
			(net "GND")
			(options
				(clearance outline)
				(anchor circle)
			)
			(primitives
				(gr_poly
					(pts
						(arc
							(start 0.3048 -0.2032)
							(mid 0.275042 -0.275042)
							(end 0.2032 -0.3048)
						)
						(arc
							(start -0.2032 -0.3048)
							(mid -0.275042 -0.275042)
							(end -0.3048 -0.2032)
						)
						(arc
							(start -0.3048 0.2032)
							(mid -0.275042 0.275042)
							(end -0.2032 0.3048)
						)
						(arc
							(start 0.2032 0.3048)
							(mid 0.275042 0.275042)
							(end 0.3048 0.2032)
						)
					)
					(width 0)
					(fill yes)
				)
			)
		)
	)
	(footprint ""
		(layer "F.Cu")
		(at 33.4772 -77.8256 90)
		(property "Reference" "PR63"
			(at 0 0 90)
			(layer "F.SilkS")
			(hide yes)
			(effects
				(font
					(size 1.27 1.27)
				)
			)
		)
		(property "Value" "0R3J-0-U-GP"
			(at -0.0254 -2.5146 90)
			(unlocked yes)
			(layer "F.Fab")
			(hide yes)
			(effects
				(font
					(size 1.016 1.016)
					(thickness 0.1524)
				)
			)
		)
		(property "Device Type" "R603H22"
			(at -0.0254 -4.0386 90)
			(unlocked yes)
			(layer "F.Fab")
			(hide yes)
			(effects
				(font
					(size 1.016 1.016)
					(thickness 0.1524)
				)
			)
		)
		(duplicate_pad_numbers_are_jumpers no)
		(fp_line
			(start 0.2032 0)
			(end 0.4826 0)
			(stroke
				(width 0.2032)
				(type default)
			)
			(layer "F.SilkS")
		)
		(fp_line
			(start -0.4826 0)
			(end -0.2032 0)
			(stroke
				(width 0.2032)
				(type default)
			)
			(layer "F.SilkS")
		)
		(fp_rect
			(start -0.5842 1.3335)
			(end 0.5842 -1.3335)
			(stroke
				(width 0)
				(type default)
			)
			(fill no)
			(layer "F.CrtYd")
		)
		(fp_rect
			(start -0.5842 1.3335)
			(end 0.5842 -1.3335)
			(stroke
				(width 0)
				(type default)
			)
			(fill no)
			(layer "F.Fab")
		)
		(pad "1" smd custom
			(at 0 -0.762 90)
			(size 0.2159 0.2159)
			(layers "F.Cu" "F.Mask" "F.Paste")
			(net "P5V_STBY_BS")
			(options
				(clearance outline)
				(anchor circle)
			)
			(primitives
				(gr_poly
					(pts
						(arc
							(start -0.3302 -0.4318)
							(mid -0.402042 -0.402042)
							(end -0.4318 -0.3302)
						)
						(arc
							(start -0.4318 0.3302)
							(mid -0.402042 0.402042)
							(end -0.3302 0.4318)
						)
						(arc
							(start 0.3302 0.4318)
							(mid 0.402042 0.402042)
							(end 0.4318 0.3302)
						)
						(arc
							(start 0.4318 -0.3302)
							(mid 0.402042 -0.402042)
							(end 0.3302 -0.4318)
						)
					)
					(width 0)
					(fill yes)
				)
			)
		)
		(pad "2" smd custom
			(at 0 0.762 90)
			(size 0.2159 0.2159)
			(layers "F.Cu" "F.Mask" "F.Paste")
			(net "P5V_STBY_BS_RC")
			(options
				(clearance outline)
				(anchor circle)
			)
			(primitives
				(gr_poly
					(pts
						(arc
							(start -0.3302 -0.4318)
							(mid -0.402042 -0.402042)
							(end -0.4318 -0.3302)
						)
						(arc
							(start -0.4318 0.3302)
							(mid -0.402042 0.402042)
							(end -0.3302 0.4318)
						)
						(arc
							(start 0.3302 0.4318)
							(mid 0.402042 0.402042)
							(end 0.4318 0.3302)
						)
						(arc
							(start 0.4318 -0.3302)
							(mid 0.402042 -0.402042)
							(end 0.3302 -0.4318)
						)
					)
					(width 0)
					(fill yes)
				)
			)
		)
	)
	(footprint ""
		(layer "F.Cu")
		(at 271.442942 -5.75183 180)
		(property "Reference" "R253"
			(at 0 0 180)
			(layer "F.SilkS")
			(hide yes)
			(effects
				(font
					(size 1.27 1.27)
				)
			)
		)
		(property "Value" "4K7R2F-GP"
			(at 0.064008 -3.993896 180)
			(unlocked yes)
			(layer "F.Fab")
			(hide yes)
			(effects
				(font
					(size 1.016 1.016)
					(thickness 0.1524)
				)
			)
		)
		(property "Device Type" "R402H16"
			(at 0.064008 -5.517896 180)
			(unlocked yes)
			(layer "F.Fab")
			(hide yes)
			(effects
				(font
					(size 1.016 1.016)
					(thickness 0.1524)
				)
			)
		)
		(duplicate_pad_numbers_are_jumpers no)
		(fp_line
			(start 0.508 -0.9398)
			(end -0.508 -0.9398)
			(stroke
				(width 0.1524)
				(type default)
			)
			(layer "F.SilkS")
		)
		(fp_line
			(start -0.508 -0.9398)
			(end -0.508 0.9398)
			(stroke
				(width 0.1524)
				(type default)
			)
			(layer "F.SilkS")
		)
		(fp_rect
			(start -0.508 0.9398)
			(end 0.508 -0.9398)
			(stroke
				(width 0)
				(type default)
			)
			(fill no)
			(layer "F.CrtYd")
		)
		(fp_rect
			(start -0.508 0.9398)
			(end 0.508 -0.9398)
			(stroke
				(width 0)
				(type default)
			)
			(fill no)
			(layer "F.Fab")
		)
		(pad "1" smd custom
			(at 0 -0.4445 180)
			(size 0.1397 0.1397)
			(layers "F.Cu" "F.Mask" "F.Paste")
			(net "P3V3_STBY")
			(options
				(clearance outline)
				(anchor circle)
			)
			(primitives
				(gr_poly
					(pts
						(arc
							(start -0.1778 -0.2794)
							(mid -0.249642 -0.249642)
							(end -0.2794 -0.1778)
						)
						(arc
							(start -0.2794 0.1778)
							(mid -0.249642 0.249642)
							(end -0.1778 0.2794)
						)
						(arc
							(start 0.1778 0.2794)
							(mid 0.249642 0.249642)
							(end 0.2794 0.1778)
						)
						(arc
							(start 0.2794 -0.1778)
							(mid 0.249642 -0.249642)
							(end 0.1778 -0.2794)
						)
					)
					(width 0)
					(fill yes)
				)
			)
		)
		(pad "2" smd custom
			(at 0 0.4445 180)
			(size 0.1397 0.1397)
			(layers "F.Cu" "F.Mask" "F.Paste")
			(net "CLK_P_7_R")
			(options
				(clearance outline)
				(anchor circle)
			)
			(primitives
				(gr_poly
					(pts
						(arc
							(start -0.1778 -0.2794)
							(mid -0.249642 -0.249642)
							(end -0.2794 -0.1778)
						)
						(arc
							(start -0.2794 0.1778)
							(mid -0.249642 0.249642)
							(end -0.1778 0.2794)
						)
						(arc
							(start 0.1778 0.2794)
							(mid 0.249642 0.249642)
							(end 0.2794 0.1778)
						)
						(arc
							(start 0.2794 -0.1778)
							(mid 0.249642 -0.249642)
							(end 0.1778 -0.2794)
						)
					)
					(width 0)
					(fill yes)
				)
			)
		)
	)
	(footprint ""
		(layer "F.Cu")
		(at 327.914 -76.2 -90)
		(property "Reference" "R14"
			(at 0 0 270)
			(layer "F.SilkS")
			(hide yes)
			(effects
				(font
					(size 1.27 1.27)
				)
			)
		)
		(property "Value" "0R2J-2-GP"
			(at 0.064008 -3.993896 270)
			(unlocked yes)
			(layer "F.Fab")
			(hide yes)
			(effects
				(font
					(size 1.016 1.016)
					(thickness 0.1524)
				)
			)
		)
		(property "Device Type" "R402H16"
			(at 0.064008 -5.517896 270)
			(unlocked yes)
			(layer "F.Fab")
			(hide yes)
			(effects
				(font
					(size 1.016 1.016)
					(thickness 0.1524)
				)
			)
		)
		(duplicate_pad_numbers_are_jumpers no)
		(fp_line
			(start -0.508 -0.9398)
			(end -0.508 0.9398)
			(stroke
				(width 0.1524)
				(type default)
			)
			(layer "F.SilkS")
		)
		(fp_line
			(start 0.508 -0.9398)
			(end -0.508 -0.9398)
			(stroke
				(width 0.1524)
				(type default)
			)
			(layer "F.SilkS")
		)
		(fp_rect
			(start -0.508 0.9398)
			(end 0.508 -0.9398)
			(stroke
				(width 0)
				(type default)
			)
			(fill no)
			(layer "F.CrtYd")
		)
		(fp_rect
			(start -0.508 0.9398)
			(end 0.508 -0.9398)
			(stroke
				(width 0)
				(type default)
			)
			(fill no)
			(layer "F.Fab")
		)
		(pad "1" smd custom
			(at 0 -0.4445 270)
			(size 0.1397 0.1397)
			(layers "F.Cu" "F.Mask" "F.Paste")
			(net "AVS_ENB2_R")
			(options
				(clearance outline)
				(anchor circle)
			)
			(primitives
				(gr_poly
					(pts
						(arc
							(start -0.1778 -0.2794)
							(mid -0.249642 -0.249642)
							(end -0.2794 -0.1778)
						)
						(arc
							(start -0.2794 0.1778)
							(mid -0.249642 0.249642)
							(end -0.1778 0.2794)
						)
						(arc
							(start 0.1778 0.2794)
							(mid 0.249642 0.249642)
							(end 0.2794 0.1778)
						)
						(arc
							(start 0.2794 -0.1778)
							(mid 0.249642 -0.249642)
							(end 0.1778 -0.2794)
						)
					)
					(width 0)
					(fill yes)
				)
			)
		)
		(pad "2" smd custom
			(at 0 0.4445 270)
			(size 0.1397 0.1397)
			(layers "F.Cu" "F.Mask" "F.Paste")
			(net "AVS_ENB")
			(options
				(clearance outline)
				(anchor circle)
			)
			(primitives
				(gr_poly
					(pts
						(arc
							(start -0.1778 -0.2794)
							(mid -0.249642 -0.249642)
							(end -0.2794 -0.1778)
						)
						(arc
							(start -0.2794 0.1778)
							(mid -0.249642 0.249642)
							(end -0.1778 0.2794)
						)
						(arc
							(start 0.1778 0.2794)
							(mid 0.249642 0.249642)
							(end 0.2794 0.1778)
						)
						(arc
							(start 0.2794 -0.1778)
							(mid 0.249642 -0.249642)
							(end 0.1778 -0.2794)
						)
					)
					(width 0)
					(fill yes)
				)
			)
		)
	)
	(footprint ""
		(layer "F.Cu")
		(at 34.05886 -118.30812)
		(property "Reference" "TP227"
			(at 0 0 0)
			(layer "F.SilkS")
			(hide yes)
			(effects
				(font
					(size 1.27 1.27)
				)
			)
		)
		(property "Value" "TPAD28-2-GP"
			(at -0.0127 -1.6637 0)
			(unlocked yes)
			(layer "F.Fab")
			(hide yes)
			(effects
				(font
					(size 1.016 1.016)
					(thickness 0.1524)
				)
			)
		)
		(property "Device Type" "TPAD28"
			(at -0.0127 -3.1877 0)
			(unlocked yes)
			(layer "F.Fab")
			(hide yes)
			(effects
				(font
					(size 1.016 1.016)
					(thickness 0.1524)
				)
			)
		)
		(duplicate_pad_numbers_are_jumpers no)
		(fp_poly
			(pts
				(arc
					(start 0.3556 0)
					(mid -0.3556 0)
					(end 0.3556 0)
				)
			)
			(stroke
				(width 0)
				(type default)
			)
			(fill no)
			(layer "F.CrtYd")
		)
		(fp_poly
			(pts
				(arc
					(start 0.6096 0)
					(mid -0.6096 0)
					(end 0.6096 0)
				)
			)
			(stroke
				(width 0)
				(type default)
			)
			(fill no)
			(layer "F.Fab")
		)
		(pad "1" smd circle
			(at 0 0)
			(size 0.7112 0.7112)
			(layers "F.Cu" "F.Mask" "F.Paste")
			(net "TP_GPIOE2")
		)
	)
	(footprint ""
		(layer "F.Cu")
		(at 163.195 -33.528)
		(property "Reference" "C396"
			(at 0 0 0)
			(layer "F.SilkS")
			(hide yes)
			(effects
				(font
					(size 1.27 1.27)
				)
			)
		)
		(property "Value" "SCD22U10V2KX-1GP"
			(at 1.1811 -2.7051 0)
			(unlocked yes)
			(layer "F.Fab")
			(hide yes)
			(effects
				(font
					(size 1.016 1.016)
					(thickness 0.1524)
				)
			)
		)
		(property "Device Type" "C402H22"
			(at 1.1811 -4.2291 0)
			(unlocked yes)
			(layer "F.Fab")
			(hide yes)
			(effects
				(font
					(size 1.016 1.016)
					(thickness 0.1524)
				)
			)
		)
		(duplicate_pad_numbers_are_jumpers no)
		(fp_rect
			(start -0.4318 0.9525)
			(end 0.4318 -0.9525)
			(stroke
				(width 0)
				(type default)
			)
			(fill no)
			(layer "F.CrtYd")
		)
		(fp_rect
			(start -0.4318 0.9525)
			(end 0.4318 -0.9525)
			(stroke
				(width 0)
				(type default)
			)
			(fill no)
			(layer "F.Fab")
		)
		(pad "1" smd custom
			(at 0 -0.4445)
			(size 0.1524 0.1524)
			(layers "F.Cu" "F.Mask" "F.Paste")
			(net "PCIE_TX_CAP_P88")
			(options
				(clearance outline)
				(anchor circle)
			)
			(primitives
				(gr_poly
					(pts
						(arc
							(start 0.3048 -0.2032)
							(mid 0.275042 -0.275042)
							(end 0.2032 -0.3048)
						)
						(arc
							(start -0.2032 -0.3048)
							(mid -0.275042 -0.275042)
							(end -0.3048 -0.2032)
						)
						(arc
							(start -0.3048 0.2032)
							(mid -0.275042 0.275042)
							(end -0.2032 0.3048)
						)
						(arc
							(start 0.2032 0.3048)
							(mid 0.275042 0.275042)
							(end 0.3048 0.2032)
						)
					)
					(width 0)
					(fill yes)
				)
			)
		)
		(pad "2" smd custom
			(at 0 0.4445)
			(size 0.1524 0.1524)
			(layers "F.Cu" "F.Mask" "F.Paste")
			(net "PCIE_TX_P88")
			(options
				(clearance outline)
				(anchor circle)
			)
			(primitives
				(gr_poly
					(pts
						(arc
							(start 0.3048 -0.2032)
							(mid 0.275042 -0.275042)
							(end 0.2032 -0.3048)
						)
						(arc
							(start -0.2032 -0.3048)
							(mid -0.275042 -0.275042)
							(end -0.3048 -0.2032)
						)
						(arc
							(start -0.3048 0.2032)
							(mid -0.275042 0.275042)
							(end -0.2032 0.3048)
						)
						(arc
							(start 0.2032 0.3048)
							(mid 0.275042 0.275042)
							(end 0.3048 0.2032)
						)
					)
					(width 0)
					(fill yes)
				)
			)
		)
	)
	(footprint ""
		(layer "F.Cu")
		(at 23.2664 -86.9696)
		(property "Reference" "R402"
			(at 0 0 0)
			(layer "F.SilkS")
			(hide yes)
			(effects
				(font
					(size 1.27 1.27)
				)
			)
		)
		(property "Value" "3K3R2F-2-GP"
			(at 0.064008 -3.993896 0)
			(unlocked yes)
			(layer "F.Fab")
			(hide yes)
			(effects
				(font
					(size 1.016 1.016)
					(thickness 0.1524)
				)
			)
		)
		(property "Device Type" "R402H16"
			(at 0.064008 -5.517896 0)
			(unlocked yes)
			(layer "F.Fab")
			(hide yes)
			(effects
				(font
					(size 1.016 1.016)
					(thickness 0.1524)
				)
			)
		)
		(duplicate_pad_numbers_are_jumpers no)
		(fp_line
			(start -0.508 -0.9398)
			(end -0.508 0.9398)
			(stroke
				(width 0.1524)
				(type default)
			)
			(layer "F.SilkS")
		)
		(fp_line
			(start 0.508 -0.9398)
			(end -0.508 -0.9398)
			(stroke
				(width 0.1524)
				(type default)
			)
			(layer "F.SilkS")
		)
		(fp_rect
			(start -0.508 0.9398)
			(end 0.508 -0.9398)
			(stroke
				(width 0)
				(type default)
			)
			(fill no)
			(layer "F.CrtYd")
		)
		(fp_rect
			(start -0.508 0.9398)
			(end 0.508 -0.9398)
			(stroke
				(width 0)
				(type default)
			)
			(fill no)
			(layer "F.Fab")
		)
		(pad "1" smd custom
			(at 0 -0.4445)
			(size 0.1397 0.1397)
			(layers "F.Cu" "F.Mask" "F.Paste")
			(net "P3V3_STBY")
			(options
				(clearance outline)
				(anchor circle)
			)
			(primitives
				(gr_poly
					(pts
						(arc
							(start -0.1778 -0.2794)
							(mid -0.249642 -0.249642)
							(end -0.2794 -0.1778)
						)
						(arc
							(start -0.2794 0.1778)
							(mid -0.249642 0.249642)
							(end -0.1778 0.2794)
						)
						(arc
							(start 0.1778 0.2794)
							(mid 0.249642 0.249642)
							(end 0.2794 0.1778)
						)
						(arc
							(start 0.2794 -0.1778)
							(mid 0.249642 -0.249642)
							(end 0.1778 -0.2794)
						)
					)
					(width 0)
					(fill yes)
				)
			)
		)
		(pad "2" smd custom
			(at 0 0.4445)
			(size 0.1397 0.1397)
			(layers "F.Cu" "F.Mask" "F.Paste")
			(net "NIC_JTCK")
			(options
				(clearance outline)
				(anchor circle)
			)
			(primitives
				(gr_poly
					(pts
						(arc
							(start -0.1778 -0.2794)
							(mid -0.249642 -0.249642)
							(end -0.2794 -0.1778)
						)
						(arc
							(start -0.2794 0.1778)
							(mid -0.249642 0.249642)
							(end -0.1778 0.2794)
						)
						(arc
							(start 0.1778 0.2794)
							(mid 0.249642 0.249642)
							(end 0.2794 0.1778)
						)
						(arc
							(start 0.2794 -0.1778)
							(mid 0.249642 -0.249642)
							(end 0.1778 -0.2794)
						)
					)
					(width 0)
					(fill yes)
				)
			)
		)
	)
	(footprint ""
		(layer "F.Cu")
		(at 19.304 -154.432)
		(property "Reference" "R8005"
			(at 0 0 0)
			(layer "F.SilkS")
			(hide yes)
			(effects
				(font
					(size 1.27 1.27)
				)
			)
		)
		(property "Value" "0R2J-2-GP"
			(at 0.064008 -3.993896 0)
			(unlocked yes)
			(layer "F.Fab")
			(hide yes)
			(effects
				(font
					(size 1.016 1.016)
					(thickness 0.1524)
				)
			)
		)
		(property "Device Type" "R402H16"
			(at 0.064008 -5.517896 0)
			(unlocked yes)
			(layer "F.Fab")
			(hide yes)
			(effects
				(font
					(size 1.016 1.016)
					(thickness 0.1524)
				)
			)
		)
		(duplicate_pad_numbers_are_jumpers no)
		(fp_line
			(start -0.508 -0.9398)
			(end -0.508 0.9398)
			(stroke
				(width 0.1524)
				(type default)
			)
			(layer "F.SilkS")
		)
		(fp_line
			(start 0.508 -0.9398)
			(end -0.508 -0.9398)
			(stroke
				(width 0.1524)
				(type default)
			)
			(layer "F.SilkS")
		)
		(fp_rect
			(start -0.508 0.9398)
			(end 0.508 -0.9398)
			(stroke
				(width 0)
				(type default)
			)
			(fill no)
			(layer "F.CrtYd")
		)
		(fp_rect
			(start -0.508 0.9398)
			(end 0.508 -0.9398)
			(stroke
				(width 0)
				(type default)
			)
			(fill no)
			(layer "F.Fab")
		)
		(pad "1" smd custom
			(at 0 -0.4445)
			(size 0.1397 0.1397)
			(layers "F.Cu" "F.Mask" "F.Paste")
			(net "HOST_I2C_RESET_N_D")
			(options
				(clearance outline)
				(anchor circle)
			)
			(primitives
				(gr_poly
					(pts
						(arc
							(start -0.1778 -0.2794)
							(mid -0.249642 -0.249642)
							(end -0.2794 -0.1778)
						)
						(arc
							(start -0.2794 0.1778)
							(mid -0.249642 0.249642)
							(end -0.1778 0.2794)
						)
						(arc
							(start 0.1778 0.2794)
							(mid 0.249642 0.249642)
							(end 0.2794 0.1778)
						)
						(arc
							(start 0.2794 -0.1778)
							(mid 0.249642 -0.249642)
							(end 0.1778 -0.2794)
						)
					)
					(width 0)
					(fill yes)
				)
			)
		)
		(pad "2" smd custom
			(at 0 0.4445)
			(size 0.1397 0.1397)
			(layers "F.Cu" "F.Mask" "F.Paste")
			(net "FM_BMC_RESET_Q36")
			(options
				(clearance outline)
				(anchor circle)
			)
			(primitives
				(gr_poly
					(pts
						(arc
							(start -0.1778 -0.2794)
							(mid -0.249642 -0.249642)
							(end -0.2794 -0.1778)
						)
						(arc
							(start -0.2794 0.1778)
							(mid -0.249642 0.249642)
							(end -0.1778 0.2794)
						)
						(arc
							(start 0.1778 0.2794)
							(mid 0.249642 0.249642)
							(end 0.2794 0.1778)
						)
						(arc
							(start 0.2794 -0.1778)
							(mid 0.249642 -0.249642)
							(end 0.1778 -0.2794)
						)
					)
					(width 0)
					(fill yes)
				)
			)
		)
	)
	(footprint ""
		(layer "F.Cu")
		(at 159.807402 -53.189632 90)
		(property "Reference" "R76"
			(at 0 0 90)
			(layer "F.SilkS")
			(hide yes)
			(effects
				(font
					(size 1.27 1.27)
				)
			)
		)
		(property "Value" "0R2J-2-GP"
			(at 0.064008 -3.993896 90)
			(unlocked yes)
			(layer "F.Fab")
			(hide yes)
			(effects
				(font
					(size 1.016 1.016)
					(thickness 0.1524)
				)
			)
		)
		(property "Device Type" "R402H16"
			(at 0.064008 -5.517896 90)
			(unlocked yes)
			(layer "F.Fab")
			(hide yes)
			(effects
				(font
					(size 1.016 1.016)
					(thickness 0.1524)
				)
			)
		)
		(duplicate_pad_numbers_are_jumpers no)
		(fp_line
			(start 0.508 -0.9398)
			(end -0.508 -0.9398)
			(stroke
				(width 0.1524)
				(type default)
			)
			(layer "F.SilkS")
		)
		(fp_line
			(start -0.508 -0.9398)
			(end -0.508 0.9398)
			(stroke
				(width 0.1524)
				(type default)
			)
			(layer "F.SilkS")
		)
		(fp_rect
			(start -0.508 0.9398)
			(end 0.508 -0.9398)
			(stroke
				(width 0)
				(type default)
			)
			(fill no)
			(layer "F.CrtYd")
		)
		(fp_rect
			(start -0.508 0.9398)
			(end 0.508 -0.9398)
			(stroke
				(width 0)
				(type default)
			)
			(fill no)
			(layer "F.Fab")
		)
		(pad "1" smd custom
			(at 0 -0.4445 90)
			(size 0.1397 0.1397)
			(layers "F.Cu" "F.Mask" "F.Paste")
			(net "P0V9_VFB_R")
			(options
				(clearance outline)
				(anchor circle)
			)
			(primitives
				(gr_poly
					(pts
						(arc
							(start -0.1778 -0.2794)
							(mid -0.249642 -0.249642)
							(end -0.2794 -0.1778)
						)
						(arc
							(start -0.2794 0.1778)
							(mid -0.249642 0.249642)
							(end -0.1778 0.2794)
						)
						(arc
							(start 0.1778 0.2794)
							(mid 0.249642 0.249642)
							(end 0.2794 0.1778)
						)
						(arc
							(start 0.2794 -0.1778)
							(mid 0.249642 -0.249642)
							(end 0.1778 -0.2794)
						)
					)
					(width 0)
					(fill yes)
				)
			)
		)
		(pad "2" smd custom
			(at 0 0.4445 90)
			(size 0.1397 0.1397)
			(layers "F.Cu" "F.Mask" "F.Paste")
			(net "DUT_AVD_PCIE")
			(options
				(clearance outline)
				(anchor circle)
			)
			(primitives
				(gr_poly
					(pts
						(arc
							(start -0.1778 -0.2794)
							(mid -0.249642 -0.249642)
							(end -0.2794 -0.1778)
						)
						(arc
							(start -0.2794 0.1778)
							(mid -0.249642 0.249642)
							(end -0.1778 0.2794)
						)
						(arc
							(start 0.1778 0.2794)
							(mid 0.249642 0.249642)
							(end 0.2794 0.1778)
						)
						(arc
							(start 0.2794 -0.1778)
							(mid 0.249642 -0.249642)
							(end 0.1778 -0.2794)
						)
					)
					(width 0)
					(fill yes)
				)
			)
		)
	)
	(footprint ""
		(layer "F.Cu")
		(at 331.597 -99.568 180)
		(property "Reference" "R4158"
			(at 0 0 180)
			(layer "F.SilkS")
			(hide yes)
			(effects
				(font
					(size 1.27 1.27)
				)
			)
		)
		(property "Value" "4K7R2F-GP"
			(at 0.064008 -3.993896 180)
			(unlocked yes)
			(layer "F.Fab")
			(hide yes)
			(effects
				(font
					(size 1.016 1.016)
					(thickness 0.1524)
				)
			)
		)
		(property "Device Type" "R402H16"
			(at 0.064008 -5.517896 180)
			(unlocked yes)
			(layer "F.Fab")
			(hide yes)
			(effects
				(font
					(size 1.016 1.016)
					(thickness 0.1524)
				)
			)
		)
		(duplicate_pad_numbers_are_jumpers no)
		(fp_line
			(start 0.508 -0.9398)
			(end -0.508 -0.9398)
			(stroke
				(width 0.1524)
				(type default)
			)
			(layer "F.SilkS")
		)
		(fp_line
			(start -0.508 -0.9398)
			(end -0.508 0.9398)
			(stroke
				(width 0.1524)
				(type default)
			)
			(layer "F.SilkS")
		)
		(fp_rect
			(start -0.508 0.9398)
			(end 0.508 -0.9398)
			(stroke
				(width 0)
				(type default)
			)
			(fill no)
			(layer "F.CrtYd")
		)
		(fp_rect
			(start -0.508 0.9398)
			(end 0.508 -0.9398)
			(stroke
				(width 0)
				(type default)
			)
			(fill no)
			(layer "F.Fab")
		)
		(pad "1" smd custom
			(at 0 -0.4445 180)
			(size 0.1397 0.1397)
			(layers "F.Cu" "F.Mask" "F.Paste")
			(net "VS1_LED")
			(options
				(clearance outline)
				(anchor circle)
			)
			(primitives
				(gr_poly
					(pts
						(arc
							(start -0.1778 -0.2794)
							(mid -0.249642 -0.249642)
							(end -0.2794 -0.1778)
						)
						(arc
							(start -0.2794 0.1778)
							(mid -0.249642 0.249642)
							(end -0.1778 0.2794)
						)
						(arc
							(start 0.1778 0.2794)
							(mid 0.249642 0.249642)
							(end 0.2794 0.1778)
						)
						(arc
							(start 0.2794 -0.1778)
							(mid 0.249642 -0.249642)
							(end 0.1778 -0.2794)
						)
					)
					(width 0)
					(fill yes)
				)
			)
		)
		(pad "2" smd custom
			(at 0 0.4445 180)
			(size 0.1397 0.1397)
			(layers "F.Cu" "F.Mask" "F.Paste")
			(net "P3V3_STBY")
			(options
				(clearance outline)
				(anchor circle)
			)
			(primitives
				(gr_poly
					(pts
						(arc
							(start -0.1778 -0.2794)
							(mid -0.249642 -0.249642)
							(end -0.2794 -0.1778)
						)
						(arc
							(start -0.2794 0.1778)
							(mid -0.249642 0.249642)
							(end -0.1778 0.2794)
						)
						(arc
							(start 0.1778 0.2794)
							(mid 0.249642 0.249642)
							(end 0.2794 0.1778)
						)
						(arc
							(start 0.2794 -0.1778)
							(mid 0.249642 -0.249642)
							(end 0.1778 -0.2794)
						)
					)
					(width 0)
					(fill yes)
				)
			)
		)
	)
	(footprint ""
		(layer "F.Cu")
		(at 154.45486 -84.41944)
		(property "Reference" "R98"
			(at 0 0 0)
			(layer "F.SilkS")
			(hide yes)
			(effects
				(font
					(size 1.27 1.27)
				)
			)
		)
		(property "Value" "10KR2F-2-GP"
			(at 0.064008 -3.993896 0)
			(unlocked yes)
			(layer "F.Fab")
			(hide yes)
			(effects
				(font
					(size 1.016 1.016)
					(thickness 0.1524)
				)
			)
		)
		(property "Device Type" "R402H16"
			(at 0.064008 -5.517896 0)
			(unlocked yes)
			(layer "F.Fab")
			(hide yes)
			(effects
				(font
					(size 1.016 1.016)
					(thickness 0.1524)
				)
			)
		)
		(duplicate_pad_numbers_are_jumpers no)
		(fp_line
			(start -0.508 -0.9398)
			(end -0.508 0.9398)
			(stroke
				(width 0.1524)
				(type default)
			)
			(layer "F.SilkS")
		)
		(fp_line
			(start 0.508 -0.9398)
			(end -0.508 -0.9398)
			(stroke
				(width 0.1524)
				(type default)
			)
			(layer "F.SilkS")
		)
		(fp_rect
			(start -0.508 0.9398)
			(end 0.508 -0.9398)
			(stroke
				(width 0)
				(type default)
			)
			(fill no)
			(layer "F.CrtYd")
		)
		(fp_rect
			(start -0.508 0.9398)
			(end 0.508 -0.9398)
			(stroke
				(width 0)
				(type default)
			)
			(fill no)
			(layer "F.Fab")
		)
		(pad "1" smd custom
			(at 0 -0.4445)
			(size 0.1397 0.1397)
			(layers "F.Cu" "F.Mask" "F.Paste")
			(net "CLKGNE_SADR_R")
			(options
				(clearance outline)
				(anchor circle)
			)
			(primitives
				(gr_poly
					(pts
						(arc
							(start -0.1778 -0.2794)
							(mid -0.249642 -0.249642)
							(end -0.2794 -0.1778)
						)
						(arc
							(start -0.2794 0.1778)
							(mid -0.249642 0.249642)
							(end -0.1778 0.2794)
						)
						(arc
							(start 0.1778 0.2794)
							(mid 0.249642 0.249642)
							(end 0.2794 0.1778)
						)
						(arc
							(start 0.2794 -0.1778)
							(mid 0.249642 -0.249642)
							(end 0.1778 -0.2794)
						)
					)
					(width 0)
					(fill yes)
				)
			)
		)
		(pad "2" smd custom
			(at 0 0.4445)
			(size 0.1397 0.1397)
			(layers "F.Cu" "F.Mask" "F.Paste")
			(net "P1V8_STBY")
			(options
				(clearance outline)
				(anchor circle)
			)
			(primitives
				(gr_poly
					(pts
						(arc
							(start -0.1778 -0.2794)
							(mid -0.249642 -0.249642)
							(end -0.2794 -0.1778)
						)
						(arc
							(start -0.2794 0.1778)
							(mid -0.249642 0.249642)
							(end -0.1778 0.2794)
						)
						(arc
							(start 0.1778 0.2794)
							(mid 0.249642 0.249642)
							(end 0.2794 0.1778)
						)
						(arc
							(start 0.2794 -0.1778)
							(mid 0.249642 -0.249642)
							(end 0.1778 -0.2794)
						)
					)
					(width 0)
					(fill yes)
				)
			)
		)
	)
	(footprint ""
		(layer "F.Cu")
		(at 87.8078 -85.2424 90)
		(property "Reference" "SR948"
			(at 0 0 90)
			(layer "F.SilkS")
			(hide yes)
			(effects
				(font
					(size 1.27 1.27)
				)
			)
		)
		(property "Value" "0R2J-2-GP"
			(at 0.064008 -3.993896 90)
			(unlocked yes)
			(layer "F.Fab")
			(hide yes)
			(effects
				(font
					(size 1.016 1.016)
					(thickness 0.1524)
				)
			)
		)
		(property "Device Type" "R402H16"
			(at 0.064008 -5.517896 90)
			(unlocked yes)
			(layer "F.Fab")
			(hide yes)
			(effects
				(font
					(size 1.016 1.016)
					(thickness 0.1524)
				)
			)
		)
		(duplicate_pad_numbers_are_jumpers no)
		(fp_line
			(start 0.508 -0.9398)
			(end -0.508 -0.9398)
			(stroke
				(width 0.1524)
				(type default)
			)
			(layer "F.SilkS")
		)
		(fp_line
			(start -0.508 -0.9398)
			(end -0.508 0.9398)
			(stroke
				(width 0.1524)
				(type default)
			)
			(layer "F.SilkS")
		)
		(fp_rect
			(start -0.508 0.9398)
			(end 0.508 -0.9398)
			(stroke
				(width 0)
				(type default)
			)
			(fill no)
			(layer "F.CrtYd")
		)
		(fp_rect
			(start -0.508 0.9398)
			(end 0.508 -0.9398)
			(stroke
				(width 0)
				(type default)
			)
			(fill no)
			(layer "F.Fab")
		)
		(pad "1" smd custom
			(at 0 -0.4445 90)
			(size 0.1397 0.1397)
			(layers "F.Cu" "F.Mask" "F.Paste")
			(net "EXP_SMART_TX")
			(options
				(clearance outline)
				(anchor circle)
			)
			(primitives
				(gr_poly
					(pts
						(arc
							(start -0.1778 -0.2794)
							(mid -0.249642 -0.249642)
							(end -0.2794 -0.1778)
						)
						(arc
							(start -0.2794 0.1778)
							(mid -0.249642 0.249642)
							(end -0.1778 0.2794)
						)
						(arc
							(start 0.1778 0.2794)
							(mid 0.249642 0.249642)
							(end 0.2794 0.1778)
						)
						(arc
							(start 0.2794 -0.1778)
							(mid 0.249642 -0.249642)
							(end 0.1778 -0.2794)
						)
					)
					(width 0)
					(fill yes)
				)
			)
		)
		(pad "2" smd custom
			(at 0 0.4445 90)
			(size 0.1397 0.1397)
			(layers "F.Cu" "F.Mask" "F.Paste")
			(net "EXP_SMART_TX_R")
			(options
				(clearance outline)
				(anchor circle)
			)
			(primitives
				(gr_poly
					(pts
						(arc
							(start -0.1778 -0.2794)
							(mid -0.249642 -0.249642)
							(end -0.2794 -0.1778)
						)
						(arc
							(start -0.2794 0.1778)
							(mid -0.249642 0.249642)
							(end -0.1778 0.2794)
						)
						(arc
							(start 0.1778 0.2794)
							(mid 0.249642 0.249642)
							(end 0.2794 0.1778)
						)
						(arc
							(start 0.2794 -0.1778)
							(mid 0.249642 -0.249642)
							(end 0.1778 -0.2794)
						)
					)
					(width 0)
					(fill yes)
				)
			)
		)
	)
	(footprint ""
		(layer "F.Cu")
		(at 17.7038 -177.9778)
		(property "Reference" "C339"
			(at 0 0 0)
			(layer "F.SilkS")
			(hide yes)
			(effects
				(font
					(size 1.27 1.27)
				)
			)
		)
		(property "Value" "SC22UF16V6KX-GP"
			(at 0 -6.8072 0)
			(unlocked yes)
			(layer "F.Fab")
			(hide yes)
			(effects
				(font
					(size 1.016 1.016)
					(thickness 0.1524)
				)
			)
		)
		(property "Device Type" "C1206H75"
			(at 0 -8.7122 0)
			(unlocked yes)
			(layer "F.Fab")
			(hide yes)
			(effects
				(font
					(size 1.016 1.016)
					(thickness 0.1524)
				)
			)
		)
		(duplicate_pad_numbers_are_jumpers no)
		(fp_line
			(start -1.016 -2.2352)
			(end -1.016 -0.8382)
			(stroke
				(width 0.1524)
				(type default)
			)
			(layer "F.SilkS")
		)
		(fp_line
			(start -1.016 2.2352)
			(end -1.016 0.8128)
			(stroke
				(width 0.1524)
				(type default)
			)
			(layer "F.SilkS")
		)
		(fp_line
			(start 1.016 -2.2352)
			(end -1.016 -2.2352)
			(stroke
				(width 0.1524)
				(type default)
			)
			(layer "F.SilkS")
		)
		(fp_line
			(start 1.016 -2.2352)
			(end 1.016 -0.8382)
			(stroke
				(width 0.1524)
				(type default)
			)
			(layer "F.SilkS")
		)
		(fp_line
			(start 1.016 0.8382)
			(end 1.016 2.2352)
			(stroke
				(width 0.1524)
				(type default)
			)
			(layer "F.SilkS")
		)
		(fp_line
			(start 1.016 2.2352)
			(end -1.016 2.2352)
			(stroke
				(width 0.1524)
				(type default)
			)
			(layer "F.SilkS")
		)
		(fp_rect
			(start -1.0922 2.3114)
			(end 1.0922 -2.3114)
			(stroke
				(width 0)
				(type default)
			)
			(fill no)
			(layer "F.CrtYd")
		)
		(fp_poly
			(pts
				(xy -1.0922 -2.3114) (xy 1.0922 -2.3114) (xy 1.0922 2.3114) (xy -1.0922 2.3114)
			)
			(stroke
				(width 0)
				(type default)
			)
			(fill no)
			(layer "F.Fab")
		)
		(pad "1" smd rect
			(at 0 -1.397)
			(size 1.651 1.27)
			(layers "F.Cu" "F.Mask" "F.Paste")
			(net "MB0_HS_ENABLE")
		)
		(pad "2" smd rect
			(at 0 1.397)
			(size 1.651 1.27)
			(layers "F.Cu" "F.Mask" "F.Paste")
			(net "GND")
		)
	)
	(footprint ""
		(layer "F.Cu")
		(at 128.9558 -43.1292 180)
		(property "Reference" "R623"
			(at 0 0 180)
			(layer "F.SilkS")
			(hide yes)
			(effects
				(font
					(size 1.27 1.27)
				)
			)
		)
		(property "Value" "0R2J-2-GP"
			(at 0.064008 -3.993896 180)
			(unlocked yes)
			(layer "F.Fab")
			(hide yes)
			(effects
				(font
					(size 1.016 1.016)
					(thickness 0.1524)
				)
			)
		)
		(property "Device Type" "R402H16"
			(at 0.064008 -5.517896 180)
			(unlocked yes)
			(layer "F.Fab")
			(hide yes)
			(effects
				(font
					(size 1.016 1.016)
					(thickness 0.1524)
				)
			)
		)
		(duplicate_pad_numbers_are_jumpers no)
		(fp_line
			(start 0.508 -0.9398)
			(end -0.508 -0.9398)
			(stroke
				(width 0.1524)
				(type default)
			)
			(layer "F.SilkS")
		)
		(fp_line
			(start -0.508 -0.9398)
			(end -0.508 0.9398)
			(stroke
				(width 0.1524)
				(type default)
			)
			(layer "F.SilkS")
		)
		(fp_rect
			(start -0.508 0.9398)
			(end 0.508 -0.9398)
			(stroke
				(width 0)
				(type default)
			)
			(fill no)
			(layer "F.CrtYd")
		)
		(fp_rect
			(start -0.508 0.9398)
			(end 0.508 -0.9398)
			(stroke
				(width 0)
				(type default)
			)
			(fill no)
			(layer "F.Fab")
		)
		(pad "1" smd custom
			(at 0 -0.4445 180)
			(size 0.1397 0.1397)
			(layers "F.Cu" "F.Mask" "F.Paste")
			(net "UPLINK4_R")
			(options
				(clearance outline)
				(anchor circle)
			)
			(primitives
				(gr_poly
					(pts
						(arc
							(start -0.1778 -0.2794)
							(mid -0.249642 -0.249642)
							(end -0.2794 -0.1778)
						)
						(arc
							(start -0.2794 0.1778)
							(mid -0.249642 0.249642)
							(end -0.1778 0.2794)
						)
						(arc
							(start 0.1778 0.2794)
							(mid 0.249642 0.249642)
							(end 0.2794 0.1778)
						)
						(arc
							(start 0.2794 -0.1778)
							(mid 0.249642 -0.249642)
							(end 0.1778 -0.2794)
						)
					)
					(width 0)
					(fill yes)
				)
			)
		)
		(pad "2" smd custom
			(at 0 0.4445 180)
			(size 0.1397 0.1397)
			(layers "F.Cu" "F.Mask" "F.Paste")
			(net "UPLINK4")
			(options
				(clearance outline)
				(anchor circle)
			)
			(primitives
				(gr_poly
					(pts
						(arc
							(start -0.1778 -0.2794)
							(mid -0.249642 -0.249642)
							(end -0.2794 -0.1778)
						)
						(arc
							(start -0.2794 0.1778)
							(mid -0.249642 0.249642)
							(end -0.1778 0.2794)
						)
						(arc
							(start 0.1778 0.2794)
							(mid 0.249642 0.249642)
							(end 0.2794 0.1778)
						)
						(arc
							(start 0.2794 -0.1778)
							(mid 0.249642 -0.249642)
							(end 0.1778 -0.2794)
						)
					)
					(width 0)
					(fill yes)
				)
			)
		)
	)
	(footprint ""
		(layer "F.Cu")
		(at 9.779 -118.364 90)
		(property "Reference" "R294"
			(at 0 0 90)
			(layer "F.SilkS")
			(hide yes)
			(effects
				(font
					(size 1.27 1.27)
				)
			)
		)
		(property "Value" "4K7R2F-GP"
			(at 0.064008 -3.993896 90)
			(unlocked yes)
			(layer "F.Fab")
			(hide yes)
			(effects
				(font
					(size 1.016 1.016)
					(thickness 0.1524)
				)
			)
		)
		(property "Device Type" "R402H16"
			(at 0.064008 -5.517896 90)
			(unlocked yes)
			(layer "F.Fab")
			(hide yes)
			(effects
				(font
					(size 1.016 1.016)
					(thickness 0.1524)
				)
			)
		)
		(duplicate_pad_numbers_are_jumpers no)
		(fp_line
			(start 0.508 -0.9398)
			(end -0.508 -0.9398)
			(stroke
				(width 0.1524)
				(type default)
			)
			(layer "F.SilkS")
		)
		(fp_line
			(start -0.508 -0.9398)
			(end -0.508 0.9398)
			(stroke
				(width 0.1524)
				(type default)
			)
			(layer "F.SilkS")
		)
		(fp_rect
			(start -0.508 0.9398)
			(end 0.508 -0.9398)
			(stroke
				(width 0)
				(type default)
			)
			(fill no)
			(layer "F.CrtYd")
		)
		(fp_rect
			(start -0.508 0.9398)
			(end 0.508 -0.9398)
			(stroke
				(width 0)
				(type default)
			)
			(fill no)
			(layer "F.Fab")
		)
		(pad "1" smd custom
			(at 0 -0.4445 90)
			(size 0.1397 0.1397)
			(layers "F.Cu" "F.Mask" "F.Paste")
			(net "P3V3_STBY")
			(options
				(clearance outline)
				(anchor circle)
			)
			(primitives
				(gr_poly
					(pts
						(arc
							(start -0.1778 -0.2794)
							(mid -0.249642 -0.249642)
							(end -0.2794 -0.1778)
						)
						(arc
							(start -0.2794 0.1778)
							(mid -0.249642 0.249642)
							(end -0.1778 0.2794)
						)
						(arc
							(start 0.1778 0.2794)
							(mid 0.249642 0.249642)
							(end 0.2794 0.1778)
						)
						(arc
							(start 0.2794 -0.1778)
							(mid 0.249642 -0.249642)
							(end 0.1778 -0.2794)
						)
					)
					(width 0)
					(fill yes)
				)
			)
		)
		(pad "2" smd custom
			(at 0 0.4445 90)
			(size 0.1397 0.1397)
			(layers "F.Cu" "F.Mask" "F.Paste")
			(net "I2C1_LS_G1")
			(options
				(clearance outline)
				(anchor circle)
			)
			(primitives
				(gr_poly
					(pts
						(arc
							(start -0.1778 -0.2794)
							(mid -0.249642 -0.249642)
							(end -0.2794 -0.1778)
						)
						(arc
							(start -0.2794 0.1778)
							(mid -0.249642 0.249642)
							(end -0.1778 0.2794)
						)
						(arc
							(start 0.1778 0.2794)
							(mid 0.249642 0.249642)
							(end 0.2794 0.1778)
						)
						(arc
							(start 0.2794 -0.1778)
							(mid 0.249642 -0.249642)
							(end 0.1778 -0.2794)
						)
					)
					(width 0)
					(fill yes)
				)
			)
		)
	)
	(footprint ""
		(layer "F.Cu")
		(at 117.5258 -97.1042 180)
		(property "Reference" "R430"
			(at 0 0 180)
			(layer "F.SilkS")
			(hide yes)
			(effects
				(font
					(size 1.27 1.27)
				)
			)
		)
		(property "Value" "10KR2F-2-GP"
			(at 0.064008 -3.993896 180)
			(unlocked yes)
			(layer "F.Fab")
			(hide yes)
			(effects
				(font
					(size 1.016 1.016)
					(thickness 0.1524)
				)
			)
		)
		(property "Device Type" "R402H16"
			(at 0.064008 -5.517896 180)
			(unlocked yes)
			(layer "F.Fab")
			(hide yes)
			(effects
				(font
					(size 1.016 1.016)
					(thickness 0.1524)
				)
			)
		)
		(duplicate_pad_numbers_are_jumpers no)
		(fp_line
			(start 0.508 -0.9398)
			(end -0.508 -0.9398)
			(stroke
				(width 0.1524)
				(type default)
			)
			(layer "F.SilkS")
		)
		(fp_line
			(start -0.508 -0.9398)
			(end -0.508 0.9398)
			(stroke
				(width 0.1524)
				(type default)
			)
			(layer "F.SilkS")
		)
		(fp_rect
			(start -0.508 0.9398)
			(end 0.508 -0.9398)
			(stroke
				(width 0)
				(type default)
			)
			(fill no)
			(layer "F.CrtYd")
		)
		(fp_rect
			(start -0.508 0.9398)
			(end 0.508 -0.9398)
			(stroke
				(width 0)
				(type default)
			)
			(fill no)
			(layer "F.Fab")
		)
		(pad "1" smd custom
			(at 0 -0.4445 180)
			(size 0.1397 0.1397)
			(layers "F.Cu" "F.Mask" "F.Paste")
			(net "I2C10_BUF_READY")
			(options
				(clearance outline)
				(anchor circle)
			)
			(primitives
				(gr_poly
					(pts
						(arc
							(start -0.1778 -0.2794)
							(mid -0.249642 -0.249642)
							(end -0.2794 -0.1778)
						)
						(arc
							(start -0.2794 0.1778)
							(mid -0.249642 0.249642)
							(end -0.1778 0.2794)
						)
						(arc
							(start 0.1778 0.2794)
							(mid 0.249642 0.249642)
							(end 0.2794 0.1778)
						)
						(arc
							(start 0.2794 -0.1778)
							(mid 0.249642 -0.249642)
							(end 0.1778 -0.2794)
						)
					)
					(width 0)
					(fill yes)
				)
			)
		)
		(pad "2" smd custom
			(at 0 0.4445 180)
			(size 0.1397 0.1397)
			(layers "F.Cu" "F.Mask" "F.Paste")
			(net "P3V3_STBY")
			(options
				(clearance outline)
				(anchor circle)
			)
			(primitives
				(gr_poly
					(pts
						(arc
							(start -0.1778 -0.2794)
							(mid -0.249642 -0.249642)
							(end -0.2794 -0.1778)
						)
						(arc
							(start -0.2794 0.1778)
							(mid -0.249642 0.249642)
							(end -0.1778 0.2794)
						)
						(arc
							(start 0.1778 0.2794)
							(mid 0.249642 0.249642)
							(end 0.2794 0.1778)
						)
						(arc
							(start 0.2794 -0.1778)
							(mid 0.249642 -0.249642)
							(end 0.1778 -0.2794)
						)
					)
					(width 0)
					(fill yes)
				)
			)
		)
	)
	(footprint ""
		(layer "F.Cu")
		(at 35.2806 -186.0042 -90)
		(property "Reference" "R966"
			(at 0 0 270)
			(layer "F.SilkS")
			(hide yes)
			(effects
				(font
					(size 1.27 1.27)
				)
			)
		)
		(property "Value" "0R2J-2-GP"
			(at 0.064008 -3.993896 270)
			(unlocked yes)
			(layer "F.Fab")
			(hide yes)
			(effects
				(font
					(size 1.016 1.016)
					(thickness 0.1524)
				)
			)
		)
		(property "Device Type" "R402H16"
			(at 0.064008 -5.517896 270)
			(unlocked yes)
			(layer "F.Fab")
			(hide yes)
			(effects
				(font
					(size 1.016 1.016)
					(thickness 0.1524)
				)
			)
		)
		(duplicate_pad_numbers_are_jumpers no)
		(fp_line
			(start -0.508 -0.9398)
			(end -0.508 0.9398)
			(stroke
				(width 0.1524)
				(type default)
			)
			(layer "F.SilkS")
		)
		(fp_line
			(start 0.508 -0.9398)
			(end -0.508 -0.9398)
			(stroke
				(width 0.1524)
				(type default)
			)
			(layer "F.SilkS")
		)
		(fp_rect
			(start -0.508 0.9398)
			(end 0.508 -0.9398)
			(stroke
				(width 0)
				(type default)
			)
			(fill no)
			(layer "F.CrtYd")
		)
		(fp_rect
			(start -0.508 0.9398)
			(end 0.508 -0.9398)
			(stroke
				(width 0)
				(type default)
			)
			(fill no)
			(layer "F.Fab")
		)
		(pad "1" smd custom
			(at 0 -0.4445 270)
			(size 0.1397 0.1397)
			(layers "F.Cu" "F.Mask" "F.Paste")
			(net "BMC_I2C5_D_PEB_DEVICE_SCL")
			(options
				(clearance outline)
				(anchor circle)
			)
			(primitives
				(gr_poly
					(pts
						(arc
							(start -0.1778 -0.2794)
							(mid -0.249642 -0.249642)
							(end -0.2794 -0.1778)
						)
						(arc
							(start -0.2794 0.1778)
							(mid -0.249642 0.249642)
							(end -0.1778 0.2794)
						)
						(arc
							(start 0.1778 0.2794)
							(mid 0.249642 0.249642)
							(end 0.2794 0.1778)
						)
						(arc
							(start 0.2794 -0.1778)
							(mid 0.249642 -0.249642)
							(end 0.1778 -0.2794)
						)
					)
					(width 0)
					(fill yes)
				)
			)
		)
		(pad "2" smd custom
			(at 0 0.4445 270)
			(size 0.1397 0.1397)
			(layers "F.Cu" "F.Mask" "F.Paste")
			(net "BUF_I2C5_SCL_R")
			(options
				(clearance outline)
				(anchor circle)
			)
			(primitives
				(gr_poly
					(pts
						(arc
							(start -0.1778 -0.2794)
							(mid -0.249642 -0.249642)
							(end -0.2794 -0.1778)
						)
						(arc
							(start -0.2794 0.1778)
							(mid -0.249642 0.249642)
							(end -0.1778 0.2794)
						)
						(arc
							(start 0.1778 0.2794)
							(mid 0.249642 0.249642)
							(end 0.2794 0.1778)
						)
						(arc
							(start 0.2794 -0.1778)
							(mid 0.249642 -0.249642)
							(end 0.1778 -0.2794)
						)
					)
					(width 0)
					(fill yes)
				)
			)
		)
	)
	(footprint ""
		(layer "F.Cu")
		(at 38.608 -51.943 90)
		(property "Reference" "TC17"
			(at 0 0 90)
			(layer "F.SilkS")
			(hide yes)
			(effects
				(font
					(size 1.27 1.27)
				)
			)
		)
		(property "Value" "ST150U6D3VDM-28-GP"
			(at 0 -9.6012 90)
			(unlocked yes)
			(layer "F.Fab")
			(hide yes)
			(effects
				(font
					(size 1.016 1.016)
					(thickness 0.1524)
				)
			)
		)
		(property "Device Type" "CT7343H83"
			(at 0 -11.1252 90)
			(unlocked yes)
			(layer "F.Fab")
			(hide yes)
			(effects
				(font
					(size 1.016 1.016)
					(thickness 0.1524)
				)
			)
		)
		(duplicate_pad_numbers_are_jumpers no)
		(fp_line
			(start 2.286 -4.8768)
			(end -2.286 -4.8768)
			(stroke
				(width 0.1524)
				(type default)
			)
			(layer "F.SilkS")
		)
		(fp_line
			(start -2.286 -4.8768)
			(end -2.286 -2.032)
			(stroke
				(width 0.1524)
				(type default)
			)
			(layer "F.SilkS")
		)
		(fp_line
			(start 2.1082 -4.699)
			(end -2.1082 -4.699)
			(stroke
				(width 0.508)
				(type default)
			)
			(layer "F.SilkS")
		)
		(fp_line
			(start 2.286 -2.032)
			(end 2.286 -4.8768)
			(stroke
				(width 0.1524)
				(type default)
			)
			(layer "F.SilkS")
		)
		(fp_line
			(start 2.286 2.032)
			(end 2.286 4.8768)
			(stroke
				(width 0.1524)
				(type default)
			)
			(layer "F.SilkS")
		)
		(fp_line
			(start 2.286 4.8768)
			(end -2.286 4.8768)
			(stroke
				(width 0.1524)
				(type default)
			)
			(layer "F.SilkS")
		)
		(fp_line
			(start -2.286 4.8768)
			(end -2.286 2.032)
			(stroke
				(width 0.1524)
				(type default)
			)
			(layer "F.SilkS")
		)
		(fp_rect
			(start -2.1463 3.6449)
			(end 2.1463 -3.6449)
			(stroke
				(width 0)
				(type default)
			)
			(fill no)
			(layer "F.CrtYd")
		)
		(fp_poly
			(pts
				(xy -2.54 4.953) (xy -2.54 4.2926) (xy -3.81 4.2926) (xy -3.81 -4.2926) (xy -2.54 -4.2926) (xy -2.54 -4.953)
				(xy 2.54 -4.953) (xy 2.54 -4.2926) (xy 3.81 -4.2926) (xy 3.81 -1.6256) (xy 2.1463 -1.6256) (xy 2.1463 -3.6449)
				(xy -2.1463 -3.6449) (xy -2.1463 3.6449) (xy 2.1463 3.6449) (xy 2.1463 -1.6129) (xy 3.81 -1.6129)
				(xy 3.81 4.2926) (xy 2.54 4.2926) (xy 2.54 4.953)
			)
			(stroke
				(width 0)
				(type default)
			)
			(fill no)
			(layer "F.CrtYd")
		)
		(fp_rect
			(start 2.54 4.2926)
			(end 3.81 -4.2926)
			(stroke
				(width 0)
				(type default)
			)
			(fill no)
			(layer "F.Fab")
		)
		(fp_rect
			(start -3.81 4.2926)
			(end -2.54 -4.2926)
			(stroke
				(width 0)
				(type default)
			)
			(fill no)
			(layer "F.Fab")
		)
		(fp_rect
			(start -2.54 4.953)
			(end 2.54 -4.953)
			(stroke
				(width 0)
				(type default)
			)
			(fill no)
			(layer "F.Fab")
		)
		(pad "1" smd rect
			(at 0 -3.1496 90)
			(size 2.413 2.286)
			(layers "F.Cu" "F.Mask" "F.Paste")
			(net "P5V_USB")
		)
		(pad "2" smd rect
			(at 0 3.1496 90)
			(size 2.413 2.286)
			(layers "F.Cu" "F.Mask" "F.Paste")
			(net "GND")
		)
		(zone
			(layer "F.Cu")
			(hatch none 0.5)
			(connect_pads
				(clearance 0)
			)
			(min_thickness 0.25)
			(keepout
				(tracks allowed)
				(vias not_allowed)
				(pads allowed)
				(copperpour not_allowed)
				(footprints allowed)
			)
			(placement
				(enabled no)
				(sheetname "")
			)
			(fill
				(thermal_gap 0.5)
				(thermal_bridge_width 0.5)
				(island_removal_mode 0)
			)
			(polygon
				(pts
					(xy 36.9189 -53.4543) (xy 34.0106 -53.4543) (xy 34.0106 -50.4317) (xy 36.9062 -50.4317) (xy 37.2364 -50.4317)
					(xy 37.2364 -53.4543)
				)
			)
		)
		(zone
			(layer "F.Cu")
			(hatch none 0.5)
			(connect_pads
				(clearance 0)
			)
			(min_thickness 0.25)
			(keepout
				(tracks allowed)
				(vias not_allowed)
				(pads allowed)
				(copperpour not_allowed)
				(footprints allowed)
			)
			(placement
				(enabled no)
				(sheetname "")
			)
			(fill
				(thermal_gap 0.5)
				(thermal_bridge_width 0.5)
				(island_removal_mode 0)
			)
			(polygon
				(pts
					(xy 43.2054 -50.4317) (xy 43.2054 -53.4543) (xy 40.3098 -53.4543) (xy 39.9796 -53.4543) (xy 39.9796 -50.4317)
					(xy 40.3098 -50.4317)
				)
			)
		)
	)
	(footprint ""
		(layer "F.Cu")
		(at 20.5994 -52.0192 90)
		(property "Reference" "D18"
			(at 0 0 90)
			(layer "F.SilkS")
			(hide yes)
			(effects
				(font
					(size 1.27 1.27)
				)
			)
		)
		(property "Value" "PGB1010603MR-GP"
			(at -0.0254 -2.8956 90)
			(unlocked yes)
			(layer "F.Fab")
			(hide yes)
			(effects
				(font
					(size 1.016 1.016)
					(thickness 0.1524)
				)
			)
		)
		(property "Device Type" "L1608-UH15"
			(at -0.0254 -4.4196 90)
			(unlocked yes)
			(layer "F.Fab")
			(hide yes)
			(effects
				(font
					(size 1.016 1.016)
					(thickness 0.1524)
				)
			)
		)
		(duplicate_pad_numbers_are_jumpers no)
		(fp_line
			(start 0.254 0)
			(end -0.254 0)
			(stroke
				(width 0.2032)
				(type default)
			)
			(layer "F.SilkS")
		)
		(fp_rect
			(start -0.5842 1.3335)
			(end 0.5842 -1.3335)
			(stroke
				(width 0)
				(type default)
			)
			(fill no)
			(layer "F.CrtYd")
		)
		(fp_rect
			(start -0.5842 1.3335)
			(end 0.5842 -1.3335)
			(stroke
				(width 0)
				(type default)
			)
			(fill no)
			(layer "F.Fab")
		)
		(pad "1" smd custom
			(at 0 -0.762 90)
			(size 0.2159 0.2159)
			(layers "F.Cu" "F.Mask" "F.Paste")
			(net "NIC0_MDI0_N2_R")
			(options
				(clearance outline)
				(anchor circle)
			)
			(primitives
				(gr_poly
					(pts
						(arc
							(start -0.3302 -0.4318)
							(mid -0.402042 -0.402042)
							(end -0.4318 -0.3302)
						)
						(arc
							(start -0.4318 0.3302)
							(mid -0.402042 0.402042)
							(end -0.3302 0.4318)
						)
						(arc
							(start 0.3302 0.4318)
							(mid 0.402042 0.402042)
							(end 0.4318 0.3302)
						)
						(arc
							(start 0.4318 -0.3302)
							(mid 0.402042 -0.402042)
							(end 0.3302 -0.4318)
						)
					)
					(width 0)
					(fill yes)
				)
			)
		)
		(pad "2" smd custom
			(at 0 0.762 90)
			(size 0.2159 0.2159)
			(layers "F.Cu" "F.Mask" "F.Paste")
			(net "GND")
			(options
				(clearance outline)
				(anchor circle)
			)
			(primitives
				(gr_poly
					(pts
						(arc
							(start -0.3302 -0.4318)
							(mid -0.402042 -0.402042)
							(end -0.4318 -0.3302)
						)
						(arc
							(start -0.4318 0.3302)
							(mid -0.402042 0.402042)
							(end -0.3302 0.4318)
						)
						(arc
							(start 0.3302 0.4318)
							(mid 0.402042 0.402042)
							(end 0.4318 0.3302)
						)
						(arc
							(start 0.4318 -0.3302)
							(mid 0.402042 -0.402042)
							(end 0.3302 -0.4318)
						)
					)
					(width 0)
					(fill yes)
				)
			)
		)
	)
	(footprint ""
		(layer "F.Cu")
		(at 333.788512 -172.432218)
		(property "Reference" "R7936"
			(at 0 0 0)
			(layer "F.SilkS")
			(hide yes)
			(effects
				(font
					(size 1.27 1.27)
				)
			)
		)
		(property "Value" "0R2J-2-GP"
			(at 0.064008 -3.993896 0)
			(unlocked yes)
			(layer "F.Fab")
			(hide yes)
			(effects
				(font
					(size 1.016 1.016)
					(thickness 0.1524)
				)
			)
		)
		(property "Device Type" "R402H16"
			(at 0.064008 -5.517896 0)
			(unlocked yes)
			(layer "F.Fab")
			(hide yes)
			(effects
				(font
					(size 1.016 1.016)
					(thickness 0.1524)
				)
			)
		)
		(duplicate_pad_numbers_are_jumpers no)
		(fp_line
			(start -0.508 -0.9398)
			(end -0.508 0.9398)
			(stroke
				(width 0.1524)
				(type default)
			)
			(layer "F.SilkS")
		)
		(fp_line
			(start 0.508 -0.9398)
			(end -0.508 -0.9398)
			(stroke
				(width 0.1524)
				(type default)
			)
			(layer "F.SilkS")
		)
		(fp_rect
			(start -0.508 0.9398)
			(end 0.508 -0.9398)
			(stroke
				(width 0)
				(type default)
			)
			(fill no)
			(layer "F.CrtYd")
		)
		(fp_rect
			(start -0.508 0.9398)
			(end 0.508 -0.9398)
			(stroke
				(width 0)
				(type default)
			)
			(fill no)
			(layer "F.Fab")
		)
		(pad "1" smd custom
			(at 0 -0.4445)
			(size 0.1397 0.1397)
			(layers "F.Cu" "F.Mask" "F.Paste")
			(net "SSD_ATNLED#4")
			(options
				(clearance outline)
				(anchor circle)
			)
			(primitives
				(gr_poly
					(pts
						(arc
							(start -0.1778 -0.2794)
							(mid -0.249642 -0.249642)
							(end -0.2794 -0.1778)
						)
						(arc
							(start -0.2794 0.1778)
							(mid -0.249642 0.249642)
							(end -0.1778 0.2794)
						)
						(arc
							(start 0.1778 0.2794)
							(mid 0.249642 0.249642)
							(end 0.2794 0.1778)
						)
						(arc
							(start 0.2794 -0.1778)
							(mid 0.249642 -0.249642)
							(end 0.1778 -0.2794)
						)
					)
					(width 0)
					(fill yes)
				)
			)
		)
		(pad "2" smd custom
			(at 0 0.4445)
			(size 0.1397 0.1397)
			(layers "F.Cu" "F.Mask" "F.Paste")
			(net "SSD_ATNLED#4_R")
			(options
				(clearance outline)
				(anchor circle)
			)
			(primitives
				(gr_poly
					(pts
						(arc
							(start -0.1778 -0.2794)
							(mid -0.249642 -0.249642)
							(end -0.2794 -0.1778)
						)
						(arc
							(start -0.2794 0.1778)
							(mid -0.249642 0.249642)
							(end -0.1778 0.2794)
						)
						(arc
							(start 0.1778 0.2794)
							(mid 0.249642 0.249642)
							(end 0.2794 0.1778)
						)
						(arc
							(start 0.2794 -0.1778)
							(mid 0.249642 -0.249642)
							(end 0.1778 -0.2794)
						)
					)
					(width 0)
					(fill yes)
				)
			)
		)
	)
	(footprint ""
		(layer "F.Cu")
		(at 149.352 -33.528)
		(property "Reference" "C393"
			(at 0 0 0)
			(layer "F.SilkS")
			(hide yes)
			(effects
				(font
					(size 1.27 1.27)
				)
			)
		)
		(property "Value" "SCD22U10V2KX-1GP"
			(at 1.1811 -2.7051 0)
			(unlocked yes)
			(layer "F.Fab")
			(hide yes)
			(effects
				(font
					(size 1.016 1.016)
					(thickness 0.1524)
				)
			)
		)
		(property "Device Type" "C402H22"
			(at 1.1811 -4.2291 0)
			(unlocked yes)
			(layer "F.Fab")
			(hide yes)
			(effects
				(font
					(size 1.016 1.016)
					(thickness 0.1524)
				)
			)
		)
		(duplicate_pad_numbers_are_jumpers no)
		(fp_rect
			(start -0.4318 0.9525)
			(end 0.4318 -0.9525)
			(stroke
				(width 0)
				(type default)
			)
			(fill no)
			(layer "F.CrtYd")
		)
		(fp_rect
			(start -0.4318 0.9525)
			(end 0.4318 -0.9525)
			(stroke
				(width 0)
				(type default)
			)
			(fill no)
			(layer "F.Fab")
		)
		(pad "1" smd custom
			(at 0 -0.4445)
			(size 0.1524 0.1524)
			(layers "F.Cu" "F.Mask" "F.Paste")
			(net "PCIE_TX_CAP_N86")
			(options
				(clearance outline)
				(anchor circle)
			)
			(primitives
				(gr_poly
					(pts
						(arc
							(start 0.3048 -0.2032)
							(mid 0.275042 -0.275042)
							(end 0.2032 -0.3048)
						)
						(arc
							(start -0.2032 -0.3048)
							(mid -0.275042 -0.275042)
							(end -0.3048 -0.2032)
						)
						(arc
							(start -0.3048 0.2032)
							(mid -0.275042 0.275042)
							(end -0.2032 0.3048)
						)
						(arc
							(start 0.2032 0.3048)
							(mid 0.275042 0.275042)
							(end 0.3048 0.2032)
						)
					)
					(width 0)
					(fill yes)
				)
			)
		)
		(pad "2" smd custom
			(at 0 0.4445)
			(size 0.1524 0.1524)
			(layers "F.Cu" "F.Mask" "F.Paste")
			(net "PCIE_TX_N86")
			(options
				(clearance outline)
				(anchor circle)
			)
			(primitives
				(gr_poly
					(pts
						(arc
							(start 0.3048 -0.2032)
							(mid 0.275042 -0.275042)
							(end 0.2032 -0.3048)
						)
						(arc
							(start -0.2032 -0.3048)
							(mid -0.275042 -0.275042)
							(end -0.3048 -0.2032)
						)
						(arc
							(start -0.3048 0.2032)
							(mid -0.275042 0.275042)
							(end -0.2032 0.3048)
						)
						(arc
							(start 0.2032 0.3048)
							(mid 0.275042 0.275042)
							(end 0.3048 0.2032)
						)
					)
					(width 0)
					(fill yes)
				)
			)
		)
	)
	(footprint ""
		(layer "F.Cu")
		(at 53.721 -128.524 90)
		(property "Reference" "R452"
			(at 0 0 90)
			(layer "F.SilkS")
			(hide yes)
			(effects
				(font
					(size 1.27 1.27)
				)
			)
		)
		(property "Value" "0R2J-2-GP"
			(at 0.064008 -3.993896 90)
			(unlocked yes)
			(layer "F.Fab")
			(hide yes)
			(effects
				(font
					(size 1.016 1.016)
					(thickness 0.1524)
				)
			)
		)
		(property "Device Type" "R402H16"
			(at 0.064008 -5.517896 90)
			(unlocked yes)
			(layer "F.Fab")
			(hide yes)
			(effects
				(font
					(size 1.016 1.016)
					(thickness 0.1524)
				)
			)
		)
		(duplicate_pad_numbers_are_jumpers no)
		(fp_line
			(start 0.508 -0.9398)
			(end -0.508 -0.9398)
			(stroke
				(width 0.1524)
				(type default)
			)
			(layer "F.SilkS")
		)
		(fp_line
			(start -0.508 -0.9398)
			(end -0.508 0.9398)
			(stroke
				(width 0.1524)
				(type default)
			)
			(layer "F.SilkS")
		)
		(fp_rect
			(start -0.508 0.9398)
			(end 0.508 -0.9398)
			(stroke
				(width 0)
				(type default)
			)
			(fill no)
			(layer "F.CrtYd")
		)
		(fp_rect
			(start -0.508 0.9398)
			(end 0.508 -0.9398)
			(stroke
				(width 0)
				(type default)
			)
			(fill no)
			(layer "F.Fab")
		)
		(pad "1" smd custom
			(at 0 -0.4445 90)
			(size 0.1397 0.1397)
			(layers "F.Cu" "F.Mask" "F.Paste")
			(net "BMC_USB1_HDN")
			(options
				(clearance outline)
				(anchor circle)
			)
			(primitives
				(gr_poly
					(pts
						(arc
							(start -0.1778 -0.2794)
							(mid -0.249642 -0.249642)
							(end -0.2794 -0.1778)
						)
						(arc
							(start -0.2794 0.1778)
							(mid -0.249642 0.249642)
							(end -0.1778 0.2794)
						)
						(arc
							(start 0.1778 0.2794)
							(mid 0.249642 0.249642)
							(end 0.2794 0.1778)
						)
						(arc
							(start 0.2794 -0.1778)
							(mid 0.249642 -0.249642)
							(end 0.1778 -0.2794)
						)
					)
					(width 0)
					(fill yes)
				)
			)
		)
		(pad "2" smd custom
			(at 0 0.4445 90)
			(size 0.1397 0.1397)
			(layers "F.Cu" "F.Mask" "F.Paste")
			(net "USB_P2_DN")
			(options
				(clearance outline)
				(anchor circle)
			)
			(primitives
				(gr_poly
					(pts
						(arc
							(start -0.1778 -0.2794)
							(mid -0.249642 -0.249642)
							(end -0.2794 -0.1778)
						)
						(arc
							(start -0.2794 0.1778)
							(mid -0.249642 0.249642)
							(end -0.1778 0.2794)
						)
						(arc
							(start 0.1778 0.2794)
							(mid 0.249642 0.249642)
							(end 0.2794 0.1778)
						)
						(arc
							(start 0.2794 -0.1778)
							(mid 0.249642 -0.249642)
							(end 0.1778 -0.2794)
						)
					)
					(width 0)
					(fill yes)
				)
			)
		)
	)
	(footprint ""
		(layer "F.Cu")
		(at 333.19974 -36.90874 90)
		(property "Reference" "R625"
			(at 0 0 90)
			(layer "F.SilkS")
			(hide yes)
			(effects
				(font
					(size 1.27 1.27)
				)
			)
		)
		(property "Value" "0R2J-2-GP"
			(at 0.064008 -3.993896 90)
			(unlocked yes)
			(layer "F.Fab")
			(hide yes)
			(effects
				(font
					(size 1.016 1.016)
					(thickness 0.1524)
				)
			)
		)
		(property "Device Type" "R402H16"
			(at 0.064008 -5.517896 90)
			(unlocked yes)
			(layer "F.Fab")
			(hide yes)
			(effects
				(font
					(size 1.016 1.016)
					(thickness 0.1524)
				)
			)
		)
		(duplicate_pad_numbers_are_jumpers no)
		(fp_line
			(start 0.508 -0.9398)
			(end -0.508 -0.9398)
			(stroke
				(width 0.1524)
				(type default)
			)
			(layer "F.SilkS")
		)
		(fp_line
			(start -0.508 -0.9398)
			(end -0.508 0.9398)
			(stroke
				(width 0.1524)
				(type default)
			)
			(layer "F.SilkS")
		)
		(fp_rect
			(start -0.508 0.9398)
			(end 0.508 -0.9398)
			(stroke
				(width 0)
				(type default)
			)
			(fill no)
			(layer "F.CrtYd")
		)
		(fp_rect
			(start -0.508 0.9398)
			(end 0.508 -0.9398)
			(stroke
				(width 0)
				(type default)
			)
			(fill no)
			(layer "F.Fab")
		)
		(pad "1" smd custom
			(at 0 -0.4445 90)
			(size 0.1397 0.1397)
			(layers "F.Cu" "F.Mask" "F.Paste")
			(net "UPLINK6_R")
			(options
				(clearance outline)
				(anchor circle)
			)
			(primitives
				(gr_poly
					(pts
						(arc
							(start -0.1778 -0.2794)
							(mid -0.249642 -0.249642)
							(end -0.2794 -0.1778)
						)
						(arc
							(start -0.2794 0.1778)
							(mid -0.249642 0.249642)
							(end -0.1778 0.2794)
						)
						(arc
							(start 0.1778 0.2794)
							(mid 0.249642 0.249642)
							(end 0.2794 0.1778)
						)
						(arc
							(start 0.2794 -0.1778)
							(mid 0.249642 -0.249642)
							(end 0.1778 -0.2794)
						)
					)
					(width 0)
					(fill yes)
				)
			)
		)
		(pad "2" smd custom
			(at 0 0.4445 90)
			(size 0.1397 0.1397)
			(layers "F.Cu" "F.Mask" "F.Paste")
			(net "UPLINK6")
			(options
				(clearance outline)
				(anchor circle)
			)
			(primitives
				(gr_poly
					(pts
						(arc
							(start -0.1778 -0.2794)
							(mid -0.249642 -0.249642)
							(end -0.2794 -0.1778)
						)
						(arc
							(start -0.2794 0.1778)
							(mid -0.249642 0.249642)
							(end -0.1778 0.2794)
						)
						(arc
							(start 0.1778 0.2794)
							(mid 0.249642 0.249642)
							(end 0.2794 0.1778)
						)
						(arc
							(start 0.2794 -0.1778)
							(mid 0.249642 -0.249642)
							(end 0.1778 -0.2794)
						)
					)
					(width 0)
					(fill yes)
				)
			)
		)
	)
	(footprint ""
		(layer "F.Cu")
		(at 340.9442 -172.339)
		(property "Reference" "R9038"
			(at 0 0 0)
			(layer "F.SilkS")
			(hide yes)
			(effects
				(font
					(size 1.27 1.27)
				)
			)
		)
		(property "Value" "4K7R2F-GP"
			(at 0.064008 -3.993896 0)
			(unlocked yes)
			(layer "F.Fab")
			(hide yes)
			(effects
				(font
					(size 1.016 1.016)
					(thickness 0.1524)
				)
			)
		)
		(property "Device Type" "R402H16"
			(at 0.064008 -5.517896 0)
			(unlocked yes)
			(layer "F.Fab")
			(hide yes)
			(effects
				(font
					(size 1.016 1.016)
					(thickness 0.1524)
				)
			)
		)
		(duplicate_pad_numbers_are_jumpers no)
		(fp_line
			(start -0.508 -0.9398)
			(end -0.508 0.9398)
			(stroke
				(width 0.1524)
				(type default)
			)
			(layer "F.SilkS")
		)
		(fp_line
			(start 0.508 -0.9398)
			(end -0.508 -0.9398)
			(stroke
				(width 0.1524)
				(type default)
			)
			(layer "F.SilkS")
		)
		(fp_rect
			(start -0.508 0.9398)
			(end 0.508 -0.9398)
			(stroke
				(width 0)
				(type default)
			)
			(fill no)
			(layer "F.CrtYd")
		)
		(fp_rect
			(start -0.508 0.9398)
			(end 0.508 -0.9398)
			(stroke
				(width 0)
				(type default)
			)
			(fill no)
			(layer "F.Fab")
		)
		(pad "1" smd custom
			(at 0 -0.4445)
			(size 0.1397 0.1397)
			(layers "F.Cu" "F.Mask" "F.Paste")
			(net "SSD_PERST#9")
			(options
				(clearance outline)
				(anchor circle)
			)
			(primitives
				(gr_poly
					(pts
						(arc
							(start -0.1778 -0.2794)
							(mid -0.249642 -0.249642)
							(end -0.2794 -0.1778)
						)
						(arc
							(start -0.2794 0.1778)
							(mid -0.249642 0.249642)
							(end -0.1778 0.2794)
						)
						(arc
							(start 0.1778 0.2794)
							(mid 0.249642 0.249642)
							(end 0.2794 0.1778)
						)
						(arc
							(start 0.2794 -0.1778)
							(mid 0.249642 -0.249642)
							(end 0.1778 -0.2794)
						)
					)
					(width 0)
					(fill yes)
				)
			)
		)
		(pad "2" smd custom
			(at 0 0.4445)
			(size 0.1397 0.1397)
			(layers "F.Cu" "F.Mask" "F.Paste")
			(net "GND")
			(options
				(clearance outline)
				(anchor circle)
			)
			(primitives
				(gr_poly
					(pts
						(arc
							(start -0.1778 -0.2794)
							(mid -0.249642 -0.249642)
							(end -0.2794 -0.1778)
						)
						(arc
							(start -0.2794 0.1778)
							(mid -0.249642 0.249642)
							(end -0.1778 0.2794)
						)
						(arc
							(start 0.1778 0.2794)
							(mid 0.249642 0.249642)
							(end 0.2794 0.1778)
						)
						(arc
							(start 0.2794 -0.1778)
							(mid 0.249642 -0.249642)
							(end 0.1778 -0.2794)
						)
					)
					(width 0)
					(fill yes)
				)
			)
		)
	)
	(footprint ""
		(layer "F.Cu")
		(at 59.81827 -37.175948)
		(property "Reference" "PR32"
			(at 0 0 0)
			(layer "F.SilkS")
			(hide yes)
			(effects
				(font
					(size 1.27 1.27)
				)
			)
		)
		(property "Value" "866KR2F-GP"
			(at 0.064008 -3.993896 0)
			(unlocked yes)
			(layer "F.Fab")
			(hide yes)
			(effects
				(font
					(size 1.016 1.016)
					(thickness 0.1524)
				)
			)
		)
		(property "Device Type" "R402H16"
			(at 0.064008 -5.517896 0)
			(unlocked yes)
			(layer "F.Fab")
			(hide yes)
			(effects
				(font
					(size 1.016 1.016)
					(thickness 0.1524)
				)
			)
		)
		(duplicate_pad_numbers_are_jumpers no)
		(fp_line
			(start -0.508 -0.9398)
			(end -0.508 0.9398)
			(stroke
				(width 0.1524)
				(type default)
			)
			(layer "F.SilkS")
		)
		(fp_line
			(start 0.508 -0.9398)
			(end -0.508 -0.9398)
			(stroke
				(width 0.1524)
				(type default)
			)
			(layer "F.SilkS")
		)
		(fp_rect
			(start -0.508 0.9398)
			(end 0.508 -0.9398)
			(stroke
				(width 0)
				(type default)
			)
			(fill no)
			(layer "F.CrtYd")
		)
		(fp_rect
			(start -0.508 0.9398)
			(end 0.508 -0.9398)
			(stroke
				(width 0)
				(type default)
			)
			(fill no)
			(layer "F.Fab")
		)
		(pad "1" smd custom
			(at 0 -0.4445)
			(size 0.1397 0.1397)
			(layers "F.Cu" "F.Mask" "F.Paste")
			(net "P3V3_STBY_VREG")
			(options
				(clearance outline)
				(anchor circle)
			)
			(primitives
				(gr_poly
					(pts
						(arc
							(start -0.1778 -0.2794)
							(mid -0.249642 -0.249642)
							(end -0.2794 -0.1778)
						)
						(arc
							(start -0.2794 0.1778)
							(mid -0.249642 0.249642)
							(end -0.1778 0.2794)
						)
						(arc
							(start 0.1778 0.2794)
							(mid 0.249642 0.249642)
							(end 0.2794 0.1778)
						)
						(arc
							(start 0.2794 -0.1778)
							(mid 0.249642 -0.249642)
							(end 0.1778 -0.2794)
						)
					)
					(width 0)
					(fill yes)
				)
			)
		)
		(pad "2" smd custom
			(at 0 0.4445)
			(size 0.1397 0.1397)
			(layers "F.Cu" "F.Mask" "F.Paste")
			(net "P3V3_STBY_RF")
			(options
				(clearance outline)
				(anchor circle)
			)
			(primitives
				(gr_poly
					(pts
						(arc
							(start -0.1778 -0.2794)
							(mid -0.249642 -0.249642)
							(end -0.2794 -0.1778)
						)
						(arc
							(start -0.2794 0.1778)
							(mid -0.249642 0.249642)
							(end -0.1778 0.2794)
						)
						(arc
							(start 0.1778 0.2794)
							(mid 0.249642 0.249642)
							(end 0.2794 0.1778)
						)
						(arc
							(start 0.2794 -0.1778)
							(mid 0.249642 -0.249642)
							(end 0.1778 -0.2794)
						)
					)
					(width 0)
					(fill yes)
				)
			)
		)
	)
	(footprint ""
		(layer "F.Cu")
		(at 37.1348 -116.713 180)
		(property "Reference" "R281"
			(at 0 0 180)
			(layer "F.SilkS")
			(hide yes)
			(effects
				(font
					(size 1.27 1.27)
				)
			)
		)
		(property "Value" "0R2J-2-GP"
			(at 0.064008 -3.993896 180)
			(unlocked yes)
			(layer "F.Fab")
			(hide yes)
			(effects
				(font
					(size 1.016 1.016)
					(thickness 0.1524)
				)
			)
		)
		(property "Device Type" "R402H16"
			(at 0.064008 -5.517896 180)
			(unlocked yes)
			(layer "F.Fab")
			(hide yes)
			(effects
				(font
					(size 1.016 1.016)
					(thickness 0.1524)
				)
			)
		)
		(duplicate_pad_numbers_are_jumpers no)
		(fp_line
			(start 0.508 -0.9398)
			(end -0.508 -0.9398)
			(stroke
				(width 0.1524)
				(type default)
			)
			(layer "F.SilkS")
		)
		(fp_line
			(start -0.508 -0.9398)
			(end -0.508 0.9398)
			(stroke
				(width 0.1524)
				(type default)
			)
			(layer "F.SilkS")
		)
		(fp_rect
			(start -0.508 0.9398)
			(end 0.508 -0.9398)
			(stroke
				(width 0)
				(type default)
			)
			(fill no)
			(layer "F.CrtYd")
		)
		(fp_rect
			(start -0.508 0.9398)
			(end 0.508 -0.9398)
			(stroke
				(width 0)
				(type default)
			)
			(fill no)
			(layer "F.Fab")
		)
		(pad "1" smd custom
			(at 0 -0.4445 180)
			(size 0.1397 0.1397)
			(layers "F.Cu" "F.Mask" "F.Paste")
			(net "RMII_BMC_TX_EN")
			(options
				(clearance outline)
				(anchor circle)
			)
			(primitives
				(gr_poly
					(pts
						(arc
							(start -0.1778 -0.2794)
							(mid -0.249642 -0.249642)
							(end -0.2794 -0.1778)
						)
						(arc
							(start -0.2794 0.1778)
							(mid -0.249642 0.249642)
							(end -0.1778 0.2794)
						)
						(arc
							(start 0.1778 0.2794)
							(mid 0.249642 0.249642)
							(end 0.2794 0.1778)
						)
						(arc
							(start 0.2794 -0.1778)
							(mid 0.249642 -0.249642)
							(end 0.1778 -0.2794)
						)
					)
					(width 0)
					(fill yes)
				)
			)
		)
		(pad "2" smd custom
			(at 0 0.4445 180)
			(size 0.1397 0.1397)
			(layers "F.Cu" "F.Mask" "F.Paste")
			(net "RMII0_BMC_C_TX_EN")
			(options
				(clearance outline)
				(anchor circle)
			)
			(primitives
				(gr_poly
					(pts
						(arc
							(start -0.1778 -0.2794)
							(mid -0.249642 -0.249642)
							(end -0.2794 -0.1778)
						)
						(arc
							(start -0.2794 0.1778)
							(mid -0.249642 0.249642)
							(end -0.1778 0.2794)
						)
						(arc
							(start 0.1778 0.2794)
							(mid 0.249642 0.249642)
							(end 0.2794 0.1778)
						)
						(arc
							(start 0.2794 -0.1778)
							(mid 0.249642 -0.249642)
							(end 0.1778 -0.2794)
						)
					)
					(width 0)
					(fill yes)
				)
			)
		)
	)
	(footprint ""
		(layer "F.Cu")
		(at 137.586974 -74.365104)
		(property "Reference" "R615"
			(at 0 0 0)
			(layer "F.SilkS")
			(hide yes)
			(effects
				(font
					(size 1.27 1.27)
				)
			)
		)
		(property "Value" "100KR2F-L1-GP"
			(at 0.064008 -3.993896 0)
			(unlocked yes)
			(layer "F.Fab")
			(hide yes)
			(effects
				(font
					(size 1.016 1.016)
					(thickness 0.1524)
				)
			)
		)
		(property "Device Type" "R402H16"
			(at 0.064008 -5.517896 0)
			(unlocked yes)
			(layer "F.Fab")
			(hide yes)
			(effects
				(font
					(size 1.016 1.016)
					(thickness 0.1524)
				)
			)
		)
		(duplicate_pad_numbers_are_jumpers no)
		(fp_line
			(start -0.508 -0.9398)
			(end -0.508 0.9398)
			(stroke
				(width 0.1524)
				(type default)
			)
			(layer "F.SilkS")
		)
		(fp_line
			(start 0.508 -0.9398)
			(end -0.508 -0.9398)
			(stroke
				(width 0.1524)
				(type default)
			)
			(layer "F.SilkS")
		)
		(fp_rect
			(start -0.508 0.9398)
			(end 0.508 -0.9398)
			(stroke
				(width 0)
				(type default)
			)
			(fill no)
			(layer "F.CrtYd")
		)
		(fp_rect
			(start -0.508 0.9398)
			(end 0.508 -0.9398)
			(stroke
				(width 0)
				(type default)
			)
			(fill no)
			(layer "F.Fab")
		)
		(pad "1" smd custom
			(at 0 -0.4445)
			(size 0.1397 0.1397)
			(layers "F.Cu" "F.Mask" "F.Paste")
			(net "DUT_VDDO")
			(options
				(clearance outline)
				(anchor circle)
			)
			(primitives
				(gr_poly
					(pts
						(arc
							(start -0.1778 -0.2794)
							(mid -0.249642 -0.249642)
							(end -0.2794 -0.1778)
						)
						(arc
							(start -0.2794 0.1778)
							(mid -0.249642 0.249642)
							(end -0.1778 0.2794)
						)
						(arc
							(start 0.1778 0.2794)
							(mid 0.249642 0.249642)
							(end 0.2794 0.1778)
						)
						(arc
							(start 0.2794 -0.1778)
							(mid 0.249642 -0.249642)
							(end 0.1778 -0.2794)
						)
					)
					(width 0)
					(fill yes)
				)
			)
		)
		(pad "2" smd custom
			(at 0 0.4445)
			(size 0.1397 0.1397)
			(layers "F.Cu" "F.Mask" "F.Paste")
			(net "SPI_DATA0_0_R")
			(options
				(clearance outline)
				(anchor circle)
			)
			(primitives
				(gr_poly
					(pts
						(arc
							(start -0.1778 -0.2794)
							(mid -0.249642 -0.249642)
							(end -0.2794 -0.1778)
						)
						(arc
							(start -0.2794 0.1778)
							(mid -0.249642 0.249642)
							(end -0.1778 0.2794)
						)
						(arc
							(start 0.1778 0.2794)
							(mid 0.249642 0.249642)
							(end 0.2794 0.1778)
						)
						(arc
							(start 0.2794 -0.1778)
							(mid 0.249642 -0.249642)
							(end 0.1778 -0.2794)
						)
					)
					(width 0)
					(fill yes)
				)
			)
		)
	)
	(footprint ""
		(layer "F.Cu")
		(at 30.65272 -118.36908)
		(property "Reference" "TP305"
			(at 0 0 0)
			(layer "F.SilkS")
			(hide yes)
			(effects
				(font
					(size 1.27 1.27)
				)
			)
		)
		(property "Value" "TPAD28-2-GP"
			(at -0.0127 -1.6637 0)
			(unlocked yes)
			(layer "F.Fab")
			(hide yes)
			(effects
				(font
					(size 1.016 1.016)
					(thickness 0.1524)
				)
			)
		)
		(property "Device Type" "TPAD28"
			(at -0.0127 -3.1877 0)
			(unlocked yes)
			(layer "F.Fab")
			(hide yes)
			(effects
				(font
					(size 1.016 1.016)
					(thickness 0.1524)
				)
			)
		)
		(duplicate_pad_numbers_are_jumpers no)
		(fp_poly
			(pts
				(arc
					(start 0.3556 0)
					(mid -0.3556 0)
					(end 0.3556 0)
				)
			)
			(stroke
				(width 0)
				(type default)
			)
			(fill no)
			(layer "F.CrtYd")
		)
		(fp_poly
			(pts
				(arc
					(start 0.6096 0)
					(mid -0.6096 0)
					(end 0.6096 0)
				)
			)
			(stroke
				(width 0)
				(type default)
			)
			(fill no)
			(layer "F.Fab")
		)
		(pad "1" smd circle
			(at 0 0)
			(size 0.7112 0.7112)
			(layers "F.Cu" "F.Mask" "F.Paste")
			(net "TP_GPIOD0")
		)
	)
	(footprint ""
		(layer "F.Cu")
		(at 12.446 -120.65)
		(property "Reference" "R16"
			(at 0 0 0)
			(layer "F.SilkS")
			(hide yes)
			(effects
				(font
					(size 1.27 1.27)
				)
			)
		)
		(property "Value" "0R2J-2-GP"
			(at 0.064008 -3.993896 0)
			(unlocked yes)
			(layer "F.Fab")
			(hide yes)
			(effects
				(font
					(size 1.016 1.016)
					(thickness 0.1524)
				)
			)
		)
		(property "Device Type" "R402H16"
			(at 0.064008 -5.517896 0)
			(unlocked yes)
			(layer "F.Fab")
			(hide yes)
			(effects
				(font
					(size 1.016 1.016)
					(thickness 0.1524)
				)
			)
		)
		(duplicate_pad_numbers_are_jumpers no)
		(fp_line
			(start -0.508 -0.9398)
			(end -0.508 0.9398)
			(stroke
				(width 0.1524)
				(type default)
			)
			(layer "F.SilkS")
		)
		(fp_line
			(start 0.508 -0.9398)
			(end -0.508 -0.9398)
			(stroke
				(width 0.1524)
				(type default)
			)
			(layer "F.SilkS")
		)
		(fp_rect
			(start -0.508 0.9398)
			(end 0.508 -0.9398)
			(stroke
				(width 0)
				(type default)
			)
			(fill no)
			(layer "F.CrtYd")
		)
		(fp_rect
			(start -0.508 0.9398)
			(end 0.508 -0.9398)
			(stroke
				(width 0)
				(type default)
			)
			(fill no)
			(layer "F.Fab")
		)
		(pad "1" smd custom
			(at 0 -0.4445)
			(size 0.1397 0.1397)
			(layers "F.Cu" "F.Mask" "F.Paste")
			(net "BMC_I2C1_MINI1_SCL_S")
			(options
				(clearance outline)
				(anchor circle)
			)
			(primitives
				(gr_poly
					(pts
						(arc
							(start -0.1778 -0.2794)
							(mid -0.249642 -0.249642)
							(end -0.2794 -0.1778)
						)
						(arc
							(start -0.2794 0.1778)
							(mid -0.249642 0.249642)
							(end -0.1778 0.2794)
						)
						(arc
							(start 0.1778 0.2794)
							(mid 0.249642 0.249642)
							(end 0.2794 0.1778)
						)
						(arc
							(start 0.2794 -0.1778)
							(mid 0.249642 -0.249642)
							(end 0.1778 -0.2794)
						)
					)
					(width 0)
					(fill yes)
				)
			)
		)
		(pad "2" smd custom
			(at 0 0.4445)
			(size 0.1397 0.1397)
			(layers "F.Cu" "F.Mask" "F.Paste")
			(net "BMC_I2C1_MINI1_SCL")
			(options
				(clearance outline)
				(anchor circle)
			)
			(primitives
				(gr_poly
					(pts
						(arc
							(start -0.1778 -0.2794)
							(mid -0.249642 -0.249642)
							(end -0.2794 -0.1778)
						)
						(arc
							(start -0.2794 0.1778)
							(mid -0.249642 0.249642)
							(end -0.1778 0.2794)
						)
						(arc
							(start 0.1778 0.2794)
							(mid 0.249642 0.249642)
							(end 0.2794 0.1778)
						)
						(arc
							(start 0.2794 -0.1778)
							(mid 0.249642 -0.249642)
							(end 0.1778 -0.2794)
						)
					)
					(width 0)
					(fill yes)
				)
			)
		)
	)
	(footprint ""
		(layer "F.Cu")
		(at 20.828 -154.051 90)
		(property "Reference" "R8007"
			(at 0 0 90)
			(layer "F.SilkS")
			(hide yes)
			(effects
				(font
					(size 1.27 1.27)
				)
			)
		)
		(property "Value" "0R2J-2-GP"
			(at 0.064008 -3.993896 90)
			(unlocked yes)
			(layer "F.Fab")
			(hide yes)
			(effects
				(font
					(size 1.016 1.016)
					(thickness 0.1524)
				)
			)
		)
		(property "Device Type" "R402H16"
			(at 0.064008 -5.517896 90)
			(unlocked yes)
			(layer "F.Fab")
			(hide yes)
			(effects
				(font
					(size 1.016 1.016)
					(thickness 0.1524)
				)
			)
		)
		(duplicate_pad_numbers_are_jumpers no)
		(fp_line
			(start 0.508 -0.9398)
			(end -0.508 -0.9398)
			(stroke
				(width 0.1524)
				(type default)
			)
			(layer "F.SilkS")
		)
		(fp_line
			(start -0.508 -0.9398)
			(end -0.508 0.9398)
			(stroke
				(width 0.1524)
				(type default)
			)
			(layer "F.SilkS")
		)
		(fp_rect
			(start -0.508 0.9398)
			(end 0.508 -0.9398)
			(stroke
				(width 0)
				(type default)
			)
			(fill no)
			(layer "F.CrtYd")
		)
		(fp_rect
			(start -0.508 0.9398)
			(end 0.508 -0.9398)
			(stroke
				(width 0)
				(type default)
			)
			(fill no)
			(layer "F.Fab")
		)
		(pad "1" smd custom
			(at 0 -0.4445 90)
			(size 0.1397 0.1397)
			(layers "F.Cu" "F.Mask" "F.Paste")
			(net "FM_BMC_RESET_Q36")
			(options
				(clearance outline)
				(anchor circle)
			)
			(primitives
				(gr_poly
					(pts
						(arc
							(start -0.1778 -0.2794)
							(mid -0.249642 -0.249642)
							(end -0.2794 -0.1778)
						)
						(arc
							(start -0.2794 0.1778)
							(mid -0.249642 0.249642)
							(end -0.1778 0.2794)
						)
						(arc
							(start 0.1778 0.2794)
							(mid 0.249642 0.249642)
							(end 0.2794 0.1778)
						)
						(arc
							(start 0.2794 -0.1778)
							(mid 0.249642 -0.249642)
							(end 0.1778 -0.2794)
						)
					)
					(width 0)
					(fill yes)
				)
			)
		)
		(pad "2" smd custom
			(at 0 0.4445 90)
			(size 0.1397 0.1397)
			(layers "F.Cu" "F.Mask" "F.Paste")
			(net "FM_BMC_RESET_Q36_R")
			(options
				(clearance outline)
				(anchor circle)
			)
			(primitives
				(gr_poly
					(pts
						(arc
							(start -0.1778 -0.2794)
							(mid -0.249642 -0.249642)
							(end -0.2794 -0.1778)
						)
						(arc
							(start -0.2794 0.1778)
							(mid -0.249642 0.249642)
							(end -0.1778 0.2794)
						)
						(arc
							(start 0.1778 0.2794)
							(mid 0.249642 0.249642)
							(end 0.2794 0.1778)
						)
						(arc
							(start 0.2794 -0.1778)
							(mid 0.249642 -0.249642)
							(end 0.1778 -0.2794)
						)
					)
					(width 0)
					(fill yes)
				)
			)
		)
	)
	(footprint ""
		(layer "F.Cu")
		(at 319.405 -99.568 180)
		(property "Reference" "C3702"
			(at 0 0 180)
			(layer "F.SilkS")
			(hide yes)
			(effects
				(font
					(size 1.27 1.27)
				)
			)
		)
		(property "Value" "SCD047U25V2KX-GP"
			(at 1.1811 -2.7051 180)
			(unlocked yes)
			(layer "F.Fab")
			(hide yes)
			(effects
				(font
					(size 1.016 1.016)
					(thickness 0.1524)
				)
			)
		)
		(property "Device Type" "C402H22"
			(at 1.1811 -4.2291 180)
			(unlocked yes)
			(layer "F.Fab")
			(hide yes)
			(effects
				(font
					(size 1.016 1.016)
					(thickness 0.1524)
				)
			)
		)
		(duplicate_pad_numbers_are_jumpers no)
		(fp_rect
			(start -0.4318 0.9525)
			(end 0.4318 -0.9525)
			(stroke
				(width 0)
				(type default)
			)
			(fill no)
			(layer "F.CrtYd")
		)
		(fp_rect
			(start -0.4318 0.9525)
			(end 0.4318 -0.9525)
			(stroke
				(width 0)
				(type default)
			)
			(fill no)
			(layer "F.Fab")
		)
		(pad "1" smd custom
			(at 0 -0.4445 180)
			(size 0.1524 0.1524)
			(layers "F.Cu" "F.Mask" "F.Paste")
			(net "P3V3_STBY")
			(options
				(clearance outline)
				(anchor circle)
			)
			(primitives
				(gr_poly
					(pts
						(arc
							(start 0.3048 -0.2032)
							(mid 0.275042 -0.275042)
							(end 0.2032 -0.3048)
						)
						(arc
							(start -0.2032 -0.3048)
							(mid -0.275042 -0.275042)
							(end -0.3048 -0.2032)
						)
						(arc
							(start -0.3048 0.2032)
							(mid -0.275042 0.275042)
							(end -0.2032 0.3048)
						)
						(arc
							(start 0.2032 0.3048)
							(mid 0.275042 0.275042)
							(end 0.3048 0.2032)
						)
					)
					(width 0)
					(fill yes)
				)
			)
		)
		(pad "2" smd custom
			(at 0 0.4445 180)
			(size 0.1524 0.1524)
			(layers "F.Cu" "F.Mask" "F.Paste")
			(net "GND")
			(options
				(clearance outline)
				(anchor circle)
			)
			(primitives
				(gr_poly
					(pts
						(arc
							(start 0.3048 -0.2032)
							(mid 0.275042 -0.275042)
							(end 0.2032 -0.3048)
						)
						(arc
							(start -0.2032 -0.3048)
							(mid -0.275042 -0.275042)
							(end -0.3048 -0.2032)
						)
						(arc
							(start -0.3048 0.2032)
							(mid -0.275042 0.275042)
							(end -0.2032 0.3048)
						)
						(arc
							(start 0.2032 0.3048)
							(mid 0.275042 0.275042)
							(end 0.3048 0.2032)
						)
					)
					(width 0)
					(fill yes)
				)
			)
		)
	)
	(footprint ""
		(layer "F.Cu")
		(at 28.939236 -112.0521 -90)
		(property "Reference" "R709"
			(at 0 0 270)
			(layer "F.SilkS")
			(hide yes)
			(effects
				(font
					(size 1.27 1.27)
				)
			)
		)
		(property "Value" "10KR2F-2-GP"
			(at 0.064008 -3.993896 270)
			(unlocked yes)
			(layer "F.Fab")
			(hide yes)
			(effects
				(font
					(size 1.016 1.016)
					(thickness 0.1524)
				)
			)
		)
		(property "Device Type" "R402H16"
			(at 0.064008 -5.517896 270)
			(unlocked yes)
			(layer "F.Fab")
			(hide yes)
			(effects
				(font
					(size 1.016 1.016)
					(thickness 0.1524)
				)
			)
		)
		(duplicate_pad_numbers_are_jumpers no)
		(fp_line
			(start -0.508 -0.9398)
			(end -0.508 0.9398)
			(stroke
				(width 0.1524)
				(type default)
			)
			(layer "F.SilkS")
		)
		(fp_line
			(start 0.508 -0.9398)
			(end -0.508 -0.9398)
			(stroke
				(width 0.1524)
				(type default)
			)
			(layer "F.SilkS")
		)
		(fp_rect
			(start -0.508 0.9398)
			(end 0.508 -0.9398)
			(stroke
				(width 0)
				(type default)
			)
			(fill no)
			(layer "F.CrtYd")
		)
		(fp_rect
			(start -0.508 0.9398)
			(end 0.508 -0.9398)
			(stroke
				(width 0)
				(type default)
			)
			(fill no)
			(layer "F.Fab")
		)
		(pad "1" smd custom
			(at 0 -0.4445 270)
			(size 0.1397 0.1397)
			(layers "F.Cu" "F.Mask" "F.Paste")
			(net "P3V3_STBY")
			(options
				(clearance outline)
				(anchor circle)
			)
			(primitives
				(gr_poly
					(pts
						(arc
							(start -0.1778 -0.2794)
							(mid -0.249642 -0.249642)
							(end -0.2794 -0.1778)
						)
						(arc
							(start -0.2794 0.1778)
							(mid -0.249642 0.249642)
							(end -0.1778 0.2794)
						)
						(arc
							(start 0.1778 0.2794)
							(mid 0.249642 0.249642)
							(end 0.2794 0.1778)
						)
						(arc
							(start 0.2794 -0.1778)
							(mid 0.249642 -0.249642)
							(end 0.1778 -0.2794)
						)
					)
					(width 0)
					(fill yes)
				)
			)
		)
		(pad "2" smd custom
			(at 0 0.4445 270)
			(size 0.1397 0.1397)
			(layers "F.Cu" "F.Mask" "F.Paste")
			(net "LAN_SMB_ALERT_N")
			(options
				(clearance outline)
				(anchor circle)
			)
			(primitives
				(gr_poly
					(pts
						(arc
							(start -0.1778 -0.2794)
							(mid -0.249642 -0.249642)
							(end -0.2794 -0.1778)
						)
						(arc
							(start -0.2794 0.1778)
							(mid -0.249642 0.249642)
							(end -0.1778 0.2794)
						)
						(arc
							(start 0.1778 0.2794)
							(mid 0.249642 0.249642)
							(end 0.2794 0.1778)
						)
						(arc
							(start 0.2794 -0.1778)
							(mid 0.249642 -0.249642)
							(end 0.1778 -0.2794)
						)
					)
					(width 0)
					(fill yes)
				)
			)
		)
	)
	(footprint ""
		(layer "F.Cu")
		(at 294.207946 -212.420454 180)
		(property "Reference" "C78"
			(at 0 0 180)
			(layer "F.SilkS")
			(hide yes)
			(effects
				(font
					(size 1.27 1.27)
				)
			)
		)
		(property "Value" "SCD22U10V2KX-1GP"
			(at 1.1811 -2.7051 180)
			(unlocked yes)
			(layer "F.Fab")
			(hide yes)
			(effects
				(font
					(size 1.016 1.016)
					(thickness 0.1524)
				)
			)
		)
		(property "Device Type" "C402H22"
			(at 1.1811 -4.2291 180)
			(unlocked yes)
			(layer "F.Fab")
			(hide yes)
			(effects
				(font
					(size 1.016 1.016)
					(thickness 0.1524)
				)
			)
		)
		(duplicate_pad_numbers_are_jumpers no)
		(fp_rect
			(start -0.4318 0.9525)
			(end 0.4318 -0.9525)
			(stroke
				(width 0)
				(type default)
			)
			(fill no)
			(layer "F.CrtYd")
		)
		(fp_rect
			(start -0.4318 0.9525)
			(end 0.4318 -0.9525)
			(stroke
				(width 0)
				(type default)
			)
			(fill no)
			(layer "F.Fab")
		)
		(pad "1" smd custom
			(at 0 -0.4445 180)
			(size 0.1524 0.1524)
			(layers "F.Cu" "F.Mask" "F.Paste")
			(net "PCIE_TX_CAP_N28")
			(options
				(clearance outline)
				(anchor circle)
			)
			(primitives
				(gr_poly
					(pts
						(arc
							(start 0.3048 -0.2032)
							(mid 0.275042 -0.275042)
							(end 0.2032 -0.3048)
						)
						(arc
							(start -0.2032 -0.3048)
							(mid -0.275042 -0.275042)
							(end -0.3048 -0.2032)
						)
						(arc
							(start -0.3048 0.2032)
							(mid -0.275042 0.275042)
							(end -0.2032 0.3048)
						)
						(arc
							(start 0.2032 0.3048)
							(mid 0.275042 0.275042)
							(end 0.3048 0.2032)
						)
					)
					(width 0)
					(fill yes)
				)
			)
		)
		(pad "2" smd custom
			(at 0 0.4445 180)
			(size 0.1524 0.1524)
			(layers "F.Cu" "F.Mask" "F.Paste")
			(net "PCIE_TX_N28")
			(options
				(clearance outline)
				(anchor circle)
			)
			(primitives
				(gr_poly
					(pts
						(arc
							(start 0.3048 -0.2032)
							(mid 0.275042 -0.275042)
							(end 0.2032 -0.3048)
						)
						(arc
							(start -0.2032 -0.3048)
							(mid -0.275042 -0.275042)
							(end -0.3048 -0.2032)
						)
						(arc
							(start -0.3048 0.2032)
							(mid -0.275042 0.275042)
							(end -0.2032 0.3048)
						)
						(arc
							(start 0.2032 0.3048)
							(mid 0.275042 0.275042)
							(end 0.3048 0.2032)
						)
					)
					(width 0)
					(fill yes)
				)
			)
		)
	)
	(footprint ""
		(layer "F.Cu")
		(at 144.0688 -41.402 180)
		(property "Reference" "R769"
			(at 0 0 180)
			(layer "F.SilkS")
			(hide yes)
			(effects
				(font
					(size 1.27 1.27)
				)
			)
		)
		(property "Value" "4K7R2F-GP"
			(at 0.064008 -3.993896 180)
			(unlocked yes)
			(layer "F.Fab")
			(hide yes)
			(effects
				(font
					(size 1.016 1.016)
					(thickness 0.1524)
				)
			)
		)
		(property "Device Type" "R402H16"
			(at 0.064008 -5.517896 180)
			(unlocked yes)
			(layer "F.Fab")
			(hide yes)
			(effects
				(font
					(size 1.016 1.016)
					(thickness 0.1524)
				)
			)
		)
		(duplicate_pad_numbers_are_jumpers no)
		(fp_line
			(start 0.508 -0.9398)
			(end -0.508 -0.9398)
			(stroke
				(width 0.1524)
				(type default)
			)
			(layer "F.SilkS")
		)
		(fp_line
			(start -0.508 -0.9398)
			(end -0.508 0.9398)
			(stroke
				(width 0.1524)
				(type default)
			)
			(layer "F.SilkS")
		)
		(fp_rect
			(start -0.508 0.9398)
			(end 0.508 -0.9398)
			(stroke
				(width 0)
				(type default)
			)
			(fill no)
			(layer "F.CrtYd")
		)
		(fp_rect
			(start -0.508 0.9398)
			(end 0.508 -0.9398)
			(stroke
				(width 0)
				(type default)
			)
			(fill no)
			(layer "F.Fab")
		)
		(pad "1" smd custom
			(at 0 -0.4445 180)
			(size 0.1397 0.1397)
			(layers "F.Cu" "F.Mask" "F.Paste")
			(net "DUT_VDDO")
			(options
				(clearance outline)
				(anchor circle)
			)
			(primitives
				(gr_poly
					(pts
						(arc
							(start -0.1778 -0.2794)
							(mid -0.249642 -0.249642)
							(end -0.2794 -0.1778)
						)
						(arc
							(start -0.2794 0.1778)
							(mid -0.249642 0.249642)
							(end -0.1778 0.2794)
						)
						(arc
							(start 0.1778 0.2794)
							(mid 0.249642 0.249642)
							(end 0.2794 0.1778)
						)
						(arc
							(start 0.2794 -0.1778)
							(mid 0.249642 -0.249642)
							(end 0.1778 -0.2794)
						)
					)
					(width 0)
					(fill yes)
				)
			)
		)
		(pad "2" smd custom
			(at 0 0.4445 180)
			(size 0.1397 0.1397)
			(layers "F.Cu" "F.Mask" "F.Paste")
			(net "EJTAG_TCK")
			(options
				(clearance outline)
				(anchor circle)
			)
			(primitives
				(gr_poly
					(pts
						(arc
							(start -0.1778 -0.2794)
							(mid -0.249642 -0.249642)
							(end -0.2794 -0.1778)
						)
						(arc
							(start -0.2794 0.1778)
							(mid -0.249642 0.249642)
							(end -0.1778 0.2794)
						)
						(arc
							(start 0.1778 0.2794)
							(mid 0.249642 0.249642)
							(end 0.2794 0.1778)
						)
						(arc
							(start 0.2794 -0.1778)
							(mid 0.249642 -0.249642)
							(end 0.1778 -0.2794)
						)
					)
					(width 0)
					(fill yes)
				)
			)
		)
	)
	(footprint ""
		(layer "F.Cu")
		(at 227.584 -1.143 180)
		(property "Reference" "C4"
			(at 0 0 180)
			(layer "F.SilkS")
			(hide yes)
			(effects
				(font
					(size 1.27 1.27)
				)
			)
		)
		(property "Value" "SCD1U16V2KX-3GP"
			(at 1.1811 -2.7051 180)
			(unlocked yes)
			(layer "F.Fab")
			(hide yes)
			(effects
				(font
					(size 1.016 1.016)
					(thickness 0.1524)
				)
			)
		)
		(property "Device Type" "C402H22"
			(at 1.1811 -4.2291 180)
			(unlocked yes)
			(layer "F.Fab")
			(hide yes)
			(effects
				(font
					(size 1.016 1.016)
					(thickness 0.1524)
				)
			)
		)
		(duplicate_pad_numbers_are_jumpers no)
		(fp_rect
			(start -0.4318 0.9525)
			(end 0.4318 -0.9525)
			(stroke
				(width 0)
				(type default)
			)
			(fill no)
			(layer "F.CrtYd")
		)
		(fp_rect
			(start -0.4318 0.9525)
			(end 0.4318 -0.9525)
			(stroke
				(width 0)
				(type default)
			)
			(fill no)
			(layer "F.Fab")
		)
		(pad "1" smd custom
			(at 0 -0.4445 180)
			(size 0.1524 0.1524)
			(layers "F.Cu" "F.Mask" "F.Paste")
			(net "P3V3_STBY")
			(options
				(clearance outline)
				(anchor circle)
			)
			(primitives
				(gr_poly
					(pts
						(arc
							(start 0.3048 -0.2032)
							(mid 0.275042 -0.275042)
							(end 0.2032 -0.3048)
						)
						(arc
							(start -0.2032 -0.3048)
							(mid -0.275042 -0.275042)
							(end -0.3048 -0.2032)
						)
						(arc
							(start -0.3048 0.2032)
							(mid -0.275042 0.275042)
							(end -0.2032 0.3048)
						)
						(arc
							(start 0.2032 0.3048)
							(mid 0.275042 0.275042)
							(end 0.3048 0.2032)
						)
					)
					(width 0)
					(fill yes)
				)
			)
		)
		(pad "2" smd custom
			(at 0 0.4445 180)
			(size 0.1524 0.1524)
			(layers "F.Cu" "F.Mask" "F.Paste")
			(net "GND")
			(options
				(clearance outline)
				(anchor circle)
			)
			(primitives
				(gr_poly
					(pts
						(arc
							(start 0.3048 -0.2032)
							(mid 0.275042 -0.275042)
							(end 0.2032 -0.3048)
						)
						(arc
							(start -0.2032 -0.3048)
							(mid -0.275042 -0.275042)
							(end -0.3048 -0.2032)
						)
						(arc
							(start -0.3048 0.2032)
							(mid -0.275042 0.275042)
							(end -0.2032 0.3048)
						)
						(arc
							(start 0.2032 0.3048)
							(mid 0.275042 0.275042)
							(end 0.3048 0.2032)
						)
					)
					(width 0)
					(fill yes)
				)
			)
		)
	)
	(footprint ""
		(layer "F.Cu")
		(at 320.559176 -33.507426)
		(property "Reference" "C46"
			(at 0 0 0)
			(layer "F.SilkS")
			(hide yes)
			(effects
				(font
					(size 1.27 1.27)
				)
			)
		)
		(property "Value" "SCD22U10V2KX-1GP"
			(at 1.1811 -2.7051 0)
			(unlocked yes)
			(layer "F.Fab")
			(hide yes)
			(effects
				(font
					(size 1.016 1.016)
					(thickness 0.1524)
				)
			)
		)
		(property "Device Type" "C402H22"
			(at 1.1811 -4.2291 0)
			(unlocked yes)
			(layer "F.Fab")
			(hide yes)
			(effects
				(font
					(size 1.016 1.016)
					(thickness 0.1524)
				)
			)
		)
		(duplicate_pad_numbers_are_jumpers no)
		(fp_rect
			(start -0.4318 0.9525)
			(end 0.4318 -0.9525)
			(stroke
				(width 0)
				(type default)
			)
			(fill no)
			(layer "F.CrtYd")
		)
		(fp_rect
			(start -0.4318 0.9525)
			(end 0.4318 -0.9525)
			(stroke
				(width 0)
				(type default)
			)
			(fill no)
			(layer "F.Fab")
		)
		(pad "1" smd custom
			(at 0 -0.4445)
			(size 0.1524 0.1524)
			(layers "F.Cu" "F.Mask" "F.Paste")
			(net "PCIE_TX_CAP_N12")
			(options
				(clearance outline)
				(anchor circle)
			)
			(primitives
				(gr_poly
					(pts
						(arc
							(start 0.3048 -0.2032)
							(mid 0.275042 -0.275042)
							(end 0.2032 -0.3048)
						)
						(arc
							(start -0.2032 -0.3048)
							(mid -0.275042 -0.275042)
							(end -0.3048 -0.2032)
						)
						(arc
							(start -0.3048 0.2032)
							(mid -0.275042 0.275042)
							(end -0.2032 0.3048)
						)
						(arc
							(start 0.2032 0.3048)
							(mid 0.275042 0.275042)
							(end 0.3048 0.2032)
						)
					)
					(width 0)
					(fill yes)
				)
			)
		)
		(pad "2" smd custom
			(at 0 0.4445)
			(size 0.1524 0.1524)
			(layers "F.Cu" "F.Mask" "F.Paste")
			(net "PCIE_TX_N12")
			(options
				(clearance outline)
				(anchor circle)
			)
			(primitives
				(gr_poly
					(pts
						(arc
							(start 0.3048 -0.2032)
							(mid 0.275042 -0.275042)
							(end 0.2032 -0.3048)
						)
						(arc
							(start -0.2032 -0.3048)
							(mid -0.275042 -0.275042)
							(end -0.3048 -0.2032)
						)
						(arc
							(start -0.3048 0.2032)
							(mid -0.275042 0.275042)
							(end -0.2032 0.3048)
						)
						(arc
							(start 0.2032 0.3048)
							(mid 0.275042 0.275042)
							(end 0.3048 0.2032)
						)
					)
					(width 0)
					(fill yes)
				)
			)
		)
	)
	(footprint ""
		(layer "F.Cu")
		(at 85.3948 -52.6288 180)
		(property "Reference" "JP1"
			(at 0 0 180)
			(layer "F.SilkS")
			(hide yes)
			(effects
				(font
					(size 1.27 1.27)
				)
			)
		)
		(property "Value" "PIN-CON3-S-GP"
			(at -5.588 -5.3086 180)
			(unlocked yes)
			(layer "F.Fab")
			(hide yes)
			(effects
				(font
					(size 1.016 1.016)
					(thickness 0.1524)
				)
			)
		)
		(property "Device Type" "21S-91-03GB01"
			(at -5.588 -6.8326 180)
			(unlocked yes)
			(layer "F.Fab")
			(hide yes)
			(effects
				(font
					(size 1.016 1.016)
					(thickness 0.1524)
				)
			)
		)
		(duplicate_pad_numbers_are_jumpers no)
		(fp_line
			(start 3.8862 1.4986)
			(end 3.8862 -1.4986)
			(stroke
				(width 0.1524)
				(type default)
			)
			(layer "F.SilkS")
		)
		(fp_line
			(start 3.8862 -1.4986)
			(end -3.8862 -1.4986)
			(stroke
				(width 0.1524)
				(type default)
			)
			(layer "F.SilkS")
		)
		(fp_line
			(start -3.8862 1.4986)
			(end 3.8862 1.4986)
			(stroke
				(width 0.1524)
				(type default)
			)
			(layer "F.SilkS")
		)
		(fp_line
			(start -3.8862 -1.4986)
			(end -3.8862 1.4986)
			(stroke
				(width 0.1524)
				(type default)
			)
			(layer "F.SilkS")
		)
		(fp_line
			(start -4.0132 -0.3556)
			(end -4.0132 -1.6256)
			(stroke
				(width 0.4064)
				(type default)
			)
			(layer "F.SilkS")
		)
		(fp_line
			(start -4.0132 -1.6256)
			(end -2.7432 -1.6256)
			(stroke
				(width 0.4064)
				(type default)
			)
			(layer "F.SilkS")
		)
		(fp_circle
			(center 2.54 0)
			(end 1.4732 0)
			(stroke
				(width 0.3048)
				(type default)
			)
			(fill no)
			(layer "F.SilkS")
		)
		(fp_circle
			(center 0 0)
			(end -1.0668 0)
			(stroke
				(width 0.3048)
				(type default)
			)
			(fill no)
			(layer "F.SilkS")
		)
		(fp_circle
			(center -2.54 0)
			(end -3.6068 0)
			(stroke
				(width 0.3048)
				(type default)
			)
			(fill no)
			(layer "F.SilkS")
		)
		(fp_rect
			(start -3.6322 1.2446)
			(end 3.6322 -1.2446)
			(stroke
				(width 0)
				(type default)
			)
			(fill no)
			(layer "F.CrtYd")
		)
		(fp_poly
			(pts
				(xy 4.1402 -1.2446) (xy -3.6322 -1.2446) (xy -3.6322 1.2446) (xy 3.6322 1.2446) (xy 3.6322 -1.2319)
				(xy 4.1402 -1.2319) (xy 4.1402 1.7526) (xy -4.1402 1.7526) (xy -4.1402 -1.7526) (xy 4.1402 -1.7526)
			)
			(stroke
				(width 0)
				(type default)
			)
			(fill no)
			(layer "F.CrtYd")
		)
		(fp_rect
			(start -4.1402 1.7526)
			(end 4.1402 -1.7526)
			(stroke
				(width 0)
				(type default)
			)
			(fill no)
			(layer "F.Fab")
		)
		(pad "1" thru_hole circle
			(at -2.54 0 180)
			(size 1.4224 1.4224)
			(drill 1.016)
			(layers "*.Cu" "*.Mask")
			(remove_unused_layers no)
			(net "ROMA0")
			(clearance 0.1524)
			(thermal_gap 0.1524)
		)
		(pad "2" thru_hole circle
			(at 0 0 180)
			(size 1.4224 1.4224)
			(drill 1.016)
			(layers "*.Cu" "*.Mask")
			(remove_unused_layers no)
			(net "AS_ROMA0_R")
			(clearance 0.1524)
			(thermal_gap 0.1524)
		)
		(pad "3" thru_hole circle
			(at 2.54 0 180)
			(size 1.4224 1.4224)
			(drill 1.016)
			(layers "*.Cu" "*.Mask")
			(remove_unused_layers no)
			(net "Net_517")
			(clearance 0.1524)
			(thermal_gap 0.1524)
		)
	)
	(footprint ""
		(layer "F.Cu")
		(at 28.2956 -186.7662 180)
		(property "Reference" "C259"
			(at 0 0 180)
			(layer "F.SilkS")
			(hide yes)
			(effects
				(font
					(size 1.27 1.27)
				)
			)
		)
		(property "Value" "SC220P50V3JN-GP"
			(at 0 -2.8194 180)
			(unlocked yes)
			(layer "F.Fab")
			(hide yes)
			(effects
				(font
					(size 1.016 1.016)
					(thickness 0.1524)
				)
			)
		)
		(property "Device Type" "C603H36"
			(at 0 -4.3434 180)
			(unlocked yes)
			(layer "F.Fab")
			(hide yes)
			(effects
				(font
					(size 1.016 1.016)
					(thickness 0.1524)
				)
			)
		)
		(duplicate_pad_numbers_are_jumpers no)
		(fp_line
			(start 0.508 0)
			(end -0.508 0)
			(stroke
				(width 0.2032)
				(type default)
			)
			(layer "F.SilkS")
		)
		(fp_rect
			(start -0.5842 1.3335)
			(end 0.5842 -1.3335)
			(stroke
				(width 0)
				(type default)
			)
			(fill no)
			(layer "F.CrtYd")
		)
		(fp_rect
			(start -0.5842 1.3335)
			(end 0.5842 -1.3335)
			(stroke
				(width 0)
				(type default)
			)
			(fill no)
			(layer "F.Fab")
		)
		(pad "1" smd custom
			(at 0 -0.762 180)
			(size 0.2159 0.2159)
			(layers "F.Cu" "F.Mask" "F.Paste")
			(net "BMC_I2C5_SCL_R")
			(options
				(clearance outline)
				(anchor circle)
			)
			(primitives
				(gr_poly
					(pts
						(arc
							(start -0.3302 -0.4318)
							(mid -0.402042 -0.402042)
							(end -0.4318 -0.3302)
						)
						(arc
							(start -0.4318 0.3302)
							(mid -0.402042 0.402042)
							(end -0.3302 0.4318)
						)
						(arc
							(start 0.3302 0.4318)
							(mid 0.402042 0.402042)
							(end 0.4318 0.3302)
						)
						(arc
							(start 0.4318 -0.3302)
							(mid 0.402042 -0.402042)
							(end 0.3302 -0.4318)
						)
					)
					(width 0)
					(fill yes)
				)
			)
		)
		(pad "2" smd custom
			(at 0 0.762 180)
			(size 0.2159 0.2159)
			(layers "F.Cu" "F.Mask" "F.Paste")
			(net "GND")
			(options
				(clearance outline)
				(anchor circle)
			)
			(primitives
				(gr_poly
					(pts
						(arc
							(start -0.3302 -0.4318)
							(mid -0.402042 -0.402042)
							(end -0.4318 -0.3302)
						)
						(arc
							(start -0.4318 0.3302)
							(mid -0.402042 0.402042)
							(end -0.3302 0.4318)
						)
						(arc
							(start 0.3302 0.4318)
							(mid 0.402042 0.402042)
							(end 0.4318 0.3302)
						)
						(arc
							(start 0.4318 -0.3302)
							(mid 0.402042 -0.402042)
							(end 0.3302 -0.4318)
						)
					)
					(width 0)
					(fill yes)
				)
			)
		)
	)
	(footprint ""
		(layer "F.Cu")
		(at 36.322 -98.552 90)
		(property "Reference" "U50"
			(at 0 0 90)
			(layer "F.SilkS")
			(hide yes)
			(effects
				(font
					(size 1.27 1.27)
				)
			)
		)
		(property "Value" "SN74CBTLV3257RGYR-1-GP"
			(at -3.774948 -0.185674 90)
			(unlocked yes)
			(layer "F.Fab")
			(hide yes)
			(effects
				(font
					(size 1.016 1.016)
					(thickness 0.1524)
				)
			)
		)
		(property "Device Type" "QFN16G3540-G215265H40"
			(at -3.774948 -1.709674 90)
			(unlocked yes)
			(layer "F.Fab")
			(hide yes)
			(effects
				(font
					(size 1.016 1.016)
					(thickness 0.1524)
				)
			)
		)
		(duplicate_pad_numbers_are_jumpers no)
		(fp_line
			(start -3.0099 -2.7686)
			(end -1.7399 -2.7686)
			(stroke
				(width 0.1524)
				(type default)
			)
			(layer "F.SilkS")
		)
		(fp_line
			(start -0.249936 -2.54)
			(end -0.249936 -3.048)
			(stroke
				(width 0.1524)
				(type default)
			)
			(layer "F.SilkS")
		)
		(fp_line
			(start -3.0099 -1.4986)
			(end -3.0099 -2.7686)
			(stroke
				(width 0.1524)
				(type default)
			)
			(layer "F.SilkS")
		)
		(fp_line
			(start 3.0099 1.4986)
			(end 3.0099 2.7686)
			(stroke
				(width 0.1524)
				(type default)
			)
			(layer "F.SilkS")
		)
		(fp_line
			(start -3.0099 1.4986)
			(end -3.0099 2.7686)
			(stroke
				(width 0.1524)
				(type default)
			)
			(layer "F.SilkS")
		)
		(fp_line
			(start 1.249934 2.54)
			(end 1.249934 3.048)
			(stroke
				(width 0.1524)
				(type default)
			)
			(layer "F.SilkS")
		)
		(fp_line
			(start -1.249934 2.54)
			(end -1.249934 3.302)
			(stroke
				(width 0.1524)
				(type default)
			)
			(layer "F.SilkS")
		)
		(fp_line
			(start 3.0099 2.7686)
			(end 1.7399 2.7686)
			(stroke
				(width 0.1524)
				(type default)
			)
			(layer "F.SilkS")
		)
		(fp_line
			(start -3.0099 2.7686)
			(end -1.7399 2.7686)
			(stroke
				(width 0.1524)
				(type default)
			)
			(layer "F.SilkS")
		)
		(fp_poly
			(pts
				(xy 1.7399 -2.7686) (xy 3.0099 -1.4986) (xy 3.0099 -2.7686)
			)
			(stroke
				(width 0)
				(type default)
			)
			(fill yes)
			(layer "F.SilkS")
		)
		(fp_rect
			(start -1.9939 1.7526)
			(end 1.9939 -1.7526)
			(stroke
				(width 0)
				(type default)
			)
			(fill no)
			(layer "F.CrtYd")
		)
		(fp_poly
			(pts
				(xy -3.0099 2.7686) (xy -3.0099 -2.7686) (xy 3.0099 -2.7686) (xy 3.0099 -0.2286) (xy 1.9939 -0.2286)
				(xy 1.9939 -1.7526) (xy -1.9939 -1.7526) (xy -1.9939 1.7526) (xy 1.9939 1.7526) (xy 1.9939 -0.22352)
				(xy 3.0099 -0.22352) (xy 3.0099 2.7686)
			)
			(stroke
				(width 0)
				(type default)
			)
			(fill no)
			(layer "F.CrtYd")
		)
		(fp_rect
			(start -3.0099 2.7686)
			(end 3.0099 -2.7686)
			(stroke
				(width 0)
				(type default)
			)
			(fill no)
			(layer "F.Fab")
		)
		(pad "1" smd rect
			(at 2.0193 -0.750062 90)
			(size 0.9652 0.3048)
			(layers "F.Cu" "F.Mask" "F.Paste")
			(net "SPI_FLASH_SELECT_R")
		)
		(pad "2" smd rect
			(at 1.249934 -1.778 90)
			(size 0.3048 0.9652)
			(layers "F.Cu" "F.Mask" "F.Paste")
			(net "SPICS0_N")
		)
		(pad "3" smd rect
			(at 0.750062 -1.778 90)
			(size 0.3048 0.9652)
			(layers "F.Cu" "F.Mask" "F.Paste")
			(net "I210_CS_N_R")
		)
		(pad "4" smd rect
			(at 0.249936 -1.778 90)
			(size 0.3048 0.9652)
			(layers "F.Cu" "F.Mask" "F.Paste")
			(net "I2C_MUX_1A")
		)
		(pad "5" smd rect
			(at -0.249936 -1.778 90)
			(size 0.3048 0.9652)
			(layers "F.Cu" "F.Mask" "F.Paste")
			(net "SPICK")
		)
		(pad "6" smd rect
			(at -0.750062 -1.778 90)
			(size 0.3048 0.9652)
			(layers "F.Cu" "F.Mask" "F.Paste")
			(net "I210_SK_R")
		)
		(pad "7" smd rect
			(at -1.249934 -1.778 90)
			(size 0.3048 0.9652)
			(layers "F.Cu" "F.Mask" "F.Paste")
			(net "I2C_MUX_2A")
		)
		(pad "8" smd rect
			(at -2.0193 -0.750062 90)
			(size 0.9652 0.3048)
			(layers "F.Cu" "F.Mask" "F.Paste")
			(net "GND")
		)
		(pad "9" smd rect
			(at -2.0193 0.75311 90)
			(size 0.9652 0.3048)
			(layers "F.Cu" "F.Mask" "F.Paste")
			(net "I2C_MUX_3A")
		)
		(pad "10" smd rect
			(at -1.249934 1.778 90)
			(size 0.3048 0.9652)
			(layers "F.Cu" "F.Mask" "F.Paste")
			(net "I210_SO_R")
		)
		(pad "11" smd rect
			(at -0.750062 1.778 90)
			(size 0.3048 0.9652)
			(layers "F.Cu" "F.Mask" "F.Paste")
			(net "SPIDO")
		)
		(pad "12" smd rect
			(at -0.249936 1.778 90)
			(size 0.3048 0.9652)
			(layers "F.Cu" "F.Mask" "F.Paste")
			(net "I2C_MUX_4A")
		)
		(pad "13" smd rect
			(at 0.249936 1.778 90)
			(size 0.3048 0.9652)
			(layers "F.Cu" "F.Mask" "F.Paste")
			(net "I210_SI_R")
		)
		(pad "14" smd rect
			(at 0.750062 1.778 90)
			(size 0.3048 0.9652)
			(layers "F.Cu" "F.Mask" "F.Paste")
			(net "SPIDI")
		)
		(pad "15" smd rect
			(at 1.249934 1.778 90)
			(size 0.3048 0.9652)
			(layers "F.Cu" "F.Mask" "F.Paste")
			(net "BUS_SW_OE#")
		)
		(pad "16" smd rect
			(at 2.0193 0.750062 90)
			(size 0.9652 0.3048)
			(layers "F.Cu" "F.Mask" "F.Paste")
			(net "P3V3_I2C_MUX")
		)
		(pad "17" smd rect
			(at 0 0 90)
			(size 2.6416 2.159)
			(layers "F.Cu" "F.Mask" "F.Paste")
			(net "GND")
		)
	)
	(footprint ""
		(layer "F.Cu")
		(at 331.978 -71.247 180)
		(property "Reference" "PR152"
			(at 0 0 180)
			(layer "F.SilkS")
			(hide yes)
			(effects
				(font
					(size 1.27 1.27)
				)
			)
		)
		(property "Value" "0R2J-2-GP"
			(at 0.064008 -3.993896 180)
			(unlocked yes)
			(layer "F.Fab")
			(hide yes)
			(effects
				(font
					(size 1.016 1.016)
					(thickness 0.1524)
				)
			)
		)
		(property "Device Type" "R402H16"
			(at 0.064008 -5.517896 180)
			(unlocked yes)
			(layer "F.Fab")
			(hide yes)
			(effects
				(font
					(size 1.016 1.016)
					(thickness 0.1524)
				)
			)
		)
		(duplicate_pad_numbers_are_jumpers no)
		(fp_line
			(start 0.508 -0.9398)
			(end -0.508 -0.9398)
			(stroke
				(width 0.1524)
				(type default)
			)
			(layer "F.SilkS")
		)
		(fp_line
			(start -0.508 -0.9398)
			(end -0.508 0.9398)
			(stroke
				(width 0.1524)
				(type default)
			)
			(layer "F.SilkS")
		)
		(fp_rect
			(start -0.508 0.9398)
			(end 0.508 -0.9398)
			(stroke
				(width 0)
				(type default)
			)
			(fill no)
			(layer "F.CrtYd")
		)
		(fp_rect
			(start -0.508 0.9398)
			(end 0.508 -0.9398)
			(stroke
				(width 0)
				(type default)
			)
			(fill no)
			(layer "F.Fab")
		)
		(pad "1" smd custom
			(at 0 -0.4445 180)
			(size 0.1397 0.1397)
			(layers "F.Cu" "F.Mask" "F.Paste")
			(net "P0V9_E_EN")
			(options
				(clearance outline)
				(anchor circle)
			)
			(primitives
				(gr_poly
					(pts
						(arc
							(start -0.1778 -0.2794)
							(mid -0.249642 -0.249642)
							(end -0.2794 -0.1778)
						)
						(arc
							(start -0.2794 0.1778)
							(mid -0.249642 0.249642)
							(end -0.1778 0.2794)
						)
						(arc
							(start 0.1778 0.2794)
							(mid 0.249642 0.249642)
							(end 0.2794 0.1778)
						)
						(arc
							(start 0.2794 -0.1778)
							(mid 0.249642 -0.249642)
							(end 0.1778 -0.2794)
						)
					)
					(width 0)
					(fill yes)
				)
			)
		)
		(pad "2" smd custom
			(at 0 0.4445 180)
			(size 0.1397 0.1397)
			(layers "F.Cu" "F.Mask" "F.Paste")
			(net "P0V9_PG")
			(options
				(clearance outline)
				(anchor circle)
			)
			(primitives
				(gr_poly
					(pts
						(arc
							(start -0.1778 -0.2794)
							(mid -0.249642 -0.249642)
							(end -0.2794 -0.1778)
						)
						(arc
							(start -0.2794 0.1778)
							(mid -0.249642 0.249642)
							(end -0.1778 0.2794)
						)
						(arc
							(start 0.1778 0.2794)
							(mid 0.249642 0.249642)
							(end 0.2794 0.1778)
						)
						(arc
							(start 0.2794 -0.1778)
							(mid 0.249642 -0.249642)
							(end 0.1778 -0.2794)
						)
					)
					(width 0)
					(fill yes)
				)
			)
		)
	)
	(footprint ""
		(layer "F.Cu")
		(at 22.72919 -123.445016 90)
		(property "Reference" "C368"
			(at 0 0 90)
			(layer "F.SilkS")
			(hide yes)
			(effects
				(font
					(size 1.27 1.27)
				)
			)
		)
		(property "Value" "SCD22U10V2KX-1GP"
			(at 1.1811 -2.7051 90)
			(unlocked yes)
			(layer "F.Fab")
			(hide yes)
			(effects
				(font
					(size 1.016 1.016)
					(thickness 0.1524)
				)
			)
		)
		(property "Device Type" "C402H22"
			(at 1.1811 -4.2291 90)
			(unlocked yes)
			(layer "F.Fab")
			(hide yes)
			(effects
				(font
					(size 1.016 1.016)
					(thickness 0.1524)
				)
			)
		)
		(duplicate_pad_numbers_are_jumpers no)
		(fp_rect
			(start -0.4318 0.9525)
			(end 0.4318 -0.9525)
			(stroke
				(width 0)
				(type default)
			)
			(fill no)
			(layer "F.CrtYd")
		)
		(fp_rect
			(start -0.4318 0.9525)
			(end 0.4318 -0.9525)
			(stroke
				(width 0)
				(type default)
			)
			(fill no)
			(layer "F.Fab")
		)
		(pad "1" smd custom
			(at 0 -0.4445 90)
			(size 0.1524 0.1524)
			(layers "F.Cu" "F.Mask" "F.Paste")
			(net "PCIE_TX_CAP_N76")
			(options
				(clearance outline)
				(anchor circle)
			)
			(primitives
				(gr_poly
					(pts
						(arc
							(start 0.3048 -0.2032)
							(mid 0.275042 -0.275042)
							(end 0.2032 -0.3048)
						)
						(arc
							(start -0.2032 -0.3048)
							(mid -0.275042 -0.275042)
							(end -0.3048 -0.2032)
						)
						(arc
							(start -0.3048 0.2032)
							(mid -0.275042 0.275042)
							(end -0.2032 0.3048)
						)
						(arc
							(start 0.2032 0.3048)
							(mid 0.275042 0.275042)
							(end 0.3048 0.2032)
						)
					)
					(width 0)
					(fill yes)
				)
			)
		)
		(pad "2" smd custom
			(at 0 0.4445 90)
			(size 0.1524 0.1524)
			(layers "F.Cu" "F.Mask" "F.Paste")
			(net "PCIE_TX_N76")
			(options
				(clearance outline)
				(anchor circle)
			)
			(primitives
				(gr_poly
					(pts
						(arc
							(start 0.3048 -0.2032)
							(mid 0.275042 -0.275042)
							(end 0.2032 -0.3048)
						)
						(arc
							(start -0.2032 -0.3048)
							(mid -0.275042 -0.275042)
							(end -0.3048 -0.2032)
						)
						(arc
							(start -0.3048 0.2032)
							(mid -0.275042 0.275042)
							(end -0.2032 0.3048)
						)
						(arc
							(start 0.2032 0.3048)
							(mid 0.275042 0.275042)
							(end 0.3048 0.2032)
						)
					)
					(width 0)
					(fill yes)
				)
			)
		)
	)
	(footprint ""
		(layer "F.Cu")
		(at 154.813 -92.992702)
		(property "Reference" "C413"
			(at 0 0 0)
			(layer "F.SilkS")
			(hide yes)
			(effects
				(font
					(size 1.27 1.27)
				)
			)
		)
		(property "Value" "SC12P50V2JN-3GP"
			(at 1.1811 -2.7051 0)
			(unlocked yes)
			(layer "F.Fab")
			(hide yes)
			(effects
				(font
					(size 1.016 1.016)
					(thickness 0.1524)
				)
			)
		)
		(property "Device Type" "C402H24"
			(at 1.1811 -4.2291 0)
			(unlocked yes)
			(layer "F.Fab")
			(hide yes)
			(effects
				(font
					(size 1.016 1.016)
					(thickness 0.1524)
				)
			)
		)
		(duplicate_pad_numbers_are_jumpers no)
		(fp_rect
			(start -0.4318 0.9525)
			(end 0.4318 -0.9525)
			(stroke
				(width 0)
				(type default)
			)
			(fill no)
			(layer "F.CrtYd")
		)
		(fp_rect
			(start -0.4318 0.9525)
			(end 0.4318 -0.9525)
			(stroke
				(width 0)
				(type default)
			)
			(fill no)
			(layer "F.Fab")
		)
		(pad "1" smd custom
			(at 0 -0.4445)
			(size 0.1524 0.1524)
			(layers "F.Cu" "F.Mask" "F.Paste")
			(net "XTAL_X1")
			(options
				(clearance outline)
				(anchor circle)
			)
			(primitives
				(gr_poly
					(pts
						(arc
							(start 0.3048 -0.2032)
							(mid 0.275042 -0.275042)
							(end 0.2032 -0.3048)
						)
						(arc
							(start -0.2032 -0.3048)
							(mid -0.275042 -0.275042)
							(end -0.3048 -0.2032)
						)
						(arc
							(start -0.3048 0.2032)
							(mid -0.275042 0.275042)
							(end -0.2032 0.3048)
						)
						(arc
							(start 0.2032 0.3048)
							(mid 0.275042 0.275042)
							(end 0.3048 0.2032)
						)
					)
					(width 0)
					(fill yes)
				)
			)
		)
		(pad "2" smd custom
			(at 0 0.4445)
			(size 0.1524 0.1524)
			(layers "F.Cu" "F.Mask" "F.Paste")
			(net "GND")
			(options
				(clearance outline)
				(anchor circle)
			)
			(primitives
				(gr_poly
					(pts
						(arc
							(start 0.3048 -0.2032)
							(mid 0.275042 -0.275042)
							(end 0.2032 -0.3048)
						)
						(arc
							(start -0.2032 -0.3048)
							(mid -0.275042 -0.275042)
							(end -0.3048 -0.2032)
						)
						(arc
							(start -0.3048 0.2032)
							(mid -0.275042 0.275042)
							(end -0.2032 0.3048)
						)
						(arc
							(start 0.2032 0.3048)
							(mid 0.275042 0.275042)
							(end 0.3048 0.2032)
						)
					)
					(width 0)
					(fill yes)
				)
			)
		)
	)
	(footprint ""
		(layer "F.Cu")
		(at 5.5372 -46.3804 180)
		(property "Reference" "C333"
			(at 0 0 180)
			(layer "F.SilkS")
			(hide yes)
			(effects
				(font
					(size 1.27 1.27)
				)
			)
		)
		(property "Value" "SCD1U16V2KX-3GP"
			(at 1.1811 -2.7051 180)
			(unlocked yes)
			(layer "F.Fab")
			(hide yes)
			(effects
				(font
					(size 1.016 1.016)
					(thickness 0.1524)
				)
			)
		)
		(property "Device Type" "C402H22"
			(at 1.1811 -4.2291 180)
			(unlocked yes)
			(layer "F.Fab")
			(hide yes)
			(effects
				(font
					(size 1.016 1.016)
					(thickness 0.1524)
				)
			)
		)
		(duplicate_pad_numbers_are_jumpers no)
		(fp_rect
			(start -0.4318 0.9525)
			(end 0.4318 -0.9525)
			(stroke
				(width 0)
				(type default)
			)
			(fill no)
			(layer "F.CrtYd")
		)
		(fp_rect
			(start -0.4318 0.9525)
			(end 0.4318 -0.9525)
			(stroke
				(width 0)
				(type default)
			)
			(fill no)
			(layer "F.Fab")
		)
		(pad "1" smd custom
			(at 0 -0.4445 180)
			(size 0.1524 0.1524)
			(layers "F.Cu" "F.Mask" "F.Paste")
			(net "NIC0_CT_POWER")
			(options
				(clearance outline)
				(anchor circle)
			)
			(primitives
				(gr_poly
					(pts
						(arc
							(start 0.3048 -0.2032)
							(mid 0.275042 -0.275042)
							(end 0.2032 -0.3048)
						)
						(arc
							(start -0.2032 -0.3048)
							(mid -0.275042 -0.275042)
							(end -0.3048 -0.2032)
						)
						(arc
							(start -0.3048 0.2032)
							(mid -0.275042 0.275042)
							(end -0.2032 0.3048)
						)
						(arc
							(start 0.2032 0.3048)
							(mid 0.275042 0.275042)
							(end 0.3048 0.2032)
						)
					)
					(width 0)
					(fill yes)
				)
			)
		)
		(pad "2" smd custom
			(at 0 0.4445 180)
			(size 0.1524 0.1524)
			(layers "F.Cu" "F.Mask" "F.Paste")
			(net "GND")
			(options
				(clearance outline)
				(anchor circle)
			)
			(primitives
				(gr_poly
					(pts
						(arc
							(start 0.3048 -0.2032)
							(mid 0.275042 -0.275042)
							(end 0.2032 -0.3048)
						)
						(arc
							(start -0.2032 -0.3048)
							(mid -0.275042 -0.275042)
							(end -0.3048 -0.2032)
						)
						(arc
							(start -0.3048 0.2032)
							(mid -0.275042 0.275042)
							(end -0.2032 0.3048)
						)
						(arc
							(start 0.2032 0.3048)
							(mid 0.275042 0.275042)
							(end 0.3048 0.2032)
						)
					)
					(width 0)
					(fill yes)
				)
			)
		)
	)
	(footprint ""
		(layer "F.Cu")
		(at 8.2042 -135.509 90)
		(property "Reference" "R687"
			(at 0 0 90)
			(layer "F.SilkS")
			(hide yes)
			(effects
				(font
					(size 1.27 1.27)
				)
			)
		)
		(property "Value" "0R2J-2-GP"
			(at 0.064008 -3.993896 90)
			(unlocked yes)
			(layer "F.Fab")
			(hide yes)
			(effects
				(font
					(size 1.016 1.016)
					(thickness 0.1524)
				)
			)
		)
		(property "Device Type" "R402H16"
			(at 0.064008 -5.517896 90)
			(unlocked yes)
			(layer "F.Fab")
			(hide yes)
			(effects
				(font
					(size 1.016 1.016)
					(thickness 0.1524)
				)
			)
		)
		(duplicate_pad_numbers_are_jumpers no)
		(fp_line
			(start 0.508 -0.9398)
			(end -0.508 -0.9398)
			(stroke
				(width 0.1524)
				(type default)
			)
			(layer "F.SilkS")
		)
		(fp_line
			(start -0.508 -0.9398)
			(end -0.508 0.9398)
			(stroke
				(width 0.1524)
				(type default)
			)
			(layer "F.SilkS")
		)
		(fp_rect
			(start -0.508 0.9398)
			(end 0.508 -0.9398)
			(stroke
				(width 0)
				(type default)
			)
			(fill no)
			(layer "F.CrtYd")
		)
		(fp_rect
			(start -0.508 0.9398)
			(end 0.508 -0.9398)
			(stroke
				(width 0)
				(type default)
			)
			(fill no)
			(layer "F.Fab")
		)
		(pad "1" smd custom
			(at 0 -0.4445 90)
			(size 0.1397 0.1397)
			(layers "F.Cu" "F.Mask" "F.Paste")
			(net "FM_BMC_RESET_Q36")
			(options
				(clearance outline)
				(anchor circle)
			)
			(primitives
				(gr_poly
					(pts
						(arc
							(start -0.1778 -0.2794)
							(mid -0.249642 -0.249642)
							(end -0.2794 -0.1778)
						)
						(arc
							(start -0.2794 0.1778)
							(mid -0.249642 0.249642)
							(end -0.1778 0.2794)
						)
						(arc
							(start 0.1778 0.2794)
							(mid 0.249642 0.249642)
							(end 0.2794 0.1778)
						)
						(arc
							(start 0.2794 -0.1778)
							(mid 0.249642 -0.249642)
							(end 0.1778 -0.2794)
						)
					)
					(width 0)
					(fill yes)
				)
			)
		)
		(pad "2" smd custom
			(at 0 0.4445 90)
			(size 0.1397 0.1397)
			(layers "F.Cu" "F.Mask" "F.Paste")
			(net "TRAY_RESET_N_R")
			(options
				(clearance outline)
				(anchor circle)
			)
			(primitives
				(gr_poly
					(pts
						(arc
							(start -0.1778 -0.2794)
							(mid -0.249642 -0.249642)
							(end -0.2794 -0.1778)
						)
						(arc
							(start -0.2794 0.1778)
							(mid -0.249642 0.249642)
							(end -0.1778 0.2794)
						)
						(arc
							(start 0.1778 0.2794)
							(mid 0.249642 0.249642)
							(end 0.2794 0.1778)
						)
						(arc
							(start 0.2794 -0.1778)
							(mid 0.249642 -0.249642)
							(end 0.1778 -0.2794)
						)
					)
					(width 0)
					(fill yes)
				)
			)
		)
	)
	(footprint ""
		(layer "F.Cu")
		(at 25.4508 -98.1964)
		(property "Reference" "R495"
			(at 0 0 0)
			(layer "F.SilkS")
			(hide yes)
			(effects
				(font
					(size 1.27 1.27)
				)
			)
		)
		(property "Value" "0R2J-2-GP"
			(at 0.064008 -3.993896 0)
			(unlocked yes)
			(layer "F.Fab")
			(hide yes)
			(effects
				(font
					(size 1.016 1.016)
					(thickness 0.1524)
				)
			)
		)
		(property "Device Type" "R402H16"
			(at 0.064008 -5.517896 0)
			(unlocked yes)
			(layer "F.Fab")
			(hide yes)
			(effects
				(font
					(size 1.016 1.016)
					(thickness 0.1524)
				)
			)
		)
		(duplicate_pad_numbers_are_jumpers no)
		(fp_line
			(start -0.508 -0.9398)
			(end -0.508 0.9398)
			(stroke
				(width 0.1524)
				(type default)
			)
			(layer "F.SilkS")
		)
		(fp_line
			(start 0.508 -0.9398)
			(end -0.508 -0.9398)
			(stroke
				(width 0.1524)
				(type default)
			)
			(layer "F.SilkS")
		)
		(fp_rect
			(start -0.508 0.9398)
			(end 0.508 -0.9398)
			(stroke
				(width 0)
				(type default)
			)
			(fill no)
			(layer "F.CrtYd")
		)
		(fp_rect
			(start -0.508 0.9398)
			(end 0.508 -0.9398)
			(stroke
				(width 0)
				(type default)
			)
			(fill no)
			(layer "F.Fab")
		)
		(pad "1" smd custom
			(at 0 -0.4445)
			(size 0.1397 0.1397)
			(layers "F.Cu" "F.Mask" "F.Paste")
			(net "FM_TPM_PRES_RST_N_C")
			(options
				(clearance outline)
				(anchor circle)
			)
			(primitives
				(gr_poly
					(pts
						(arc
							(start -0.1778 -0.2794)
							(mid -0.249642 -0.249642)
							(end -0.2794 -0.1778)
						)
						(arc
							(start -0.2794 0.1778)
							(mid -0.249642 0.249642)
							(end -0.1778 0.2794)
						)
						(arc
							(start 0.1778 0.2794)
							(mid 0.249642 0.249642)
							(end 0.2794 0.1778)
						)
						(arc
							(start 0.2794 -0.1778)
							(mid 0.249642 -0.249642)
							(end 0.1778 -0.2794)
						)
					)
					(width 0)
					(fill yes)
				)
			)
		)
		(pad "2" smd custom
			(at 0 0.4445)
			(size 0.1397 0.1397)
			(layers "F.Cu" "F.Mask" "F.Paste")
			(net "FM_TPM_PRES_RST_N")
			(options
				(clearance outline)
				(anchor circle)
			)
			(primitives
				(gr_poly
					(pts
						(arc
							(start -0.1778 -0.2794)
							(mid -0.249642 -0.249642)
							(end -0.2794 -0.1778)
						)
						(arc
							(start -0.2794 0.1778)
							(mid -0.249642 0.249642)
							(end -0.1778 0.2794)
						)
						(arc
							(start 0.1778 0.2794)
							(mid 0.249642 0.249642)
							(end 0.2794 0.1778)
						)
						(arc
							(start 0.2794 -0.1778)
							(mid 0.249642 -0.249642)
							(end 0.1778 -0.2794)
						)
					)
					(width 0)
					(fill yes)
				)
			)
		)
	)
	(footprint ""
		(layer "F.Cu")
		(at 203.192126 -212.420454 180)
		(property "Reference" "C115"
			(at 0 0 180)
			(layer "F.SilkS")
			(hide yes)
			(effects
				(font
					(size 1.27 1.27)
				)
			)
		)
		(property "Value" "SCD22U10V2KX-1GP"
			(at 1.1811 -2.7051 180)
			(unlocked yes)
			(layer "F.Fab")
			(hide yes)
			(effects
				(font
					(size 1.016 1.016)
					(thickness 0.1524)
				)
			)
		)
		(property "Device Type" "C402H22"
			(at 1.1811 -4.2291 180)
			(unlocked yes)
			(layer "F.Fab")
			(hide yes)
			(effects
				(font
					(size 1.016 1.016)
					(thickness 0.1524)
				)
			)
		)
		(duplicate_pad_numbers_are_jumpers no)
		(fp_rect
			(start -0.4318 0.9525)
			(end 0.4318 -0.9525)
			(stroke
				(width 0)
				(type default)
			)
			(fill no)
			(layer "F.CrtYd")
		)
		(fp_rect
			(start -0.4318 0.9525)
			(end 0.4318 -0.9525)
			(stroke
				(width 0)
				(type default)
			)
			(fill no)
			(layer "F.Fab")
		)
		(pad "1" smd custom
			(at 0 -0.4445 180)
			(size 0.1524 0.1524)
			(layers "F.Cu" "F.Mask" "F.Paste")
			(net "PCIE_TX_CAP_P41")
			(options
				(clearance outline)
				(anchor circle)
			)
			(primitives
				(gr_poly
					(pts
						(arc
							(start 0.3048 -0.2032)
							(mid 0.275042 -0.275042)
							(end 0.2032 -0.3048)
						)
						(arc
							(start -0.2032 -0.3048)
							(mid -0.275042 -0.275042)
							(end -0.3048 -0.2032)
						)
						(arc
							(start -0.3048 0.2032)
							(mid -0.275042 0.275042)
							(end -0.2032 0.3048)
						)
						(arc
							(start 0.2032 0.3048)
							(mid 0.275042 0.275042)
							(end 0.3048 0.2032)
						)
					)
					(width 0)
					(fill yes)
				)
			)
		)
		(pad "2" smd custom
			(at 0 0.4445 180)
			(size 0.1524 0.1524)
			(layers "F.Cu" "F.Mask" "F.Paste")
			(net "PCIE_TX_P41")
			(options
				(clearance outline)
				(anchor circle)
			)
			(primitives
				(gr_poly
					(pts
						(arc
							(start 0.3048 -0.2032)
							(mid 0.275042 -0.275042)
							(end 0.2032 -0.3048)
						)
						(arc
							(start -0.2032 -0.3048)
							(mid -0.275042 -0.275042)
							(end -0.3048 -0.2032)
						)
						(arc
							(start -0.3048 0.2032)
							(mid -0.275042 0.275042)
							(end -0.2032 0.3048)
						)
						(arc
							(start 0.2032 0.3048)
							(mid 0.275042 0.275042)
							(end 0.3048 0.2032)
						)
					)
					(width 0)
					(fill yes)
				)
			)
		)
	)
	(footprint ""
		(layer "F.Cu")
		(at 166.116 -87.5284 90)
		(property "Reference" "R87"
			(at 0 0 90)
			(layer "F.SilkS")
			(hide yes)
			(effects
				(font
					(size 1.27 1.27)
				)
			)
		)
		(property "Value" "0R2J-2-GP"
			(at 0.064008 -3.993896 90)
			(unlocked yes)
			(layer "F.Fab")
			(hide yes)
			(effects
				(font
					(size 1.016 1.016)
					(thickness 0.1524)
				)
			)
		)
		(property "Device Type" "R402H16"
			(at 0.064008 -5.517896 90)
			(unlocked yes)
			(layer "F.Fab")
			(hide yes)
			(effects
				(font
					(size 1.016 1.016)
					(thickness 0.1524)
				)
			)
		)
		(duplicate_pad_numbers_are_jumpers no)
		(fp_line
			(start 0.508 -0.9398)
			(end -0.508 -0.9398)
			(stroke
				(width 0.1524)
				(type default)
			)
			(layer "F.SilkS")
		)
		(fp_line
			(start -0.508 -0.9398)
			(end -0.508 0.9398)
			(stroke
				(width 0.1524)
				(type default)
			)
			(layer "F.SilkS")
		)
		(fp_rect
			(start -0.508 0.9398)
			(end 0.508 -0.9398)
			(stroke
				(width 0)
				(type default)
			)
			(fill no)
			(layer "F.CrtYd")
		)
		(fp_rect
			(start -0.508 0.9398)
			(end 0.508 -0.9398)
			(stroke
				(width 0)
				(type default)
			)
			(fill no)
			(layer "F.Fab")
		)
		(pad "1" smd custom
			(at 0 -0.4445 90)
			(size 0.1397 0.1397)
			(layers "F.Cu" "F.Mask" "F.Paste")
			(net "CLKGEN_OE1_R")
			(options
				(clearance outline)
				(anchor circle)
			)
			(primitives
				(gr_poly
					(pts
						(arc
							(start -0.1778 -0.2794)
							(mid -0.249642 -0.249642)
							(end -0.2794 -0.1778)
						)
						(arc
							(start -0.2794 0.1778)
							(mid -0.249642 0.249642)
							(end -0.1778 0.2794)
						)
						(arc
							(start 0.1778 0.2794)
							(mid 0.249642 0.249642)
							(end 0.2794 0.1778)
						)
						(arc
							(start 0.2794 -0.1778)
							(mid 0.249642 -0.249642)
							(end 0.1778 -0.2794)
						)
					)
					(width 0)
					(fill yes)
				)
			)
		)
		(pad "2" smd custom
			(at 0 0.4445 90)
			(size 0.1397 0.1397)
			(layers "F.Cu" "F.Mask" "F.Paste")
			(net "CLKGEN_OE1")
			(options
				(clearance outline)
				(anchor circle)
			)
			(primitives
				(gr_poly
					(pts
						(arc
							(start -0.1778 -0.2794)
							(mid -0.249642 -0.249642)
							(end -0.2794 -0.1778)
						)
						(arc
							(start -0.2794 0.1778)
							(mid -0.249642 0.249642)
							(end -0.1778 0.2794)
						)
						(arc
							(start 0.1778 0.2794)
							(mid 0.249642 0.249642)
							(end 0.2794 0.1778)
						)
						(arc
							(start 0.2794 -0.1778)
							(mid 0.249642 -0.249642)
							(end 0.1778 -0.2794)
						)
					)
					(width 0)
					(fill yes)
				)
			)
		)
	)
	(footprint ""
		(layer "F.Cu")
		(at 20.955 -135.7122 90)
		(property "Reference" "R289"
			(at 0 0 90)
			(layer "F.SilkS")
			(hide yes)
			(effects
				(font
					(size 1.27 1.27)
				)
			)
		)
		(property "Value" "0R2J-2-GP"
			(at 0.064008 -3.993896 90)
			(unlocked yes)
			(layer "F.Fab")
			(hide yes)
			(effects
				(font
					(size 1.016 1.016)
					(thickness 0.1524)
				)
			)
		)
		(property "Device Type" "R402H16"
			(at 0.064008 -5.517896 90)
			(unlocked yes)
			(layer "F.Fab")
			(hide yes)
			(effects
				(font
					(size 1.016 1.016)
					(thickness 0.1524)
				)
			)
		)
		(duplicate_pad_numbers_are_jumpers no)
		(fp_line
			(start 0.508 -0.9398)
			(end -0.508 -0.9398)
			(stroke
				(width 0.1524)
				(type default)
			)
			(layer "F.SilkS")
		)
		(fp_line
			(start -0.508 -0.9398)
			(end -0.508 0.9398)
			(stroke
				(width 0.1524)
				(type default)
			)
			(layer "F.SilkS")
		)
		(fp_rect
			(start -0.508 0.9398)
			(end 0.508 -0.9398)
			(stroke
				(width 0)
				(type default)
			)
			(fill no)
			(layer "F.CrtYd")
		)
		(fp_rect
			(start -0.508 0.9398)
			(end 0.508 -0.9398)
			(stroke
				(width 0)
				(type default)
			)
			(fill no)
			(layer "F.Fab")
		)
		(pad "1" smd custom
			(at 0 -0.4445 90)
			(size 0.1397 0.1397)
			(layers "F.Cu" "F.Mask" "F.Paste")
			(net "BMC_INT_N")
			(options
				(clearance outline)
				(anchor circle)
			)
			(primitives
				(gr_poly
					(pts
						(arc
							(start -0.1778 -0.2794)
							(mid -0.249642 -0.249642)
							(end -0.2794 -0.1778)
						)
						(arc
							(start -0.2794 0.1778)
							(mid -0.249642 0.249642)
							(end -0.1778 0.2794)
						)
						(arc
							(start 0.1778 0.2794)
							(mid 0.249642 0.249642)
							(end 0.2794 0.1778)
						)
						(arc
							(start 0.2794 -0.1778)
							(mid 0.249642 -0.249642)
							(end 0.1778 -0.2794)
						)
					)
					(width 0)
					(fill yes)
				)
			)
		)
		(pad "2" smd custom
			(at 0 0.4445 90)
			(size 0.1397 0.1397)
			(layers "F.Cu" "F.Mask" "F.Paste")
			(net "GPIOR4_BMC_INT_N_R")
			(options
				(clearance outline)
				(anchor circle)
			)
			(primitives
				(gr_poly
					(pts
						(arc
							(start -0.1778 -0.2794)
							(mid -0.249642 -0.249642)
							(end -0.2794 -0.1778)
						)
						(arc
							(start -0.2794 0.1778)
							(mid -0.249642 0.249642)
							(end -0.1778 0.2794)
						)
						(arc
							(start 0.1778 0.2794)
							(mid 0.249642 0.249642)
							(end 0.2794 0.1778)
						)
						(arc
							(start 0.2794 -0.1778)
							(mid 0.249642 -0.249642)
							(end 0.1778 -0.2794)
						)
					)
					(width 0)
					(fill yes)
				)
			)
		)
	)
	(footprint ""
		(layer "F.Cu")
		(at 175.992028 -212.420454 180)
		(property "Reference" "C128"
			(at 0 0 180)
			(layer "F.SilkS")
			(hide yes)
			(effects
				(font
					(size 1.27 1.27)
				)
			)
		)
		(property "Value" "SCD22U10V2KX-1GP"
			(at 1.1811 -2.7051 180)
			(unlocked yes)
			(layer "F.Fab")
			(hide yes)
			(effects
				(font
					(size 1.016 1.016)
					(thickness 0.1524)
				)
			)
		)
		(property "Device Type" "C402H22"
			(at 1.1811 -4.2291 180)
			(unlocked yes)
			(layer "F.Fab")
			(hide yes)
			(effects
				(font
					(size 1.016 1.016)
					(thickness 0.1524)
				)
			)
		)
		(duplicate_pad_numbers_are_jumpers no)
		(fp_rect
			(start -0.4318 0.9525)
			(end 0.4318 -0.9525)
			(stroke
				(width 0)
				(type default)
			)
			(fill no)
			(layer "F.CrtYd")
		)
		(fp_rect
			(start -0.4318 0.9525)
			(end 0.4318 -0.9525)
			(stroke
				(width 0)
				(type default)
			)
			(fill no)
			(layer "F.Fab")
		)
		(pad "1" smd custom
			(at 0 -0.4445 180)
			(size 0.1524 0.1524)
			(layers "F.Cu" "F.Mask" "F.Paste")
			(net "PCIE_TX_CAP_P48")
			(options
				(clearance outline)
				(anchor circle)
			)
			(primitives
				(gr_poly
					(pts
						(arc
							(start 0.3048 -0.2032)
							(mid 0.275042 -0.275042)
							(end 0.2032 -0.3048)
						)
						(arc
							(start -0.2032 -0.3048)
							(mid -0.275042 -0.275042)
							(end -0.3048 -0.2032)
						)
						(arc
							(start -0.3048 0.2032)
							(mid -0.275042 0.275042)
							(end -0.2032 0.3048)
						)
						(arc
							(start 0.2032 0.3048)
							(mid 0.275042 0.275042)
							(end 0.3048 0.2032)
						)
					)
					(width 0)
					(fill yes)
				)
			)
		)
		(pad "2" smd custom
			(at 0 0.4445 180)
			(size 0.1524 0.1524)
			(layers "F.Cu" "F.Mask" "F.Paste")
			(net "PCIE_TX_P48")
			(options
				(clearance outline)
				(anchor circle)
			)
			(primitives
				(gr_poly
					(pts
						(arc
							(start 0.3048 -0.2032)
							(mid 0.275042 -0.275042)
							(end 0.2032 -0.3048)
						)
						(arc
							(start -0.2032 -0.3048)
							(mid -0.275042 -0.275042)
							(end -0.3048 -0.2032)
						)
						(arc
							(start -0.3048 0.2032)
							(mid -0.275042 0.275042)
							(end -0.2032 0.3048)
						)
						(arc
							(start 0.2032 0.3048)
							(mid 0.275042 0.275042)
							(end 0.3048 0.2032)
						)
					)
					(width 0)
					(fill yes)
				)
			)
		)
	)
	(footprint ""
		(layer "F.Cu")
		(at 273.939 -14.478 90)
		(property "Reference" "C7"
			(at 0 0 90)
			(layer "F.SilkS")
			(hide yes)
			(effects
				(font
					(size 1.27 1.27)
				)
			)
		)
		(property "Value" "SCD22U10V2KX-1GP"
			(at 1.1811 -2.7051 90)
			(unlocked yes)
			(layer "F.Fab")
			(hide yes)
			(effects
				(font
					(size 1.016 1.016)
					(thickness 0.1524)
				)
			)
		)
		(property "Device Type" "C402H22"
			(at 1.1811 -4.2291 90)
			(unlocked yes)
			(layer "F.Fab")
			(hide yes)
			(effects
				(font
					(size 1.016 1.016)
					(thickness 0.1524)
				)
			)
		)
		(duplicate_pad_numbers_are_jumpers no)
		(fp_rect
			(start -0.4318 0.9525)
			(end 0.4318 -0.9525)
			(stroke
				(width 0)
				(type default)
			)
			(fill no)
			(layer "F.CrtYd")
		)
		(fp_rect
			(start -0.4318 0.9525)
			(end 0.4318 -0.9525)
			(stroke
				(width 0)
				(type default)
			)
			(fill no)
			(layer "F.Fab")
		)
		(pad "1" smd custom
			(at 0 -0.4445 90)
			(size 0.1524 0.1524)
			(layers "F.Cu" "F.Mask" "F.Paste")
			(net "PCIE_TX_CAP_P1")
			(options
				(clearance outline)
				(anchor circle)
			)
			(primitives
				(gr_poly
					(pts
						(arc
							(start 0.3048 -0.2032)
							(mid 0.275042 -0.275042)
							(end 0.2032 -0.3048)
						)
						(arc
							(start -0.2032 -0.3048)
							(mid -0.275042 -0.275042)
							(end -0.3048 -0.2032)
						)
						(arc
							(start -0.3048 0.2032)
							(mid -0.275042 0.275042)
							(end -0.2032 0.3048)
						)
						(arc
							(start 0.2032 0.3048)
							(mid 0.275042 0.275042)
							(end 0.3048 0.2032)
						)
					)
					(width 0)
					(fill yes)
				)
			)
		)
		(pad "2" smd custom
			(at 0 0.4445 90)
			(size 0.1524 0.1524)
			(layers "F.Cu" "F.Mask" "F.Paste")
			(net "PCIE_TX_P1")
			(options
				(clearance outline)
				(anchor circle)
			)
			(primitives
				(gr_poly
					(pts
						(arc
							(start 0.3048 -0.2032)
							(mid 0.275042 -0.275042)
							(end 0.2032 -0.3048)
						)
						(arc
							(start -0.2032 -0.3048)
							(mid -0.275042 -0.275042)
							(end -0.3048 -0.2032)
						)
						(arc
							(start -0.3048 0.2032)
							(mid -0.275042 0.275042)
							(end -0.2032 0.3048)
						)
						(arc
							(start 0.2032 0.3048)
							(mid 0.275042 0.275042)
							(end 0.3048 0.2032)
						)
					)
					(width 0)
					(fill yes)
				)
			)
		)
	)
	(footprint ""
		(layer "F.Cu")
		(at 185.600086 -17.500092 -90)
		(property "Reference" "LED19"
			(at 0 0 270)
			(layer "F.SilkS")
			(hide yes)
			(effects
				(font
					(size 1.27 1.27)
				)
			)
		)
		(property "Value" "LED-YG-51-GP"
			(at -2.6924 -1.4224 270)
			(unlocked yes)
			(layer "F.Fab")
			(hide yes)
			(effects
				(font
					(size 1.016 1.016)
					(thickness 0.1524)
				)
			)
		)
		(property "Device Type" "LED1608AKH40"
			(at -2.6924 -2.9464 270)
			(unlocked yes)
			(layer "F.Fab")
			(hide yes)
			(effects
				(font
					(size 1.016 1.016)
					(thickness 0.1524)
				)
			)
		)
		(duplicate_pad_numbers_are_jumpers no)
		(fp_line
			(start -0.7493 1.651)
			(end -0.7493 1.1811)
			(stroke
				(width 0.3302)
				(type default)
			)
			(layer "F.SilkS")
		)
		(fp_line
			(start 0.7493 1.651)
			(end 0.7493 1.1811)
			(stroke
				(width 0.3302)
				(type default)
			)
			(layer "F.SilkS")
		)
		(fp_line
			(start -0.5969 1.5494)
			(end 0.5842 1.5494)
			(stroke
				(width 0.508)
				(type default)
			)
			(layer "F.SilkS")
		)
		(fp_line
			(start -0.6604 1.3716)
			(end -0.6604 -1.3716)
			(stroke
				(width 0.1524)
				(type default)
			)
			(layer "F.SilkS")
		)
		(fp_line
			(start 0.6604 1.3716)
			(end -0.6604 1.3716)
			(stroke
				(width 0.1524)
				(type default)
			)
			(layer "F.SilkS")
		)
		(fp_line
			(start -0.6604 -1.3716)
			(end 0.6604 -1.3716)
			(stroke
				(width 0.1524)
				(type default)
			)
			(layer "F.SilkS")
		)
		(fp_line
			(start 0.6604 -1.3716)
			(end 0.6604 1.3716)
			(stroke
				(width 0.1524)
				(type default)
			)
			(layer "F.SilkS")
		)
		(fp_rect
			(start -0.6223 1.3335)
			(end 0.6223 -1.3335)
			(stroke
				(width 0)
				(type default)
			)
			(fill no)
			(layer "F.CrtYd")
		)
		(fp_rect
			(start -0.6223 1.3335)
			(end 0.6223 -1.3335)
			(stroke
				(width 0)
				(type default)
			)
			(fill no)
			(layer "F.Fab")
		)
		(pad "A" smd custom
			(at 0 -0.762 270)
			(size 0.2159 0.2159)
			(layers "F.Cu" "F.Mask" "F.Paste")
			(net "LED_R_10")
			(options
				(clearance outline)
				(anchor circle)
			)
			(primitives
				(gr_poly
					(pts
						(arc
							(start -0.3302 -0.4318)
							(mid -0.402042 -0.402042)
							(end -0.4318 -0.3302)
						)
						(arc
							(start -0.4318 0.3302)
							(mid -0.402042 0.402042)
							(end -0.3302 0.4318)
						)
						(arc
							(start 0.3302 0.4318)
							(mid 0.402042 0.402042)
							(end 0.4318 0.3302)
						)
						(arc
							(start 0.4318 -0.3302)
							(mid 0.402042 -0.402042)
							(end 0.3302 -0.4318)
						)
					)
					(width 0)
					(fill yes)
				)
			)
		)
		(pad "K" smd custom
			(at 0 0.762 270)
			(size 0.2159 0.2159)
			(layers "F.Cu" "F.Mask" "F.Paste")
			(net "LED_Q_10")
			(options
				(clearance outline)
				(anchor circle)
			)
			(primitives
				(gr_poly
					(pts
						(arc
							(start -0.3302 -0.4318)
							(mid -0.402042 -0.402042)
							(end -0.4318 -0.3302)
						)
						(arc
							(start -0.4318 0.3302)
							(mid -0.402042 0.402042)
							(end -0.3302 0.4318)
						)
						(arc
							(start 0.3302 0.4318)
							(mid 0.402042 0.402042)
							(end 0.4318 0.3302)
						)
						(arc
							(start 0.4318 -0.3302)
							(mid 0.402042 -0.402042)
							(end 0.3302 -0.4318)
						)
					)
					(width 0)
					(fill yes)
				)
			)
		)
	)
	(footprint ""
		(layer "F.Cu")
		(at 345.694 -48.768 180)
		(property "Reference" "PL8"
			(at 0 0 180)
			(layer "F.SilkS")
			(hide yes)
			(effects
				(font
					(size 1.27 1.27)
				)
			)
		)
		(property "Value" "BLM41PG600-GP"
			(at -3.690874 -7.441184 180)
			(unlocked yes)
			(layer "F.Fab")
			(hide yes)
			(effects
				(font
					(size 1.016 1.016)
					(thickness 0.1524)
				)
			)
		)
		(property "Device Type" "L451616H71"
			(at -3.690874 -5.917184 180)
			(unlocked yes)
			(layer "F.Fab")
			(hide yes)
			(effects
				(font
					(size 1.016 1.016)
					(thickness 0.1524)
				)
			)
		)
		(duplicate_pad_numbers_are_jumpers no)
		(fp_line
			(start 2.8702 1.2954)
			(end 2.8702 -1.2954)
			(stroke
				(width 0.1524)
				(type default)
			)
			(layer "F.SilkS")
		)
		(fp_line
			(start 2.8702 1.2954)
			(end 2.8702 -1.2954)
			(stroke
				(width 0.1524)
				(type default)
			)
			(layer "F.SilkS")
		)
		(fp_line
			(start 2.8702 -1.2954)
			(end -2.8702 -1.2954)
			(stroke
				(width 0.1524)
				(type default)
			)
			(layer "F.SilkS")
		)
		(fp_line
			(start 2.8702 -1.2954)
			(end -2.8702 -1.2954)
			(stroke
				(width 0.1524)
				(type default)
			)
			(layer "F.SilkS")
		)
		(fp_line
			(start -2.8702 1.2954)
			(end 2.8702 1.2954)
			(stroke
				(width 0.1524)
				(type default)
			)
			(layer "F.SilkS")
		)
		(fp_line
			(start -2.8702 1.2954)
			(end 2.8702 1.2954)
			(stroke
				(width 0.1524)
				(type default)
			)
			(layer "F.SilkS")
		)
		(fp_line
			(start -2.8702 -1.2954)
			(end -2.8702 1.2954)
			(stroke
				(width 0.1524)
				(type default)
			)
			(layer "F.SilkS")
		)
		(fp_line
			(start -2.8702 -1.2954)
			(end -2.8702 1.2954)
			(stroke
				(width 0.1524)
				(type default)
			)
			(layer "F.SilkS")
		)
		(fp_poly
			(pts
				(xy -2.8702 1.2954) (xy 2.8702 1.2954) (xy 2.8702 -1.2954) (xy -2.8702 -1.2954)
			)
			(stroke
				(width 0)
				(type default)
			)
			(fill no)
			(layer "F.CrtYd")
		)
		(fp_poly
			(pts
				(xy -2.8702 1.2954) (xy 2.8702 1.2954) (xy 2.8702 -1.2954) (xy -2.8702 -1.2954)
			)
			(stroke
				(width 0)
				(type default)
			)
			(fill no)
			(layer "F.Fab")
		)
		(pad "1" smd rect
			(at -1.9685 0 180)
			(size 1.3716 1.8796)
			(layers "F.Cu" "F.Mask" "F.Paste")
			(net "P12V")
		)
		(pad "2" smd rect
			(at 1.9685 0 180)
			(size 1.3716 1.8796)
			(layers "F.Cu" "F.Mask" "F.Paste")
			(net "P0V9_E_VIN")
		)
	)
	(footprint ""
		(layer "F.Cu")
		(at 130.195066 -208.8769 180)
		(property "Reference" "R7941"
			(at 0 0 180)
			(layer "F.SilkS")
			(hide yes)
			(effects
				(font
					(size 1.27 1.27)
				)
			)
		)
		(property "Value" "0R2J-2-GP"
			(at 0.064008 -3.993896 180)
			(unlocked yes)
			(layer "F.Fab")
			(hide yes)
			(effects
				(font
					(size 1.016 1.016)
					(thickness 0.1524)
				)
			)
		)
		(property "Device Type" "R402H16"
			(at 0.064008 -5.517896 180)
			(unlocked yes)
			(layer "F.Fab")
			(hide yes)
			(effects
				(font
					(size 1.016 1.016)
					(thickness 0.1524)
				)
			)
		)
		(duplicate_pad_numbers_are_jumpers no)
		(fp_line
			(start 0.508 -0.9398)
			(end -0.508 -0.9398)
			(stroke
				(width 0.1524)
				(type default)
			)
			(layer "F.SilkS")
		)
		(fp_line
			(start -0.508 -0.9398)
			(end -0.508 0.9398)
			(stroke
				(width 0.1524)
				(type default)
			)
			(layer "F.SilkS")
		)
		(fp_rect
			(start -0.508 0.9398)
			(end 0.508 -0.9398)
			(stroke
				(width 0)
				(type default)
			)
			(fill no)
			(layer "F.CrtYd")
		)
		(fp_rect
			(start -0.508 0.9398)
			(end 0.508 -0.9398)
			(stroke
				(width 0)
				(type default)
			)
			(fill no)
			(layer "F.Fab")
		)
		(pad "1" smd custom
			(at 0 -0.4445 180)
			(size 0.1397 0.1397)
			(layers "F.Cu" "F.Mask" "F.Paste")
			(net "SSD_ATNLED#7")
			(options
				(clearance outline)
				(anchor circle)
			)
			(primitives
				(gr_poly
					(pts
						(arc
							(start -0.1778 -0.2794)
							(mid -0.249642 -0.249642)
							(end -0.2794 -0.1778)
						)
						(arc
							(start -0.2794 0.1778)
							(mid -0.249642 0.249642)
							(end -0.1778 0.2794)
						)
						(arc
							(start 0.1778 0.2794)
							(mid 0.249642 0.249642)
							(end 0.2794 0.1778)
						)
						(arc
							(start 0.2794 -0.1778)
							(mid 0.249642 -0.249642)
							(end 0.1778 -0.2794)
						)
					)
					(width 0)
					(fill yes)
				)
			)
		)
		(pad "2" smd custom
			(at 0 0.4445 180)
			(size 0.1397 0.1397)
			(layers "F.Cu" "F.Mask" "F.Paste")
			(net "SSD_ATNLED#7_R")
			(options
				(clearance outline)
				(anchor circle)
			)
			(primitives
				(gr_poly
					(pts
						(arc
							(start -0.1778 -0.2794)
							(mid -0.249642 -0.249642)
							(end -0.2794 -0.1778)
						)
						(arc
							(start -0.2794 0.1778)
							(mid -0.249642 0.249642)
							(end -0.1778 0.2794)
						)
						(arc
							(start 0.1778 0.2794)
							(mid 0.249642 0.249642)
							(end 0.2794 0.1778)
						)
						(arc
							(start 0.2794 -0.1778)
							(mid 0.249642 -0.249642)
							(end 0.1778 -0.2794)
						)
					)
					(width 0)
					(fill yes)
				)
			)
		)
	)
	(footprint ""
		(layer "F.Cu")
		(at 35.28822 -118.27764)
		(property "Reference" "TP233"
			(at 0 0 0)
			(layer "F.SilkS")
			(hide yes)
			(effects
				(font
					(size 1.27 1.27)
				)
			)
		)
		(property "Value" "TPAD28-2-GP"
			(at -0.0127 -1.6637 0)
			(unlocked yes)
			(layer "F.Fab")
			(hide yes)
			(effects
				(font
					(size 1.016 1.016)
					(thickness 0.1524)
				)
			)
		)
		(property "Device Type" "TPAD28"
			(at -0.0127 -3.1877 0)
			(unlocked yes)
			(layer "F.Fab")
			(hide yes)
			(effects
				(font
					(size 1.016 1.016)
					(thickness 0.1524)
				)
			)
		)
		(duplicate_pad_numbers_are_jumpers no)
		(fp_poly
			(pts
				(arc
					(start 0.3556 0)
					(mid -0.3556 0)
					(end 0.3556 0)
				)
			)
			(stroke
				(width 0)
				(type default)
			)
			(fill no)
			(layer "F.CrtYd")
		)
		(fp_poly
			(pts
				(arc
					(start 0.6096 0)
					(mid -0.6096 0)
					(end 0.6096 0)
				)
			)
			(stroke
				(width 0)
				(type default)
			)
			(fill no)
			(layer "F.Fab")
		)
		(pad "1" smd circle
			(at 0 0)
			(size 0.7112 0.7112)
			(layers "F.Cu" "F.Mask" "F.Paste")
			(net "TP_GPIOE3")
		)
	)
	(footprint ""
		(layer "F.Cu")
		(at 88.9 -45.0342)
		(property "Reference" "PG9"
			(at 0 0 0)
			(layer "F.SilkS")
			(hide yes)
			(effects
				(font
					(size 1.27 1.27)
				)
			)
		)
		(property "Value" "GAP-CLOSE-PWR-3-GP"
			(at 0.0254 -6.5786 0)
			(unlocked yes)
			(layer "F.Fab")
			(hide yes)
			(effects
				(font
					(size 1.016 1.016)
					(thickness 0.1524)
				)
			)
		)
		(property "Device Type" "GAP-CLOSE-PWR-3"
			(at 0.0254 -8.255 0)
			(unlocked yes)
			(layer "F.Fab")
			(hide yes)
			(effects
				(font
					(size 1.016 1.016)
					(thickness 0.1524)
				)
			)
		)
		(duplicate_pad_numbers_are_jumpers no)
		(fp_rect
			(start -0.7112 0.4572)
			(end 0.7112 -0.4572)
			(stroke
				(width 0)
				(type default)
			)
			(fill no)
			(layer "F.CrtYd")
		)
		(fp_poly
			(pts
				(xy -0.7112 -0.4572) (xy 0.7112 -0.4572) (xy 0.7112 0.4572) (xy -0.7112 0.4572)
			)
			(stroke
				(width 0)
				(type default)
			)
			(fill no)
			(layer "F.Fab")
		)
		(pad "1" smd rect
			(at -0.3048 0)
			(size 0.6604 0.762)
			(layers "F.Cu" "F.Mask" "F.Paste")
			(net "P3V3_PWR")
		)
		(pad "2" smd rect
			(at 0.3048 0)
			(size 0.6604 0.762)
			(layers "F.Cu" "F.Mask" "F.Paste")
			(net "P3V3_STBY")
		)
	)
	(footprint ""
		(layer "F.Cu")
		(at 325.918322 -33.45942)
		(property "Reference" "C50"
			(at 0 0 0)
			(layer "F.SilkS")
			(hide yes)
			(effects
				(font
					(size 1.27 1.27)
				)
			)
		)
		(property "Value" "SCD22U10V2KX-1GP"
			(at 1.1811 -2.7051 0)
			(unlocked yes)
			(layer "F.Fab")
			(hide yes)
			(effects
				(font
					(size 1.016 1.016)
					(thickness 0.1524)
				)
			)
		)
		(property "Device Type" "C402H22"
			(at 1.1811 -4.2291 0)
			(unlocked yes)
			(layer "F.Fab")
			(hide yes)
			(effects
				(font
					(size 1.016 1.016)
					(thickness 0.1524)
				)
			)
		)
		(duplicate_pad_numbers_are_jumpers no)
		(fp_rect
			(start -0.4318 0.9525)
			(end 0.4318 -0.9525)
			(stroke
				(width 0)
				(type default)
			)
			(fill no)
			(layer "F.CrtYd")
		)
		(fp_rect
			(start -0.4318 0.9525)
			(end 0.4318 -0.9525)
			(stroke
				(width 0)
				(type default)
			)
			(fill no)
			(layer "F.Fab")
		)
		(pad "1" smd custom
			(at 0 -0.4445)
			(size 0.1524 0.1524)
			(layers "F.Cu" "F.Mask" "F.Paste")
			(net "PCIE_TX_CAP_P14")
			(options
				(clearance outline)
				(anchor circle)
			)
			(primitives
				(gr_poly
					(pts
						(arc
							(start 0.3048 -0.2032)
							(mid 0.275042 -0.275042)
							(end 0.2032 -0.3048)
						)
						(arc
							(start -0.2032 -0.3048)
							(mid -0.275042 -0.275042)
							(end -0.3048 -0.2032)
						)
						(arc
							(start -0.3048 0.2032)
							(mid -0.275042 0.275042)
							(end -0.2032 0.3048)
						)
						(arc
							(start 0.2032 0.3048)
							(mid 0.275042 0.275042)
							(end 0.3048 0.2032)
						)
					)
					(width 0)
					(fill yes)
				)
			)
		)
		(pad "2" smd custom
			(at 0 0.4445)
			(size 0.1524 0.1524)
			(layers "F.Cu" "F.Mask" "F.Paste")
			(net "PCIE_TX_P14")
			(options
				(clearance outline)
				(anchor circle)
			)
			(primitives
				(gr_poly
					(pts
						(arc
							(start 0.3048 -0.2032)
							(mid 0.275042 -0.275042)
							(end 0.2032 -0.3048)
						)
						(arc
							(start -0.2032 -0.3048)
							(mid -0.275042 -0.275042)
							(end -0.3048 -0.2032)
						)
						(arc
							(start -0.3048 0.2032)
							(mid -0.275042 0.275042)
							(end -0.2032 0.3048)
						)
						(arc
							(start 0.2032 0.3048)
							(mid 0.275042 0.275042)
							(end 0.3048 0.2032)
						)
					)
					(width 0)
					(fill yes)
				)
			)
		)
	)
	(footprint ""
		(layer "F.Cu")
		(at 20.3454 -184.7342 -90)
		(property "Reference" "R2123"
			(at 0 0 270)
			(layer "F.SilkS")
			(hide yes)
			(effects
				(font
					(size 1.27 1.27)
				)
			)
		)
		(property "Value" "10R2F-L-GP"
			(at 0.064008 -3.993896 270)
			(unlocked yes)
			(layer "F.Fab")
			(hide yes)
			(effects
				(font
					(size 1.016 1.016)
					(thickness 0.1524)
				)
			)
		)
		(property "Device Type" "R402H14"
			(at 0.064008 -5.517896 270)
			(unlocked yes)
			(layer "F.Fab")
			(hide yes)
			(effects
				(font
					(size 1.016 1.016)
					(thickness 0.1524)
				)
			)
		)
		(duplicate_pad_numbers_are_jumpers no)
		(fp_line
			(start -0.508 -0.9398)
			(end -0.508 0.9398)
			(stroke
				(width 0.1524)
				(type default)
			)
			(layer "F.SilkS")
		)
		(fp_line
			(start 0.508 -0.9398)
			(end -0.508 -0.9398)
			(stroke
				(width 0.1524)
				(type default)
			)
			(layer "F.SilkS")
		)
		(fp_rect
			(start -0.508 0.9398)
			(end 0.508 -0.9398)
			(stroke
				(width 0)
				(type default)
			)
			(fill no)
			(layer "F.CrtYd")
		)
		(fp_rect
			(start -0.508 0.9398)
			(end 0.508 -0.9398)
			(stroke
				(width 0)
				(type default)
			)
			(fill no)
			(layer "F.Fab")
		)
		(pad "1" smd custom
			(at 0 -0.4445 270)
			(size 0.1397 0.1397)
			(layers "F.Cu" "F.Mask" "F.Paste")
			(net "MB0_CM_SENSE_R1_N")
			(options
				(clearance outline)
				(anchor circle)
			)
			(primitives
				(gr_poly
					(pts
						(arc
							(start -0.1778 -0.2794)
							(mid -0.249642 -0.249642)
							(end -0.2794 -0.1778)
						)
						(arc
							(start -0.2794 0.1778)
							(mid -0.249642 0.249642)
							(end -0.1778 0.2794)
						)
						(arc
							(start 0.1778 0.2794)
							(mid 0.249642 0.249642)
							(end 0.2794 0.1778)
						)
						(arc
							(start 0.2794 -0.1778)
							(mid 0.249642 -0.249642)
							(end 0.1778 -0.2794)
						)
					)
					(width 0)
					(fill yes)
				)
			)
		)
		(pad "2" smd custom
			(at 0 0.4445 270)
			(size 0.1397 0.1397)
			(layers "F.Cu" "F.Mask" "F.Paste")
			(net "ADM1278_HS_N")
			(options
				(clearance outline)
				(anchor circle)
			)
			(primitives
				(gr_poly
					(pts
						(arc
							(start -0.1778 -0.2794)
							(mid -0.249642 -0.249642)
							(end -0.2794 -0.1778)
						)
						(arc
							(start -0.2794 0.1778)
							(mid -0.249642 0.249642)
							(end -0.1778 0.2794)
						)
						(arc
							(start 0.1778 0.2794)
							(mid 0.249642 0.249642)
							(end 0.2794 0.1778)
						)
						(arc
							(start 0.2794 -0.1778)
							(mid 0.249642 -0.249642)
							(end 0.1778 -0.2794)
						)
					)
					(width 0)
					(fill yes)
				)
			)
		)
	)
	(footprint ""
		(layer "F.Cu")
		(at 276.607016 -10.384282 90)
		(property "Reference" "R2902"
			(at 0 0 90)
			(layer "F.SilkS")
			(hide yes)
			(effects
				(font
					(size 1.27 1.27)
				)
			)
		)
		(property "Value" "0R2J-2-GP"
			(at 0.064008 -3.993896 90)
			(unlocked yes)
			(layer "F.Fab")
			(hide yes)
			(effects
				(font
					(size 1.016 1.016)
					(thickness 0.1524)
				)
			)
		)
		(property "Device Type" "R402H16"
			(at 0.064008 -5.517896 90)
			(unlocked yes)
			(layer "F.Fab")
			(hide yes)
			(effects
				(font
					(size 1.016 1.016)
					(thickness 0.1524)
				)
			)
		)
		(duplicate_pad_numbers_are_jumpers no)
		(fp_line
			(start 0.508 -0.9398)
			(end -0.508 -0.9398)
			(stroke
				(width 0.1524)
				(type default)
			)
			(layer "F.SilkS")
		)
		(fp_line
			(start -0.508 -0.9398)
			(end -0.508 0.9398)
			(stroke
				(width 0.1524)
				(type default)
			)
			(layer "F.SilkS")
		)
		(fp_rect
			(start -0.508 0.9398)
			(end 0.508 -0.9398)
			(stroke
				(width 0)
				(type default)
			)
			(fill no)
			(layer "F.CrtYd")
		)
		(fp_rect
			(start -0.508 0.9398)
			(end 0.508 -0.9398)
			(stroke
				(width 0)
				(type default)
			)
			(fill no)
			(layer "F.Fab")
		)
		(pad "1" smd custom
			(at 0 -0.4445 90)
			(size 0.1397 0.1397)
			(layers "F.Cu" "F.Mask" "F.Paste")
			(net "CBL_PRSNT_N_5")
			(options
				(clearance outline)
				(anchor circle)
			)
			(primitives
				(gr_poly
					(pts
						(arc
							(start -0.1778 -0.2794)
							(mid -0.249642 -0.249642)
							(end -0.2794 -0.1778)
						)
						(arc
							(start -0.2794 0.1778)
							(mid -0.249642 0.249642)
							(end -0.1778 0.2794)
						)
						(arc
							(start 0.1778 0.2794)
							(mid 0.249642 0.249642)
							(end 0.2794 0.1778)
						)
						(arc
							(start 0.2794 -0.1778)
							(mid 0.249642 -0.249642)
							(end 0.1778 -0.2794)
						)
					)
					(width 0)
					(fill yes)
				)
			)
		)
		(pad "2" smd custom
			(at 0 0.4445 90)
			(size 0.1397 0.1397)
			(layers "F.Cu" "F.Mask" "F.Paste")
			(net "8644_CBL_PRSNT_R_5")
			(options
				(clearance outline)
				(anchor circle)
			)
			(primitives
				(gr_poly
					(pts
						(arc
							(start -0.1778 -0.2794)
							(mid -0.249642 -0.249642)
							(end -0.2794 -0.1778)
						)
						(arc
							(start -0.2794 0.1778)
							(mid -0.249642 0.249642)
							(end -0.1778 0.2794)
						)
						(arc
							(start 0.1778 0.2794)
							(mid 0.249642 0.249642)
							(end 0.2794 0.1778)
						)
						(arc
							(start 0.2794 -0.1778)
							(mid 0.249642 -0.249642)
							(end 0.1778 -0.2794)
						)
					)
					(width 0)
					(fill yes)
				)
			)
		)
	)
	(footprint ""
		(layer "F.Cu")
		(at 58.928 -149.86 -90)
		(property "Reference" "R162"
			(at 0 0 270)
			(layer "F.SilkS")
			(hide yes)
			(effects
				(font
					(size 1.27 1.27)
				)
			)
		)
		(property "Value" "0R2J-2-GP"
			(at 0.064008 -3.993896 270)
			(unlocked yes)
			(layer "F.Fab")
			(hide yes)
			(effects
				(font
					(size 1.016 1.016)
					(thickness 0.1524)
				)
			)
		)
		(property "Device Type" "R402H16"
			(at 0.064008 -5.517896 270)
			(unlocked yes)
			(layer "F.Fab")
			(hide yes)
			(effects
				(font
					(size 1.016 1.016)
					(thickness 0.1524)
				)
			)
		)
		(duplicate_pad_numbers_are_jumpers no)
		(fp_line
			(start -0.508 -0.9398)
			(end -0.508 0.9398)
			(stroke
				(width 0.1524)
				(type default)
			)
			(layer "F.SilkS")
		)
		(fp_line
			(start 0.508 -0.9398)
			(end -0.508 -0.9398)
			(stroke
				(width 0.1524)
				(type default)
			)
			(layer "F.SilkS")
		)
		(fp_rect
			(start -0.508 0.9398)
			(end 0.508 -0.9398)
			(stroke
				(width 0)
				(type default)
			)
			(fill no)
			(layer "F.CrtYd")
		)
		(fp_rect
			(start -0.508 0.9398)
			(end 0.508 -0.9398)
			(stroke
				(width 0)
				(type default)
			)
			(fill no)
			(layer "F.Fab")
		)
		(pad "1" smd custom
			(at 0 -0.4445 270)
			(size 0.1397 0.1397)
			(layers "F.Cu" "F.Mask" "F.Paste")
			(net "BMC_I2C5_D_PEB_SCL")
			(options
				(clearance outline)
				(anchor circle)
			)
			(primitives
				(gr_poly
					(pts
						(arc
							(start -0.1778 -0.2794)
							(mid -0.249642 -0.249642)
							(end -0.2794 -0.1778)
						)
						(arc
							(start -0.2794 0.1778)
							(mid -0.249642 0.249642)
							(end -0.1778 0.2794)
						)
						(arc
							(start 0.1778 0.2794)
							(mid 0.249642 0.249642)
							(end 0.2794 0.1778)
						)
						(arc
							(start 0.2794 -0.1778)
							(mid 0.249642 -0.249642)
							(end 0.1778 -0.2794)
						)
					)
					(width 0)
					(fill yes)
				)
			)
		)
		(pad "2" smd custom
			(at 0 0.4445 270)
			(size 0.1397 0.1397)
			(layers "F.Cu" "F.Mask" "F.Paste")
			(net "TEMP_2_SCL")
			(options
				(clearance outline)
				(anchor circle)
			)
			(primitives
				(gr_poly
					(pts
						(arc
							(start -0.1778 -0.2794)
							(mid -0.249642 -0.249642)
							(end -0.2794 -0.1778)
						)
						(arc
							(start -0.2794 0.1778)
							(mid -0.249642 0.249642)
							(end -0.1778 0.2794)
						)
						(arc
							(start 0.1778 0.2794)
							(mid 0.249642 0.249642)
							(end 0.2794 0.1778)
						)
						(arc
							(start 0.2794 -0.1778)
							(mid 0.249642 -0.249642)
							(end 0.1778 -0.2794)
						)
					)
					(width 0)
					(fill yes)
				)
			)
		)
	)
	(footprint ""
		(layer "F.Cu")
		(at 37.084 -93.726 180)
		(property "Reference" "R49"
			(at 0 0 180)
			(layer "F.SilkS")
			(hide yes)
			(effects
				(font
					(size 1.27 1.27)
				)
			)
		)
		(property "Value" "0R2J-2-GP"
			(at 0.064008 -3.993896 180)
			(unlocked yes)
			(layer "F.Fab")
			(hide yes)
			(effects
				(font
					(size 1.016 1.016)
					(thickness 0.1524)
				)
			)
		)
		(property "Device Type" "R402H16"
			(at 0.064008 -5.517896 180)
			(unlocked yes)
			(layer "F.Fab")
			(hide yes)
			(effects
				(font
					(size 1.016 1.016)
					(thickness 0.1524)
				)
			)
		)
		(duplicate_pad_numbers_are_jumpers no)
		(fp_line
			(start 0.508 -0.9398)
			(end -0.508 -0.9398)
			(stroke
				(width 0.1524)
				(type default)
			)
			(layer "F.SilkS")
		)
		(fp_line
			(start -0.508 -0.9398)
			(end -0.508 0.9398)
			(stroke
				(width 0.1524)
				(type default)
			)
			(layer "F.SilkS")
		)
		(fp_rect
			(start -0.508 0.9398)
			(end 0.508 -0.9398)
			(stroke
				(width 0)
				(type default)
			)
			(fill no)
			(layer "F.CrtYd")
		)
		(fp_rect
			(start -0.508 0.9398)
			(end 0.508 -0.9398)
			(stroke
				(width 0)
				(type default)
			)
			(fill no)
			(layer "F.Fab")
		)
		(pad "1" smd custom
			(at 0 -0.4445 180)
			(size 0.1397 0.1397)
			(layers "F.Cu" "F.Mask" "F.Paste")
			(net "NVM_SO_R")
			(options
				(clearance outline)
				(anchor circle)
			)
			(primitives
				(gr_poly
					(pts
						(arc
							(start -0.1778 -0.2794)
							(mid -0.249642 -0.249642)
							(end -0.2794 -0.1778)
						)
						(arc
							(start -0.2794 0.1778)
							(mid -0.249642 0.249642)
							(end -0.1778 0.2794)
						)
						(arc
							(start 0.1778 0.2794)
							(mid 0.249642 0.249642)
							(end 0.2794 0.1778)
						)
						(arc
							(start 0.2794 -0.1778)
							(mid 0.249642 -0.249642)
							(end 0.1778 -0.2794)
						)
					)
					(width 0)
					(fill yes)
				)
			)
		)
		(pad "2" smd custom
			(at 0 0.4445 180)
			(size 0.1397 0.1397)
			(layers "F.Cu" "F.Mask" "F.Paste")
			(net "I2C_MUX_3A")
			(options
				(clearance outline)
				(anchor circle)
			)
			(primitives
				(gr_poly
					(pts
						(arc
							(start -0.1778 -0.2794)
							(mid -0.249642 -0.249642)
							(end -0.2794 -0.1778)
						)
						(arc
							(start -0.2794 0.1778)
							(mid -0.249642 0.249642)
							(end -0.1778 0.2794)
						)
						(arc
							(start 0.1778 0.2794)
							(mid 0.249642 0.249642)
							(end 0.2794 0.1778)
						)
						(arc
							(start 0.2794 -0.1778)
							(mid 0.249642 -0.249642)
							(end 0.1778 -0.2794)
						)
					)
					(width 0)
					(fill yes)
				)
			)
		)
	)
	(footprint ""
		(layer "F.Cu")
		(at 37.193474 -114.751612 180)
		(property "Reference" "R556"
			(at 0 0 180)
			(layer "F.SilkS")
			(hide yes)
			(effects
				(font
					(size 1.27 1.27)
				)
			)
		)
		(property "Value" "10KR2F-2-GP"
			(at 0.064008 -3.993896 180)
			(unlocked yes)
			(layer "F.Fab")
			(hide yes)
			(effects
				(font
					(size 1.016 1.016)
					(thickness 0.1524)
				)
			)
		)
		(property "Device Type" "R402H16"
			(at 0.064008 -5.517896 180)
			(unlocked yes)
			(layer "F.Fab")
			(hide yes)
			(effects
				(font
					(size 1.016 1.016)
					(thickness 0.1524)
				)
			)
		)
		(duplicate_pad_numbers_are_jumpers no)
		(fp_line
			(start 0.508 -0.9398)
			(end -0.508 -0.9398)
			(stroke
				(width 0.1524)
				(type default)
			)
			(layer "F.SilkS")
		)
		(fp_line
			(start -0.508 -0.9398)
			(end -0.508 0.9398)
			(stroke
				(width 0.1524)
				(type default)
			)
			(layer "F.SilkS")
		)
		(fp_rect
			(start -0.508 0.9398)
			(end 0.508 -0.9398)
			(stroke
				(width 0)
				(type default)
			)
			(fill no)
			(layer "F.CrtYd")
		)
		(fp_rect
			(start -0.508 0.9398)
			(end 0.508 -0.9398)
			(stroke
				(width 0)
				(type default)
			)
			(fill no)
			(layer "F.Fab")
		)
		(pad "1" smd custom
			(at 0 -0.4445 180)
			(size 0.1397 0.1397)
			(layers "F.Cu" "F.Mask" "F.Paste")
			(net "GND")
			(options
				(clearance outline)
				(anchor circle)
			)
			(primitives
				(gr_poly
					(pts
						(arc
							(start -0.1778 -0.2794)
							(mid -0.249642 -0.249642)
							(end -0.2794 -0.1778)
						)
						(arc
							(start -0.2794 0.1778)
							(mid -0.249642 0.249642)
							(end -0.1778 0.2794)
						)
						(arc
							(start 0.1778 0.2794)
							(mid 0.249642 0.249642)
							(end 0.2794 0.1778)
						)
						(arc
							(start 0.2794 -0.1778)
							(mid 0.249642 -0.249642)
							(end 0.1778 -0.2794)
						)
					)
					(width 0)
					(fill yes)
				)
			)
		)
		(pad "2" smd custom
			(at 0 0.4445 180)
			(size 0.1397 0.1397)
			(layers "F.Cu" "F.Mask" "F.Paste")
			(net "RMII_BMC_CRS_DV")
			(options
				(clearance outline)
				(anchor circle)
			)
			(primitives
				(gr_poly
					(pts
						(arc
							(start -0.1778 -0.2794)
							(mid -0.249642 -0.249642)
							(end -0.2794 -0.1778)
						)
						(arc
							(start -0.2794 0.1778)
							(mid -0.249642 0.249642)
							(end -0.1778 0.2794)
						)
						(arc
							(start 0.1778 0.2794)
							(mid 0.249642 0.249642)
							(end 0.2794 0.1778)
						)
						(arc
							(start 0.2794 -0.1778)
							(mid 0.249642 -0.249642)
							(end 0.1778 -0.2794)
						)
					)
					(width 0)
					(fill yes)
				)
			)
		)
	)
	(footprint ""
		(layer "F.Cu")
		(at 70.715124 -195.681092)
		(property "Reference" "R7913"
			(at 0 0 0)
			(layer "F.SilkS")
			(hide yes)
			(effects
				(font
					(size 1.27 1.27)
				)
			)
		)
		(property "Value" "0R2J-2-GP"
			(at 0.064008 -3.993896 0)
			(unlocked yes)
			(layer "F.Fab")
			(hide yes)
			(effects
				(font
					(size 1.016 1.016)
					(thickness 0.1524)
				)
			)
		)
		(property "Device Type" "R402H16"
			(at 0.064008 -5.517896 0)
			(unlocked yes)
			(layer "F.Fab")
			(hide yes)
			(effects
				(font
					(size 1.016 1.016)
					(thickness 0.1524)
				)
			)
		)
		(duplicate_pad_numbers_are_jumpers no)
		(fp_line
			(start -0.508 -0.9398)
			(end -0.508 0.9398)
			(stroke
				(width 0.1524)
				(type default)
			)
			(layer "F.SilkS")
		)
		(fp_line
			(start 0.508 -0.9398)
			(end -0.508 -0.9398)
			(stroke
				(width 0.1524)
				(type default)
			)
			(layer "F.SilkS")
		)
		(fp_rect
			(start -0.508 0.9398)
			(end 0.508 -0.9398)
			(stroke
				(width 0)
				(type default)
			)
			(fill no)
			(layer "F.CrtYd")
		)
		(fp_rect
			(start -0.508 0.9398)
			(end 0.508 -0.9398)
			(stroke
				(width 0)
				(type default)
			)
			(fill no)
			(layer "F.Fab")
		)
		(pad "1" smd custom
			(at 0 -0.4445)
			(size 0.1397 0.1397)
			(layers "F.Cu" "F.Mask" "F.Paste")
			(net "TWI_SCL1")
			(options
				(clearance outline)
				(anchor circle)
			)
			(primitives
				(gr_poly
					(pts
						(arc
							(start -0.1778 -0.2794)
							(mid -0.249642 -0.249642)
							(end -0.2794 -0.1778)
						)
						(arc
							(start -0.2794 0.1778)
							(mid -0.249642 0.249642)
							(end -0.1778 0.2794)
						)
						(arc
							(start 0.1778 0.2794)
							(mid 0.249642 0.249642)
							(end 0.2794 0.1778)
						)
						(arc
							(start 0.2794 -0.1778)
							(mid 0.249642 -0.249642)
							(end 0.1778 -0.2794)
						)
					)
					(width 0)
					(fill yes)
				)
			)
		)
		(pad "2" smd custom
			(at 0 0.4445)
			(size 0.1397 0.1397)
			(layers "F.Cu" "F.Mask" "F.Paste")
			(net "I2C_GPIO_SCL_1")
			(options
				(clearance outline)
				(anchor circle)
			)
			(primitives
				(gr_poly
					(pts
						(arc
							(start -0.1778 -0.2794)
							(mid -0.249642 -0.249642)
							(end -0.2794 -0.1778)
						)
						(arc
							(start -0.2794 0.1778)
							(mid -0.249642 0.249642)
							(end -0.1778 0.2794)
						)
						(arc
							(start 0.1778 0.2794)
							(mid 0.249642 0.249642)
							(end 0.2794 0.1778)
						)
						(arc
							(start 0.2794 -0.1778)
							(mid 0.249642 -0.249642)
							(end 0.1778 -0.2794)
						)
					)
					(width 0)
					(fill yes)
				)
			)
		)
	)
	(footprint ""
		(layer "F.Cu")
		(at 30.9626 -185.3692 180)
		(property "Reference" "U34"
			(at 0 0 180)
			(layer "F.SilkS")
			(hide yes)
			(effects
				(font
					(size 1.27 1.27)
				)
			)
		)
		(property "Value" "PCA9511ADP-T-GP"
			(at 0 -13.1572 180)
			(unlocked yes)
			(layer "F.Fab")
			(hide yes)
			(effects
				(font
					(size 1.016 1.016)
					(thickness 0.1524)
				)
			)
		)
		(property "Device Type" "SSOIC8-2H44"
			(at 0 -15.1892 180)
			(unlocked yes)
			(layer "F.Fab")
			(hide yes)
			(effects
				(font
					(size 1.016 1.016)
					(thickness 0.1524)
				)
			)
		)
		(duplicate_pad_numbers_are_jumpers no)
		(fp_line
			(start 1.0922 1.016)
			(end -1.9304 1.016)
			(stroke
				(width 0.1524)
				(type default)
			)
			(layer "F.SilkS")
		)
		(fp_line
			(start 1.0922 -1.016)
			(end 1.0922 1.016)
			(stroke
				(width 0.1524)
				(type default)
			)
			(layer "F.SilkS")
		)
		(fp_line
			(start -1.524 0)
			(end -1.9304 0.4064)
			(stroke
				(width 0.1524)
				(type default)
			)
			(layer "F.SilkS")
		)
		(fp_line
			(start -1.524 0)
			(end -1.9304 -0.4064)
			(stroke
				(width 0.1524)
				(type default)
			)
			(layer "F.SilkS")
		)
		(fp_line
			(start -1.7018 1.0414)
			(end -1.7018 2.9718)
			(stroke
				(width 0.635)
				(type default)
			)
			(layer "F.SilkS")
		)
		(fp_line
			(start -1.9304 1.016)
			(end -1.9304 -1.016)
			(stroke
				(width 0.1524)
				(type default)
			)
			(layer "F.SilkS")
		)
		(fp_line
			(start -1.9304 -1.016)
			(end 1.0922 -1.016)
			(stroke
				(width 0.1524)
				(type default)
			)
			(layer "F.SilkS")
		)
		(fp_poly
			(pts
				(xy -1.1938 -1.016) (xy 1.0922 -1.016) (xy 1.0922 1.016) (xy -1.1938 1.016)
			)
			(stroke
				(width 0)
				(type default)
			)
			(fill yes)
			(layer "F.SilkS")
		)
		(fp_rect
			(start -2.0066 3.3401)
			(end 2.0066 -3.3401)
			(stroke
				(width 0)
				(type default)
			)
			(fill no)
			(layer "F.CrtYd")
		)
		(fp_poly
			(pts
				(xy -2.0066 -3.3401) (xy 2.0066 -3.3401) (xy 2.0066 3.3401) (xy -2.0066 3.3401)
			)
			(stroke
				(width 0)
				(type default)
			)
			(fill no)
			(layer "F.Fab")
		)
		(pad "1" smd rect
			(at -0.97536 2.0701 180)
			(size 0.4064 1.524)
			(layers "F.Cu" "F.Mask" "F.Paste")
			(net "I2C5_BUFF_EN")
		)
		(pad "2" smd rect
			(at -0.32512 2.0701 180)
			(size 0.4064 1.524)
			(layers "F.Cu" "F.Mask" "F.Paste")
			(net "BUF_I2C5_SCL_R")
		)
		(pad "3" smd rect
			(at 0.32512 2.0701 180)
			(size 0.4064 1.524)
			(layers "F.Cu" "F.Mask" "F.Paste")
			(net "BMC_I2C5_SCL_R")
		)
		(pad "4" smd rect
			(at 0.97536 2.0701 180)
			(size 0.4064 1.524)
			(layers "F.Cu" "F.Mask" "F.Paste")
			(net "GND")
		)
		(pad "5" smd rect
			(at 0.97536 -2.0701 180)
			(size 0.4064 1.524)
			(layers "F.Cu" "F.Mask" "F.Paste")
			(net "BMC_I2C5_BUF_READY")
		)
		(pad "6" smd rect
			(at 0.32512 -2.0701 180)
			(size 0.4064 1.524)
			(layers "F.Cu" "F.Mask" "F.Paste")
			(net "BMC_I2C5_SDA_R")
		)
		(pad "7" smd rect
			(at -0.32512 -2.0701 180)
			(size 0.4064 1.524)
			(layers "F.Cu" "F.Mask" "F.Paste")
			(net "BUF_I2C5_SDA_R")
		)
		(pad "8" smd rect
			(at -0.97536 -2.0701 180)
			(size 0.4064 1.524)
			(layers "F.Cu" "F.Mask" "F.Paste")
			(net "P3V3_STBY")
		)
	)
	(footprint ""
		(layer "F.Cu")
		(at 26.4287 -33.89884)
		(property "Reference" "C420"
			(at 0 0 0)
			(layer "F.SilkS")
			(hide yes)
			(effects
				(font
					(size 1.27 1.27)
				)
			)
		)
		(property "Value" "SCD1U16V2KX-3GP"
			(at 1.1811 -2.7051 0)
			(unlocked yes)
			(layer "F.Fab")
			(hide yes)
			(effects
				(font
					(size 1.016 1.016)
					(thickness 0.1524)
				)
			)
		)
		(property "Device Type" "C402H22"
			(at 1.1811 -4.2291 0)
			(unlocked yes)
			(layer "F.Fab")
			(hide yes)
			(effects
				(font
					(size 1.016 1.016)
					(thickness 0.1524)
				)
			)
		)
		(duplicate_pad_numbers_are_jumpers no)
		(fp_rect
			(start -0.4318 0.9525)
			(end 0.4318 -0.9525)
			(stroke
				(width 0)
				(type default)
			)
			(fill no)
			(layer "F.CrtYd")
		)
		(fp_rect
			(start -0.4318 0.9525)
			(end 0.4318 -0.9525)
			(stroke
				(width 0)
				(type default)
			)
			(fill no)
			(layer "F.Fab")
		)
		(pad "1" smd custom
			(at 0 -0.4445)
			(size 0.1524 0.1524)
			(layers "F.Cu" "F.Mask" "F.Paste")
			(net "LED_MDI0_100M_N_R")
			(options
				(clearance outline)
				(anchor circle)
			)
			(primitives
				(gr_poly
					(pts
						(arc
							(start 0.3048 -0.2032)
							(mid 0.275042 -0.275042)
							(end 0.2032 -0.3048)
						)
						(arc
							(start -0.2032 -0.3048)
							(mid -0.275042 -0.275042)
							(end -0.3048 -0.2032)
						)
						(arc
							(start -0.3048 0.2032)
							(mid -0.275042 0.275042)
							(end -0.2032 0.3048)
						)
						(arc
							(start 0.2032 0.3048)
							(mid 0.275042 0.275042)
							(end 0.3048 0.2032)
						)
					)
					(width 0)
					(fill yes)
				)
			)
		)
		(pad "2" smd custom
			(at 0 0.4445)
			(size 0.1524 0.1524)
			(layers "F.Cu" "F.Mask" "F.Paste")
			(net "GND")
			(options
				(clearance outline)
				(anchor circle)
			)
			(primitives
				(gr_poly
					(pts
						(arc
							(start 0.3048 -0.2032)
							(mid 0.275042 -0.275042)
							(end 0.2032 -0.3048)
						)
						(arc
							(start -0.2032 -0.3048)
							(mid -0.275042 -0.275042)
							(end -0.3048 -0.2032)
						)
						(arc
							(start -0.3048 0.2032)
							(mid -0.275042 0.275042)
							(end -0.2032 0.3048)
						)
						(arc
							(start 0.2032 0.3048)
							(mid 0.275042 0.275042)
							(end 0.3048 0.2032)
						)
					)
					(width 0)
					(fill yes)
				)
			)
		)
	)
	(footprint ""
		(layer "F.Cu")
		(at 301.244 -68.834 180)
		(property "Reference" "C456"
			(at 0 0 180)
			(layer "F.SilkS")
			(hide yes)
			(effects
				(font
					(size 1.27 1.27)
				)
			)
		)
		(property "Value" "SC100U4V5MX-1-GP"
			(at -0.0762 -6.1214 180)
			(unlocked yes)
			(layer "F.Fab")
			(hide yes)
			(effects
				(font
					(size 1.016 1.016)
					(thickness 0.1524)
				)
			)
		)
		(property "Device Type" "C805H58"
			(at -0.0762 -8.1534 180)
			(unlocked yes)
			(layer "F.Fab")
			(hide yes)
			(effects
				(font
					(size 1.016 1.016)
					(thickness 0.1524)
				)
			)
		)
		(duplicate_pad_numbers_are_jumpers no)
		(fp_line
			(start 0.635 0)
			(end -0.635 0)
			(stroke
				(width 0.508)
				(type default)
			)
			(layer "F.SilkS")
		)
		(fp_rect
			(start -0.9652 1.778)
			(end 0.9652 -1.778)
			(stroke
				(width 0)
				(type default)
			)
			(fill no)
			(layer "F.CrtYd")
		)
		(fp_poly
			(pts
				(xy -0.9652 -1.778) (xy 0.9652 -1.778) (xy 0.9652 1.778) (xy -0.9652 1.778)
			)
			(stroke
				(width 0)
				(type default)
			)
			(fill no)
			(layer "F.Fab")
		)
		(pad "1" smd rect
			(at 0 -0.9652 180)
			(size 1.397 1.143)
			(layers "F.Cu" "F.Mask" "F.Paste")
			(net "DUT_VDD")
		)
		(pad "2" smd rect
			(at 0 0.9652 180)
			(size 1.397 1.143)
			(layers "F.Cu" "F.Mask" "F.Paste")
			(net "GND")
		)
	)
	(footprint ""
		(layer "F.Cu")
		(at 33.0962 -212.09 90)
		(property "Reference" "C7274"
			(at 0 0 90)
			(layer "F.SilkS")
			(hide yes)
			(effects
				(font
					(size 1.27 1.27)
				)
			)
		)
		(property "Value" "SCD1U25V3KX-GP"
			(at 0 -2.8194 90)
			(unlocked yes)
			(layer "F.Fab")
			(hide yes)
			(effects
				(font
					(size 1.016 1.016)
					(thickness 0.1524)
				)
			)
		)
		(property "Device Type" "C603H36"
			(at 0 -4.3434 90)
			(unlocked yes)
			(layer "F.Fab")
			(hide yes)
			(effects
				(font
					(size 1.016 1.016)
					(thickness 0.1524)
				)
			)
		)
		(duplicate_pad_numbers_are_jumpers no)
		(fp_line
			(start 0.508 0)
			(end -0.508 0)
			(stroke
				(width 0.2032)
				(type default)
			)
			(layer "F.SilkS")
		)
		(fp_rect
			(start -0.5842 1.3335)
			(end 0.5842 -1.3335)
			(stroke
				(width 0)
				(type default)
			)
			(fill no)
			(layer "F.CrtYd")
		)
		(fp_rect
			(start -0.5842 1.3335)
			(end 0.5842 -1.3335)
			(stroke
				(width 0)
				(type default)
			)
			(fill no)
			(layer "F.Fab")
		)
		(pad "1" smd custom
			(at 0 -0.762 90)
			(size 0.2159 0.2159)
			(layers "F.Cu" "F.Mask" "F.Paste")
			(net "P12V_PCIE")
			(options
				(clearance outline)
				(anchor circle)
			)
			(primitives
				(gr_poly
					(pts
						(arc
							(start -0.3302 -0.4318)
							(mid -0.402042 -0.402042)
							(end -0.4318 -0.3302)
						)
						(arc
							(start -0.4318 0.3302)
							(mid -0.402042 0.402042)
							(end -0.3302 0.4318)
						)
						(arc
							(start 0.3302 0.4318)
							(mid 0.402042 0.402042)
							(end 0.4318 0.3302)
						)
						(arc
							(start 0.4318 -0.3302)
							(mid 0.402042 -0.402042)
							(end 0.3302 -0.4318)
						)
					)
					(width 0)
					(fill yes)
				)
			)
		)
		(pad "2" smd custom
			(at 0 0.762 90)
			(size 0.2159 0.2159)
			(layers "F.Cu" "F.Mask" "F.Paste")
			(net "GND")
			(options
				(clearance outline)
				(anchor circle)
			)
			(primitives
				(gr_poly
					(pts
						(arc
							(start -0.3302 -0.4318)
							(mid -0.402042 -0.402042)
							(end -0.4318 -0.3302)
						)
						(arc
							(start -0.4318 0.3302)
							(mid -0.402042 0.402042)
							(end -0.3302 0.4318)
						)
						(arc
							(start 0.3302 0.4318)
							(mid 0.402042 0.402042)
							(end 0.4318 0.3302)
						)
						(arc
							(start 0.4318 -0.3302)
							(mid 0.402042 -0.402042)
							(end 0.3302 -0.4318)
						)
					)
					(width 0)
					(fill yes)
				)
			)
		)
	)
	(footprint ""
		(layer "F.Cu")
		(at 59.69 -129.413 -90)
		(property "Reference" "L4"
			(at 0 0 270)
			(layer "F.SilkS")
			(hide yes)
			(effects
				(font
					(size 1.27 1.27)
				)
			)
		)
		(property "Value" "MMZ2012S601ATA1N-GP"
			(at 0 -4.2418 270)
			(unlocked yes)
			(layer "F.Fab")
			(hide yes)
			(effects
				(font
					(size 1.016 1.016)
					(thickness 0.1524)
				)
			)
		)
		(property "Device Type" "L805H42"
			(at 0 -5.7912 270)
			(unlocked yes)
			(layer "F.Fab")
			(hide yes)
			(effects
				(font
					(size 1.016 1.016)
					(thickness 0.1524)
				)
			)
		)
		(duplicate_pad_numbers_are_jumpers no)
		(fp_line
			(start -0.889 1.7018)
			(end -0.889 -1.7018)
			(stroke
				(width 0.1524)
				(type default)
			)
			(layer "F.SilkS")
		)
		(fp_line
			(start 0.889 1.7018)
			(end -0.889 1.7018)
			(stroke
				(width 0.1524)
				(type default)
			)
			(layer "F.SilkS")
		)
		(fp_line
			(start -0.889 -1.7018)
			(end 0.889 -1.7018)
			(stroke
				(width 0.1524)
				(type default)
			)
			(layer "F.SilkS")
		)
		(fp_line
			(start 0.889 -1.7018)
			(end 0.889 1.7018)
			(stroke
				(width 0.1524)
				(type default)
			)
			(layer "F.SilkS")
		)
		(fp_rect
			(start -0.9652 1.778)
			(end 0.9652 -1.778)
			(stroke
				(width 0)
				(type default)
			)
			(fill no)
			(layer "F.CrtYd")
		)
		(fp_rect
			(start -0.9652 1.778)
			(end 0.9652 -1.778)
			(stroke
				(width 0)
				(type default)
			)
			(fill no)
			(layer "F.Fab")
		)
		(pad "1" smd rect
			(at 0 -0.9652 270)
			(size 1.397 1.143)
			(layers "F.Cu" "F.Mask" "F.Paste")
			(net "P3V3_STBY")
		)
		(pad "2" smd rect
			(at 0 0.9652 270)
			(size 1.397 1.143)
			(layers "F.Cu" "F.Mask" "F.Paste")
			(net "ADCAV33")
		)
	)
	(footprint ""
		(layer "F.Cu")
		(at 175.961802 -71.071232 -90)
		(property "Reference" "PG31"
			(at 0 0 270)
			(layer "F.SilkS")
			(hide yes)
			(effects
				(font
					(size 1.27 1.27)
				)
			)
		)
		(property "Value" "GAP-CLOSE-PWR-3-GP"
			(at 0.0254 -6.5786 270)
			(unlocked yes)
			(layer "F.Fab")
			(hide yes)
			(effects
				(font
					(size 1.016 1.016)
					(thickness 0.1524)
				)
			)
		)
		(property "Device Type" "GAP-CLOSE-PWR-3"
			(at 0.0254 -8.255 270)
			(unlocked yes)
			(layer "F.Fab")
			(hide yes)
			(effects
				(font
					(size 1.016 1.016)
					(thickness 0.1524)
				)
			)
		)
		(duplicate_pad_numbers_are_jumpers no)
		(fp_rect
			(start -0.7112 0.4572)
			(end 0.7112 -0.4572)
			(stroke
				(width 0)
				(type default)
			)
			(fill no)
			(layer "F.CrtYd")
		)
		(fp_poly
			(pts
				(xy -0.7112 -0.4572) (xy 0.7112 -0.4572) (xy 0.7112 0.4572) (xy -0.7112 0.4572)
			)
			(stroke
				(width 0)
				(type default)
			)
			(fill no)
			(layer "F.Fab")
		)
		(pad "1" smd rect
			(at -0.3048 0 270)
			(size 0.6604 0.762)
			(layers "F.Cu" "F.Mask" "F.Paste")
			(net "DUT_AVD_TX")
		)
		(pad "2" smd rect
			(at 0.3048 0 270)
			(size 0.6604 0.762)
			(layers "F.Cu" "F.Mask" "F.Paste")
			(net "P0V9")
		)
	)
	(footprint ""
		(layer "F.Cu")
		(at 37.393626 -72.690482 90)
		(property "Reference" "PL1"
			(at 0 0 90)
			(layer "F.SilkS")
			(hide yes)
			(effects
				(font
					(size 1.27 1.27)
				)
			)
		)
		(property "Value" "IND-15UH-87-GP"
			(at -3.8989 1.2954 90)
			(unlocked yes)
			(layer "F.Fab")
			(hide yes)
			(effects
				(font
					(size 1.016 1.016)
					(thickness 0.1524)
				)
			)
		)
		(property "Device Type" "L47474716H158"
			(at -3.8989 -0.2286 90)
			(unlocked yes)
			(layer "F.Fab")
			(hide yes)
			(effects
				(font
					(size 1.016 1.016)
					(thickness 0.1524)
				)
			)
		)
		(duplicate_pad_numbers_are_jumpers no)
		(fp_line
			(start 2.6289 -3.3909)
			(end 2.6289 3.3909)
			(stroke
				(width 0.1524)
				(type default)
			)
			(layer "F.SilkS")
		)
		(fp_line
			(start -2.6289 -3.3909)
			(end 2.6289 -3.3909)
			(stroke
				(width 0.1524)
				(type default)
			)
			(layer "F.SilkS")
		)
		(fp_line
			(start 2.6289 3.3909)
			(end -2.6289 3.3909)
			(stroke
				(width 0.1524)
				(type default)
			)
			(layer "F.SilkS")
		)
		(fp_line
			(start -2.6289 3.3909)
			(end -2.6289 -3.3909)
			(stroke
				(width 0.1524)
				(type default)
			)
			(layer "F.SilkS")
		)
		(fp_rect
			(start -2.3495 2.3495)
			(end 2.3495 -2.3495)
			(stroke
				(width 0)
				(type default)
			)
			(fill no)
			(layer "F.CrtYd")
		)
		(fp_poly
			(pts
				(xy -2.8829 3.4671) (xy -2.8829 -2.3368) (xy -2.3495 -2.3368) (xy -2.3495 2.3495) (xy 2.3495 2.3495)
				(xy 2.3495 -2.3495) (xy -2.8829 -2.3495) (xy -2.8829 -3.4671) (xy 2.8829 -3.4671) (xy 2.8829 3.4671)
			)
			(stroke
				(width 0)
				(type default)
			)
			(fill no)
			(layer "F.CrtYd")
		)
		(fp_poly
			(pts
				(xy -2.8829 3.4671) (xy 2.8829 3.4671) (xy 2.8829 -3.4671) (xy -2.8829 -3.4671)
			)
			(stroke
				(width 0)
				(type default)
			)
			(fill no)
			(layer "F.Fab")
		)
		(pad "1" smd rect
			(at 0 -1.8161 90)
			(size 4.7498 2.6416)
			(layers "F.Cu" "F.Mask" "F.Paste")
			(net "P5V_STBY_LX")
		)
		(pad "2" smd rect
			(at 0 1.8161 90)
			(size 4.7498 2.6416)
			(layers "F.Cu" "F.Mask" "F.Paste")
			(net "P5V_STBY_LR")
		)
	)
	(footprint ""
		(layer "F.Cu")
		(at 51.816 -177.165 180)
		(property "Reference" "R904"
			(at 0 0 180)
			(layer "F.SilkS")
			(hide yes)
			(effects
				(font
					(size 1.27 1.27)
				)
			)
		)
		(property "Value" "0R2J-2-GP"
			(at 0.064008 -3.993896 180)
			(unlocked yes)
			(layer "F.Fab")
			(hide yes)
			(effects
				(font
					(size 1.016 1.016)
					(thickness 0.1524)
				)
			)
		)
		(property "Device Type" "R402H16"
			(at 0.064008 -5.517896 180)
			(unlocked yes)
			(layer "F.Fab")
			(hide yes)
			(effects
				(font
					(size 1.016 1.016)
					(thickness 0.1524)
				)
			)
		)
		(duplicate_pad_numbers_are_jumpers no)
		(fp_line
			(start 0.508 -0.9398)
			(end -0.508 -0.9398)
			(stroke
				(width 0.1524)
				(type default)
			)
			(layer "F.SilkS")
		)
		(fp_line
			(start -0.508 -0.9398)
			(end -0.508 0.9398)
			(stroke
				(width 0.1524)
				(type default)
			)
			(layer "F.SilkS")
		)
		(fp_rect
			(start -0.508 0.9398)
			(end 0.508 -0.9398)
			(stroke
				(width 0)
				(type default)
			)
			(fill no)
			(layer "F.CrtYd")
		)
		(fp_rect
			(start -0.508 0.9398)
			(end 0.508 -0.9398)
			(stroke
				(width 0)
				(type default)
			)
			(fill no)
			(layer "F.Fab")
		)
		(pad "1" smd custom
			(at 0 -0.4445 180)
			(size 0.1397 0.1397)
			(layers "F.Cu" "F.Mask" "F.Paste")
			(net "BMC_I2C8_CLKBUF1_SCL")
			(options
				(clearance outline)
				(anchor circle)
			)
			(primitives
				(gr_poly
					(pts
						(arc
							(start -0.1778 -0.2794)
							(mid -0.249642 -0.249642)
							(end -0.2794 -0.1778)
						)
						(arc
							(start -0.2794 0.1778)
							(mid -0.249642 0.249642)
							(end -0.1778 0.2794)
						)
						(arc
							(start 0.1778 0.2794)
							(mid 0.249642 0.249642)
							(end 0.2794 0.1778)
						)
						(arc
							(start 0.2794 -0.1778)
							(mid 0.249642 -0.249642)
							(end 0.1778 -0.2794)
						)
					)
					(width 0)
					(fill yes)
				)
			)
		)
		(pad "2" smd custom
			(at 0 0.4445 180)
			(size 0.1397 0.1397)
			(layers "F.Cu" "F.Mask" "F.Paste")
			(net "BMC_I2C8_CLKBUF1_SCL_R")
			(options
				(clearance outline)
				(anchor circle)
			)
			(primitives
				(gr_poly
					(pts
						(arc
							(start -0.1778 -0.2794)
							(mid -0.249642 -0.249642)
							(end -0.2794 -0.1778)
						)
						(arc
							(start -0.2794 0.1778)
							(mid -0.249642 0.249642)
							(end -0.1778 0.2794)
						)
						(arc
							(start 0.1778 0.2794)
							(mid 0.249642 0.249642)
							(end 0.2794 0.1778)
						)
						(arc
							(start 0.2794 -0.1778)
							(mid 0.249642 -0.249642)
							(end 0.1778 -0.2794)
						)
					)
					(width 0)
					(fill yes)
				)
			)
		)
	)
	(footprint ""
		(layer "F.Cu")
		(at 209.325972 -12.542266 180)
		(property "Reference" "R7889"
			(at 0 0 180)
			(layer "F.SilkS")
			(hide yes)
			(effects
				(font
					(size 1.27 1.27)
				)
			)
		)
		(property "Value" "0R2J-2-GP"
			(at 0.064008 -3.993896 180)
			(unlocked yes)
			(layer "F.Fab")
			(hide yes)
			(effects
				(font
					(size 1.016 1.016)
					(thickness 0.1524)
				)
			)
		)
		(property "Device Type" "R402H16"
			(at 0.064008 -5.517896 180)
			(unlocked yes)
			(layer "F.Fab")
			(hide yes)
			(effects
				(font
					(size 1.016 1.016)
					(thickness 0.1524)
				)
			)
		)
		(duplicate_pad_numbers_are_jumpers no)
		(fp_line
			(start 0.508 -0.9398)
			(end -0.508 -0.9398)
			(stroke
				(width 0.1524)
				(type default)
			)
			(layer "F.SilkS")
		)
		(fp_line
			(start -0.508 -0.9398)
			(end -0.508 0.9398)
			(stroke
				(width 0.1524)
				(type default)
			)
			(layer "F.SilkS")
		)
		(fp_rect
			(start -0.508 0.9398)
			(end 0.508 -0.9398)
			(stroke
				(width 0)
				(type default)
			)
			(fill no)
			(layer "F.CrtYd")
		)
		(fp_rect
			(start -0.508 0.9398)
			(end 0.508 -0.9398)
			(stroke
				(width 0)
				(type default)
			)
			(fill no)
			(layer "F.Fab")
		)
		(pad "1" smd custom
			(at 0 -0.4445 180)
			(size 0.1397 0.1397)
			(layers "F.Cu" "F.Mask" "F.Paste")
			(net "BMC_ID_LED")
			(options
				(clearance outline)
				(anchor circle)
			)
			(primitives
				(gr_poly
					(pts
						(arc
							(start -0.1778 -0.2794)
							(mid -0.249642 -0.249642)
							(end -0.2794 -0.1778)
						)
						(arc
							(start -0.2794 0.1778)
							(mid -0.249642 0.249642)
							(end -0.1778 0.2794)
						)
						(arc
							(start 0.1778 0.2794)
							(mid 0.249642 0.249642)
							(end 0.2794 0.1778)
						)
						(arc
							(start 0.2794 -0.1778)
							(mid 0.249642 -0.249642)
							(end 0.1778 -0.2794)
						)
					)
					(width 0)
					(fill yes)
				)
			)
		)
		(pad "2" smd custom
			(at 0 0.4445 180)
			(size 0.1397 0.1397)
			(layers "F.Cu" "F.Mask" "F.Paste")
			(net "BMC_ID_LED_R")
			(options
				(clearance outline)
				(anchor circle)
			)
			(primitives
				(gr_poly
					(pts
						(arc
							(start -0.1778 -0.2794)
							(mid -0.249642 -0.249642)
							(end -0.2794 -0.1778)
						)
						(arc
							(start -0.2794 0.1778)
							(mid -0.249642 0.249642)
							(end -0.1778 0.2794)
						)
						(arc
							(start 0.1778 0.2794)
							(mid 0.249642 0.249642)
							(end 0.2794 0.1778)
						)
						(arc
							(start 0.2794 -0.1778)
							(mid 0.249642 -0.249642)
							(end 0.1778 -0.2794)
						)
					)
					(width 0)
					(fill yes)
				)
			)
		)
	)
	(footprint ""
		(layer "F.Cu")
		(at 145.177002 -70.182232 -90)
		(property "Reference" "PC199"
			(at 0 0 270)
			(layer "F.SilkS")
			(hide yes)
			(effects
				(font
					(size 1.27 1.27)
				)
			)
		)
		(property "Value" "SC22U25V6KX-GP-U"
			(at -2.860802 -5.279644 270)
			(unlocked yes)
			(layer "F.Fab")
			(hide yes)
			(effects
				(font
					(size 1.016 1.016)
					(thickness 0.1524)
				)
			)
		)
		(property "Device Type" "C1206-TO0D3H75"
			(at -2.860802 -6.803644 270)
			(unlocked yes)
			(layer "F.Fab")
			(hide yes)
			(effects
				(font
					(size 1.016 1.016)
					(thickness 0.1524)
				)
			)
		)
		(duplicate_pad_numbers_are_jumpers no)
		(fp_line
			(start -1.3081 2.3749)
			(end -1.3081 -2.3749)
			(stroke
				(width 0.1524)
				(type default)
			)
			(layer "F.SilkS")
		)
		(fp_line
			(start 1.3081 2.3749)
			(end -1.3081 2.3749)
			(stroke
				(width 0.1524)
				(type default)
			)
			(layer "F.SilkS")
		)
		(fp_line
			(start -1.3081 -2.3749)
			(end 1.3081 -2.3749)
			(stroke
				(width 0.1524)
				(type default)
			)
			(layer "F.SilkS")
		)
		(fp_line
			(start 1.3081 -2.3749)
			(end 1.3081 2.3749)
			(stroke
				(width 0.1524)
				(type default)
			)
			(layer "F.SilkS")
		)
		(fp_rect
			(start -0.8001 1.6002)
			(end 0.8001 -1.6002)
			(stroke
				(width 0)
				(type default)
			)
			(fill no)
			(layer "F.CrtYd")
		)
		(fp_poly
			(pts
				(xy -1.5621 2.4511) (xy -1.5621 1.6002) (xy 0.8001 1.6002) (xy 0.8001 -1.6002) (xy -0.8001 -1.6002)
				(xy -0.8001 1.5875) (xy -1.5621 1.5875) (xy -1.5621 -2.4511) (xy 1.5621 -2.4511) (xy 1.5621 2.4511)
			)
			(stroke
				(width 0)
				(type default)
			)
			(fill no)
			(layer "F.CrtYd")
		)
		(fp_rect
			(start -1.5621 2.4511)
			(end 1.5621 -2.4511)
			(stroke
				(width 0)
				(type default)
			)
			(fill no)
			(layer "F.Fab")
		)
		(pad "1" smd rect
			(at 0 -1.392936 270)
			(size 2.1082 1.4478)
			(layers "F.Cu" "F.Mask" "F.Paste")
			(net "P0V9_VIN")
		)
		(pad "2" smd rect
			(at 0 1.392936 270)
			(size 2.1082 1.4478)
			(layers "F.Cu" "F.Mask" "F.Paste")
			(net "GND")
		)
	)
	(footprint ""
		(layer "F.Cu")
		(at 20.642326 -130.32486 90)
		(property "Reference" "R348"
			(at 0 0 90)
			(layer "F.SilkS")
			(hide yes)
			(effects
				(font
					(size 1.27 1.27)
				)
			)
		)
		(property "Value" "3K3R2F-2-GP"
			(at 0.064008 -3.993896 90)
			(unlocked yes)
			(layer "F.Fab")
			(hide yes)
			(effects
				(font
					(size 1.016 1.016)
					(thickness 0.1524)
				)
			)
		)
		(property "Device Type" "R402H16"
			(at 0.064008 -5.517896 90)
			(unlocked yes)
			(layer "F.Fab")
			(hide yes)
			(effects
				(font
					(size 1.016 1.016)
					(thickness 0.1524)
				)
			)
		)
		(duplicate_pad_numbers_are_jumpers no)
		(fp_line
			(start 0.508 -0.9398)
			(end -0.508 -0.9398)
			(stroke
				(width 0.1524)
				(type default)
			)
			(layer "F.SilkS")
		)
		(fp_line
			(start -0.508 -0.9398)
			(end -0.508 0.9398)
			(stroke
				(width 0.1524)
				(type default)
			)
			(layer "F.SilkS")
		)
		(fp_rect
			(start -0.508 0.9398)
			(end 0.508 -0.9398)
			(stroke
				(width 0)
				(type default)
			)
			(fill no)
			(layer "F.CrtYd")
		)
		(fp_rect
			(start -0.508 0.9398)
			(end 0.508 -0.9398)
			(stroke
				(width 0)
				(type default)
			)
			(fill no)
			(layer "F.Fab")
		)
		(pad "1" smd custom
			(at 0 -0.4445 90)
			(size 0.1397 0.1397)
			(layers "F.Cu" "F.Mask" "F.Paste")
			(net "P3V3_STBY")
			(options
				(clearance outline)
				(anchor circle)
			)
			(primitives
				(gr_poly
					(pts
						(arc
							(start -0.1778 -0.2794)
							(mid -0.249642 -0.249642)
							(end -0.2794 -0.1778)
						)
						(arc
							(start -0.2794 0.1778)
							(mid -0.249642 0.249642)
							(end -0.1778 0.2794)
						)
						(arc
							(start 0.1778 0.2794)
							(mid 0.249642 0.249642)
							(end 0.2794 0.1778)
						)
						(arc
							(start 0.2794 -0.1778)
							(mid 0.249642 -0.249642)
							(end 0.1778 -0.2794)
						)
					)
					(width 0)
					(fill yes)
				)
			)
		)
		(pad "2" smd custom
			(at 0 0.4445 90)
			(size 0.1397 0.1397)
			(layers "F.Cu" "F.Mask" "F.Paste")
			(net "ROMA10")
			(options
				(clearance outline)
				(anchor circle)
			)
			(primitives
				(gr_poly
					(pts
						(arc
							(start -0.1778 -0.2794)
							(mid -0.249642 -0.249642)
							(end -0.2794 -0.1778)
						)
						(arc
							(start -0.2794 0.1778)
							(mid -0.249642 0.249642)
							(end -0.1778 0.2794)
						)
						(arc
							(start 0.1778 0.2794)
							(mid 0.249642 0.249642)
							(end 0.2794 0.1778)
						)
						(arc
							(start 0.2794 -0.1778)
							(mid 0.249642 -0.249642)
							(end 0.1778 -0.2794)
						)
					)
					(width 0)
					(fill yes)
				)
			)
		)
	)
	(footprint ""
		(layer "F.Cu")
		(at 27.1526 -186.3852)
		(property "Reference" "R502"
			(at 0 0 0)
			(layer "F.SilkS")
			(hide yes)
			(effects
				(font
					(size 1.27 1.27)
				)
			)
		)
		(property "Value" "2KR2F-3-GP"
			(at 0.064008 -3.993896 0)
			(unlocked yes)
			(layer "F.Fab")
			(hide yes)
			(effects
				(font
					(size 1.016 1.016)
					(thickness 0.1524)
				)
			)
		)
		(property "Device Type" "R402H16"
			(at 0.064008 -5.517896 0)
			(unlocked yes)
			(layer "F.Fab")
			(hide yes)
			(effects
				(font
					(size 1.016 1.016)
					(thickness 0.1524)
				)
			)
		)
		(duplicate_pad_numbers_are_jumpers no)
		(fp_line
			(start -0.508 -0.9398)
			(end -0.508 0.9398)
			(stroke
				(width 0.1524)
				(type default)
			)
			(layer "F.SilkS")
		)
		(fp_line
			(start 0.508 -0.9398)
			(end -0.508 -0.9398)
			(stroke
				(width 0.1524)
				(type default)
			)
			(layer "F.SilkS")
		)
		(fp_rect
			(start -0.508 0.9398)
			(end 0.508 -0.9398)
			(stroke
				(width 0)
				(type default)
			)
			(fill no)
			(layer "F.CrtYd")
		)
		(fp_rect
			(start -0.508 0.9398)
			(end 0.508 -0.9398)
			(stroke
				(width 0)
				(type default)
			)
			(fill no)
			(layer "F.Fab")
		)
		(pad "1" smd custom
			(at 0 -0.4445)
			(size 0.1397 0.1397)
			(layers "F.Cu" "F.Mask" "F.Paste")
			(net "P3V3_STBY")
			(options
				(clearance outline)
				(anchor circle)
			)
			(primitives
				(gr_poly
					(pts
						(arc
							(start -0.1778 -0.2794)
							(mid -0.249642 -0.249642)
							(end -0.2794 -0.1778)
						)
						(arc
							(start -0.2794 0.1778)
							(mid -0.249642 0.249642)
							(end -0.1778 0.2794)
						)
						(arc
							(start 0.1778 0.2794)
							(mid 0.249642 0.249642)
							(end 0.2794 0.1778)
						)
						(arc
							(start 0.2794 -0.1778)
							(mid 0.249642 -0.249642)
							(end 0.1778 -0.2794)
						)
					)
					(width 0)
					(fill yes)
				)
			)
		)
		(pad "2" smd custom
			(at 0 0.4445)
			(size 0.1397 0.1397)
			(layers "F.Cu" "F.Mask" "F.Paste")
			(net "BMC_I2C5_SCL_R")
			(options
				(clearance outline)
				(anchor circle)
			)
			(primitives
				(gr_poly
					(pts
						(arc
							(start -0.1778 -0.2794)
							(mid -0.249642 -0.249642)
							(end -0.2794 -0.1778)
						)
						(arc
							(start -0.2794 0.1778)
							(mid -0.249642 0.249642)
							(end -0.1778 0.2794)
						)
						(arc
							(start 0.1778 0.2794)
							(mid 0.249642 0.249642)
							(end 0.2794 0.1778)
						)
						(arc
							(start 0.2794 -0.1778)
							(mid 0.249642 -0.249642)
							(end 0.1778 -0.2794)
						)
					)
					(width 0)
					(fill yes)
				)
			)
		)
	)
	(footprint ""
		(layer "F.Cu")
		(at 340.233 -58.42 -90)
		(property "Reference" "PC218"
			(at 0 0 270)
			(layer "F.SilkS")
			(hide yes)
			(effects
				(font
					(size 1.27 1.27)
				)
			)
		)
		(property "Value" "SC22U25V6KX-GP-U"
			(at -2.860802 -5.279644 270)
			(unlocked yes)
			(layer "F.Fab")
			(hide yes)
			(effects
				(font
					(size 1.016 1.016)
					(thickness 0.1524)
				)
			)
		)
		(property "Device Type" "C1206-TO0D3H75"
			(at -2.860802 -6.803644 270)
			(unlocked yes)
			(layer "F.Fab")
			(hide yes)
			(effects
				(font
					(size 1.016 1.016)
					(thickness 0.1524)
				)
			)
		)
		(duplicate_pad_numbers_are_jumpers no)
		(fp_line
			(start -1.3081 2.3749)
			(end -1.3081 -2.3749)
			(stroke
				(width 0.1524)
				(type default)
			)
			(layer "F.SilkS")
		)
		(fp_line
			(start 1.3081 2.3749)
			(end -1.3081 2.3749)
			(stroke
				(width 0.1524)
				(type default)
			)
			(layer "F.SilkS")
		)
		(fp_line
			(start -1.3081 -2.3749)
			(end 1.3081 -2.3749)
			(stroke
				(width 0.1524)
				(type default)
			)
			(layer "F.SilkS")
		)
		(fp_line
			(start 1.3081 -2.3749)
			(end 1.3081 2.3749)
			(stroke
				(width 0.1524)
				(type default)
			)
			(layer "F.SilkS")
		)
		(fp_rect
			(start -0.8001 1.6002)
			(end 0.8001 -1.6002)
			(stroke
				(width 0)
				(type default)
			)
			(fill no)
			(layer "F.CrtYd")
		)
		(fp_poly
			(pts
				(xy -1.5621 2.4511) (xy -1.5621 1.6002) (xy 0.8001 1.6002) (xy 0.8001 -1.6002) (xy -0.8001 -1.6002)
				(xy -0.8001 1.5875) (xy -1.5621 1.5875) (xy -1.5621 -2.4511) (xy 1.5621 -2.4511) (xy 1.5621 2.4511)
			)
			(stroke
				(width 0)
				(type default)
			)
			(fill no)
			(layer "F.CrtYd")
		)
		(fp_rect
			(start -1.5621 2.4511)
			(end 1.5621 -2.4511)
			(stroke
				(width 0)
				(type default)
			)
			(fill no)
			(layer "F.Fab")
		)
		(pad "1" smd rect
			(at 0 -1.392936 270)
			(size 2.1082 1.4478)
			(layers "F.Cu" "F.Mask" "F.Paste")
			(net "P0V9_E_VIN")
		)
		(pad "2" smd rect
			(at 0 1.392936 270)
			(size 2.1082 1.4478)
			(layers "F.Cu" "F.Mask" "F.Paste")
			(net "GND")
		)
	)
	(footprint ""
		(layer "F.Cu")
		(at 31.9278 -192.1002 90)
		(property "Reference" "R2118"
			(at 0 0 90)
			(layer "F.SilkS")
			(hide yes)
			(effects
				(font
					(size 1.27 1.27)
				)
			)
		)
		(property "Value" "1MR3J-L-GP"
			(at -0.0254 -2.5146 90)
			(unlocked yes)
			(layer "F.Fab")
			(hide yes)
			(effects
				(font
					(size 1.016 1.016)
					(thickness 0.1524)
				)
			)
		)
		(property "Device Type" "R603H22"
			(at -0.0254 -4.0386 90)
			(unlocked yes)
			(layer "F.Fab")
			(hide yes)
			(effects
				(font
					(size 1.016 1.016)
					(thickness 0.1524)
				)
			)
		)
		(duplicate_pad_numbers_are_jumpers no)
		(fp_line
			(start 0.2032 0)
			(end 0.4826 0)
			(stroke
				(width 0.2032)
				(type default)
			)
			(layer "F.SilkS")
		)
		(fp_line
			(start -0.4826 0)
			(end -0.2032 0)
			(stroke
				(width 0.2032)
				(type default)
			)
			(layer "F.SilkS")
		)
		(fp_rect
			(start -0.5842 1.3335)
			(end 0.5842 -1.3335)
			(stroke
				(width 0)
				(type default)
			)
			(fill no)
			(layer "F.CrtYd")
		)
		(fp_rect
			(start -0.5842 1.3335)
			(end 0.5842 -1.3335)
			(stroke
				(width 0)
				(type default)
			)
			(fill no)
			(layer "F.Fab")
		)
		(pad "1" smd custom
			(at 0 -0.762 90)
			(size 0.2159 0.2159)
			(layers "F.Cu" "F.Mask" "F.Paste")
			(net "MB0_CM_GATE_R")
			(options
				(clearance outline)
				(anchor circle)
			)
			(primitives
				(gr_poly
					(pts
						(arc
							(start -0.3302 -0.4318)
							(mid -0.402042 -0.402042)
							(end -0.4318 -0.3302)
						)
						(arc
							(start -0.4318 0.3302)
							(mid -0.402042 0.402042)
							(end -0.3302 0.4318)
						)
						(arc
							(start 0.3302 0.4318)
							(mid 0.402042 0.402042)
							(end 0.4318 0.3302)
						)
						(arc
							(start 0.4318 -0.3302)
							(mid 0.402042 -0.402042)
							(end 0.3302 -0.4318)
						)
					)
					(width 0)
					(fill yes)
				)
			)
		)
		(pad "2" smd custom
			(at 0 0.762 90)
			(size 0.2159 0.2159)
			(layers "F.Cu" "F.Mask" "F.Paste")
			(net "GND")
			(options
				(clearance outline)
				(anchor circle)
			)
			(primitives
				(gr_poly
					(pts
						(arc
							(start -0.3302 -0.4318)
							(mid -0.402042 -0.402042)
							(end -0.4318 -0.3302)
						)
						(arc
							(start -0.4318 0.3302)
							(mid -0.402042 0.402042)
							(end -0.3302 0.4318)
						)
						(arc
							(start 0.3302 0.4318)
							(mid 0.402042 0.402042)
							(end 0.4318 0.3302)
						)
						(arc
							(start 0.4318 -0.3302)
							(mid 0.402042 -0.402042)
							(end 0.3302 -0.4318)
						)
					)
					(width 0)
					(fill yes)
				)
			)
		)
	)
	(footprint ""
		(layer "F.Cu")
		(at 76.689966 -90.61196 180)
		(property "Reference" "SR707"
			(at 0 0 180)
			(layer "F.SilkS")
			(hide yes)
			(effects
				(font
					(size 1.27 1.27)
				)
			)
		)
		(property "Value" "150R2F-1-GP"
			(at 0.064008 -3.993896 180)
			(unlocked yes)
			(layer "F.Fab")
			(hide yes)
			(effects
				(font
					(size 1.016 1.016)
					(thickness 0.1524)
				)
			)
		)
		(property "Device Type" "R402H16"
			(at 0.064008 -5.517896 180)
			(unlocked yes)
			(layer "F.Fab")
			(hide yes)
			(effects
				(font
					(size 1.016 1.016)
					(thickness 0.1524)
				)
			)
		)
		(duplicate_pad_numbers_are_jumpers no)
		(fp_line
			(start 0.508 -0.9398)
			(end -0.508 -0.9398)
			(stroke
				(width 0.1524)
				(type default)
			)
			(layer "F.SilkS")
		)
		(fp_line
			(start -0.508 -0.9398)
			(end -0.508 0.9398)
			(stroke
				(width 0.1524)
				(type default)
			)
			(layer "F.SilkS")
		)
		(fp_rect
			(start -0.508 0.9398)
			(end 0.508 -0.9398)
			(stroke
				(width 0)
				(type default)
			)
			(fill no)
			(layer "F.CrtYd")
		)
		(fp_rect
			(start -0.508 0.9398)
			(end 0.508 -0.9398)
			(stroke
				(width 0)
				(type default)
			)
			(fill no)
			(layer "F.Fab")
		)
		(pad "1" smd custom
			(at 0 -0.4445 180)
			(size 0.1397 0.1397)
			(layers "F.Cu" "F.Mask" "F.Paste")
			(net "P3V3_STBY")
			(options
				(clearance outline)
				(anchor circle)
			)
			(primitives
				(gr_poly
					(pts
						(arc
							(start -0.1778 -0.2794)
							(mid -0.249642 -0.249642)
							(end -0.2794 -0.1778)
						)
						(arc
							(start -0.2794 0.1778)
							(mid -0.249642 0.249642)
							(end -0.1778 0.2794)
						)
						(arc
							(start 0.1778 0.2794)
							(mid 0.249642 0.249642)
							(end 0.2794 0.1778)
						)
						(arc
							(start 0.2794 -0.1778)
							(mid 0.249642 -0.249642)
							(end 0.1778 -0.2794)
						)
					)
					(width 0)
					(fill yes)
				)
			)
		)
		(pad "2" smd custom
			(at 0 0.4445 180)
			(size 0.1397 0.1397)
			(layers "F.Cu" "F.Mask" "F.Paste")
			(net "EXP_BMC_HB_LED_R")
			(options
				(clearance outline)
				(anchor circle)
			)
			(primitives
				(gr_poly
					(pts
						(arc
							(start -0.1778 -0.2794)
							(mid -0.249642 -0.249642)
							(end -0.2794 -0.1778)
						)
						(arc
							(start -0.2794 0.1778)
							(mid -0.249642 0.249642)
							(end -0.1778 0.2794)
						)
						(arc
							(start 0.1778 0.2794)
							(mid 0.249642 0.249642)
							(end 0.2794 0.1778)
						)
						(arc
							(start 0.2794 -0.1778)
							(mid 0.249642 -0.249642)
							(end 0.1778 -0.2794)
						)
					)
					(width 0)
					(fill yes)
				)
			)
		)
	)
	(footprint ""
		(layer "F.Cu")
		(at 142.247874 -85.08492 -90)
		(property "Reference" "PR9033"
			(at 0 0 270)
			(layer "F.SilkS")
			(hide yes)
			(effects
				(font
					(size 1.27 1.27)
				)
			)
		)
		(property "Value" "3K65R2F-1-GP"
			(at 0.064008 -3.993896 270)
			(unlocked yes)
			(layer "F.Fab")
			(hide yes)
			(effects
				(font
					(size 1.016 1.016)
					(thickness 0.1524)
				)
			)
		)
		(property "Device Type" "R402H16"
			(at 0.064008 -5.517896 270)
			(unlocked yes)
			(layer "F.Fab")
			(hide yes)
			(effects
				(font
					(size 1.016 1.016)
					(thickness 0.1524)
				)
			)
		)
		(duplicate_pad_numbers_are_jumpers no)
		(fp_line
			(start -0.508 -0.9398)
			(end -0.508 0.9398)
			(stroke
				(width 0.1524)
				(type default)
			)
			(layer "F.SilkS")
		)
		(fp_line
			(start 0.508 -0.9398)
			(end -0.508 -0.9398)
			(stroke
				(width 0.1524)
				(type default)
			)
			(layer "F.SilkS")
		)
		(fp_rect
			(start -0.508 0.9398)
			(end 0.508 -0.9398)
			(stroke
				(width 0)
				(type default)
			)
			(fill no)
			(layer "F.CrtYd")
		)
		(fp_rect
			(start -0.508 0.9398)
			(end 0.508 -0.9398)
			(stroke
				(width 0)
				(type default)
			)
			(fill no)
			(layer "F.Fab")
		)
		(pad "1" smd custom
			(at 0 -0.4445 270)
			(size 0.1397 0.1397)
			(layers "F.Cu" "F.Mask" "F.Paste")
			(net "P1V8_PWR")
			(options
				(clearance outline)
				(anchor circle)
			)
			(primitives
				(gr_poly
					(pts
						(arc
							(start -0.1778 -0.2794)
							(mid -0.249642 -0.249642)
							(end -0.2794 -0.1778)
						)
						(arc
							(start -0.2794 0.1778)
							(mid -0.249642 0.249642)
							(end -0.1778 0.2794)
						)
						(arc
							(start 0.1778 0.2794)
							(mid 0.249642 0.249642)
							(end 0.2794 0.1778)
						)
						(arc
							(start 0.2794 -0.1778)
							(mid 0.249642 -0.249642)
							(end 0.1778 -0.2794)
						)
					)
					(width 0)
					(fill yes)
				)
			)
		)
		(pad "2" smd custom
			(at 0 0.4445 270)
			(size 0.1397 0.1397)
			(layers "F.Cu" "F.Mask" "F.Paste")
			(net "VR_P1V8_STBY_FB")
			(options
				(clearance outline)
				(anchor circle)
			)
			(primitives
				(gr_poly
					(pts
						(arc
							(start -0.1778 -0.2794)
							(mid -0.249642 -0.249642)
							(end -0.2794 -0.1778)
						)
						(arc
							(start -0.2794 0.1778)
							(mid -0.249642 0.249642)
							(end -0.1778 0.2794)
						)
						(arc
							(start 0.1778 0.2794)
							(mid 0.249642 0.249642)
							(end 0.2794 0.1778)
						)
						(arc
							(start 0.2794 -0.1778)
							(mid 0.249642 -0.249642)
							(end 0.1778 -0.2794)
						)
					)
					(width 0)
					(fill yes)
				)
			)
		)
	)
	(footprint ""
		(layer "F.Cu")
		(at 178.1048 -64.643 180)
		(property "Reference" "PG16"
			(at 0 0 180)
			(layer "F.SilkS")
			(hide yes)
			(effects
				(font
					(size 1.27 1.27)
				)
			)
		)
		(property "Value" "GAP-CLOSE-PWR-3-GP"
			(at 0.0254 -6.5786 180)
			(unlocked yes)
			(layer "F.Fab")
			(hide yes)
			(effects
				(font
					(size 1.016 1.016)
					(thickness 0.1524)
				)
			)
		)
		(property "Device Type" "GAP-CLOSE-PWR-3"
			(at 0.0254 -8.255 180)
			(unlocked yes)
			(layer "F.Fab")
			(hide yes)
			(effects
				(font
					(size 1.016 1.016)
					(thickness 0.1524)
				)
			)
		)
		(duplicate_pad_numbers_are_jumpers no)
		(fp_rect
			(start -0.7112 0.4572)
			(end 0.7112 -0.4572)
			(stroke
				(width 0)
				(type default)
			)
			(fill no)
			(layer "F.CrtYd")
		)
		(fp_poly
			(pts
				(xy -0.7112 -0.4572) (xy 0.7112 -0.4572) (xy 0.7112 0.4572) (xy -0.7112 0.4572)
			)
			(stroke
				(width 0)
				(type default)
			)
			(fill no)
			(layer "F.Fab")
		)
		(pad "1" smd rect
			(at -0.3048 0 180)
			(size 0.6604 0.762)
			(layers "F.Cu" "F.Mask" "F.Paste")
			(net "DUT_AVD_PCIE")
		)
		(pad "2" smd rect
			(at 0.3048 0 180)
			(size 0.6604 0.762)
			(layers "F.Cu" "F.Mask" "F.Paste")
			(net "P0V9")
		)
	)
	(footprint ""
		(layer "F.Cu")
		(at 209.868008 -4.064)
		(property "Reference" "R681"
			(at 0 0 0)
			(layer "F.SilkS")
			(hide yes)
			(effects
				(font
					(size 1.27 1.27)
				)
			)
		)
		(property "Value" "100KR2F-L1-GP"
			(at 0.064008 -3.993896 0)
			(unlocked yes)
			(layer "F.Fab")
			(hide yes)
			(effects
				(font
					(size 1.016 1.016)
					(thickness 0.1524)
				)
			)
		)
		(property "Device Type" "R402H16"
			(at 0.064008 -5.517896 0)
			(unlocked yes)
			(layer "F.Fab")
			(hide yes)
			(effects
				(font
					(size 1.016 1.016)
					(thickness 0.1524)
				)
			)
		)
		(duplicate_pad_numbers_are_jumpers no)
		(fp_line
			(start -0.508 -0.9398)
			(end -0.508 0.9398)
			(stroke
				(width 0.1524)
				(type default)
			)
			(layer "F.SilkS")
		)
		(fp_line
			(start 0.508 -0.9398)
			(end -0.508 -0.9398)
			(stroke
				(width 0.1524)
				(type default)
			)
			(layer "F.SilkS")
		)
		(fp_rect
			(start -0.508 0.9398)
			(end 0.508 -0.9398)
			(stroke
				(width 0)
				(type default)
			)
			(fill no)
			(layer "F.CrtYd")
		)
		(fp_rect
			(start -0.508 0.9398)
			(end 0.508 -0.9398)
			(stroke
				(width 0)
				(type default)
			)
			(fill no)
			(layer "F.Fab")
		)
		(pad "1" smd custom
			(at 0 -0.4445)
			(size 0.1397 0.1397)
			(layers "F.Cu" "F.Mask" "F.Paste")
			(net "HOST7_RST_N")
			(options
				(clearance outline)
				(anchor circle)
			)
			(primitives
				(gr_poly
					(pts
						(arc
							(start -0.1778 -0.2794)
							(mid -0.249642 -0.249642)
							(end -0.2794 -0.1778)
						)
						(arc
							(start -0.2794 0.1778)
							(mid -0.249642 0.249642)
							(end -0.1778 0.2794)
						)
						(arc
							(start 0.1778 0.2794)
							(mid 0.249642 0.249642)
							(end 0.2794 0.1778)
						)
						(arc
							(start 0.2794 -0.1778)
							(mid 0.249642 -0.249642)
							(end 0.1778 -0.2794)
						)
					)
					(width 0)
					(fill yes)
				)
			)
		)
		(pad "2" smd custom
			(at 0 0.4445)
			(size 0.1397 0.1397)
			(layers "F.Cu" "F.Mask" "F.Paste")
			(net "GND")
			(options
				(clearance outline)
				(anchor circle)
			)
			(primitives
				(gr_poly
					(pts
						(arc
							(start -0.1778 -0.2794)
							(mid -0.249642 -0.249642)
							(end -0.2794 -0.1778)
						)
						(arc
							(start -0.2794 0.1778)
							(mid -0.249642 0.249642)
							(end -0.1778 0.2794)
						)
						(arc
							(start 0.1778 0.2794)
							(mid 0.249642 0.249642)
							(end 0.2794 0.1778)
						)
						(arc
							(start 0.2794 -0.1778)
							(mid 0.249642 -0.249642)
							(end 0.1778 -0.2794)
						)
					)
					(width 0)
					(fill yes)
				)
			)
		)
	)
	(footprint ""
		(layer "F.Cu")
		(at 162.753802 -65.432432 90)
		(property "Reference" "PL11"
			(at 0 0 90)
			(layer "F.SilkS")
			(hide yes)
			(effects
				(font
					(size 1.27 1.27)
				)
			)
		)
		(property "Value" "IND-300NH-8-GP"
			(at -5.6769 -0.4572 90)
			(unlocked yes)
			(layer "F.Fab")
			(hide yes)
			(effects
				(font
					(size 1.016 1.016)
					(thickness 0.1524)
				)
			)
		)
		(property "Device Type" "L102078-254224H296"
			(at -5.6769 -1.9812 90)
			(unlocked yes)
			(layer "F.Fab")
			(hide yes)
			(effects
				(font
					(size 1.016 1.016)
					(thickness 0.1524)
				)
			)
		)
		(duplicate_pad_numbers_are_jumpers no)
		(fp_line
			(start 4.1529 -5.9944)
			(end -4.1529 -5.9944)
			(stroke
				(width 0.1524)
				(type default)
			)
			(layer "F.SilkS")
		)
		(fp_line
			(start -4.1529 -5.9944)
			(end -4.1529 5.9944)
			(stroke
				(width 0.1524)
				(type default)
			)
			(layer "F.SilkS")
		)
		(fp_line
			(start 4.1529 5.9944)
			(end 4.1529 -5.9944)
			(stroke
				(width 0.1524)
				(type default)
			)
			(layer "F.SilkS")
		)
		(fp_line
			(start -4.1529 5.9944)
			(end 4.1529 5.9944)
			(stroke
				(width 0.1524)
				(type default)
			)
			(layer "F.SilkS")
		)
		(fp_poly
			(pts
				(xy -3.8989 -5.1054) (xy -3.8989 5.1054) (xy 3.8989 5.1054) (xy 3.8989 -5.1054)
			)
			(stroke
				(width 0)
				(type default)
			)
			(fill no)
			(layer "F.CrtYd")
		)
		(fp_poly
			(pts
				(xy -3.8989 -5.1054) (xy 4.4069 -5.1054) (xy 4.4069 -6.0706) (xy -4.4069 -6.0706) (xy -4.4069 6.0706)
				(xy 4.4069 6.0706) (xy 4.4069 -5.0927) (xy 3.8989 -5.0927) (xy 3.8989 5.1054) (xy -3.8989 5.1054)
			)
			(stroke
				(width 0)
				(type default)
			)
			(fill no)
			(layer "F.CrtYd")
		)
		(fp_rect
			(start -4.4069 6.0706)
			(end 4.4069 -6.0706)
			(stroke
				(width 0)
				(type default)
			)
			(fill no)
			(layer "F.Fab")
		)
		(pad "1" smd rect
			(at 0 -4.020566 90)
			(size 2.4892 3.429)
			(layers "F.Cu" "F.Mask" "F.Paste")
			(net "P0V9_LX")
		)
		(pad "2" smd rect
			(at 0 4.020566 90)
			(size 2.4892 3.429)
			(layers "F.Cu" "F.Mask" "F.Paste")
			(net "P0V9")
		)
	)
	(footprint ""
		(layer "F.Cu")
		(at 144.8054 -51.816)
		(property "Reference" "R755"
			(at 0 0 0)
			(layer "F.SilkS")
			(hide yes)
			(effects
				(font
					(size 1.27 1.27)
				)
			)
		)
		(property "Value" "150R2F-1-GP"
			(at 0.064008 -3.993896 0)
			(unlocked yes)
			(layer "F.Fab")
			(hide yes)
			(effects
				(font
					(size 1.016 1.016)
					(thickness 0.1524)
				)
			)
		)
		(property "Device Type" "R402H16"
			(at 0.064008 -5.517896 0)
			(unlocked yes)
			(layer "F.Fab")
			(hide yes)
			(effects
				(font
					(size 1.016 1.016)
					(thickness 0.1524)
				)
			)
		)
		(duplicate_pad_numbers_are_jumpers no)
		(fp_line
			(start -0.508 -0.9398)
			(end -0.508 0.9398)
			(stroke
				(width 0.1524)
				(type default)
			)
			(layer "F.SilkS")
		)
		(fp_line
			(start 0.508 -0.9398)
			(end -0.508 -0.9398)
			(stroke
				(width 0.1524)
				(type default)
			)
			(layer "F.SilkS")
		)
		(fp_rect
			(start -0.508 0.9398)
			(end 0.508 -0.9398)
			(stroke
				(width 0)
				(type default)
			)
			(fill no)
			(layer "F.CrtYd")
		)
		(fp_rect
			(start -0.508 0.9398)
			(end 0.508 -0.9398)
			(stroke
				(width 0)
				(type default)
			)
			(fill no)
			(layer "F.Fab")
		)
		(pad "1" smd custom
			(at 0 -0.4445)
			(size 0.1397 0.1397)
			(layers "F.Cu" "F.Mask" "F.Paste")
			(net "DUT_VDDO")
			(options
				(clearance outline)
				(anchor circle)
			)
			(primitives
				(gr_poly
					(pts
						(arc
							(start -0.1778 -0.2794)
							(mid -0.249642 -0.249642)
							(end -0.2794 -0.1778)
						)
						(arc
							(start -0.2794 0.1778)
							(mid -0.249642 0.249642)
							(end -0.1778 0.2794)
						)
						(arc
							(start 0.1778 0.2794)
							(mid 0.249642 0.249642)
							(end 0.2794 0.1778)
						)
						(arc
							(start 0.2794 -0.1778)
							(mid 0.249642 -0.249642)
							(end 0.1778 -0.2794)
						)
					)
					(width 0)
					(fill yes)
				)
			)
		)
		(pad "2" smd custom
			(at 0 0.4445)
			(size 0.1397 0.1397)
			(layers "F.Cu" "F.Mask" "F.Paste")
			(net "EJTAG_PWR")
			(options
				(clearance outline)
				(anchor circle)
			)
			(primitives
				(gr_poly
					(pts
						(arc
							(start -0.1778 -0.2794)
							(mid -0.249642 -0.249642)
							(end -0.2794 -0.1778)
						)
						(arc
							(start -0.2794 0.1778)
							(mid -0.249642 0.249642)
							(end -0.1778 0.2794)
						)
						(arc
							(start 0.1778 0.2794)
							(mid 0.249642 0.249642)
							(end 0.2794 0.1778)
						)
						(arc
							(start 0.2794 -0.1778)
							(mid 0.249642 -0.249642)
							(end 0.1778 -0.2794)
						)
					)
					(width 0)
					(fill yes)
				)
			)
		)
	)
	(footprint ""
		(layer "F.Cu")
		(at 50.5206 -69.690488)
		(property "Reference" "SCN8"
			(at 0 0 0)
			(layer "F.SilkS")
			(hide yes)
			(effects
				(font
					(size 1.27 1.27)
				)
			)
		)
		(property "Value" "JWT-CON4-S24-GP"
			(at -7.3787 1.4351 0)
			(unlocked yes)
			(layer "F.Fab")
			(hide yes)
			(effects
				(font
					(size 1.016 1.016)
					(thickness 0.1524)
				)
			)
		)
		(property "Device Type" "A2541WV0-1QX4PA-6T"
			(at -7.3787 -0.0889 0)
			(unlocked yes)
			(layer "F.Fab")
			(hide yes)
			(effects
				(font
					(size 1.016 1.016)
					(thickness 0.1524)
				)
			)
		)
		(duplicate_pad_numbers_are_jumpers no)
		(fp_line
			(start -5.461 -1.651)
			(end -5.461 -0.381)
			(stroke
				(width 0.4064)
				(type default)
			)
			(layer "F.SilkS")
		)
		(fp_line
			(start -5.334 -1.524)
			(end -5.334 1.524)
			(stroke
				(width 0.1524)
				(type default)
			)
			(layer "F.SilkS")
		)
		(fp_line
			(start -5.334 1.524)
			(end 5.334 1.524)
			(stroke
				(width 0.1524)
				(type default)
			)
			(layer "F.SilkS")
		)
		(fp_line
			(start -4.191 -1.651)
			(end -5.461 -1.651)
			(stroke
				(width 0.4064)
				(type default)
			)
			(layer "F.SilkS")
		)
		(fp_line
			(start 5.334 -1.524)
			(end -5.334 -1.524)
			(stroke
				(width 0.1524)
				(type default)
			)
			(layer "F.SilkS")
		)
		(fp_line
			(start 5.334 1.524)
			(end 5.334 -1.524)
			(stroke
				(width 0.1524)
				(type default)
			)
			(layer "F.SilkS")
		)
		(fp_circle
			(center -3.81 0)
			(end -2.7432 0)
			(stroke
				(width 0.3048)
				(type default)
			)
			(fill no)
			(layer "F.SilkS")
		)
		(fp_circle
			(center -1.27 0)
			(end -0.2032 0)
			(stroke
				(width 0.3048)
				(type default)
			)
			(fill no)
			(layer "F.SilkS")
		)
		(fp_circle
			(center 1.27 0)
			(end 2.3368 0)
			(stroke
				(width 0.3048)
				(type default)
			)
			(fill no)
			(layer "F.SilkS")
		)
		(fp_circle
			(center 3.81 0)
			(end 4.8768 0)
			(stroke
				(width 0.3048)
				(type default)
			)
			(fill no)
			(layer "F.SilkS")
		)
		(fp_rect
			(start -5.08 1.27)
			(end 5.08 -1.27)
			(stroke
				(width 0)
				(type default)
			)
			(fill no)
			(layer "F.CrtYd")
		)
		(fp_poly
			(pts
				(xy -5.588 1.778) (xy -5.588 -1.778) (xy 5.588 -1.778) (xy 5.588 1.2573) (xy 5.08 1.2573) (xy 5.08 -1.27)
				(xy -5.08 -1.27) (xy -5.08 1.27) (xy 5.588 1.27) (xy 5.588 1.778)
			)
			(stroke
				(width 0)
				(type default)
			)
			(fill no)
			(layer "F.CrtYd")
		)
		(fp_rect
			(start -5.588 1.778)
			(end 5.588 -1.778)
			(stroke
				(width 0)
				(type default)
			)
			(fill no)
			(layer "F.Fab")
		)
		(pad "1" thru_hole circle
			(at -3.81 0)
			(size 1.4224 1.4224)
			(drill 1.016)
			(layers "*.Cu" "*.Mask")
			(remove_unused_layers no)
			(net "P5V_STBY")
			(clearance 0.1524)
			(thermal_gap 0.1524)
		)
		(pad "2" thru_hole circle
			(at -1.27 0)
			(size 1.4224 1.4224)
			(drill 1.016)
			(layers "*.Cu" "*.Mask")
			(remove_unused_layers no)
			(net "BMC_R_TXD5")
			(clearance 0.1524)
			(thermal_gap 0.1524)
		)
		(pad "3" thru_hole circle
			(at 1.27 0)
			(size 1.4224 1.4224)
			(drill 1.016)
			(layers "*.Cu" "*.Mask")
			(remove_unused_layers no)
			(net "BMC_R_RXD5")
			(clearance 0.1524)
			(thermal_gap 0.1524)
		)
		(pad "4" thru_hole circle
			(at 3.81 0)
			(size 1.4224 1.4224)
			(drill 1.016)
			(layers "*.Cu" "*.Mask")
			(remove_unused_layers no)
			(net "GND")
			(clearance 0.1524)
			(thermal_gap 0.1524)
		)
	)
	(footprint ""
		(layer "F.Cu")
		(at 332.7908 -184.8866)
		(property "Reference" "R563"
			(at 0 0 0)
			(layer "F.SilkS")
			(hide yes)
			(effects
				(font
					(size 1.27 1.27)
				)
			)
		)
		(property "Value" "10KR2F-2-GP"
			(at 0.064008 -3.993896 0)
			(unlocked yes)
			(layer "F.Fab")
			(hide yes)
			(effects
				(font
					(size 1.016 1.016)
					(thickness 0.1524)
				)
			)
		)
		(property "Device Type" "R402H16"
			(at 0.064008 -5.517896 0)
			(unlocked yes)
			(layer "F.Fab")
			(hide yes)
			(effects
				(font
					(size 1.016 1.016)
					(thickness 0.1524)
				)
			)
		)
		(duplicate_pad_numbers_are_jumpers no)
		(fp_line
			(start -0.508 -0.9398)
			(end -0.508 0.9398)
			(stroke
				(width 0.1524)
				(type default)
			)
			(layer "F.SilkS")
		)
		(fp_line
			(start 0.508 -0.9398)
			(end -0.508 -0.9398)
			(stroke
				(width 0.1524)
				(type default)
			)
			(layer "F.SilkS")
		)
		(fp_rect
			(start -0.508 0.9398)
			(end 0.508 -0.9398)
			(stroke
				(width 0)
				(type default)
			)
			(fill no)
			(layer "F.CrtYd")
		)
		(fp_rect
			(start -0.508 0.9398)
			(end 0.508 -0.9398)
			(stroke
				(width 0)
				(type default)
			)
			(fill no)
			(layer "F.Fab")
		)
		(pad "1" smd custom
			(at 0 -0.4445)
			(size 0.1397 0.1397)
			(layers "F.Cu" "F.Mask" "F.Paste")
			(net "GND")
			(options
				(clearance outline)
				(anchor circle)
			)
			(primitives
				(gr_poly
					(pts
						(arc
							(start -0.1778 -0.2794)
							(mid -0.249642 -0.249642)
							(end -0.2794 -0.1778)
						)
						(arc
							(start -0.2794 0.1778)
							(mid -0.249642 0.249642)
							(end -0.1778 0.2794)
						)
						(arc
							(start 0.1778 0.2794)
							(mid 0.249642 0.249642)
							(end 0.2794 0.1778)
						)
						(arc
							(start 0.2794 -0.1778)
							(mid 0.249642 -0.249642)
							(end 0.1778 -0.2794)
						)
					)
					(width 0)
					(fill yes)
				)
			)
		)
		(pad "2" smd custom
			(at 0 0.4445)
			(size 0.1397 0.1397)
			(layers "F.Cu" "F.Mask" "F.Paste")
			(net "IOEXP4_AD0")
			(options
				(clearance outline)
				(anchor circle)
			)
			(primitives
				(gr_poly
					(pts
						(arc
							(start -0.1778 -0.2794)
							(mid -0.249642 -0.249642)
							(end -0.2794 -0.1778)
						)
						(arc
							(start -0.2794 0.1778)
							(mid -0.249642 0.249642)
							(end -0.1778 0.2794)
						)
						(arc
							(start 0.1778 0.2794)
							(mid 0.249642 0.249642)
							(end 0.2794 0.1778)
						)
						(arc
							(start 0.2794 -0.1778)
							(mid 0.249642 -0.249642)
							(end 0.1778 -0.2794)
						)
					)
					(width 0)
					(fill yes)
				)
			)
		)
	)
	(footprint ""
		(layer "F.Cu")
		(at 64.447674 -67.12712 180)
		(property "Reference" "U19"
			(at 0 0 180)
			(layer "F.SilkS")
			(hide yes)
			(effects
				(font
					(size 1.27 1.27)
				)
			)
		)
		(property "Value" "MX25L25635FMI-10G-GP"
			(at 0 -14.6812 180)
			(unlocked yes)
			(layer "F.Fab")
			(hide yes)
			(effects
				(font
					(size 1.016 1.016)
					(thickness 0.1524)
				)
			)
		)
		(property "Device Type" "SOIC16-6H105"
			(at 0 -16.2052 180)
			(unlocked yes)
			(layer "F.Fab")
			(hide yes)
			(effects
				(font
					(size 1.016 1.016)
					(thickness 0.1524)
				)
			)
		)
		(duplicate_pad_numbers_are_jumpers no)
		(fp_line
			(start 4.7498 3.2258)
			(end -5.588 3.2258)
			(stroke
				(width 0.1524)
				(type default)
			)
			(layer "F.SilkS")
		)
		(fp_line
			(start 4.7498 -3.2258)
			(end 4.7498 3.2258)
			(stroke
				(width 0.1524)
				(type default)
			)
			(layer "F.SilkS")
		)
		(fp_line
			(start -5.08762 0)
			(end -5.588 0.50038)
			(stroke
				(width 0.1524)
				(type default)
			)
			(layer "F.SilkS")
		)
		(fp_line
			(start -5.4102 3.2258)
			(end -5.4102 5.7912)
			(stroke
				(width 0.508)
				(type default)
			)
			(layer "F.SilkS")
		)
		(fp_line
			(start -5.588 3.2258)
			(end -5.588 -3.2258)
			(stroke
				(width 0.1524)
				(type default)
			)
			(layer "F.SilkS")
		)
		(fp_line
			(start -5.588 -0.50038)
			(end -5.08762 0)
			(stroke
				(width 0.1524)
				(type default)
			)
			(layer "F.SilkS")
		)
		(fp_line
			(start -5.588 -3.2258)
			(end 4.7498 -3.2258)
			(stroke
				(width 0.1524)
				(type default)
			)
			(layer "F.SilkS")
		)
		(fp_poly
			(pts
				(xy -4.764786 -3.2258) (xy 4.7625 -3.2258) (xy 4.7625 3.2258) (xy -4.764786 3.2258)
			)
			(stroke
				(width 0)
				(type default)
			)
			(fill yes)
			(layer "F.SilkS")
		)
		(fp_poly
			(pts
				(xy -5.6642 6.0452) (xy 5.6642 6.0452) (xy 5.6642 -6.0452) (xy -5.6642 -6.0452)
			)
			(stroke
				(width 0)
				(type default)
			)
			(fill no)
			(layer "F.CrtYd")
		)
		(fp_poly
			(pts
				(xy -5.6642 -6.0452) (xy 5.6642 -6.0452) (xy 5.6642 6.0452) (xy -5.6642 6.0452)
			)
			(stroke
				(width 0)
				(type default)
			)
			(fill no)
			(layer "F.Fab")
		)
		(pad "1" smd rect
			(at -4.445 4.71805 180)
			(size 0.635 1.651)
			(layers "F.Cu" "F.Mask" "F.Paste")
			(net "PU_IBMC_BT_HOLD_N")
		)
		(pad "2" smd rect
			(at -3.175 4.71805 180)
			(size 0.635 1.651)
			(layers "F.Cu" "F.Mask" "F.Paste")
			(net "P3V3_STBY")
		)
		(pad "3" smd rect
			(at -1.905 4.71805 180)
			(size 0.635 1.651)
			(layers "F.Cu" "F.Mask" "F.Paste")
			(net "U19_PERST_N")
		)
		(pad "4" smd rect
			(at -0.635 4.71805 180)
			(size 0.635 1.651)
			(layers "F.Cu" "F.Mask" "F.Paste")
			(net "Net_32")
		)
		(pad "5" smd rect
			(at 0.635 4.71805 180)
			(size 0.635 1.651)
			(layers "F.Cu" "F.Mask" "F.Paste")
			(net "Net_31")
		)
		(pad "6" smd rect
			(at 1.905 4.71805 180)
			(size 0.635 1.651)
			(layers "F.Cu" "F.Mask" "F.Paste")
			(net "Net_30")
		)
		(pad "7" smd rect
			(at 3.175 4.71805 180)
			(size 0.635 1.651)
			(layers "F.Cu" "F.Mask" "F.Paste")
			(net "FLA_CS1_R")
		)
		(pad "8" smd rect
			(at 4.445 4.71805 180)
			(size 0.635 1.651)
			(layers "F.Cu" "F.Mask" "F.Paste")
			(net "ROMD2_R")
		)
		(pad "9" smd rect
			(at 4.445 -4.71805 180)
			(size 0.635 1.651)
			(layers "F.Cu" "F.Mask" "F.Paste")
			(net "FLA_WPN")
		)
		(pad "10" smd rect
			(at 3.175 -4.71805 180)
			(size 0.635 1.651)
			(layers "F.Cu" "F.Mask" "F.Paste")
			(net "GND")
		)
		(pad "11" smd rect
			(at 1.905 -4.71805 180)
			(size 0.635 1.651)
			(layers "F.Cu" "F.Mask" "F.Paste")
			(net "Net_29")
		)
		(pad "12" smd rect
			(at 0.635 -4.71805 180)
			(size 0.635 1.651)
			(layers "F.Cu" "F.Mask" "F.Paste")
			(net "Net_28")
		)
		(pad "13" smd rect
			(at -0.635 -4.71805 180)
			(size 0.635 1.651)
			(layers "F.Cu" "F.Mask" "F.Paste")
			(net "Net_27")
		)
		(pad "14" smd rect
			(at -1.905 -4.71805 180)
			(size 0.635 1.651)
			(layers "F.Cu" "F.Mask" "F.Paste")
			(net "Net_26")
		)
		(pad "15" smd rect
			(at -3.175 -4.71805 180)
			(size 0.635 1.651)
			(layers "F.Cu" "F.Mask" "F.Paste")
			(net "ROMD1_R")
		)
		(pad "16" smd rect
			(at -4.445 -4.71805 180)
			(size 0.635 1.651)
			(layers "F.Cu" "F.Mask" "F.Paste")
			(net "ROMD0_R")
		)
	)
	(footprint ""
		(layer "F.Cu")
		(at 303.00803 -212.420454 180)
		(property "Reference" "C75"
			(at 0 0 180)
			(layer "F.SilkS")
			(hide yes)
			(effects
				(font
					(size 1.27 1.27)
				)
			)
		)
		(property "Value" "SCD22U10V2KX-1GP"
			(at 1.1811 -2.7051 180)
			(unlocked yes)
			(layer "F.Fab")
			(hide yes)
			(effects
				(font
					(size 1.016 1.016)
					(thickness 0.1524)
				)
			)
		)
		(property "Device Type" "C402H22"
			(at 1.1811 -4.2291 180)
			(unlocked yes)
			(layer "F.Fab")
			(hide yes)
			(effects
				(font
					(size 1.016 1.016)
					(thickness 0.1524)
				)
			)
		)
		(duplicate_pad_numbers_are_jumpers no)
		(fp_rect
			(start -0.4318 0.9525)
			(end 0.4318 -0.9525)
			(stroke
				(width 0)
				(type default)
			)
			(fill no)
			(layer "F.CrtYd")
		)
		(fp_rect
			(start -0.4318 0.9525)
			(end 0.4318 -0.9525)
			(stroke
				(width 0)
				(type default)
			)
			(fill no)
			(layer "F.Fab")
		)
		(pad "1" smd custom
			(at 0 -0.4445 180)
			(size 0.1524 0.1524)
			(layers "F.Cu" "F.Mask" "F.Paste")
			(net "PCIE_TX_CAP_N26")
			(options
				(clearance outline)
				(anchor circle)
			)
			(primitives
				(gr_poly
					(pts
						(arc
							(start 0.3048 -0.2032)
							(mid 0.275042 -0.275042)
							(end 0.2032 -0.3048)
						)
						(arc
							(start -0.2032 -0.3048)
							(mid -0.275042 -0.275042)
							(end -0.3048 -0.2032)
						)
						(arc
							(start -0.3048 0.2032)
							(mid -0.275042 0.275042)
							(end -0.2032 0.3048)
						)
						(arc
							(start 0.2032 0.3048)
							(mid 0.275042 0.275042)
							(end 0.3048 0.2032)
						)
					)
					(width 0)
					(fill yes)
				)
			)
		)
		(pad "2" smd custom
			(at 0 0.4445 180)
			(size 0.1524 0.1524)
			(layers "F.Cu" "F.Mask" "F.Paste")
			(net "PCIE_TX_N26")
			(options
				(clearance outline)
				(anchor circle)
			)
			(primitives
				(gr_poly
					(pts
						(arc
							(start 0.3048 -0.2032)
							(mid 0.275042 -0.275042)
							(end 0.2032 -0.3048)
						)
						(arc
							(start -0.2032 -0.3048)
							(mid -0.275042 -0.275042)
							(end -0.3048 -0.2032)
						)
						(arc
							(start -0.3048 0.2032)
							(mid -0.275042 0.275042)
							(end -0.2032 0.3048)
						)
						(arc
							(start 0.2032 0.3048)
							(mid 0.275042 0.275042)
							(end 0.3048 0.2032)
						)
					)
					(width 0)
					(fill yes)
				)
			)
		)
	)
	(footprint ""
		(layer "F.Cu")
		(at 20.6502 -83.82 180)
		(property "Reference" "C643"
			(at 0 0 180)
			(layer "F.SilkS")
			(hide yes)
			(effects
				(font
					(size 1.27 1.27)
				)
			)
		)
		(property "Value" "SCD22U10V2KX-1GP"
			(at 1.1811 -2.7051 180)
			(unlocked yes)
			(layer "F.Fab")
			(hide yes)
			(effects
				(font
					(size 1.016 1.016)
					(thickness 0.1524)
				)
			)
		)
		(property "Device Type" "C402H22"
			(at 1.1811 -4.2291 180)
			(unlocked yes)
			(layer "F.Fab")
			(hide yes)
			(effects
				(font
					(size 1.016 1.016)
					(thickness 0.1524)
				)
			)
		)
		(duplicate_pad_numbers_are_jumpers no)
		(fp_rect
			(start -0.4318 0.9525)
			(end 0.4318 -0.9525)
			(stroke
				(width 0)
				(type default)
			)
			(fill no)
			(layer "F.CrtYd")
		)
		(fp_rect
			(start -0.4318 0.9525)
			(end 0.4318 -0.9525)
			(stroke
				(width 0)
				(type default)
			)
			(fill no)
			(layer "F.Fab")
		)
		(pad "1" smd custom
			(at 0 -0.4445 180)
			(size 0.1524 0.1524)
			(layers "F.Cu" "F.Mask" "F.Paste")
			(net "PCIE_RX_CAP_P78")
			(options
				(clearance outline)
				(anchor circle)
			)
			(primitives
				(gr_poly
					(pts
						(arc
							(start 0.3048 -0.2032)
							(mid 0.275042 -0.275042)
							(end 0.2032 -0.3048)
						)
						(arc
							(start -0.2032 -0.3048)
							(mid -0.275042 -0.275042)
							(end -0.3048 -0.2032)
						)
						(arc
							(start -0.3048 0.2032)
							(mid -0.275042 0.275042)
							(end -0.2032 0.3048)
						)
						(arc
							(start 0.2032 0.3048)
							(mid 0.275042 0.275042)
							(end 0.3048 0.2032)
						)
					)
					(width 0)
					(fill yes)
				)
			)
		)
		(pad "2" smd custom
			(at 0 0.4445 180)
			(size 0.1524 0.1524)
			(layers "F.Cu" "F.Mask" "F.Paste")
			(net "PCIE_RX_P78")
			(options
				(clearance outline)
				(anchor circle)
			)
			(primitives
				(gr_poly
					(pts
						(arc
							(start 0.3048 -0.2032)
							(mid 0.275042 -0.275042)
							(end 0.2032 -0.3048)
						)
						(arc
							(start -0.2032 -0.3048)
							(mid -0.275042 -0.275042)
							(end -0.3048 -0.2032)
						)
						(arc
							(start -0.3048 0.2032)
							(mid -0.275042 0.275042)
							(end -0.2032 0.3048)
						)
						(arc
							(start 0.2032 0.3048)
							(mid 0.275042 0.275042)
							(end 0.3048 0.2032)
						)
					)
					(width 0)
					(fill yes)
				)
			)
		)
	)
	(footprint ""
		(layer "F.Cu")
		(at 125.599952 -7.999984 90)
		(property "Reference" "LED10"
			(at 0 0 90)
			(layer "F.SilkS")
			(hide yes)
			(effects
				(font
					(size 1.27 1.27)
				)
			)
		)
		(property "Value" "LED-YG-51-GP"
			(at -2.6924 -1.4224 90)
			(unlocked yes)
			(layer "F.Fab")
			(hide yes)
			(effects
				(font
					(size 1.016 1.016)
					(thickness 0.1524)
				)
			)
		)
		(property "Device Type" "LED1608AKH40"
			(at -2.6924 -2.9464 90)
			(unlocked yes)
			(layer "F.Fab")
			(hide yes)
			(effects
				(font
					(size 1.016 1.016)
					(thickness 0.1524)
				)
			)
		)
		(duplicate_pad_numbers_are_jumpers no)
		(fp_line
			(start 0.6604 -1.3716)
			(end 0.6604 1.3716)
			(stroke
				(width 0.1524)
				(type default)
			)
			(layer "F.SilkS")
		)
		(fp_line
			(start -0.6604 -1.3716)
			(end 0.6604 -1.3716)
			(stroke
				(width 0.1524)
				(type default)
			)
			(layer "F.SilkS")
		)
		(fp_line
			(start 0.6604 1.3716)
			(end -0.6604 1.3716)
			(stroke
				(width 0.1524)
				(type default)
			)
			(layer "F.SilkS")
		)
		(fp_line
			(start -0.6604 1.3716)
			(end -0.6604 -1.3716)
			(stroke
				(width 0.1524)
				(type default)
			)
			(layer "F.SilkS")
		)
		(fp_line
			(start -0.5969 1.5494)
			(end 0.5842 1.5494)
			(stroke
				(width 0.508)
				(type default)
			)
			(layer "F.SilkS")
		)
		(fp_line
			(start 0.7493 1.651)
			(end 0.7493 1.1811)
			(stroke
				(width 0.3302)
				(type default)
			)
			(layer "F.SilkS")
		)
		(fp_line
			(start -0.7493 1.651)
			(end -0.7493 1.1811)
			(stroke
				(width 0.3302)
				(type default)
			)
			(layer "F.SilkS")
		)
		(fp_rect
			(start -0.6223 1.3335)
			(end 0.6223 -1.3335)
			(stroke
				(width 0)
				(type default)
			)
			(fill no)
			(layer "F.CrtYd")
		)
		(fp_rect
			(start -0.6223 1.3335)
			(end 0.6223 -1.3335)
			(stroke
				(width 0)
				(type default)
			)
			(fill no)
			(layer "F.Fab")
		)
		(pad "A" smd custom
			(at 0 -0.762 90)
			(size 0.2159 0.2159)
			(layers "F.Cu" "F.Mask" "F.Paste")
			(net "LED_R_3")
			(options
				(clearance outline)
				(anchor circle)
			)
			(primitives
				(gr_poly
					(pts
						(arc
							(start -0.3302 -0.4318)
							(mid -0.402042 -0.402042)
							(end -0.4318 -0.3302)
						)
						(arc
							(start -0.4318 0.3302)
							(mid -0.402042 0.402042)
							(end -0.3302 0.4318)
						)
						(arc
							(start 0.3302 0.4318)
							(mid 0.402042 0.402042)
							(end 0.4318 0.3302)
						)
						(arc
							(start 0.4318 -0.3302)
							(mid 0.402042 -0.402042)
							(end 0.3302 -0.4318)
						)
					)
					(width 0)
					(fill yes)
				)
			)
		)
		(pad "K" smd custom
			(at 0 0.762 90)
			(size 0.2159 0.2159)
			(layers "F.Cu" "F.Mask" "F.Paste")
			(net "LED_Q_3")
			(options
				(clearance outline)
				(anchor circle)
			)
			(primitives
				(gr_poly
					(pts
						(arc
							(start -0.3302 -0.4318)
							(mid -0.402042 -0.402042)
							(end -0.4318 -0.3302)
						)
						(arc
							(start -0.4318 0.3302)
							(mid -0.402042 0.402042)
							(end -0.3302 0.4318)
						)
						(arc
							(start 0.3302 0.4318)
							(mid 0.402042 0.402042)
							(end 0.4318 0.3302)
						)
						(arc
							(start 0.4318 -0.3302)
							(mid 0.402042 -0.402042)
							(end 0.3302 -0.4318)
						)
					)
					(width 0)
					(fill yes)
				)
			)
		)
	)
	(footprint ""
		(layer "F.Cu")
		(at 225.586798 -206.384906 90)
		(property "Reference" "C4128"
			(at 0 0 90)
			(layer "F.SilkS")
			(hide yes)
			(effects
				(font
					(size 1.27 1.27)
				)
			)
		)
		(property "Value" "SCD1U25V3KX-GP"
			(at 0 -2.8194 90)
			(unlocked yes)
			(layer "F.Fab")
			(hide yes)
			(effects
				(font
					(size 1.016 1.016)
					(thickness 0.1524)
				)
			)
		)
		(property "Device Type" "C603H36"
			(at 0 -4.3434 90)
			(unlocked yes)
			(layer "F.Fab")
			(hide yes)
			(effects
				(font
					(size 1.016 1.016)
					(thickness 0.1524)
				)
			)
		)
		(duplicate_pad_numbers_are_jumpers no)
		(fp_line
			(start 0.508 0)
			(end -0.508 0)
			(stroke
				(width 0.2032)
				(type default)
			)
			(layer "F.SilkS")
		)
		(fp_rect
			(start -0.5842 1.3335)
			(end 0.5842 -1.3335)
			(stroke
				(width 0)
				(type default)
			)
			(fill no)
			(layer "F.CrtYd")
		)
		(fp_rect
			(start -0.5842 1.3335)
			(end 0.5842 -1.3335)
			(stroke
				(width 0)
				(type default)
			)
			(fill no)
			(layer "F.Fab")
		)
		(pad "1" smd custom
			(at 0 -0.762 90)
			(size 0.2159 0.2159)
			(layers "F.Cu" "F.Mask" "F.Paste")
			(net "GND")
			(options
				(clearance outline)
				(anchor circle)
			)
			(primitives
				(gr_poly
					(pts
						(arc
							(start -0.3302 -0.4318)
							(mid -0.402042 -0.402042)
							(end -0.4318 -0.3302)
						)
						(arc
							(start -0.4318 0.3302)
							(mid -0.402042 0.402042)
							(end -0.3302 0.4318)
						)
						(arc
							(start 0.3302 0.4318)
							(mid 0.402042 0.402042)
							(end 0.4318 0.3302)
						)
						(arc
							(start 0.4318 -0.3302)
							(mid 0.402042 -0.402042)
							(end 0.3302 -0.4318)
						)
					)
					(width 0)
					(fill yes)
				)
			)
		)
		(pad "2" smd custom
			(at 0 0.762 90)
			(size 0.2159 0.2159)
			(layers "F.Cu" "F.Mask" "F.Paste")
			(net "SSD_PWREN12_R")
			(options
				(clearance outline)
				(anchor circle)
			)
			(primitives
				(gr_poly
					(pts
						(arc
							(start -0.3302 -0.4318)
							(mid -0.402042 -0.402042)
							(end -0.4318 -0.3302)
						)
						(arc
							(start -0.4318 0.3302)
							(mid -0.402042 0.402042)
							(end -0.3302 0.4318)
						)
						(arc
							(start 0.3302 0.4318)
							(mid 0.402042 0.402042)
							(end 0.4318 0.3302)
						)
						(arc
							(start 0.4318 -0.3302)
							(mid 0.402042 -0.402042)
							(end 0.3302 -0.4318)
						)
					)
					(width 0)
					(fill yes)
				)
			)
		)
	)
	(footprint ""
		(layer "F.Cu")
		(at 183.950102 -0.60452 -90)
		(property "Reference" "R670"
			(at 0 0 270)
			(layer "F.SilkS")
			(hide yes)
			(effects
				(font
					(size 1.27 1.27)
				)
			)
		)
		(property "Value" "0R2J-2-GP"
			(at 0.064008 -3.993896 270)
			(unlocked yes)
			(layer "F.Fab")
			(hide yes)
			(effects
				(font
					(size 1.016 1.016)
					(thickness 0.1524)
				)
			)
		)
		(property "Device Type" "R402H16"
			(at 0.064008 -5.517896 270)
			(unlocked yes)
			(layer "F.Fab")
			(hide yes)
			(effects
				(font
					(size 1.016 1.016)
					(thickness 0.1524)
				)
			)
		)
		(duplicate_pad_numbers_are_jumpers no)
		(fp_line
			(start -0.508 -0.9398)
			(end -0.508 0.9398)
			(stroke
				(width 0.1524)
				(type default)
			)
			(layer "F.SilkS")
		)
		(fp_line
			(start 0.508 -0.9398)
			(end -0.508 -0.9398)
			(stroke
				(width 0.1524)
				(type default)
			)
			(layer "F.SilkS")
		)
		(fp_rect
			(start -0.508 0.9398)
			(end 0.508 -0.9398)
			(stroke
				(width 0)
				(type default)
			)
			(fill no)
			(layer "F.CrtYd")
		)
		(fp_rect
			(start -0.508 0.9398)
			(end 0.508 -0.9398)
			(stroke
				(width 0)
				(type default)
			)
			(fill no)
			(layer "F.Fab")
		)
		(pad "1" smd custom
			(at 0 -0.4445 270)
			(size 0.1397 0.1397)
			(layers "F.Cu" "F.Mask" "F.Paste")
			(net "HOST1_RST_N_C")
			(options
				(clearance outline)
				(anchor circle)
			)
			(primitives
				(gr_poly
					(pts
						(arc
							(start -0.1778 -0.2794)
							(mid -0.249642 -0.249642)
							(end -0.2794 -0.1778)
						)
						(arc
							(start -0.2794 0.1778)
							(mid -0.249642 0.249642)
							(end -0.1778 0.2794)
						)
						(arc
							(start 0.1778 0.2794)
							(mid 0.249642 0.249642)
							(end 0.2794 0.1778)
						)
						(arc
							(start 0.2794 -0.1778)
							(mid 0.249642 -0.249642)
							(end 0.1778 -0.2794)
						)
					)
					(width 0)
					(fill yes)
				)
			)
		)
		(pad "2" smd custom
			(at 0 0.4445 270)
			(size 0.1397 0.1397)
			(layers "F.Cu" "F.Mask" "F.Paste")
			(net "P3V3_STBY")
			(options
				(clearance outline)
				(anchor circle)
			)
			(primitives
				(gr_poly
					(pts
						(arc
							(start -0.1778 -0.2794)
							(mid -0.249642 -0.249642)
							(end -0.2794 -0.1778)
						)
						(arc
							(start -0.2794 0.1778)
							(mid -0.249642 0.249642)
							(end -0.1778 0.2794)
						)
						(arc
							(start 0.1778 0.2794)
							(mid 0.249642 0.249642)
							(end 0.2794 0.1778)
						)
						(arc
							(start 0.2794 -0.1778)
							(mid 0.249642 -0.249642)
							(end 0.1778 -0.2794)
						)
					)
					(width 0)
					(fill yes)
				)
			)
		)
	)
	(footprint ""
		(layer "F.Cu")
		(at 192.5574 -8.9154 90)
		(property "Reference" "R683"
			(at 0 0 90)
			(layer "F.SilkS")
			(hide yes)
			(effects
				(font
					(size 1.27 1.27)
				)
			)
		)
		(property "Value" "0R2J-2-GP"
			(at 0.064008 -3.993896 90)
			(unlocked yes)
			(layer "F.Fab")
			(hide yes)
			(effects
				(font
					(size 1.016 1.016)
					(thickness 0.1524)
				)
			)
		)
		(property "Device Type" "R402H16"
			(at 0.064008 -5.517896 90)
			(unlocked yes)
			(layer "F.Fab")
			(hide yes)
			(effects
				(font
					(size 1.016 1.016)
					(thickness 0.1524)
				)
			)
		)
		(duplicate_pad_numbers_are_jumpers no)
		(fp_line
			(start 0.508 -0.9398)
			(end -0.508 -0.9398)
			(stroke
				(width 0.1524)
				(type default)
			)
			(layer "F.SilkS")
		)
		(fp_line
			(start -0.508 -0.9398)
			(end -0.508 0.9398)
			(stroke
				(width 0.1524)
				(type default)
			)
			(layer "F.SilkS")
		)
		(fp_rect
			(start -0.508 0.9398)
			(end 0.508 -0.9398)
			(stroke
				(width 0)
				(type default)
			)
			(fill no)
			(layer "F.CrtYd")
		)
		(fp_rect
			(start -0.508 0.9398)
			(end 0.508 -0.9398)
			(stroke
				(width 0)
				(type default)
			)
			(fill no)
			(layer "F.Fab")
		)
		(pad "1" smd custom
			(at 0 -0.4445 90)
			(size 0.1397 0.1397)
			(layers "F.Cu" "F.Mask" "F.Paste")
			(net "BMC_ENCLOSURE_LED_R")
			(options
				(clearance outline)
				(anchor circle)
			)
			(primitives
				(gr_poly
					(pts
						(arc
							(start -0.1778 -0.2794)
							(mid -0.249642 -0.249642)
							(end -0.2794 -0.1778)
						)
						(arc
							(start -0.2794 0.1778)
							(mid -0.249642 0.249642)
							(end -0.1778 0.2794)
						)
						(arc
							(start 0.1778 0.2794)
							(mid 0.249642 0.249642)
							(end 0.2794 0.1778)
						)
						(arc
							(start 0.2794 -0.1778)
							(mid 0.249642 -0.249642)
							(end 0.1778 -0.2794)
						)
					)
					(width 0)
					(fill yes)
				)
			)
		)
		(pad "2" smd custom
			(at 0 0.4445 90)
			(size 0.1397 0.1397)
			(layers "F.Cu" "F.Mask" "F.Paste")
			(net "BMC_ENCLOSURE_LED")
			(options
				(clearance outline)
				(anchor circle)
			)
			(primitives
				(gr_poly
					(pts
						(arc
							(start -0.1778 -0.2794)
							(mid -0.249642 -0.249642)
							(end -0.2794 -0.1778)
						)
						(arc
							(start -0.2794 0.1778)
							(mid -0.249642 0.249642)
							(end -0.1778 0.2794)
						)
						(arc
							(start 0.1778 0.2794)
							(mid 0.249642 0.249642)
							(end 0.2794 0.1778)
						)
						(arc
							(start 0.2794 -0.1778)
							(mid 0.249642 -0.249642)
							(end 0.1778 -0.2794)
						)
					)
					(width 0)
					(fill yes)
				)
			)
		)
	)
	(footprint ""
		(layer "F.Cu")
		(at 139.8016 -41.4782 180)
		(property "Reference" "R770"
			(at 0 0 180)
			(layer "F.SilkS")
			(hide yes)
			(effects
				(font
					(size 1.27 1.27)
				)
			)
		)
		(property "Value" "4K7R2F-GP"
			(at 0.064008 -3.993896 180)
			(unlocked yes)
			(layer "F.Fab")
			(hide yes)
			(effects
				(font
					(size 1.016 1.016)
					(thickness 0.1524)
				)
			)
		)
		(property "Device Type" "R402H16"
			(at 0.064008 -5.517896 180)
			(unlocked yes)
			(layer "F.Fab")
			(hide yes)
			(effects
				(font
					(size 1.016 1.016)
					(thickness 0.1524)
				)
			)
		)
		(duplicate_pad_numbers_are_jumpers no)
		(fp_line
			(start 0.508 -0.9398)
			(end -0.508 -0.9398)
			(stroke
				(width 0.1524)
				(type default)
			)
			(layer "F.SilkS")
		)
		(fp_line
			(start -0.508 -0.9398)
			(end -0.508 0.9398)
			(stroke
				(width 0.1524)
				(type default)
			)
			(layer "F.SilkS")
		)
		(fp_rect
			(start -0.508 0.9398)
			(end 0.508 -0.9398)
			(stroke
				(width 0)
				(type default)
			)
			(fill no)
			(layer "F.CrtYd")
		)
		(fp_rect
			(start -0.508 0.9398)
			(end 0.508 -0.9398)
			(stroke
				(width 0)
				(type default)
			)
			(fill no)
			(layer "F.Fab")
		)
		(pad "1" smd custom
			(at 0 -0.4445 180)
			(size 0.1397 0.1397)
			(layers "F.Cu" "F.Mask" "F.Paste")
			(net "DUT_VDDO")
			(options
				(clearance outline)
				(anchor circle)
			)
			(primitives
				(gr_poly
					(pts
						(arc
							(start -0.1778 -0.2794)
							(mid -0.249642 -0.249642)
							(end -0.2794 -0.1778)
						)
						(arc
							(start -0.2794 0.1778)
							(mid -0.249642 0.249642)
							(end -0.1778 0.2794)
						)
						(arc
							(start 0.1778 0.2794)
							(mid 0.249642 0.249642)
							(end 0.2794 0.1778)
						)
						(arc
							(start 0.2794 -0.1778)
							(mid 0.249642 -0.249642)
							(end 0.1778 -0.2794)
						)
					)
					(width 0)
					(fill yes)
				)
			)
		)
		(pad "2" smd custom
			(at 0 0.4445 180)
			(size 0.1397 0.1397)
			(layers "F.Cu" "F.Mask" "F.Paste")
			(net "EJTAG_TMS")
			(options
				(clearance outline)
				(anchor circle)
			)
			(primitives
				(gr_poly
					(pts
						(arc
							(start -0.1778 -0.2794)
							(mid -0.249642 -0.249642)
							(end -0.2794 -0.1778)
						)
						(arc
							(start -0.2794 0.1778)
							(mid -0.249642 0.249642)
							(end -0.1778 0.2794)
						)
						(arc
							(start 0.1778 0.2794)
							(mid 0.249642 0.249642)
							(end 0.2794 0.1778)
						)
						(arc
							(start 0.2794 -0.1778)
							(mid 0.249642 -0.249642)
							(end 0.1778 -0.2794)
						)
					)
					(width 0)
					(fill yes)
				)
			)
		)
	)
	(footprint ""
		(layer "F.Cu")
		(at 237.549944 -2.500122 180)
		(property "Reference" "CN3"
			(at 0 0 180)
			(layer "F.SilkS")
			(hide yes)
			(effects
				(font
					(size 1.27 1.27)
				)
			)
		)
		(property "Value" "JWT-CONN14A-1-GP"
			(at -9.8298 -4.064 180)
			(unlocked yes)
			(layer "F.Fab")
			(hide yes)
			(effects
				(font
					(size 1.016 1.016)
					(thickness 0.1524)
				)
			)
		)
		(property "Device Type" "A2005WR0-2CX7P-6T"
			(at -9.8298 -5.588 180)
			(unlocked yes)
			(layer "F.Fab")
			(hide yes)
			(effects
				(font
					(size 1.016 1.016)
					(thickness 0.1524)
				)
			)
		)
		(duplicate_pad_numbers_are_jumpers no)
		(fp_line
			(start 8.5852 -0.7366)
			(end 6.8834 -0.7366)
			(stroke
				(width 0.1524)
				(type default)
			)
			(layer "F.SilkS")
		)
		(fp_line
			(start 8.5852 -7.6454)
			(end 8.5852 -0.7366)
			(stroke
				(width 0.1524)
				(type default)
			)
			(layer "F.SilkS")
		)
		(fp_line
			(start 6.8834 1.8796)
			(end -6.8834 1.8796)
			(stroke
				(width 0.1524)
				(type default)
			)
			(layer "F.SilkS")
		)
		(fp_line
			(start 6.8834 -0.7366)
			(end 6.8834 1.8796)
			(stroke
				(width 0.1524)
				(type default)
			)
			(layer "F.SilkS")
		)
		(fp_line
			(start 1.1938 -7.6454)
			(end 1.1938 -7.1374)
			(stroke
				(width 0.1524)
				(type default)
			)
			(layer "F.SilkS")
		)
		(fp_line
			(start -1.1938 -7.1374)
			(end 1.1938 -7.1374)
			(stroke
				(width 0.1524)
				(type default)
			)
			(layer "F.SilkS")
		)
		(fp_line
			(start -1.1938 -7.6454)
			(end -1.1938 -7.1374)
			(stroke
				(width 0.1524)
				(type default)
			)
			(layer "F.SilkS")
		)
		(fp_line
			(start -5.1689 2.0574)
			(end -7.0739 2.0574)
			(stroke
				(width 0.508)
				(type default)
			)
			(layer "F.SilkS")
		)
		(fp_line
			(start -6.8834 1.8796)
			(end -6.8834 -0.7366)
			(stroke
				(width 0.1524)
				(type default)
			)
			(layer "F.SilkS")
		)
		(fp_line
			(start -6.8834 -0.7366)
			(end -8.5852 -0.7366)
			(stroke
				(width 0.1524)
				(type default)
			)
			(layer "F.SilkS")
		)
		(fp_line
			(start -7.0739 2.0574)
			(end -7.0739 0.1524)
			(stroke
				(width 0.508)
				(type default)
			)
			(layer "F.SilkS")
		)
		(fp_line
			(start -8.5852 -0.7366)
			(end -8.5852 -7.6454)
			(stroke
				(width 0.1524)
				(type default)
			)
			(layer "F.SilkS")
		)
		(fp_line
			(start -8.5852 -7.6454)
			(end 8.5852 -7.6454)
			(stroke
				(width 0.1524)
				(type default)
			)
			(layer "F.SilkS")
		)
		(fp_circle
			(center 5.99948 0.99949)
			(end 5.00888 0.99949)
			(stroke
				(width 0.3048)
				(type default)
			)
			(fill no)
			(layer "F.SilkS")
		)
		(fp_circle
			(center 5.99948 -0.99949)
			(end 5.00888 -0.99949)
			(stroke
				(width 0.3048)
				(type default)
			)
			(fill no)
			(layer "F.SilkS")
		)
		(fp_circle
			(center 4.0005 0.99949)
			(end 3.0099 0.99949)
			(stroke
				(width 0.3048)
				(type default)
			)
			(fill no)
			(layer "F.SilkS")
		)
		(fp_circle
			(center 4.0005 -0.99949)
			(end 3.0099 -0.99949)
			(stroke
				(width 0.3048)
				(type default)
			)
			(fill no)
			(layer "F.SilkS")
		)
		(fp_circle
			(center 2.00025 0.99949)
			(end 1.00965 0.99949)
			(stroke
				(width 0.3048)
				(type default)
			)
			(fill no)
			(layer "F.SilkS")
		)
		(fp_circle
			(center 2.00025 -0.99949)
			(end 1.00965 -0.99949)
			(stroke
				(width 0.3048)
				(type default)
			)
			(fill no)
			(layer "F.SilkS")
		)
		(fp_circle
			(center 0 0.99949)
			(end -0.9906 0.99949)
			(stroke
				(width 0.3048)
				(type default)
			)
			(fill no)
			(layer "F.SilkS")
		)
		(fp_circle
			(center 0 -0.99949)
			(end -0.9906 -0.99949)
			(stroke
				(width 0.3048)
				(type default)
			)
			(fill no)
			(layer "F.SilkS")
		)
		(fp_circle
			(center -2.00025 0.99949)
			(end -2.99085 0.99949)
			(stroke
				(width 0.3048)
				(type default)
			)
			(fill no)
			(layer "F.SilkS")
		)
		(fp_circle
			(center -2.00025 -0.99949)
			(end -2.99085 -0.99949)
			(stroke
				(width 0.3048)
				(type default)
			)
			(fill no)
			(layer "F.SilkS")
		)
		(fp_circle
			(center -4.0005 0.99949)
			(end -4.9911 0.99949)
			(stroke
				(width 0.3048)
				(type default)
			)
			(fill no)
			(layer "F.SilkS")
		)
		(fp_circle
			(center -4.0005 -0.99949)
			(end -4.9911 -0.99949)
			(stroke
				(width 0.3048)
				(type default)
			)
			(fill no)
			(layer "F.SilkS")
		)
		(fp_circle
			(center -5.99948 0.99949)
			(end -6.99008 0.99949)
			(stroke
				(width 0.3048)
				(type default)
			)
			(fill no)
			(layer "F.SilkS")
		)
		(fp_circle
			(center -5.99948 -0.99949)
			(end -6.99008 -0.99949)
			(stroke
				(width 0.3048)
				(type default)
			)
			(fill no)
			(layer "F.SilkS")
		)
		(fp_poly
			(pts
				(xy -6.2484 1.2446) (xy 6.2484 1.2446) (xy 6.2484 -0.9906) (xy 8.3312 -0.9906) (xy 8.3312 -7.3914)
				(xy -8.3312 -7.3914) (xy -8.3312 -0.9906) (xy -6.2484 -0.9906)
			)
			(stroke
				(width 0)
				(type default)
			)
			(fill no)
			(layer "F.CrtYd")
		)
		(fp_poly
			(pts
				(xy -7.1374 2.1336) (xy -7.1374 -0.4826) (xy -8.8392 -0.4826) (xy -8.8392 -7.8994) (xy 8.8392 -7.8994)
				(xy 8.8392 -0.4826) (xy 7.1374 -0.4826) (xy 7.1374 -0.00635) (xy 6.2484 -0.00635) (xy 6.2484 -0.9906)
				(xy 8.3312 -0.9906) (xy 8.3312 -7.3914) (xy -8.3312 -7.3914) (xy -8.3312 -0.9906) (xy -6.2484 -0.9906)
				(xy -6.2484 1.2446) (xy 6.2484 1.2446) (xy 6.2484 0.00635) (xy 7.1374 0.00635) (xy 7.1374 2.1336)
			)
			(stroke
				(width 0)
				(type default)
			)
			(fill no)
			(layer "F.CrtYd")
		)
		(fp_poly
			(pts
				(xy -7.1374 2.1336) (xy -7.1374 -0.4826) (xy -8.8392 -0.4826) (xy -8.8392 -7.8994) (xy 8.8392 -7.8994)
				(xy 8.8392 -0.4826) (xy 7.1374 -0.4826) (xy 7.1374 2.1336)
			)
			(stroke
				(width 0)
				(type default)
			)
			(fill no)
			(layer "F.Fab")
		)
		(pad "1" thru_hole circle
			(at -5.99948 0.99949 180)
			(size 1.27 1.27)
			(drill 0.889)
			(layers "*.Cu" "*.Mask")
			(remove_unused_layers no)
			(net "LOW_HEX_0")
			(clearance 0.1651)
			(thermal_gap 0.1651)
		)
		(pad "2" thru_hole circle
			(at -5.99948 -0.99949 180)
			(size 1.27 1.27)
			(drill 0.889)
			(layers "*.Cu" "*.Mask")
			(remove_unused_layers no)
			(net "LOW_HEX_1")
			(clearance 0.1651)
			(thermal_gap 0.1651)
		)
		(pad "3" thru_hole circle
			(at -4.0005 0.99949 180)
			(size 1.27 1.27)
			(drill 0.889)
			(layers "*.Cu" "*.Mask")
			(remove_unused_layers no)
			(net "LOW_HEX_2")
			(clearance 0.1651)
			(thermal_gap 0.1651)
		)
		(pad "4" thru_hole circle
			(at -4.0005 -0.99949 180)
			(size 1.27 1.27)
			(drill 0.889)
			(layers "*.Cu" "*.Mask")
			(remove_unused_layers no)
			(net "LOW_HEX_3")
			(clearance 0.1651)
			(thermal_gap 0.1651)
		)
		(pad "5" thru_hole circle
			(at -2.00025 0.99949 180)
			(size 1.27 1.27)
			(drill 0.889)
			(layers "*.Cu" "*.Mask")
			(remove_unused_layers no)
			(net "HIGH_HEX_0")
			(clearance 0.1651)
			(thermal_gap 0.1651)
		)
		(pad "6" thru_hole circle
			(at -2.00025 -0.99949 180)
			(size 1.27 1.27)
			(drill 0.889)
			(layers "*.Cu" "*.Mask")
			(remove_unused_layers no)
			(net "HIGH_HEX_1")
			(clearance 0.1651)
			(thermal_gap 0.1651)
		)
		(pad "7" thru_hole circle
			(at 0 0.99949 180)
			(size 1.27 1.27)
			(drill 0.889)
			(layers "*.Cu" "*.Mask")
			(remove_unused_layers no)
			(net "HIGH_HEX_2")
			(clearance 0.1651)
			(thermal_gap 0.1651)
		)
		(pad "8" thru_hole circle
			(at 0 -0.99949 180)
			(size 1.27 1.27)
			(drill 0.889)
			(layers "*.Cu" "*.Mask")
			(remove_unused_layers no)
			(net "HIGH_HEX_3")
			(clearance 0.1651)
			(thermal_gap 0.1651)
		)
		(pad "9" thru_hole circle
			(at 2.00025 0.99949 180)
			(size 1.27 1.27)
			(drill 0.889)
			(layers "*.Cu" "*.Mask")
			(remove_unused_layers no)
			(net "DEBUG_CARD_TX")
			(clearance 0.1651)
			(thermal_gap 0.1651)
		)
		(pad "10" thru_hole circle
			(at 2.00025 -0.99949 180)
			(size 1.27 1.27)
			(drill 0.889)
			(layers "*.Cu" "*.Mask")
			(remove_unused_layers no)
			(net "DEBUG_CARD_RX")
			(clearance 0.1651)
			(thermal_gap 0.1651)
		)
		(pad "11" thru_hole circle
			(at 4.0005 0.99949 180)
			(size 1.27 1.27)
			(drill 0.889)
			(layers "*.Cu" "*.Mask")
			(remove_unused_layers no)
			(net "DP_RST_N")
			(clearance 0.1651)
			(thermal_gap 0.1651)
		)
		(pad "12" thru_hole circle
			(at 4.0005 -0.99949 180)
			(size 1.27 1.27)
			(drill 0.889)
			(layers "*.Cu" "*.Mask")
			(remove_unused_layers no)
			(net "UART_COUNT")
			(clearance 0.1651)
			(thermal_gap 0.1651)
		)
		(pad "13" thru_hole circle
			(at 5.99948 0.99949 180)
			(size 1.27 1.27)
			(drill 0.889)
			(layers "*.Cu" "*.Mask")
			(remove_unused_layers no)
			(net "GND")
			(clearance 0.1651)
			(thermal_gap 0.1651)
		)
		(pad "14" thru_hole circle
			(at 5.99948 -0.99949 180)
			(size 1.27 1.27)
			(drill 0.889)
			(layers "*.Cu" "*.Mask")
			(remove_unused_layers no)
			(net "P5V_STBY")
			(clearance 0.1651)
			(thermal_gap 0.1651)
		)
	)
	(footprint ""
		(layer "F.Cu")
		(at 221.069408 -188.3283 90)
		(property "Reference" "C4120"
			(at 0 0 90)
			(layer "F.SilkS")
			(hide yes)
			(effects
				(font
					(size 1.27 1.27)
				)
			)
		)
		(property "Value" "SCD1U25V3KX-GP"
			(at 0 -2.8194 90)
			(unlocked yes)
			(layer "F.Fab")
			(hide yes)
			(effects
				(font
					(size 1.016 1.016)
					(thickness 0.1524)
				)
			)
		)
		(property "Device Type" "C603H36"
			(at 0 -4.3434 90)
			(unlocked yes)
			(layer "F.Fab")
			(hide yes)
			(effects
				(font
					(size 1.016 1.016)
					(thickness 0.1524)
				)
			)
		)
		(duplicate_pad_numbers_are_jumpers no)
		(fp_line
			(start 0.508 0)
			(end -0.508 0)
			(stroke
				(width 0.2032)
				(type default)
			)
			(layer "F.SilkS")
		)
		(fp_rect
			(start -0.5842 1.3335)
			(end 0.5842 -1.3335)
			(stroke
				(width 0)
				(type default)
			)
			(fill no)
			(layer "F.CrtYd")
		)
		(fp_rect
			(start -0.5842 1.3335)
			(end 0.5842 -1.3335)
			(stroke
				(width 0)
				(type default)
			)
			(fill no)
			(layer "F.Fab")
		)
		(pad "1" smd custom
			(at 0 -0.762 90)
			(size 0.2159 0.2159)
			(layers "F.Cu" "F.Mask" "F.Paste")
			(net "GND")
			(options
				(clearance outline)
				(anchor circle)
			)
			(primitives
				(gr_poly
					(pts
						(arc
							(start -0.3302 -0.4318)
							(mid -0.402042 -0.402042)
							(end -0.4318 -0.3302)
						)
						(arc
							(start -0.4318 0.3302)
							(mid -0.402042 0.402042)
							(end -0.3302 0.4318)
						)
						(arc
							(start 0.3302 0.4318)
							(mid 0.402042 0.402042)
							(end 0.4318 0.3302)
						)
						(arc
							(start 0.4318 -0.3302)
							(mid 0.402042 -0.402042)
							(end 0.3302 -0.4318)
						)
					)
					(width 0)
					(fill yes)
				)
			)
		)
		(pad "2" smd custom
			(at 0 0.762 90)
			(size 0.2159 0.2159)
			(layers "F.Cu" "F.Mask" "F.Paste")
			(net "SSD_PWREN3_R")
			(options
				(clearance outline)
				(anchor circle)
			)
			(primitives
				(gr_poly
					(pts
						(arc
							(start -0.3302 -0.4318)
							(mid -0.402042 -0.402042)
							(end -0.4318 -0.3302)
						)
						(arc
							(start -0.4318 0.3302)
							(mid -0.402042 0.402042)
							(end -0.3302 0.4318)
						)
						(arc
							(start 0.3302 0.4318)
							(mid 0.402042 0.402042)
							(end 0.4318 0.3302)
						)
						(arc
							(start 0.4318 -0.3302)
							(mid 0.402042 -0.402042)
							(end 0.3302 -0.4318)
						)
					)
					(width 0)
					(fill yes)
				)
			)
		)
	)
	(footprint ""
		(layer "F.Cu")
		(at 187.2234 -28.96108 90)
		(property "Reference" "R666"
			(at 0 0 90)
			(layer "F.SilkS")
			(hide yes)
			(effects
				(font
					(size 1.27 1.27)
				)
			)
		)
		(property "Value" "0R2J-2-GP"
			(at 0.064008 -3.993896 90)
			(unlocked yes)
			(layer "F.Fab")
			(hide yes)
			(effects
				(font
					(size 1.016 1.016)
					(thickness 0.1524)
				)
			)
		)
		(property "Device Type" "R402H16"
			(at 0.064008 -5.517896 90)
			(unlocked yes)
			(layer "F.Fab")
			(hide yes)
			(effects
				(font
					(size 1.016 1.016)
					(thickness 0.1524)
				)
			)
		)
		(duplicate_pad_numbers_are_jumpers no)
		(fp_line
			(start 0.508 -0.9398)
			(end -0.508 -0.9398)
			(stroke
				(width 0.1524)
				(type default)
			)
			(layer "F.SilkS")
		)
		(fp_line
			(start -0.508 -0.9398)
			(end -0.508 0.9398)
			(stroke
				(width 0.1524)
				(type default)
			)
			(layer "F.SilkS")
		)
		(fp_rect
			(start -0.508 0.9398)
			(end 0.508 -0.9398)
			(stroke
				(width 0)
				(type default)
			)
			(fill no)
			(layer "F.CrtYd")
		)
		(fp_rect
			(start -0.508 0.9398)
			(end 0.508 -0.9398)
			(stroke
				(width 0)
				(type default)
			)
			(fill no)
			(layer "F.Fab")
		)
		(pad "1" smd custom
			(at 0 -0.4445 90)
			(size 0.1397 0.1397)
			(layers "F.Cu" "F.Mask" "F.Paste")
			(net "8644_USB_DN4")
			(options
				(clearance outline)
				(anchor circle)
			)
			(primitives
				(gr_poly
					(pts
						(arc
							(start -0.1778 -0.2794)
							(mid -0.249642 -0.249642)
							(end -0.2794 -0.1778)
						)
						(arc
							(start -0.2794 0.1778)
							(mid -0.249642 0.249642)
							(end -0.1778 0.2794)
						)
						(arc
							(start 0.1778 0.2794)
							(mid 0.249642 0.249642)
							(end 0.2794 0.1778)
						)
						(arc
							(start 0.2794 -0.1778)
							(mid 0.249642 -0.249642)
							(end 0.1778 -0.2794)
						)
					)
					(width 0)
					(fill yes)
				)
			)
		)
		(pad "2" smd custom
			(at 0 0.4445 90)
			(size 0.1397 0.1397)
			(layers "F.Cu" "F.Mask" "F.Paste")
			(net "P3V3_STBY")
			(options
				(clearance outline)
				(anchor circle)
			)
			(primitives
				(gr_poly
					(pts
						(arc
							(start -0.1778 -0.2794)
							(mid -0.249642 -0.249642)
							(end -0.2794 -0.1778)
						)
						(arc
							(start -0.2794 0.1778)
							(mid -0.249642 0.249642)
							(end -0.1778 0.2794)
						)
						(arc
							(start 0.1778 0.2794)
							(mid 0.249642 0.249642)
							(end 0.2794 0.1778)
						)
						(arc
							(start 0.2794 -0.1778)
							(mid 0.249642 -0.249642)
							(end 0.1778 -0.2794)
						)
					)
					(width 0)
					(fill yes)
				)
			)
		)
	)
	(footprint ""
		(layer "F.Cu")
		(at 200.6219 -59.99988)
		(property "Reference" "PAD4"
			(at 0 0 0)
			(layer "F.SilkS")
			(hide yes)
			(effects
				(font
					(size 1.27 1.27)
				)
			)
		)
		(property "Value" "PAD-2P-21-GP"
			(at 7.164832 -10.8712 0)
			(unlocked yes)
			(layer "F.Fab")
			(hide yes)
			(effects
				(font
					(size 1.016 1.016)
					(thickness 0.1524)
				)
			)
		)
		(property "Device Type" "HT12X22B8R32-2P-S"
			(at 7.164832 -12.3952 0)
			(unlocked yes)
			(layer "F.Fab")
			(hide yes)
			(effects
				(font
					(size 1.016 1.016)
					(thickness 0.1524)
				)
			)
		)
		(duplicate_pad_numbers_are_jumpers no)
		(fp_poly
			(pts
				(arc
					(start 4.3053 -11.999976)
					(mid -4.3053 -11.999976)
					(end 4.3053 -11.999976)
				)
			)
			(stroke
				(width 0)
				(type default)
			)
			(fill no)
			(layer "B.CrtYd")
		)
		(fp_poly
			(pts
				(arc
					(start 4.3053 0)
					(mid -4.3053 0)
					(end 4.3053 0)
				)
			)
			(stroke
				(width 0)
				(type default)
			)
			(fill no)
			(layer "B.CrtYd")
		)
		(fp_rect
			(start -7.2898 5.3086)
			(end 5.3086 -17.2974)
			(stroke
				(width 0)
				(type default)
			)
			(fill no)
			(layer "F.CrtYd")
		)
		(fp_poly
			(pts
				(arc
					(start 4.3053 -11.999976)
					(mid -4.3053 -11.999976)
					(end 4.3053 -11.999976)
				)
			)
			(stroke
				(width 0)
				(type default)
			)
			(fill no)
			(layer "B.Fab")
		)
		(fp_poly
			(pts
				(arc
					(start 4.3053 0)
					(mid -4.3053 0)
					(end 4.3053 0)
				)
			)
			(stroke
				(width 0)
				(type default)
			)
			(fill no)
			(layer "B.Fab")
		)
		(fp_rect
			(start -7.2898 5.3086)
			(end 5.3086 -17.2974)
			(stroke
				(width 0)
				(type default)
			)
			(fill no)
			(layer "F.Fab")
		)
		(pad "1" thru_hole rect
			(at 0 0)
			(size 11.9888 21.9964)
			(drill 3.2004
				(offset -0.9906 -5.9944)
			)
			(layers "*.Cu" "*.Mask")
			(remove_unused_layers no)
			(net "GND")
			(clearance -3.8862)
			(thermal_gap 0.3048)
			(padstack
				(mode front_inner_back)
				(layer "Inner"
					(shape circle)
					(size 3.6068 3.6068)
					(clearance 0.3048)
				)
				(layer "B.Cu"
					(shape circle)
					(size 8.001 8.001)
					(clearance -1.8923)
				)
			)
		)
		(pad "2" thru_hole circle
			(at 0 -11.999976)
			(size 8.001 8.001)
			(drill 3.2004)
			(layers "*.Cu" "*.Mask")
			(remove_unused_layers no)
			(net "GND")
			(clearance -1.8923)
			(thermal_gap 0.3048)
			(padstack
				(mode front_inner_back)
				(layer "Inner"
					(shape circle)
					(size 3.6068 3.6068)
					(clearance 0.3048)
				)
				(layer "B.Cu"
					(shape circle)
					(size 8.001 8.001)
					(clearance -1.8923)
				)
			)
		)
	)
	(footprint ""
		(layer "F.Cu")
		(at 146.2532 -83.7946 -90)
		(property "Reference" "PG33"
			(at 0 0 270)
			(layer "F.SilkS")
			(hide yes)
			(effects
				(font
					(size 1.27 1.27)
				)
			)
		)
		(property "Value" "GAP-CLOSE-PWR-3-GP"
			(at 0.0254 -6.5786 270)
			(unlocked yes)
			(layer "F.Fab")
			(hide yes)
			(effects
				(font
					(size 1.016 1.016)
					(thickness 0.1524)
				)
			)
		)
		(property "Device Type" "GAP-CLOSE-PWR-3"
			(at 0.0254 -8.255 270)
			(unlocked yes)
			(layer "F.Fab")
			(hide yes)
			(effects
				(font
					(size 1.016 1.016)
					(thickness 0.1524)
				)
			)
		)
		(duplicate_pad_numbers_are_jumpers no)
		(fp_rect
			(start -0.7112 0.4572)
			(end 0.7112 -0.4572)
			(stroke
				(width 0)
				(type default)
			)
			(fill no)
			(layer "F.CrtYd")
		)
		(fp_poly
			(pts
				(xy -0.7112 -0.4572) (xy 0.7112 -0.4572) (xy 0.7112 0.4572) (xy -0.7112 0.4572)
			)
			(stroke
				(width 0)
				(type default)
			)
			(fill no)
			(layer "F.Fab")
		)
		(pad "1" smd rect
			(at -0.3048 0 270)
			(size 0.6604 0.762)
			(layers "F.Cu" "F.Mask" "F.Paste")
			(net "P1V8_PWR")
		)
		(pad "2" smd rect
			(at 0.3048 0 270)
			(size 0.6604 0.762)
			(layers "F.Cu" "F.Mask" "F.Paste")
			(net "DUT_VDDO")
		)
	)
	(footprint ""
		(layer "F.Cu")
		(at 38.689026 -146.48688)
		(property "Reference" "C178"
			(at 0 0 0)
			(layer "F.SilkS")
			(hide yes)
			(effects
				(font
					(size 1.27 1.27)
				)
			)
		)
		(property "Value" "SCD1U16V2KX-3GP"
			(at 1.1811 -2.7051 0)
			(unlocked yes)
			(layer "F.Fab")
			(hide yes)
			(effects
				(font
					(size 1.016 1.016)
					(thickness 0.1524)
				)
			)
		)
		(property "Device Type" "C402H22"
			(at 1.1811 -4.2291 0)
			(unlocked yes)
			(layer "F.Fab")
			(hide yes)
			(effects
				(font
					(size 1.016 1.016)
					(thickness 0.1524)
				)
			)
		)
		(duplicate_pad_numbers_are_jumpers no)
		(fp_rect
			(start -0.4318 0.9525)
			(end 0.4318 -0.9525)
			(stroke
				(width 0)
				(type default)
			)
			(fill no)
			(layer "F.CrtYd")
		)
		(fp_rect
			(start -0.4318 0.9525)
			(end 0.4318 -0.9525)
			(stroke
				(width 0)
				(type default)
			)
			(fill no)
			(layer "F.Fab")
		)
		(pad "1" smd custom
			(at 0 -0.4445)
			(size 0.1524 0.1524)
			(layers "F.Cu" "F.Mask" "F.Paste")
			(net "P1V53_STBY")
			(options
				(clearance outline)
				(anchor circle)
			)
			(primitives
				(gr_poly
					(pts
						(arc
							(start 0.3048 -0.2032)
							(mid 0.275042 -0.275042)
							(end 0.2032 -0.3048)
						)
						(arc
							(start -0.2032 -0.3048)
							(mid -0.275042 -0.275042)
							(end -0.3048 -0.2032)
						)
						(arc
							(start -0.3048 0.2032)
							(mid -0.275042 0.275042)
							(end -0.2032 0.3048)
						)
						(arc
							(start 0.2032 0.3048)
							(mid 0.275042 0.275042)
							(end 0.3048 0.2032)
						)
					)
					(width 0)
					(fill yes)
				)
			)
		)
		(pad "2" smd custom
			(at 0 0.4445)
			(size 0.1524 0.1524)
			(layers "F.Cu" "F.Mask" "F.Paste")
			(net "GND")
			(options
				(clearance outline)
				(anchor circle)
			)
			(primitives
				(gr_poly
					(pts
						(arc
							(start 0.3048 -0.2032)
							(mid 0.275042 -0.275042)
							(end 0.2032 -0.3048)
						)
						(arc
							(start -0.2032 -0.3048)
							(mid -0.275042 -0.275042)
							(end -0.3048 -0.2032)
						)
						(arc
							(start -0.3048 0.2032)
							(mid -0.275042 0.275042)
							(end -0.2032 0.3048)
						)
						(arc
							(start 0.2032 0.3048)
							(mid 0.275042 0.275042)
							(end 0.3048 0.2032)
						)
					)
					(width 0)
					(fill yes)
				)
			)
		)
	)
	(footprint ""
		(layer "F.Cu")
		(at 333.502 -74.041 180)
		(property "Reference" "PR156"
			(at 0 0 180)
			(layer "F.SilkS")
			(hide yes)
			(effects
				(font
					(size 1.27 1.27)
				)
			)
		)
		(property "Value" "10D7R2F-GP"
			(at 0.064008 -3.993896 180)
			(unlocked yes)
			(layer "F.Fab")
			(hide yes)
			(effects
				(font
					(size 1.016 1.016)
					(thickness 0.1524)
				)
			)
		)
		(property "Device Type" "R402H16"
			(at 0.064008 -5.517896 180)
			(unlocked yes)
			(layer "F.Fab")
			(hide yes)
			(effects
				(font
					(size 1.016 1.016)
					(thickness 0.1524)
				)
			)
		)
		(duplicate_pad_numbers_are_jumpers no)
		(fp_line
			(start 0.508 -0.9398)
			(end -0.508 -0.9398)
			(stroke
				(width 0.1524)
				(type default)
			)
			(layer "F.SilkS")
		)
		(fp_line
			(start -0.508 -0.9398)
			(end -0.508 0.9398)
			(stroke
				(width 0.1524)
				(type default)
			)
			(layer "F.SilkS")
		)
		(fp_rect
			(start -0.508 0.9398)
			(end 0.508 -0.9398)
			(stroke
				(width 0)
				(type default)
			)
			(fill no)
			(layer "F.CrtYd")
		)
		(fp_rect
			(start -0.508 0.9398)
			(end 0.508 -0.9398)
			(stroke
				(width 0)
				(type default)
			)
			(fill no)
			(layer "F.Fab")
		)
		(pad "1" smd custom
			(at 0 -0.4445 180)
			(size 0.1397 0.1397)
			(layers "F.Cu" "F.Mask" "F.Paste")
			(net "P0V9_E_VFB_R")
			(options
				(clearance outline)
				(anchor circle)
			)
			(primitives
				(gr_poly
					(pts
						(arc
							(start -0.1778 -0.2794)
							(mid -0.249642 -0.249642)
							(end -0.2794 -0.1778)
						)
						(arc
							(start -0.2794 0.1778)
							(mid -0.249642 0.249642)
							(end -0.1778 0.2794)
						)
						(arc
							(start 0.1778 0.2794)
							(mid 0.249642 0.249642)
							(end 0.2794 0.1778)
						)
						(arc
							(start 0.2794 -0.1778)
							(mid 0.249642 -0.249642)
							(end 0.1778 -0.2794)
						)
					)
					(width 0)
					(fill yes)
				)
			)
		)
		(pad "2" smd custom
			(at 0 0.4445 180)
			(size 0.1397 0.1397)
			(layers "F.Cu" "F.Mask" "F.Paste")
			(net "P0V9_E")
			(options
				(clearance outline)
				(anchor circle)
			)
			(primitives
				(gr_poly
					(pts
						(arc
							(start -0.1778 -0.2794)
							(mid -0.249642 -0.249642)
							(end -0.2794 -0.1778)
						)
						(arc
							(start -0.2794 0.1778)
							(mid -0.249642 0.249642)
							(end -0.1778 0.2794)
						)
						(arc
							(start 0.1778 0.2794)
							(mid 0.249642 0.249642)
							(end 0.2794 0.1778)
						)
						(arc
							(start 0.2794 -0.1778)
							(mid 0.249642 -0.249642)
							(end 0.1778 -0.2794)
						)
					)
					(width 0)
					(fill yes)
				)
			)
		)
	)
	(footprint ""
		(layer "F.Cu")
		(at 227.711 -3.81 180)
		(property "Reference" "R85"
			(at 0 0 180)
			(layer "F.SilkS")
			(hide yes)
			(effects
				(font
					(size 1.27 1.27)
				)
			)
		)
		(property "Value" "150R2F-1-GP"
			(at 0.064008 -3.993896 180)
			(unlocked yes)
			(layer "F.Fab")
			(hide yes)
			(effects
				(font
					(size 1.016 1.016)
					(thickness 0.1524)
				)
			)
		)
		(property "Device Type" "R402H16"
			(at 0.064008 -5.517896 180)
			(unlocked yes)
			(layer "F.Fab")
			(hide yes)
			(effects
				(font
					(size 1.016 1.016)
					(thickness 0.1524)
				)
			)
		)
		(duplicate_pad_numbers_are_jumpers no)
		(fp_line
			(start 0.508 -0.9398)
			(end -0.508 -0.9398)
			(stroke
				(width 0.1524)
				(type default)
			)
			(layer "F.SilkS")
		)
		(fp_line
			(start -0.508 -0.9398)
			(end -0.508 0.9398)
			(stroke
				(width 0.1524)
				(type default)
			)
			(layer "F.SilkS")
		)
		(fp_rect
			(start -0.508 0.9398)
			(end 0.508 -0.9398)
			(stroke
				(width 0)
				(type default)
			)
			(fill no)
			(layer "F.CrtYd")
		)
		(fp_rect
			(start -0.508 0.9398)
			(end 0.508 -0.9398)
			(stroke
				(width 0)
				(type default)
			)
			(fill no)
			(layer "F.Fab")
		)
		(pad "1" smd custom
			(at 0 -0.4445 180)
			(size 0.1397 0.1397)
			(layers "F.Cu" "F.Mask" "F.Paste")
			(net "P3V3_STBY")
			(options
				(clearance outline)
				(anchor circle)
			)
			(primitives
				(gr_poly
					(pts
						(arc
							(start -0.1778 -0.2794)
							(mid -0.249642 -0.249642)
							(end -0.2794 -0.1778)
						)
						(arc
							(start -0.2794 0.1778)
							(mid -0.249642 0.249642)
							(end -0.1778 0.2794)
						)
						(arc
							(start 0.1778 0.2794)
							(mid 0.249642 0.249642)
							(end 0.2794 0.1778)
						)
						(arc
							(start 0.2794 -0.1778)
							(mid 0.249642 -0.249642)
							(end 0.1778 -0.2794)
						)
					)
					(width 0)
					(fill yes)
				)
			)
		)
		(pad "2" smd custom
			(at 0 0.4445 180)
			(size 0.1397 0.1397)
			(layers "F.Cu" "F.Mask" "F.Paste")
			(net "CONSOLE_LED_0")
			(options
				(clearance outline)
				(anchor circle)
			)
			(primitives
				(gr_poly
					(pts
						(arc
							(start -0.1778 -0.2794)
							(mid -0.249642 -0.249642)
							(end -0.2794 -0.1778)
						)
						(arc
							(start -0.2794 0.1778)
							(mid -0.249642 0.249642)
							(end -0.1778 0.2794)
						)
						(arc
							(start 0.1778 0.2794)
							(mid 0.249642 0.249642)
							(end 0.2794 0.1778)
						)
						(arc
							(start 0.2794 -0.1778)
							(mid 0.249642 -0.249642)
							(end 0.1778 -0.2794)
						)
					)
					(width 0)
					(fill yes)
				)
			)
		)
	)
	(footprint ""
		(layer "F.Cu")
		(at 178.1048 -67.691 180)
		(property "Reference" "PG28"
			(at 0 0 180)
			(layer "F.SilkS")
			(hide yes)
			(effects
				(font
					(size 1.27 1.27)
				)
			)
		)
		(property "Value" "GAP-CLOSE-PWR-3-GP"
			(at 0.0254 -6.5786 180)
			(unlocked yes)
			(layer "F.Fab")
			(hide yes)
			(effects
				(font
					(size 1.016 1.016)
					(thickness 0.1524)
				)
			)
		)
		(property "Device Type" "GAP-CLOSE-PWR-3"
			(at 0.0254 -8.255 180)
			(unlocked yes)
			(layer "F.Fab")
			(hide yes)
			(effects
				(font
					(size 1.016 1.016)
					(thickness 0.1524)
				)
			)
		)
		(duplicate_pad_numbers_are_jumpers no)
		(fp_rect
			(start -0.7112 0.4572)
			(end 0.7112 -0.4572)
			(stroke
				(width 0)
				(type default)
			)
			(fill no)
			(layer "F.CrtYd")
		)
		(fp_poly
			(pts
				(xy -0.7112 -0.4572) (xy 0.7112 -0.4572) (xy 0.7112 0.4572) (xy -0.7112 0.4572)
			)
			(stroke
				(width 0)
				(type default)
			)
			(fill no)
			(layer "F.Fab")
		)
		(pad "1" smd rect
			(at -0.3048 0 180)
			(size 0.6604 0.762)
			(layers "F.Cu" "F.Mask" "F.Paste")
			(net "DUT_AVD_PCIE")
		)
		(pad "2" smd rect
			(at 0.3048 0 180)
			(size 0.6604 0.762)
			(layers "F.Cu" "F.Mask" "F.Paste")
			(net "P0V9")
		)
	)
	(footprint ""
		(layer "F.Cu")
		(at 43.379136 -46.148244 -90)
		(property "Reference" "R409"
			(at 0 0 270)
			(layer "F.SilkS")
			(hide yes)
			(effects
				(font
					(size 1.27 1.27)
				)
			)
		)
		(property "Value" "0R2J-2-GP"
			(at 0.064008 -3.993896 270)
			(unlocked yes)
			(layer "F.Fab")
			(hide yes)
			(effects
				(font
					(size 1.016 1.016)
					(thickness 0.1524)
				)
			)
		)
		(property "Device Type" "R402H16"
			(at 0.064008 -5.517896 270)
			(unlocked yes)
			(layer "F.Fab")
			(hide yes)
			(effects
				(font
					(size 1.016 1.016)
					(thickness 0.1524)
				)
			)
		)
		(duplicate_pad_numbers_are_jumpers no)
		(fp_line
			(start -0.508 -0.9398)
			(end -0.508 0.9398)
			(stroke
				(width 0.1524)
				(type default)
			)
			(layer "F.SilkS")
		)
		(fp_line
			(start 0.508 -0.9398)
			(end -0.508 -0.9398)
			(stroke
				(width 0.1524)
				(type default)
			)
			(layer "F.SilkS")
		)
		(fp_rect
			(start -0.508 0.9398)
			(end 0.508 -0.9398)
			(stroke
				(width 0)
				(type default)
			)
			(fill no)
			(layer "F.CrtYd")
		)
		(fp_rect
			(start -0.508 0.9398)
			(end 0.508 -0.9398)
			(stroke
				(width 0)
				(type default)
			)
			(fill no)
			(layer "F.Fab")
		)
		(pad "1" smd custom
			(at 0 -0.4445 270)
			(size 0.1397 0.1397)
			(layers "F.Cu" "F.Mask" "F.Paste")
			(net "USB_DP_R")
			(options
				(clearance outline)
				(anchor circle)
			)
			(primitives
				(gr_poly
					(pts
						(arc
							(start -0.1778 -0.2794)
							(mid -0.249642 -0.249642)
							(end -0.2794 -0.1778)
						)
						(arc
							(start -0.2794 0.1778)
							(mid -0.249642 0.249642)
							(end -0.1778 0.2794)
						)
						(arc
							(start 0.1778 0.2794)
							(mid 0.249642 0.249642)
							(end 0.2794 0.1778)
						)
						(arc
							(start 0.2794 -0.1778)
							(mid 0.249642 -0.249642)
							(end 0.1778 -0.2794)
						)
					)
					(width 0)
					(fill yes)
				)
			)
		)
		(pad "2" smd custom
			(at 0 0.4445 270)
			(size 0.1397 0.1397)
			(layers "F.Cu" "F.Mask" "F.Paste")
			(net "USB_P1_F_DP1")
			(options
				(clearance outline)
				(anchor circle)
			)
			(primitives
				(gr_poly
					(pts
						(arc
							(start -0.1778 -0.2794)
							(mid -0.249642 -0.249642)
							(end -0.2794 -0.1778)
						)
						(arc
							(start -0.2794 0.1778)
							(mid -0.249642 0.249642)
							(end -0.1778 0.2794)
						)
						(arc
							(start 0.1778 0.2794)
							(mid 0.249642 0.249642)
							(end 0.2794 0.1778)
						)
						(arc
							(start 0.2794 -0.1778)
							(mid 0.249642 -0.249642)
							(end 0.1778 -0.2794)
						)
					)
					(width 0)
					(fill yes)
				)
			)
		)
	)
	(footprint ""
		(layer "F.Cu")
		(at 160.528 -97.5614 90)
		(property "Reference" "TP77"
			(at 0 0 90)
			(layer "F.SilkS")
			(hide yes)
			(effects
				(font
					(size 1.27 1.27)
				)
			)
		)
		(property "Value" "TPAD28-2-GP"
			(at -0.0127 -1.6637 90)
			(unlocked yes)
			(layer "F.Fab")
			(hide yes)
			(effects
				(font
					(size 1.016 1.016)
					(thickness 0.1524)
				)
			)
		)
		(property "Device Type" "TPAD28"
			(at -0.0127 -3.1877 90)
			(unlocked yes)
			(layer "F.Fab")
			(hide yes)
			(effects
				(font
					(size 1.016 1.016)
					(thickness 0.1524)
				)
			)
		)
		(duplicate_pad_numbers_are_jumpers no)
		(fp_poly
			(pts
				(arc
					(start 0 0.3556)
					(mid 0 -0.3556)
					(end 0 0.3556)
				)
			)
			(stroke
				(width 0)
				(type default)
			)
			(fill no)
			(layer "F.CrtYd")
		)
		(fp_poly
			(pts
				(arc
					(start 0 0.6096)
					(mid 0 -0.6096)
					(end 0 0.6096)
				)
			)
			(stroke
				(width 0)
				(type default)
			)
			(fill no)
			(layer "F.Fab")
		)
		(pad "1" smd circle
			(at 0 0 90)
			(size 0.7112 0.7112)
			(layers "F.Cu" "F.Mask" "F.Paste")
			(net "CLKGEN_OE3")
		)
	)
	(footprint ""
		(layer "F.Cu")
		(at 215.876124 -203.047092 180)
		(property "Reference" "C3215"
			(at 0 0 180)
			(layer "F.SilkS")
			(hide yes)
			(effects
				(font
					(size 1.27 1.27)
				)
			)
		)
		(property "Value" "SCD1U25V2KX-2-GP"
			(at 1.1811 -2.7051 180)
			(unlocked yes)
			(layer "F.Fab")
			(hide yes)
			(effects
				(font
					(size 1.016 1.016)
					(thickness 0.1524)
				)
			)
		)
		(property "Device Type" "C402H22"
			(at 1.1811 -4.2291 180)
			(unlocked yes)
			(layer "F.Fab")
			(hide yes)
			(effects
				(font
					(size 1.016 1.016)
					(thickness 0.1524)
				)
			)
		)
		(duplicate_pad_numbers_are_jumpers no)
		(fp_rect
			(start -0.4318 0.9525)
			(end 0.4318 -0.9525)
			(stroke
				(width 0)
				(type default)
			)
			(fill no)
			(layer "F.CrtYd")
		)
		(fp_rect
			(start -0.4318 0.9525)
			(end 0.4318 -0.9525)
			(stroke
				(width 0)
				(type default)
			)
			(fill no)
			(layer "F.Fab")
		)
		(pad "1" smd custom
			(at 0 -0.4445 180)
			(size 0.1524 0.1524)
			(layers "F.Cu" "F.Mask" "F.Paste")
			(net "P3V3_STBY")
			(options
				(clearance outline)
				(anchor circle)
			)
			(primitives
				(gr_poly
					(pts
						(arc
							(start 0.3048 -0.2032)
							(mid 0.275042 -0.275042)
							(end 0.2032 -0.3048)
						)
						(arc
							(start -0.2032 -0.3048)
							(mid -0.275042 -0.275042)
							(end -0.3048 -0.2032)
						)
						(arc
							(start -0.3048 0.2032)
							(mid -0.275042 0.275042)
							(end -0.2032 0.3048)
						)
						(arc
							(start 0.2032 0.3048)
							(mid 0.275042 0.275042)
							(end 0.3048 0.2032)
						)
					)
					(width 0)
					(fill yes)
				)
			)
		)
		(pad "2" smd custom
			(at 0 0.4445 180)
			(size 0.1524 0.1524)
			(layers "F.Cu" "F.Mask" "F.Paste")
			(net "GND")
			(options
				(clearance outline)
				(anchor circle)
			)
			(primitives
				(gr_poly
					(pts
						(arc
							(start 0.3048 -0.2032)
							(mid 0.275042 -0.275042)
							(end 0.2032 -0.3048)
						)
						(arc
							(start -0.2032 -0.3048)
							(mid -0.275042 -0.275042)
							(end -0.3048 -0.2032)
						)
						(arc
							(start -0.3048 0.2032)
							(mid -0.275042 0.275042)
							(end -0.2032 0.3048)
						)
						(arc
							(start 0.2032 0.3048)
							(mid 0.275042 0.275042)
							(end 0.3048 0.2032)
						)
					)
					(width 0)
					(fill yes)
				)
			)
		)
	)
	(footprint ""
		(layer "F.Cu")
		(at 194.8688 -30.7848 -90)
		(property "Reference" "R800"
			(at 0 0 270)
			(layer "F.SilkS")
			(hide yes)
			(effects
				(font
					(size 1.27 1.27)
				)
			)
		)
		(property "Value" "4K7R2F-GP"
			(at 0.064008 -3.993896 270)
			(unlocked yes)
			(layer "F.Fab")
			(hide yes)
			(effects
				(font
					(size 1.016 1.016)
					(thickness 0.1524)
				)
			)
		)
		(property "Device Type" "R402H16"
			(at 0.064008 -5.517896 270)
			(unlocked yes)
			(layer "F.Fab")
			(hide yes)
			(effects
				(font
					(size 1.016 1.016)
					(thickness 0.1524)
				)
			)
		)
		(duplicate_pad_numbers_are_jumpers no)
		(fp_line
			(start -0.508 -0.9398)
			(end -0.508 0.9398)
			(stroke
				(width 0.1524)
				(type default)
			)
			(layer "F.SilkS")
		)
		(fp_line
			(start 0.508 -0.9398)
			(end -0.508 -0.9398)
			(stroke
				(width 0.1524)
				(type default)
			)
			(layer "F.SilkS")
		)
		(fp_rect
			(start -0.508 0.9398)
			(end 0.508 -0.9398)
			(stroke
				(width 0)
				(type default)
			)
			(fill no)
			(layer "F.CrtYd")
		)
		(fp_rect
			(start -0.508 0.9398)
			(end 0.508 -0.9398)
			(stroke
				(width 0)
				(type default)
			)
			(fill no)
			(layer "F.Fab")
		)
		(pad "1" smd custom
			(at 0 -0.4445 270)
			(size 0.1397 0.1397)
			(layers "F.Cu" "F.Mask" "F.Paste")
			(net "U55_A2")
			(options
				(clearance outline)
				(anchor circle)
			)
			(primitives
				(gr_poly
					(pts
						(arc
							(start -0.1778 -0.2794)
							(mid -0.249642 -0.249642)
							(end -0.2794 -0.1778)
						)
						(arc
							(start -0.2794 0.1778)
							(mid -0.249642 0.249642)
							(end -0.1778 0.2794)
						)
						(arc
							(start 0.1778 0.2794)
							(mid 0.249642 0.249642)
							(end 0.2794 0.1778)
						)
						(arc
							(start 0.2794 -0.1778)
							(mid 0.249642 -0.249642)
							(end 0.1778 -0.2794)
						)
					)
					(width 0)
					(fill yes)
				)
			)
		)
		(pad "2" smd custom
			(at 0 0.4445 270)
			(size 0.1397 0.1397)
			(layers "F.Cu" "F.Mask" "F.Paste")
			(net "P3V3_STBY")
			(options
				(clearance outline)
				(anchor circle)
			)
			(primitives
				(gr_poly
					(pts
						(arc
							(start -0.1778 -0.2794)
							(mid -0.249642 -0.249642)
							(end -0.2794 -0.1778)
						)
						(arc
							(start -0.2794 0.1778)
							(mid -0.249642 0.249642)
							(end -0.1778 0.2794)
						)
						(arc
							(start 0.1778 0.2794)
							(mid 0.249642 0.249642)
							(end 0.2794 0.1778)
						)
						(arc
							(start 0.2794 -0.1778)
							(mid 0.249642 -0.249642)
							(end 0.1778 -0.2794)
						)
					)
					(width 0)
					(fill yes)
				)
			)
		)
	)
	(footprint ""
		(layer "F.Cu")
		(at 160.782 -90.5764 90)
		(property "Reference" "U196"
			(at 0 0 90)
			(layer "F.SilkS")
			(hide yes)
			(effects
				(font
					(size 1.27 1.27)
				)
			)
		)
		(property "Value" "9FGV0431AKLFT-GP"
			(at -5.4229 -4.6482 90)
			(unlocked yes)
			(layer "F.Fab")
			(hide yes)
			(effects
				(font
					(size 1.016 1.016)
					(thickness 0.1524)
				)
			)
		)
		(property "Device Type" "QFN32-G3D3H40"
			(at -5.4229 -6.1722 90)
			(unlocked yes)
			(layer "F.Fab")
			(hide yes)
			(effects
				(font
					(size 1.016 1.016)
					(thickness 0.1524)
				)
			)
		)
		(duplicate_pad_numbers_are_jumpers no)
		(fp_line
			(start -2.2479 -3.5179)
			(end -3.5179 -3.5179)
			(stroke
				(width 0.1524)
				(type default)
			)
			(layer "F.SilkS")
		)
		(fp_line
			(start -3.5179 -3.5179)
			(end -3.5179 -2.2479)
			(stroke
				(width 0.1524)
				(type default)
			)
			(layer "F.SilkS")
		)
		(fp_line
			(start -0.249936 -3.160522)
			(end -0.249936 -3.668522)
			(stroke
				(width 0.1524)
				(type default)
			)
			(layer "F.SilkS")
		)
		(fp_line
			(start -3.160522 -1.249934)
			(end -3.922522 -1.249934)
			(stroke
				(width 0.1524)
				(type default)
			)
			(layer "F.SilkS")
		)
		(fp_line
			(start 3.160522 -0.750062)
			(end 3.922522 -0.750062)
			(stroke
				(width 0.1524)
				(type default)
			)
			(layer "F.SilkS")
		)
		(fp_line
			(start -3.160522 1.249934)
			(end -3.668522 1.249934)
			(stroke
				(width 0.1524)
				(type default)
			)
			(layer "F.SilkS")
		)
		(fp_line
			(start 3.160522 1.75006)
			(end 3.668522 1.75006)
			(stroke
				(width 0.1524)
				(type default)
			)
			(layer "F.SilkS")
		)
		(fp_line
			(start -3.5179 2.2479)
			(end -3.5179 3.5179)
			(stroke
				(width 0.1524)
				(type default)
			)
			(layer "F.SilkS")
		)
		(fp_line
			(start -0.249936 3.160522)
			(end -0.249936 3.922522)
			(stroke
				(width 0.1524)
				(type default)
			)
			(layer "F.SilkS")
		)
		(fp_line
			(start 3.5179 3.5179)
			(end 3.5179 2.2479)
			(stroke
				(width 0.1524)
				(type default)
			)
			(layer "F.SilkS")
		)
		(fp_line
			(start 2.2479 3.5179)
			(end 3.5179 3.5179)
			(stroke
				(width 0.1524)
				(type default)
			)
			(layer "F.SilkS")
		)
		(fp_line
			(start -3.5179 3.5179)
			(end -2.2479 3.5179)
			(stroke
				(width 0.1524)
				(type default)
			)
			(layer "F.SilkS")
		)
		(fp_poly
			(pts
				(xy 3.5179 -3.5179) (xy 2.2479 -3.5179) (xy 3.5179 -2.2479)
			)
			(stroke
				(width 0)
				(type default)
			)
			(fill yes)
			(layer "F.SilkS")
		)
		(fp_rect
			(start -2.5019 2.5019)
			(end 2.5019 -2.5019)
			(stroke
				(width 0)
				(type default)
			)
			(fill no)
			(layer "F.CrtYd")
		)
		(fp_poly
			(pts
				(xy -3.5179 3.5179) (xy -3.5179 -3.5179) (xy 3.5179 -3.5179) (xy 3.5179 -0.8763) (xy 2.5019 -0.8763)
				(xy 2.5019 -2.5019) (xy -2.5019 -2.5019) (xy -2.5019 2.5019) (xy 2.5019 2.5019) (xy 2.5019 -0.8636)
				(xy 3.5179 -0.8636) (xy 3.5179 3.5179)
			)
			(stroke
				(width 0)
				(type default)
			)
			(fill no)
			(layer "F.CrtYd")
		)
		(fp_rect
			(start -3.5179 3.5179)
			(end 3.5179 -3.5179)
			(stroke
				(width 0)
				(type default)
			)
			(fill no)
			(layer "F.Fab")
		)
		(pad "1" smd rect
			(at 1.75006 -2.538222 90)
			(size 0.3048 0.9398)
			(layers "F.Cu" "F.Mask" "F.Paste")
			(net "GND")
		)
		(pad "2" smd rect
			(at 1.249934 -2.487422 90)
			(size 0.3048 1.0414)
			(layers "F.Cu" "F.Mask" "F.Paste")
			(net "XTAL_X1")
		)
		(pad "3" smd rect
			(at 0.750062 -2.487422 90)
			(size 0.3048 1.0414)
			(layers "F.Cu" "F.Mask" "F.Paste")
			(net "XTAL_X2_CLKGEN")
		)
		(pad "4" smd rect
			(at 0.249936 -2.487422 90)
			(size 0.3048 1.0414)
			(layers "F.Cu" "F.Mask" "F.Paste")
			(net "P1V8_CLKGEN")
		)
		(pad "5" smd rect
			(at -0.249936 -2.487422 90)
			(size 0.3048 1.0414)
			(layers "F.Cu" "F.Mask" "F.Paste")
			(net "P1V8_CLKGEN")
		)
		(pad "6" smd rect
			(at -0.750062 -2.487422 90)
			(size 0.3048 1.0414)
			(layers "F.Cu" "F.Mask" "F.Paste")
			(net "CLKGNE_SADR")
		)
		(pad "7" smd rect
			(at -1.249934 -2.487422 90)
			(size 0.3048 1.0414)
			(layers "F.Cu" "F.Mask" "F.Paste")
			(net "GND")
		)
		(pad "8" smd rect
			(at -1.75006 -2.538222 90)
			(size 0.3048 0.9398)
			(layers "F.Cu" "F.Mask" "F.Paste")
			(net "GND")
		)
		(pad "9" smd rect
			(at -2.538222 -1.75006 90)
			(size 0.9398 0.3048)
			(layers "F.Cu" "F.Mask" "F.Paste")
			(net "P1V8_CLKGEN")
		)
		(pad "10" smd rect
			(at -2.487422 -1.249934 90)
			(size 1.0414 0.3048)
			(layers "F.Cu" "F.Mask" "F.Paste")
			(net "CLKGEN_SCL")
		)
		(pad "11" smd rect
			(at -2.487422 -0.750062 90)
			(size 1.0414 0.3048)
			(layers "F.Cu" "F.Mask" "F.Paste")
			(net "CLKGEN_SDA")
		)
		(pad "12" smd rect
			(at -2.487422 -0.249936 90)
			(size 1.0414 0.3048)
			(layers "F.Cu" "F.Mask" "F.Paste")
			(net "PCIE_CLKGEN2_OE0_R")
		)
		(pad "13" smd rect
			(at -2.487422 0.249936 90)
			(size 1.0414 0.3048)
			(layers "F.Cu" "F.Mask" "F.Paste")
			(net "PCIE_REFCLK_D_P_R")
		)
		(pad "14" smd rect
			(at -2.487422 0.750062 90)
			(size 1.0414 0.3048)
			(layers "F.Cu" "F.Mask" "F.Paste")
			(net "PCIE_REFCLK_D_N_R")
		)
		(pad "15" smd rect
			(at -2.487422 1.249934 90)
			(size 1.0414 0.3048)
			(layers "F.Cu" "F.Mask" "F.Paste")
			(net "GND")
		)
		(pad "16" smd rect
			(at -2.538222 1.75006 90)
			(size 0.9398 0.3048)
			(layers "F.Cu" "F.Mask" "F.Paste")
			(net "P1V8_CLKGEN")
		)
		(pad "17" smd rect
			(at -1.75006 2.538222 90)
			(size 0.3048 0.9398)
			(layers "F.Cu" "F.Mask" "F.Paste")
			(net "CLKGEN_OE1_R")
		)
		(pad "18" smd rect
			(at -1.249934 2.487422 90)
			(size 0.3048 1.0414)
			(layers "F.Cu" "F.Mask" "F.Paste")
			(net "CLKGEN_P1_R")
		)
		(pad "19" smd rect
			(at -0.750062 2.487422 90)
			(size 0.3048 1.0414)
			(layers "F.Cu" "F.Mask" "F.Paste")
			(net "CLKGEN_N1_R")
		)
		(pad "20" smd rect
			(at -0.249936 2.487422 90)
			(size 0.3048 1.0414)
			(layers "F.Cu" "F.Mask" "F.Paste")
			(net "GND")
		)
		(pad "21" smd rect
			(at 0.249936 2.487422 90)
			(size 0.3048 1.0414)
			(layers "F.Cu" "F.Mask" "F.Paste")
			(net "P1V8_CLKGEN_A")
		)
		(pad "22" smd rect
			(at 0.750062 2.487422 90)
			(size 0.3048 1.0414)
			(layers "F.Cu" "F.Mask" "F.Paste")
			(net "CLKGEN_P2_R")
		)
		(pad "23" smd rect
			(at 1.249934 2.487422 90)
			(size 0.3048 1.0414)
			(layers "F.Cu" "F.Mask" "F.Paste")
			(net "CLKGEN_N2_R")
		)
		(pad "24" smd rect
			(at 1.75006 2.538222 90)
			(size 0.3048 0.9398)
			(layers "F.Cu" "F.Mask" "F.Paste")
			(net "CLKGEN_OE2_R")
		)
		(pad "25" smd rect
			(at 2.538222 1.75006 90)
			(size 0.9398 0.3048)
			(layers "F.Cu" "F.Mask" "F.Paste")
			(net "P1V8_CLKGEN")
		)
		(pad "26" smd rect
			(at 2.487422 1.249934 90)
			(size 1.0414 0.3048)
			(layers "F.Cu" "F.Mask" "F.Paste")
			(net "GND")
		)
		(pad "27" smd rect
			(at 2.487422 0.750062 90)
			(size 1.0414 0.3048)
			(layers "F.Cu" "F.Mask" "F.Paste")
			(net "CLKGEN_P3_R")
		)
		(pad "28" smd rect
			(at 2.487422 0.249936 90)
			(size 1.0414 0.3048)
			(layers "F.Cu" "F.Mask" "F.Paste")
			(net "CLKGEN_N3_R")
		)
		(pad "29" smd rect
			(at 2.487422 -0.249936 90)
			(size 1.0414 0.3048)
			(layers "F.Cu" "F.Mask" "F.Paste")
			(net "CLKGEN_OE3_R")
		)
		(pad "30" smd rect
			(at 2.487422 -0.750062 90)
			(size 1.0414 0.3048)
			(layers "F.Cu" "F.Mask" "F.Paste")
			(net "GND")
		)
		(pad "31" smd rect
			(at 2.487422 -1.249934 90)
			(size 1.0414 0.3048)
			(layers "F.Cu" "F.Mask" "F.Paste")
			(net "CLKGEN_PWGD")
		)
		(pad "32" smd rect
			(at 2.538222 -1.75006 90)
			(size 0.9398 0.3048)
			(layers "F.Cu" "F.Mask" "F.Paste")
			(net "CLKGNE_SS_EN")
		)
		(pad "33" smd rect
			(at 0 0 90)
			(size 3.302 3.302)
			(layers "F.Cu" "F.Mask" "F.Paste")
			(net "GND")
		)
	)
	(footprint ""
		(layer "F.Cu")
		(at 122.4788 -99.8982 -90)
		(property "Reference" "R427"
			(at 0 0 270)
			(layer "F.SilkS")
			(hide yes)
			(effects
				(font
					(size 1.27 1.27)
				)
			)
		)
		(property "Value" "2KR2F-3-GP"
			(at 0.064008 -3.993896 270)
			(unlocked yes)
			(layer "F.Fab")
			(hide yes)
			(effects
				(font
					(size 1.016 1.016)
					(thickness 0.1524)
				)
			)
		)
		(property "Device Type" "R402H16"
			(at 0.064008 -5.517896 270)
			(unlocked yes)
			(layer "F.Fab")
			(hide yes)
			(effects
				(font
					(size 1.016 1.016)
					(thickness 0.1524)
				)
			)
		)
		(duplicate_pad_numbers_are_jumpers no)
		(fp_line
			(start -0.508 -0.9398)
			(end -0.508 0.9398)
			(stroke
				(width 0.1524)
				(type default)
			)
			(layer "F.SilkS")
		)
		(fp_line
			(start 0.508 -0.9398)
			(end -0.508 -0.9398)
			(stroke
				(width 0.1524)
				(type default)
			)
			(layer "F.SilkS")
		)
		(fp_rect
			(start -0.508 0.9398)
			(end 0.508 -0.9398)
			(stroke
				(width 0)
				(type default)
			)
			(fill no)
			(layer "F.CrtYd")
		)
		(fp_rect
			(start -0.508 0.9398)
			(end 0.508 -0.9398)
			(stroke
				(width 0)
				(type default)
			)
			(fill no)
			(layer "F.Fab")
		)
		(pad "1" smd custom
			(at 0 -0.4445 270)
			(size 0.1397 0.1397)
			(layers "F.Cu" "F.Mask" "F.Paste")
			(net "P3V3_STBY")
			(options
				(clearance outline)
				(anchor circle)
			)
			(primitives
				(gr_poly
					(pts
						(arc
							(start -0.1778 -0.2794)
							(mid -0.249642 -0.249642)
							(end -0.2794 -0.1778)
						)
						(arc
							(start -0.2794 0.1778)
							(mid -0.249642 0.249642)
							(end -0.1778 0.2794)
						)
						(arc
							(start 0.1778 0.2794)
							(mid 0.249642 0.249642)
							(end 0.2794 0.1778)
						)
						(arc
							(start 0.2794 -0.1778)
							(mid 0.249642 -0.249642)
							(end 0.1778 -0.2794)
						)
					)
					(width 0)
					(fill yes)
				)
			)
		)
		(pad "2" smd custom
			(at 0 0.4445 270)
			(size 0.1397 0.1397)
			(layers "F.Cu" "F.Mask" "F.Paste")
			(net "BUF_I2C_SCL_2_R")
			(options
				(clearance outline)
				(anchor circle)
			)
			(primitives
				(gr_poly
					(pts
						(arc
							(start -0.1778 -0.2794)
							(mid -0.249642 -0.249642)
							(end -0.2794 -0.1778)
						)
						(arc
							(start -0.2794 0.1778)
							(mid -0.249642 0.249642)
							(end -0.1778 0.2794)
						)
						(arc
							(start 0.1778 0.2794)
							(mid 0.249642 0.249642)
							(end 0.2794 0.1778)
						)
						(arc
							(start 0.2794 -0.1778)
							(mid 0.249642 -0.249642)
							(end 0.1778 -0.2794)
						)
					)
					(width 0)
					(fill yes)
				)
			)
		)
	)
	(footprint ""
		(layer "F.Cu")
		(at 217.043 -12.065)
		(property "Reference" "SC1115"
			(at 0 0 0)
			(layer "F.SilkS")
			(hide yes)
			(effects
				(font
					(size 1.27 1.27)
				)
			)
		)
		(property "Value" "SCD1U16V2KX-3GP"
			(at 1.1811 -2.7051 0)
			(unlocked yes)
			(layer "F.Fab")
			(hide yes)
			(effects
				(font
					(size 1.016 1.016)
					(thickness 0.1524)
				)
			)
		)
		(property "Device Type" "C402H22"
			(at 1.1811 -4.2291 0)
			(unlocked yes)
			(layer "F.Fab")
			(hide yes)
			(effects
				(font
					(size 1.016 1.016)
					(thickness 0.1524)
				)
			)
		)
		(duplicate_pad_numbers_are_jumpers no)
		(fp_rect
			(start -0.4318 0.9525)
			(end 0.4318 -0.9525)
			(stroke
				(width 0)
				(type default)
			)
			(fill no)
			(layer "F.CrtYd")
		)
		(fp_rect
			(start -0.4318 0.9525)
			(end 0.4318 -0.9525)
			(stroke
				(width 0)
				(type default)
			)
			(fill no)
			(layer "F.Fab")
		)
		(pad "1" smd custom
			(at 0 -0.4445)
			(size 0.1524 0.1524)
			(layers "F.Cu" "F.Mask" "F.Paste")
			(net "DUT_VDDO")
			(options
				(clearance outline)
				(anchor circle)
			)
			(primitives
				(gr_poly
					(pts
						(arc
							(start 0.3048 -0.2032)
							(mid 0.275042 -0.275042)
							(end 0.2032 -0.3048)
						)
						(arc
							(start -0.2032 -0.3048)
							(mid -0.275042 -0.275042)
							(end -0.3048 -0.2032)
						)
						(arc
							(start -0.3048 0.2032)
							(mid -0.275042 0.275042)
							(end -0.2032 0.3048)
						)
						(arc
							(start 0.2032 0.3048)
							(mid 0.275042 0.275042)
							(end 0.3048 0.2032)
						)
					)
					(width 0)
					(fill yes)
				)
			)
		)
		(pad "2" smd custom
			(at 0 0.4445)
			(size 0.1524 0.1524)
			(layers "F.Cu" "F.Mask" "F.Paste")
			(net "GND")
			(options
				(clearance outline)
				(anchor circle)
			)
			(primitives
				(gr_poly
					(pts
						(arc
							(start 0.3048 -0.2032)
							(mid 0.275042 -0.275042)
							(end 0.2032 -0.3048)
						)
						(arc
							(start -0.2032 -0.3048)
							(mid -0.275042 -0.275042)
							(end -0.3048 -0.2032)
						)
						(arc
							(start -0.3048 0.2032)
							(mid -0.275042 0.275042)
							(end -0.2032 0.3048)
						)
						(arc
							(start 0.2032 0.3048)
							(mid 0.275042 0.275042)
							(end 0.3048 0.2032)
						)
					)
					(width 0)
					(fill yes)
				)
			)
		)
	)
	(footprint ""
		(layer "F.Cu")
		(at 254.173482 -12.0523)
		(property "Reference" "R12"
			(at 0 0 0)
			(layer "F.SilkS")
			(hide yes)
			(effects
				(font
					(size 1.27 1.27)
				)
			)
		)
		(property "Value" "0R2J-2-GP"
			(at 0.064008 -3.993896 0)
			(unlocked yes)
			(layer "F.Fab")
			(hide yes)
			(effects
				(font
					(size 1.016 1.016)
					(thickness 0.1524)
				)
			)
		)
		(property "Device Type" "R402H16"
			(at 0.064008 -5.517896 0)
			(unlocked yes)
			(layer "F.Fab")
			(hide yes)
			(effects
				(font
					(size 1.016 1.016)
					(thickness 0.1524)
				)
			)
		)
		(duplicate_pad_numbers_are_jumpers no)
		(fp_line
			(start -0.508 -0.9398)
			(end -0.508 0.9398)
			(stroke
				(width 0.1524)
				(type default)
			)
			(layer "F.SilkS")
		)
		(fp_line
			(start 0.508 -0.9398)
			(end -0.508 -0.9398)
			(stroke
				(width 0.1524)
				(type default)
			)
			(layer "F.SilkS")
		)
		(fp_rect
			(start -0.508 0.9398)
			(end 0.508 -0.9398)
			(stroke
				(width 0)
				(type default)
			)
			(fill no)
			(layer "F.CrtYd")
		)
		(fp_rect
			(start -0.508 0.9398)
			(end 0.508 -0.9398)
			(stroke
				(width 0)
				(type default)
			)
			(fill no)
			(layer "F.Fab")
		)
		(pad "1" smd custom
			(at 0 -0.4445)
			(size 0.1397 0.1397)
			(layers "F.Cu" "F.Mask" "F.Paste")
			(net "THERM_BASE")
			(options
				(clearance outline)
				(anchor circle)
			)
			(primitives
				(gr_poly
					(pts
						(arc
							(start -0.1778 -0.2794)
							(mid -0.249642 -0.249642)
							(end -0.2794 -0.1778)
						)
						(arc
							(start -0.2794 0.1778)
							(mid -0.249642 0.249642)
							(end -0.1778 0.2794)
						)
						(arc
							(start 0.1778 0.2794)
							(mid 0.249642 0.249642)
							(end 0.2794 0.1778)
						)
						(arc
							(start 0.2794 -0.1778)
							(mid 0.249642 -0.249642)
							(end 0.1778 -0.2794)
						)
					)
					(width 0)
					(fill yes)
				)
			)
		)
		(pad "2" smd custom
			(at 0 0.4445)
			(size 0.1397 0.1397)
			(layers "F.Cu" "F.Mask" "F.Paste")
			(net "THERM_BASE_R")
			(options
				(clearance outline)
				(anchor circle)
			)
			(primitives
				(gr_poly
					(pts
						(arc
							(start -0.1778 -0.2794)
							(mid -0.249642 -0.249642)
							(end -0.2794 -0.1778)
						)
						(arc
							(start -0.2794 0.1778)
							(mid -0.249642 0.249642)
							(end -0.1778 0.2794)
						)
						(arc
							(start 0.1778 0.2794)
							(mid 0.249642 0.249642)
							(end 0.2794 0.1778)
						)
						(arc
							(start 0.2794 -0.1778)
							(mid 0.249642 -0.249642)
							(end 0.1778 -0.2794)
						)
					)
					(width 0)
					(fill yes)
				)
			)
		)
	)
	(footprint ""
		(layer "F.Cu")
		(at 188.849 -11.303 90)
		(property "Reference" "Q13"
			(at 0 0 90)
			(layer "F.SilkS")
			(hide yes)
			(effects
				(font
					(size 1.27 1.27)
				)
			)
		)
		(property "Value" "2N7002K-1-GP"
			(at 0.127 -8.9662 90)
			(unlocked yes)
			(layer "F.Fab")
			(hide yes)
			(effects
				(font
					(size 1.016 1.016)
					(thickness 0.1524)
				)
			)
		)
		(property "Device Type" "SOT23DGS2D4H44"
			(at 0.127 -10.4902 90)
			(unlocked yes)
			(layer "F.Fab")
			(hide yes)
			(effects
				(font
					(size 1.016 1.016)
					(thickness 0.1524)
				)
			)
		)
		(duplicate_pad_numbers_are_jumpers no)
		(fp_line
			(start 1.651 -1.778)
			(end -1.651 -1.778)
			(stroke
				(width 0.1524)
				(type default)
			)
			(layer "F.SilkS")
		)
		(fp_line
			(start -1.651 -1.778)
			(end -1.651 1.778)
			(stroke
				(width 0.1524)
				(type default)
			)
			(layer "F.SilkS")
		)
		(fp_line
			(start 1.651 1.778)
			(end 1.651 -1.778)
			(stroke
				(width 0.1524)
				(type default)
			)
			(layer "F.SilkS")
		)
		(fp_line
			(start -1.651 1.778)
			(end 1.651 1.778)
			(stroke
				(width 0.1524)
				(type default)
			)
			(layer "F.SilkS")
		)
		(fp_poly
			(pts
				(xy -1.778 1.8796) (xy -1.778 -1.8796) (xy 1.778 -1.8796) (xy 1.778 1.8796)
			)
			(stroke
				(width 0)
				(type default)
			)
			(fill no)
			(layer "F.CrtYd")
		)
		(fp_poly
			(pts
				(xy -1.778 1.8796) (xy -1.778 -1.8796) (xy 1.778 -1.8796) (xy 1.778 1.8796)
			)
			(stroke
				(width 0)
				(type default)
			)
			(fill no)
			(layer "F.Fab")
		)
		(pad "D" smd custom
			(at 0 -0.9525 90)
			(size 0.1905 0.1905)
			(layers "F.Cu" "F.Mask" "F.Paste")
			(net "ENCLO_LED_RED")
			(options
				(clearance outline)
				(anchor circle)
			)
			(primitives
				(gr_poly
					(pts
						(arc
							(start -0.1778 0.5715)
							(mid -0.321484 0.511984)
							(end -0.381 0.3683)
						)
						(arc
							(start -0.381 -0.3683)
							(mid -0.321484 -0.511984)
							(end -0.1778 -0.5715)
						)
						(arc
							(start 0.1778 -0.5715)
							(mid 0.321484 -0.511984)
							(end 0.381 -0.3683)
						)
						(arc
							(start 0.381 0.3683)
							(mid 0.321484 0.511984)
							(end 0.1778 0.5715)
						)
					)
					(width 0)
					(fill yes)
				)
			)
		)
		(pad "G" smd custom
			(at -0.98425 0.9525 90)
			(size 0.1905 0.1905)
			(layers "F.Cu" "F.Mask" "F.Paste")
			(net "ENCLO_LED_RED_D")
			(options
				(clearance outline)
				(anchor circle)
			)
			(primitives
				(gr_poly
					(pts
						(arc
							(start -0.1778 0.5715)
							(mid -0.321484 0.511984)
							(end -0.381 0.3683)
						)
						(arc
							(start -0.381 -0.3683)
							(mid -0.321484 -0.511984)
							(end -0.1778 -0.5715)
						)
						(arc
							(start 0.1778 -0.5715)
							(mid 0.321484 -0.511984)
							(end 0.381 -0.3683)
						)
						(arc
							(start 0.381 0.3683)
							(mid 0.321484 0.511984)
							(end 0.1778 0.5715)
						)
					)
					(width 0)
					(fill yes)
				)
			)
		)
		(pad "S" smd custom
			(at 0.98425 0.9525 90)
			(size 0.1905 0.1905)
			(layers "F.Cu" "F.Mask" "F.Paste")
			(net "GND")
			(options
				(clearance outline)
				(anchor circle)
			)
			(primitives
				(gr_poly
					(pts
						(arc
							(start -0.1778 0.5715)
							(mid -0.321484 0.511984)
							(end -0.381 0.3683)
						)
						(arc
							(start -0.381 -0.3683)
							(mid -0.321484 -0.511984)
							(end -0.1778 -0.5715)
						)
						(arc
							(start 0.1778 -0.5715)
							(mid 0.321484 -0.511984)
							(end 0.381 -0.3683)
						)
						(arc
							(start 0.381 0.3683)
							(mid 0.321484 0.511984)
							(end 0.1778 0.5715)
						)
					)
					(width 0)
					(fill yes)
				)
			)
		)
	)
	(footprint ""
		(layer "F.Cu")
		(at 332.994 -71.247)
		(property "Reference" "PR151"
			(at 0 0 0)
			(layer "F.SilkS")
			(hide yes)
			(effects
				(font
					(size 1.27 1.27)
				)
			)
		)
		(property "Value" "100KR2F-L1-GP"
			(at 0.064008 -3.993896 0)
			(unlocked yes)
			(layer "F.Fab")
			(hide yes)
			(effects
				(font
					(size 1.016 1.016)
					(thickness 0.1524)
				)
			)
		)
		(property "Device Type" "R402H16"
			(at 0.064008 -5.517896 0)
			(unlocked yes)
			(layer "F.Fab")
			(hide yes)
			(effects
				(font
					(size 1.016 1.016)
					(thickness 0.1524)
				)
			)
		)
		(duplicate_pad_numbers_are_jumpers no)
		(fp_line
			(start -0.508 -0.9398)
			(end -0.508 0.9398)
			(stroke
				(width 0.1524)
				(type default)
			)
			(layer "F.SilkS")
		)
		(fp_line
			(start 0.508 -0.9398)
			(end -0.508 -0.9398)
			(stroke
				(width 0.1524)
				(type default)
			)
			(layer "F.SilkS")
		)
		(fp_rect
			(start -0.508 0.9398)
			(end 0.508 -0.9398)
			(stroke
				(width 0)
				(type default)
			)
			(fill no)
			(layer "F.CrtYd")
		)
		(fp_rect
			(start -0.508 0.9398)
			(end 0.508 -0.9398)
			(stroke
				(width 0)
				(type default)
			)
			(fill no)
			(layer "F.Fab")
		)
		(pad "1" smd custom
			(at 0 -0.4445)
			(size 0.1397 0.1397)
			(layers "F.Cu" "F.Mask" "F.Paste")
			(net "P12V")
			(options
				(clearance outline)
				(anchor circle)
			)
			(primitives
				(gr_poly
					(pts
						(arc
							(start -0.1778 -0.2794)
							(mid -0.249642 -0.249642)
							(end -0.2794 -0.1778)
						)
						(arc
							(start -0.2794 0.1778)
							(mid -0.249642 0.249642)
							(end -0.1778 0.2794)
						)
						(arc
							(start 0.1778 0.2794)
							(mid 0.249642 0.249642)
							(end 0.2794 0.1778)
						)
						(arc
							(start 0.2794 -0.1778)
							(mid 0.249642 -0.249642)
							(end 0.1778 -0.2794)
						)
					)
					(width 0)
					(fill yes)
				)
			)
		)
		(pad "2" smd custom
			(at 0 0.4445)
			(size 0.1397 0.1397)
			(layers "F.Cu" "F.Mask" "F.Paste")
			(net "P0V9_E_EN")
			(options
				(clearance outline)
				(anchor circle)
			)
			(primitives
				(gr_poly
					(pts
						(arc
							(start -0.1778 -0.2794)
							(mid -0.249642 -0.249642)
							(end -0.2794 -0.1778)
						)
						(arc
							(start -0.2794 0.1778)
							(mid -0.249642 0.249642)
							(end -0.1778 0.2794)
						)
						(arc
							(start 0.1778 0.2794)
							(mid 0.249642 0.249642)
							(end 0.2794 0.1778)
						)
						(arc
							(start 0.2794 -0.1778)
							(mid 0.249642 -0.249642)
							(end 0.1778 -0.2794)
						)
					)
					(width 0)
					(fill yes)
				)
			)
		)
	)
	(footprint ""
		(layer "F.Cu")
		(at 25.419304 -109.83722)
		(property "Reference" "R9044"
			(at 0 0 0)
			(layer "F.SilkS")
			(hide yes)
			(effects
				(font
					(size 1.27 1.27)
				)
			)
		)
		(property "Value" "470R2F-GP"
			(at 0.064008 -3.993896 0)
			(unlocked yes)
			(layer "F.Fab")
			(hide yes)
			(effects
				(font
					(size 1.016 1.016)
					(thickness 0.1524)
				)
			)
		)
		(property "Device Type" "R402H16"
			(at 0.064008 -5.517896 0)
			(unlocked yes)
			(layer "F.Fab")
			(hide yes)
			(effects
				(font
					(size 1.016 1.016)
					(thickness 0.1524)
				)
			)
		)
		(duplicate_pad_numbers_are_jumpers no)
		(fp_line
			(start -0.508 -0.9398)
			(end -0.508 0.9398)
			(stroke
				(width 0.1524)
				(type default)
			)
			(layer "F.SilkS")
		)
		(fp_line
			(start 0.508 -0.9398)
			(end -0.508 -0.9398)
			(stroke
				(width 0.1524)
				(type default)
			)
			(layer "F.SilkS")
		)
		(fp_rect
			(start -0.508 0.9398)
			(end 0.508 -0.9398)
			(stroke
				(width 0)
				(type default)
			)
			(fill no)
			(layer "F.CrtYd")
		)
		(fp_rect
			(start -0.508 0.9398)
			(end 0.508 -0.9398)
			(stroke
				(width 0)
				(type default)
			)
			(fill no)
			(layer "F.Fab")
		)
		(pad "1" smd custom
			(at 0 -0.4445)
			(size 0.1397 0.1397)
			(layers "F.Cu" "F.Mask" "F.Paste")
			(net "P3V3_STBY")
			(options
				(clearance outline)
				(anchor circle)
			)
			(primitives
				(gr_poly
					(pts
						(arc
							(start -0.1778 -0.2794)
							(mid -0.249642 -0.249642)
							(end -0.2794 -0.1778)
						)
						(arc
							(start -0.2794 0.1778)
							(mid -0.249642 0.249642)
							(end -0.1778 0.2794)
						)
						(arc
							(start 0.1778 0.2794)
							(mid 0.249642 0.249642)
							(end 0.2794 0.1778)
						)
						(arc
							(start 0.2794 -0.1778)
							(mid 0.249642 -0.249642)
							(end 0.1778 -0.2794)
						)
					)
					(width 0)
					(fill yes)
				)
			)
		)
		(pad "2" smd custom
			(at 0 0.4445)
			(size 0.1397 0.1397)
			(layers "F.Cu" "F.Mask" "F.Paste")
			(net "BMC_REFCLK_P")
			(options
				(clearance outline)
				(anchor circle)
			)
			(primitives
				(gr_poly
					(pts
						(arc
							(start -0.1778 -0.2794)
							(mid -0.249642 -0.249642)
							(end -0.2794 -0.1778)
						)
						(arc
							(start -0.2794 0.1778)
							(mid -0.249642 0.249642)
							(end -0.1778 0.2794)
						)
						(arc
							(start 0.1778 0.2794)
							(mid 0.249642 0.249642)
							(end 0.2794 0.1778)
						)
						(arc
							(start 0.2794 -0.1778)
							(mid 0.249642 -0.249642)
							(end 0.1778 -0.2794)
						)
					)
					(width 0)
					(fill yes)
				)
			)
		)
	)
	(footprint ""
		(layer "F.Cu")
		(at 64.135 -47.681388 90)
		(property "Reference" "PC32"
			(at 0 0 90)
			(layer "F.SilkS")
			(hide yes)
			(effects
				(font
					(size 1.27 1.27)
				)
			)
		)
		(property "Value" "SC10U25V5KX-GP"
			(at -0.0762 -6.1214 90)
			(unlocked yes)
			(layer "F.Fab")
			(hide yes)
			(effects
				(font
					(size 1.016 1.016)
					(thickness 0.1524)
				)
			)
		)
		(property "Device Type" "C805H56"
			(at -0.0762 -8.1534 90)
			(unlocked yes)
			(layer "F.Fab")
			(hide yes)
			(effects
				(font
					(size 1.016 1.016)
					(thickness 0.1524)
				)
			)
		)
		(duplicate_pad_numbers_are_jumpers no)
		(fp_line
			(start 0.635 0)
			(end -0.635 0)
			(stroke
				(width 0.508)
				(type default)
			)
			(layer "F.SilkS")
		)
		(fp_rect
			(start -0.9652 1.778)
			(end 0.9652 -1.778)
			(stroke
				(width 0)
				(type default)
			)
			(fill no)
			(layer "F.CrtYd")
		)
		(fp_poly
			(pts
				(xy -0.9652 -1.778) (xy 0.9652 -1.778) (xy 0.9652 1.778) (xy -0.9652 1.778)
			)
			(stroke
				(width 0)
				(type default)
			)
			(fill no)
			(layer "F.Fab")
		)
		(pad "1" smd rect
			(at 0 -0.9652 90)
			(size 1.397 1.143)
			(layers "F.Cu" "F.Mask" "F.Paste")
			(net "P3V3_STBY_VIN")
		)
		(pad "2" smd rect
			(at 0 0.9652 90)
			(size 1.397 1.143)
			(layers "F.Cu" "F.Mask" "F.Paste")
			(net "GND")
		)
	)
	(footprint ""
		(layer "F.Cu")
		(at 324.485 -99.568 180)
		(property "Reference" "R7990"
			(at 0 0 180)
			(layer "F.SilkS")
			(hide yes)
			(effects
				(font
					(size 1.27 1.27)
				)
			)
		)
		(property "Value" "0R2J-2-GP"
			(at 0.064008 -3.993896 180)
			(unlocked yes)
			(layer "F.Fab")
			(hide yes)
			(effects
				(font
					(size 1.016 1.016)
					(thickness 0.1524)
				)
			)
		)
		(property "Device Type" "R402H16"
			(at 0.064008 -5.517896 180)
			(unlocked yes)
			(layer "F.Fab")
			(hide yes)
			(effects
				(font
					(size 1.016 1.016)
					(thickness 0.1524)
				)
			)
		)
		(duplicate_pad_numbers_are_jumpers no)
		(fp_line
			(start 0.508 -0.9398)
			(end -0.508 -0.9398)
			(stroke
				(width 0.1524)
				(type default)
			)
			(layer "F.SilkS")
		)
		(fp_line
			(start -0.508 -0.9398)
			(end -0.508 0.9398)
			(stroke
				(width 0.1524)
				(type default)
			)
			(layer "F.SilkS")
		)
		(fp_rect
			(start -0.508 0.9398)
			(end 0.508 -0.9398)
			(stroke
				(width 0)
				(type default)
			)
			(fill no)
			(layer "F.CrtYd")
		)
		(fp_rect
			(start -0.508 0.9398)
			(end 0.508 -0.9398)
			(stroke
				(width 0)
				(type default)
			)
			(fill no)
			(layer "F.Fab")
		)
		(pad "1" smd custom
			(at 0 -0.4445 180)
			(size 0.1397 0.1397)
			(layers "F.Cu" "F.Mask" "F.Paste")
			(net "IOEXP_PEWAKE#")
			(options
				(clearance outline)
				(anchor circle)
			)
			(primitives
				(gr_poly
					(pts
						(arc
							(start -0.1778 -0.2794)
							(mid -0.249642 -0.249642)
							(end -0.2794 -0.1778)
						)
						(arc
							(start -0.2794 0.1778)
							(mid -0.249642 0.249642)
							(end -0.1778 0.2794)
						)
						(arc
							(start 0.1778 0.2794)
							(mid 0.249642 0.249642)
							(end 0.2794 0.1778)
						)
						(arc
							(start 0.2794 -0.1778)
							(mid 0.249642 -0.249642)
							(end 0.1778 -0.2794)
						)
					)
					(width 0)
					(fill yes)
				)
			)
		)
		(pad "2" smd custom
			(at 0 0.4445 180)
			(size 0.1397 0.1397)
			(layers "F.Cu" "F.Mask" "F.Paste")
			(net "PEWAKE#")
			(options
				(clearance outline)
				(anchor circle)
			)
			(primitives
				(gr_poly
					(pts
						(arc
							(start -0.1778 -0.2794)
							(mid -0.249642 -0.249642)
							(end -0.2794 -0.1778)
						)
						(arc
							(start -0.2794 0.1778)
							(mid -0.249642 0.249642)
							(end -0.1778 0.2794)
						)
						(arc
							(start 0.1778 0.2794)
							(mid 0.249642 0.249642)
							(end 0.2794 0.1778)
						)
						(arc
							(start 0.2794 -0.1778)
							(mid 0.249642 -0.249642)
							(end 0.1778 -0.2794)
						)
					)
					(width 0)
					(fill yes)
				)
			)
		)
	)
	(footprint ""
		(layer "F.Cu")
		(at 127.992124 -196.443092)
		(property "Reference" "R7953"
			(at 0 0 0)
			(layer "F.SilkS")
			(hide yes)
			(effects
				(font
					(size 1.27 1.27)
				)
			)
		)
		(property "Value" "0R2J-2-GP"
			(at 0.064008 -3.993896 0)
			(unlocked yes)
			(layer "F.Fab")
			(hide yes)
			(effects
				(font
					(size 1.016 1.016)
					(thickness 0.1524)
				)
			)
		)
		(property "Device Type" "R402H16"
			(at 0.064008 -5.517896 0)
			(unlocked yes)
			(layer "F.Fab")
			(hide yes)
			(effects
				(font
					(size 1.016 1.016)
					(thickness 0.1524)
				)
			)
		)
		(duplicate_pad_numbers_are_jumpers no)
		(fp_line
			(start -0.508 -0.9398)
			(end -0.508 0.9398)
			(stroke
				(width 0.1524)
				(type default)
			)
			(layer "F.SilkS")
		)
		(fp_line
			(start 0.508 -0.9398)
			(end -0.508 -0.9398)
			(stroke
				(width 0.1524)
				(type default)
			)
			(layer "F.SilkS")
		)
		(fp_rect
			(start -0.508 0.9398)
			(end 0.508 -0.9398)
			(stroke
				(width 0)
				(type default)
			)
			(fill no)
			(layer "F.CrtYd")
		)
		(fp_rect
			(start -0.508 0.9398)
			(end 0.508 -0.9398)
			(stroke
				(width 0)
				(type default)
			)
			(fill no)
			(layer "F.Fab")
		)
		(pad "1" smd custom
			(at 0 -0.4445)
			(size 0.1397 0.1397)
			(layers "F.Cu" "F.Mask" "F.Paste")
			(net "SSD_PWREN1")
			(options
				(clearance outline)
				(anchor circle)
			)
			(primitives
				(gr_poly
					(pts
						(arc
							(start -0.1778 -0.2794)
							(mid -0.249642 -0.249642)
							(end -0.2794 -0.1778)
						)
						(arc
							(start -0.2794 0.1778)
							(mid -0.249642 0.249642)
							(end -0.1778 0.2794)
						)
						(arc
							(start 0.1778 0.2794)
							(mid 0.249642 0.249642)
							(end 0.2794 0.1778)
						)
						(arc
							(start 0.2794 -0.1778)
							(mid 0.249642 -0.249642)
							(end 0.1778 -0.2794)
						)
					)
					(width 0)
					(fill yes)
				)
			)
		)
		(pad "2" smd custom
			(at 0 0.4445)
			(size 0.1397 0.1397)
			(layers "F.Cu" "F.Mask" "F.Paste")
			(net "SSD_PWREN1_R")
			(options
				(clearance outline)
				(anchor circle)
			)
			(primitives
				(gr_poly
					(pts
						(arc
							(start -0.1778 -0.2794)
							(mid -0.249642 -0.249642)
							(end -0.2794 -0.1778)
						)
						(arc
							(start -0.2794 0.1778)
							(mid -0.249642 0.249642)
							(end -0.1778 0.2794)
						)
						(arc
							(start 0.1778 0.2794)
							(mid 0.249642 0.249642)
							(end 0.2794 0.1778)
						)
						(arc
							(start 0.2794 -0.1778)
							(mid 0.249642 -0.249642)
							(end 0.1778 -0.2794)
						)
					)
					(width 0)
					(fill yes)
				)
			)
		)
	)
	(footprint ""
		(layer "F.Cu")
		(at 68.3514 -120.9802)
		(property "Reference" "U23"
			(at 0 0 0)
			(layer "F.SilkS")
			(hide yes)
			(effects
				(font
					(size 1.27 1.27)
				)
			)
		)
		(property "Value" "2N7002DW-7F-GP"
			(at -2.3622 -8.2042 0)
			(unlocked yes)
			(layer "F.Fab")
			(hide yes)
			(effects
				(font
					(size 1.016 1.016)
					(thickness 0.1524)
				)
			)
		)
		(property "Device Type" "SOT-363H44"
			(at -2.3622 -10.1092 0)
			(unlocked yes)
			(layer "F.Fab")
			(hide yes)
			(effects
				(font
					(size 1.016 1.016)
					(thickness 0.1524)
				)
			)
		)
		(duplicate_pad_numbers_are_jumpers no)
		(fp_line
			(start -1.4478 -1.7018)
			(end -1.4478 1.7018)
			(stroke
				(width 0.1524)
				(type default)
			)
			(layer "F.SilkS")
		)
		(fp_line
			(start -1.4478 1.7018)
			(end 1.4478 1.7018)
			(stroke
				(width 0.1524)
				(type default)
			)
			(layer "F.SilkS")
		)
		(fp_line
			(start -1.27 1.524)
			(end -1.27 0.6604)
			(stroke
				(width 0.4826)
				(type default)
			)
			(layer "F.SilkS")
		)
		(fp_line
			(start 1.4478 -1.7018)
			(end -1.4478 -1.7018)
			(stroke
				(width 0.1524)
				(type default)
			)
			(layer "F.SilkS")
		)
		(fp_line
			(start 1.4478 1.7018)
			(end 1.4478 -1.7018)
			(stroke
				(width 0.1524)
				(type default)
			)
			(layer "F.SilkS")
		)
		(fp_poly
			(pts
				(xy -1.524 -1.778) (xy 1.524 -1.778) (xy 1.524 1.778) (xy -1.524 1.778)
			)
			(stroke
				(width 0)
				(type default)
			)
			(fill no)
			(layer "F.CrtYd")
		)
		(fp_poly
			(pts
				(xy -1.524 -1.778) (xy 1.524 -1.778) (xy 1.524 1.778) (xy -1.524 1.778)
			)
			(stroke
				(width 0)
				(type default)
			)
			(fill no)
			(layer "F.Fab")
		)
		(pad "1" smd rect
			(at -0.65024 0.9398)
			(size 0.4064 1.016)
			(layers "F.Cu" "F.Mask" "F.Paste")
			(net "BMC_I2C4_MINI4_SCL_S")
		)
		(pad "2" smd rect
			(at 0 0.9398)
			(size 0.4064 1.016)
			(layers "F.Cu" "F.Mask" "F.Paste")
			(net "I2C4_LS_G2")
		)
		(pad "3" smd rect
			(at 0.65024 0.9398)
			(size 0.4064 1.016)
			(layers "F.Cu" "F.Mask" "F.Paste")
			(net "BMC_I2C4_MINI4_SDA")
		)
		(pad "4" smd rect
			(at 0.65024 -0.9398)
			(size 0.4064 1.016)
			(layers "F.Cu" "F.Mask" "F.Paste")
			(net "BMC_I2C4_MINI4_SDA_S")
		)
		(pad "5" smd rect
			(at 0 -0.9398)
			(size 0.4064 1.016)
			(layers "F.Cu" "F.Mask" "F.Paste")
			(net "I2C4_LS_G1")
		)
		(pad "6" smd rect
			(at -0.65024 -0.9398)
			(size 0.4064 1.016)
			(layers "F.Cu" "F.Mask" "F.Paste")
			(net "BMC_I2C4_MINI4_SCL")
		)
	)
	(footprint ""
		(layer "F.Cu")
		(at 181.61 -23.622 -90)
		(property "Reference" "C408"
			(at 0 0 270)
			(layer "F.SilkS")
			(hide yes)
			(effects
				(font
					(size 1.27 1.27)
				)
			)
		)
		(property "Value" "SCD22U10V2KX-1GP"
			(at 1.1811 -2.7051 270)
			(unlocked yes)
			(layer "F.Fab")
			(hide yes)
			(effects
				(font
					(size 1.016 1.016)
					(thickness 0.1524)
				)
			)
		)
		(property "Device Type" "C402H22"
			(at 1.1811 -4.2291 270)
			(unlocked yes)
			(layer "F.Fab")
			(hide yes)
			(effects
				(font
					(size 1.016 1.016)
					(thickness 0.1524)
				)
			)
		)
		(duplicate_pad_numbers_are_jumpers no)
		(fp_rect
			(start -0.4318 0.9525)
			(end 0.4318 -0.9525)
			(stroke
				(width 0)
				(type default)
			)
			(fill no)
			(layer "F.CrtYd")
		)
		(fp_rect
			(start -0.4318 0.9525)
			(end 0.4318 -0.9525)
			(stroke
				(width 0)
				(type default)
			)
			(fill no)
			(layer "F.Fab")
		)
		(pad "1" smd custom
			(at 0 -0.4445 270)
			(size 0.1524 0.1524)
			(layers "F.Cu" "F.Mask" "F.Paste")
			(net "PCIE_TX_CAP_N94")
			(options
				(clearance outline)
				(anchor circle)
			)
			(primitives
				(gr_poly
					(pts
						(arc
							(start 0.3048 -0.2032)
							(mid 0.275042 -0.275042)
							(end 0.2032 -0.3048)
						)
						(arc
							(start -0.2032 -0.3048)
							(mid -0.275042 -0.275042)
							(end -0.3048 -0.2032)
						)
						(arc
							(start -0.3048 0.2032)
							(mid -0.275042 0.275042)
							(end -0.2032 0.3048)
						)
						(arc
							(start 0.2032 0.3048)
							(mid 0.275042 0.275042)
							(end 0.3048 0.2032)
						)
					)
					(width 0)
					(fill yes)
				)
			)
		)
		(pad "2" smd custom
			(at 0 0.4445 270)
			(size 0.1524 0.1524)
			(layers "F.Cu" "F.Mask" "F.Paste")
			(net "PCIE_TX_N94")
			(options
				(clearance outline)
				(anchor circle)
			)
			(primitives
				(gr_poly
					(pts
						(arc
							(start 0.3048 -0.2032)
							(mid 0.275042 -0.275042)
							(end 0.2032 -0.3048)
						)
						(arc
							(start -0.2032 -0.3048)
							(mid -0.275042 -0.275042)
							(end -0.3048 -0.2032)
						)
						(arc
							(start -0.3048 0.2032)
							(mid -0.275042 0.275042)
							(end -0.2032 0.3048)
						)
						(arc
							(start 0.2032 0.3048)
							(mid 0.275042 0.275042)
							(end 0.3048 0.2032)
						)
					)
					(width 0)
					(fill yes)
				)
			)
		)
	)
	(footprint ""
		(layer "F.Cu")
		(at 11.4046 -52.0446 90)
		(property "Reference" "D14"
			(at 0 0 90)
			(layer "F.SilkS")
			(hide yes)
			(effects
				(font
					(size 1.27 1.27)
				)
			)
		)
		(property "Value" "PGB1010603MR-GP"
			(at -0.0254 -2.8956 90)
			(unlocked yes)
			(layer "F.Fab")
			(hide yes)
			(effects
				(font
					(size 1.016 1.016)
					(thickness 0.1524)
				)
			)
		)
		(property "Device Type" "L1608-UH15"
			(at -0.0254 -4.4196 90)
			(unlocked yes)
			(layer "F.Fab")
			(hide yes)
			(effects
				(font
					(size 1.016 1.016)
					(thickness 0.1524)
				)
			)
		)
		(duplicate_pad_numbers_are_jumpers no)
		(fp_line
			(start 0.254 0)
			(end -0.254 0)
			(stroke
				(width 0.2032)
				(type default)
			)
			(layer "F.SilkS")
		)
		(fp_rect
			(start -0.5842 1.3335)
			(end 0.5842 -1.3335)
			(stroke
				(width 0)
				(type default)
			)
			(fill no)
			(layer "F.CrtYd")
		)
		(fp_rect
			(start -0.5842 1.3335)
			(end 0.5842 -1.3335)
			(stroke
				(width 0)
				(type default)
			)
			(fill no)
			(layer "F.Fab")
		)
		(pad "1" smd custom
			(at 0 -0.762 90)
			(size 0.2159 0.2159)
			(layers "F.Cu" "F.Mask" "F.Paste")
			(net "NIC0_MDI0_N0_R")
			(options
				(clearance outline)
				(anchor circle)
			)
			(primitives
				(gr_poly
					(pts
						(arc
							(start -0.3302 -0.4318)
							(mid -0.402042 -0.402042)
							(end -0.4318 -0.3302)
						)
						(arc
							(start -0.4318 0.3302)
							(mid -0.402042 0.402042)
							(end -0.3302 0.4318)
						)
						(arc
							(start 0.3302 0.4318)
							(mid 0.402042 0.402042)
							(end 0.4318 0.3302)
						)
						(arc
							(start 0.4318 -0.3302)
							(mid 0.402042 -0.402042)
							(end 0.3302 -0.4318)
						)
					)
					(width 0)
					(fill yes)
				)
			)
		)
		(pad "2" smd custom
			(at 0 0.762 90)
			(size 0.2159 0.2159)
			(layers "F.Cu" "F.Mask" "F.Paste")
			(net "GND")
			(options
				(clearance outline)
				(anchor circle)
			)
			(primitives
				(gr_poly
					(pts
						(arc
							(start -0.3302 -0.4318)
							(mid -0.402042 -0.402042)
							(end -0.4318 -0.3302)
						)
						(arc
							(start -0.4318 0.3302)
							(mid -0.402042 0.402042)
							(end -0.3302 0.4318)
						)
						(arc
							(start 0.3302 0.4318)
							(mid 0.402042 0.402042)
							(end 0.4318 0.3302)
						)
						(arc
							(start 0.4318 -0.3302)
							(mid 0.402042 -0.402042)
							(end 0.3302 -0.4318)
						)
					)
					(width 0)
					(fill yes)
				)
			)
		)
	)
	(footprint ""
		(layer "F.Cu")
		(at 60.8584 -37.5666 180)
		(property "Reference" "PC29"
			(at 0 0 180)
			(layer "F.SilkS")
			(hide yes)
			(effects
				(font
					(size 1.27 1.27)
				)
			)
		)
		(property "Value" "SC1U10V2KX-4-GP"
			(at 1.1811 -2.7051 180)
			(unlocked yes)
			(layer "F.Fab")
			(hide yes)
			(effects
				(font
					(size 1.016 1.016)
					(thickness 0.1524)
				)
			)
		)
		(property "Device Type" "C402H22"
			(at 1.1811 -4.2291 180)
			(unlocked yes)
			(layer "F.Fab")
			(hide yes)
			(effects
				(font
					(size 1.016 1.016)
					(thickness 0.1524)
				)
			)
		)
		(duplicate_pad_numbers_are_jumpers no)
		(fp_rect
			(start -0.4318 0.9525)
			(end 0.4318 -0.9525)
			(stroke
				(width 0)
				(type default)
			)
			(fill no)
			(layer "F.CrtYd")
		)
		(fp_rect
			(start -0.4318 0.9525)
			(end 0.4318 -0.9525)
			(stroke
				(width 0)
				(type default)
			)
			(fill no)
			(layer "F.Fab")
		)
		(pad "1" smd custom
			(at 0 -0.4445 180)
			(size 0.1524 0.1524)
			(layers "F.Cu" "F.Mask" "F.Paste")
			(net "GND")
			(options
				(clearance outline)
				(anchor circle)
			)
			(primitives
				(gr_poly
					(pts
						(arc
							(start 0.3048 -0.2032)
							(mid 0.275042 -0.275042)
							(end 0.2032 -0.3048)
						)
						(arc
							(start -0.2032 -0.3048)
							(mid -0.275042 -0.275042)
							(end -0.3048 -0.2032)
						)
						(arc
							(start -0.3048 0.2032)
							(mid -0.275042 0.275042)
							(end -0.2032 0.3048)
						)
						(arc
							(start 0.2032 0.3048)
							(mid 0.275042 0.275042)
							(end 0.3048 0.2032)
						)
					)
					(width 0)
					(fill yes)
				)
			)
		)
		(pad "2" smd custom
			(at 0 0.4445 180)
			(size 0.1524 0.1524)
			(layers "F.Cu" "F.Mask" "F.Paste")
			(net "P3V3_STBY_VREG")
			(options
				(clearance outline)
				(anchor circle)
			)
			(primitives
				(gr_poly
					(pts
						(arc
							(start 0.3048 -0.2032)
							(mid 0.275042 -0.275042)
							(end 0.2032 -0.3048)
						)
						(arc
							(start -0.2032 -0.3048)
							(mid -0.275042 -0.275042)
							(end -0.3048 -0.2032)
						)
						(arc
							(start -0.3048 0.2032)
							(mid -0.275042 0.275042)
							(end -0.2032 0.3048)
						)
						(arc
							(start 0.2032 0.3048)
							(mid 0.275042 0.275042)
							(end 0.3048 0.2032)
						)
					)
					(width 0)
					(fill yes)
				)
			)
		)
	)
	(footprint ""
		(layer "F.Cu")
		(at 327.914 -74.93 90)
		(property "Reference" "R2"
			(at 0 0 90)
			(layer "F.SilkS")
			(hide yes)
			(effects
				(font
					(size 1.27 1.27)
				)
			)
		)
		(property "Value" "20KR2F-L-GP"
			(at 0.064008 -3.993896 90)
			(unlocked yes)
			(layer "F.Fab")
			(hide yes)
			(effects
				(font
					(size 1.016 1.016)
					(thickness 0.1524)
				)
			)
		)
		(property "Device Type" "R402H16"
			(at 0.064008 -5.517896 90)
			(unlocked yes)
			(layer "F.Fab")
			(hide yes)
			(effects
				(font
					(size 1.016 1.016)
					(thickness 0.1524)
				)
			)
		)
		(duplicate_pad_numbers_are_jumpers no)
		(fp_line
			(start 0.508 -0.9398)
			(end -0.508 -0.9398)
			(stroke
				(width 0.1524)
				(type default)
			)
			(layer "F.SilkS")
		)
		(fp_line
			(start -0.508 -0.9398)
			(end -0.508 0.9398)
			(stroke
				(width 0.1524)
				(type default)
			)
			(layer "F.SilkS")
		)
		(fp_rect
			(start -0.508 0.9398)
			(end 0.508 -0.9398)
			(stroke
				(width 0)
				(type default)
			)
			(fill no)
			(layer "F.CrtYd")
		)
		(fp_rect
			(start -0.508 0.9398)
			(end 0.508 -0.9398)
			(stroke
				(width 0)
				(type default)
			)
			(fill no)
			(layer "F.Fab")
		)
		(pad "1" smd custom
			(at 0 -0.4445 90)
			(size 0.1397 0.1397)
			(layers "F.Cu" "F.Mask" "F.Paste")
			(net "DUT_VDDO")
			(options
				(clearance outline)
				(anchor circle)
			)
			(primitives
				(gr_poly
					(pts
						(arc
							(start -0.1778 -0.2794)
							(mid -0.249642 -0.249642)
							(end -0.2794 -0.1778)
						)
						(arc
							(start -0.2794 0.1778)
							(mid -0.249642 0.249642)
							(end -0.1778 0.2794)
						)
						(arc
							(start 0.1778 0.2794)
							(mid 0.249642 0.249642)
							(end 0.2794 0.1778)
						)
						(arc
							(start 0.2794 -0.1778)
							(mid 0.249642 -0.249642)
							(end 0.1778 -0.2794)
						)
					)
					(width 0)
					(fill yes)
				)
			)
		)
		(pad "2" smd custom
			(at 0 0.4445 90)
			(size 0.1397 0.1397)
			(layers "F.Cu" "F.Mask" "F.Paste")
			(net "AVS_ENB2_R")
			(options
				(clearance outline)
				(anchor circle)
			)
			(primitives
				(gr_poly
					(pts
						(arc
							(start -0.1778 -0.2794)
							(mid -0.249642 -0.249642)
							(end -0.2794 -0.1778)
						)
						(arc
							(start -0.2794 0.1778)
							(mid -0.249642 0.249642)
							(end -0.1778 0.2794)
						)
						(arc
							(start 0.1778 0.2794)
							(mid 0.249642 0.249642)
							(end 0.2794 0.1778)
						)
						(arc
							(start 0.2794 -0.1778)
							(mid 0.249642 -0.249642)
							(end 0.1778 -0.2794)
						)
					)
					(width 0)
					(fill yes)
				)
			)
		)
	)
	(footprint ""
		(layer "F.Cu")
		(at 310.007 -64.7446)
		(property "Reference" "PG57"
			(at 0 0 0)
			(layer "F.SilkS")
			(hide yes)
			(effects
				(font
					(size 1.27 1.27)
				)
			)
		)
		(property "Value" "GAP-CLOSE-PWR-3-GP"
			(at 0.0254 -6.5786 0)
			(unlocked yes)
			(layer "F.Fab")
			(hide yes)
			(effects
				(font
					(size 1.016 1.016)
					(thickness 0.1524)
				)
			)
		)
		(property "Device Type" "GAP-CLOSE-PWR-3"
			(at 0.0254 -8.255 0)
			(unlocked yes)
			(layer "F.Fab")
			(hide yes)
			(effects
				(font
					(size 1.016 1.016)
					(thickness 0.1524)
				)
			)
		)
		(duplicate_pad_numbers_are_jumpers no)
		(fp_rect
			(start -0.7112 0.4572)
			(end 0.7112 -0.4572)
			(stroke
				(width 0)
				(type default)
			)
			(fill no)
			(layer "F.CrtYd")
		)
		(fp_poly
			(pts
				(xy -0.7112 -0.4572) (xy 0.7112 -0.4572) (xy 0.7112 0.4572) (xy -0.7112 0.4572)
			)
			(stroke
				(width 0)
				(type default)
			)
			(fill no)
			(layer "F.Fab")
		)
		(pad "1" smd rect
			(at -0.3048 0)
			(size 0.6604 0.762)
			(layers "F.Cu" "F.Mask" "F.Paste")
			(net "DUT_VDD")
		)
		(pad "2" smd rect
			(at 0.3048 0)
			(size 0.6604 0.762)
			(layers "F.Cu" "F.Mask" "F.Paste")
			(net "P0V9_E")
		)
	)
	(footprint ""
		(layer "F.Cu")
		(at 335.153 -185.801)
		(property "Reference" "TP167"
			(at 0 0 0)
			(layer "F.SilkS")
			(hide yes)
			(effects
				(font
					(size 1.27 1.27)
				)
			)
		)
		(property "Value" "TPAD28-2-GP"
			(at -0.0127 -1.6637 0)
			(unlocked yes)
			(layer "F.Fab")
			(hide yes)
			(effects
				(font
					(size 1.016 1.016)
					(thickness 0.1524)
				)
			)
		)
		(property "Device Type" "TPAD28"
			(at -0.0127 -3.1877 0)
			(unlocked yes)
			(layer "F.Fab")
			(hide yes)
			(effects
				(font
					(size 1.016 1.016)
					(thickness 0.1524)
				)
			)
		)
		(duplicate_pad_numbers_are_jumpers no)
		(fp_poly
			(pts
				(arc
					(start 0.3556 0)
					(mid -0.3556 0)
					(end 0.3556 0)
				)
			)
			(stroke
				(width 0)
				(type default)
			)
			(fill no)
			(layer "F.CrtYd")
		)
		(fp_poly
			(pts
				(arc
					(start 0.6096 0)
					(mid -0.6096 0)
					(end 0.6096 0)
				)
			)
			(stroke
				(width 0)
				(type default)
			)
			(fill no)
			(layer "F.Fab")
		)
		(pad "1" smd circle
			(at 0 0)
			(size 0.7112 0.7112)
			(layers "F.Cu" "F.Mask" "F.Paste")
			(net "IOEXP4_GPIO13")
		)
	)
	(footprint ""
		(layer "F.Cu")
		(at 71.686166 -90.07856 -90)
		(property "Reference" "R479"
			(at 0 0 270)
			(layer "F.SilkS")
			(hide yes)
			(effects
				(font
					(size 1.27 1.27)
				)
			)
		)
		(property "Value" "51R2010F-GP"
			(at 0.254 -8.0772 270)
			(unlocked yes)
			(layer "F.Fab")
			(hide yes)
			(effects
				(font
					(size 1.016 1.016)
					(thickness 0.1524)
				)
			)
		)
		(property "Device Type" "R2010H28"
			(at 0.254 -9.6774 270)
			(unlocked yes)
			(layer "F.Fab")
			(hide yes)
			(effects
				(font
					(size 1.016 1.016)
					(thickness 0.1524)
				)
			)
		)
		(duplicate_pad_numbers_are_jumpers no)
		(fp_line
			(start -1.651 3.302)
			(end 1.651 3.302)
			(stroke
				(width 0.1524)
				(type default)
			)
			(layer "F.SilkS")
		)
		(fp_line
			(start 1.651 3.302)
			(end 1.651 -3.302)
			(stroke
				(width 0.1524)
				(type default)
			)
			(layer "F.SilkS")
		)
		(fp_line
			(start -1.651 -3.302)
			(end -1.651 3.302)
			(stroke
				(width 0.1524)
				(type default)
			)
			(layer "F.SilkS")
		)
		(fp_line
			(start 1.651 -3.302)
			(end -1.651 -3.302)
			(stroke
				(width 0.1524)
				(type default)
			)
			(layer "F.SilkS")
		)
		(fp_rect
			(start -1.7272 -3.3782)
			(end 1.7272 3.3782)
			(stroke
				(width 0)
				(type default)
			)
			(fill no)
			(layer "F.CrtYd")
		)
		(fp_poly
			(pts
				(xy 1.7272 3.3782) (xy 1.7272 -3.3782) (xy -1.7272 -3.3782) (xy -1.7272 3.3782)
			)
			(stroke
				(width 0)
				(type default)
			)
			(fill no)
			(layer "F.Fab")
		)
		(pad "1" smd rect
			(at 0 -2.3495 270)
			(size 2.794 1.143)
			(layers "F.Cu" "F.Mask" "F.Paste")
			(net "P3V3_STBY")
		)
		(pad "2" smd rect
			(at 0 2.3495 270)
			(size 2.794 1.143)
			(layers "F.Cu" "F.Mask" "F.Paste")
			(net "HB_OUT")
		)
	)
	(footprint ""
		(layer "F.Cu")
		(at 121.5136 -17.0688 180)
		(property "Reference" "R751"
			(at 0 0 180)
			(layer "F.SilkS")
			(hide yes)
			(effects
				(font
					(size 1.27 1.27)
				)
			)
		)
		(property "Value" "4K7R2F-GP"
			(at 0.064008 -3.993896 180)
			(unlocked yes)
			(layer "F.Fab")
			(hide yes)
			(effects
				(font
					(size 1.016 1.016)
					(thickness 0.1524)
				)
			)
		)
		(property "Device Type" "R402H16"
			(at 0.064008 -5.517896 180)
			(unlocked yes)
			(layer "F.Fab")
			(hide yes)
			(effects
				(font
					(size 1.016 1.016)
					(thickness 0.1524)
				)
			)
		)
		(duplicate_pad_numbers_are_jumpers no)
		(fp_line
			(start 0.508 -0.9398)
			(end -0.508 -0.9398)
			(stroke
				(width 0.1524)
				(type default)
			)
			(layer "F.SilkS")
		)
		(fp_line
			(start -0.508 -0.9398)
			(end -0.508 0.9398)
			(stroke
				(width 0.1524)
				(type default)
			)
			(layer "F.SilkS")
		)
		(fp_rect
			(start -0.508 0.9398)
			(end 0.508 -0.9398)
			(stroke
				(width 0)
				(type default)
			)
			(fill no)
			(layer "F.CrtYd")
		)
		(fp_rect
			(start -0.508 0.9398)
			(end 0.508 -0.9398)
			(stroke
				(width 0)
				(type default)
			)
			(fill no)
			(layer "F.Fab")
		)
		(pad "1" smd custom
			(at 0 -0.4445 180)
			(size 0.1397 0.1397)
			(layers "F.Cu" "F.Mask" "F.Paste")
			(net "GND")
			(options
				(clearance outline)
				(anchor circle)
			)
			(primitives
				(gr_poly
					(pts
						(arc
							(start -0.1778 -0.2794)
							(mid -0.249642 -0.249642)
							(end -0.2794 -0.1778)
						)
						(arc
							(start -0.2794 0.1778)
							(mid -0.249642 0.249642)
							(end -0.1778 0.2794)
						)
						(arc
							(start 0.1778 0.2794)
							(mid 0.249642 0.249642)
							(end 0.2794 0.1778)
						)
						(arc
							(start 0.2794 -0.1778)
							(mid 0.249642 -0.249642)
							(end 0.1778 -0.2794)
						)
					)
					(width 0)
					(fill yes)
				)
			)
		)
		(pad "2" smd custom
			(at 0 0.4445 180)
			(size 0.1397 0.1397)
			(layers "F.Cu" "F.Mask" "F.Paste")
			(net "U54_A2")
			(options
				(clearance outline)
				(anchor circle)
			)
			(primitives
				(gr_poly
					(pts
						(arc
							(start -0.1778 -0.2794)
							(mid -0.249642 -0.249642)
							(end -0.2794 -0.1778)
						)
						(arc
							(start -0.2794 0.1778)
							(mid -0.249642 0.249642)
							(end -0.1778 0.2794)
						)
						(arc
							(start 0.1778 0.2794)
							(mid 0.249642 0.249642)
							(end 0.2794 0.1778)
						)
						(arc
							(start 0.2794 -0.1778)
							(mid 0.249642 -0.249642)
							(end 0.1778 -0.2794)
						)
					)
					(width 0)
					(fill yes)
				)
			)
		)
	)
	(footprint ""
		(layer "F.Cu")
		(at 333.915512 -184.878218 180)
		(property "Reference" "R7999"
			(at 0 0 180)
			(layer "F.SilkS")
			(hide yes)
			(effects
				(font
					(size 1.27 1.27)
				)
			)
		)
		(property "Value" "0R2J-2-GP"
			(at 0.064008 -3.993896 180)
			(unlocked yes)
			(layer "F.Fab")
			(hide yes)
			(effects
				(font
					(size 1.016 1.016)
					(thickness 0.1524)
				)
			)
		)
		(property "Device Type" "R402H16"
			(at 0.064008 -5.517896 180)
			(unlocked yes)
			(layer "F.Fab")
			(hide yes)
			(effects
				(font
					(size 1.016 1.016)
					(thickness 0.1524)
				)
			)
		)
		(duplicate_pad_numbers_are_jumpers no)
		(fp_line
			(start 0.508 -0.9398)
			(end -0.508 -0.9398)
			(stroke
				(width 0.1524)
				(type default)
			)
			(layer "F.SilkS")
		)
		(fp_line
			(start -0.508 -0.9398)
			(end -0.508 0.9398)
			(stroke
				(width 0.1524)
				(type default)
			)
			(layer "F.SilkS")
		)
		(fp_rect
			(start -0.508 0.9398)
			(end 0.508 -0.9398)
			(stroke
				(width 0)
				(type default)
			)
			(fill no)
			(layer "F.CrtYd")
		)
		(fp_rect
			(start -0.508 0.9398)
			(end 0.508 -0.9398)
			(stroke
				(width 0)
				(type default)
			)
			(fill no)
			(layer "F.Fab")
		)
		(pad "1" smd custom
			(at 0 -0.4445 180)
			(size 0.1397 0.1397)
			(layers "F.Cu" "F.Mask" "F.Paste")
			(net "BMC_PERST#15")
			(options
				(clearance outline)
				(anchor circle)
			)
			(primitives
				(gr_poly
					(pts
						(arc
							(start -0.1778 -0.2794)
							(mid -0.249642 -0.249642)
							(end -0.2794 -0.1778)
						)
						(arc
							(start -0.2794 0.1778)
							(mid -0.249642 0.249642)
							(end -0.1778 0.2794)
						)
						(arc
							(start 0.1778 0.2794)
							(mid 0.249642 0.249642)
							(end 0.2794 0.1778)
						)
						(arc
							(start 0.2794 -0.1778)
							(mid 0.249642 -0.249642)
							(end 0.1778 -0.2794)
						)
					)
					(width 0)
					(fill yes)
				)
			)
		)
		(pad "2" smd custom
			(at 0 0.4445 180)
			(size 0.1397 0.1397)
			(layers "F.Cu" "F.Mask" "F.Paste")
			(net "BMC_PERST#_R")
			(options
				(clearance outline)
				(anchor circle)
			)
			(primitives
				(gr_poly
					(pts
						(arc
							(start -0.1778 -0.2794)
							(mid -0.249642 -0.249642)
							(end -0.2794 -0.1778)
						)
						(arc
							(start -0.2794 0.1778)
							(mid -0.249642 0.249642)
							(end -0.1778 0.2794)
						)
						(arc
							(start 0.1778 0.2794)
							(mid 0.249642 0.249642)
							(end 0.2794 0.1778)
						)
						(arc
							(start 0.2794 -0.1778)
							(mid 0.249642 -0.249642)
							(end 0.1778 -0.2794)
						)
					)
					(width 0)
					(fill yes)
				)
			)
		)
	)
	(footprint ""
		(layer "F.Cu")
		(at 64.7446 -111.4044 -90)
		(property "Reference" "R32"
			(at 0 0 270)
			(layer "F.SilkS")
			(hide yes)
			(effects
				(font
					(size 1.27 1.27)
				)
			)
		)
		(property "Value" "0R2J-2-GP"
			(at 0.064008 -3.993896 270)
			(unlocked yes)
			(layer "F.Fab")
			(hide yes)
			(effects
				(font
					(size 1.016 1.016)
					(thickness 0.1524)
				)
			)
		)
		(property "Device Type" "R402H16"
			(at 0.064008 -5.517896 270)
			(unlocked yes)
			(layer "F.Fab")
			(hide yes)
			(effects
				(font
					(size 1.016 1.016)
					(thickness 0.1524)
				)
			)
		)
		(duplicate_pad_numbers_are_jumpers no)
		(fp_line
			(start -0.508 -0.9398)
			(end -0.508 0.9398)
			(stroke
				(width 0.1524)
				(type default)
			)
			(layer "F.SilkS")
		)
		(fp_line
			(start 0.508 -0.9398)
			(end -0.508 -0.9398)
			(stroke
				(width 0.1524)
				(type default)
			)
			(layer "F.SilkS")
		)
		(fp_rect
			(start -0.508 0.9398)
			(end 0.508 -0.9398)
			(stroke
				(width 0)
				(type default)
			)
			(fill no)
			(layer "F.CrtYd")
		)
		(fp_rect
			(start -0.508 0.9398)
			(end 0.508 -0.9398)
			(stroke
				(width 0)
				(type default)
			)
			(fill no)
			(layer "F.Fab")
		)
		(pad "1" smd custom
			(at 0 -0.4445 270)
			(size 0.1397 0.1397)
			(layers "F.Cu" "F.Mask" "F.Paste")
			(net "BMC_I2C11_MINI5_SDA")
			(options
				(clearance outline)
				(anchor circle)
			)
			(primitives
				(gr_poly
					(pts
						(arc
							(start -0.1778 -0.2794)
							(mid -0.249642 -0.249642)
							(end -0.2794 -0.1778)
						)
						(arc
							(start -0.2794 0.1778)
							(mid -0.249642 0.249642)
							(end -0.1778 0.2794)
						)
						(arc
							(start 0.1778 0.2794)
							(mid 0.249642 0.249642)
							(end 0.2794 0.1778)
						)
						(arc
							(start 0.2794 -0.1778)
							(mid 0.249642 -0.249642)
							(end 0.1778 -0.2794)
						)
					)
					(width 0)
					(fill yes)
				)
			)
		)
		(pad "2" smd custom
			(at 0 0.4445 270)
			(size 0.1397 0.1397)
			(layers "F.Cu" "F.Mask" "F.Paste")
			(net "BMC_I2C11_MINI5_SDA_S")
			(options
				(clearance outline)
				(anchor circle)
			)
			(primitives
				(gr_poly
					(pts
						(arc
							(start -0.1778 -0.2794)
							(mid -0.249642 -0.249642)
							(end -0.2794 -0.1778)
						)
						(arc
							(start -0.2794 0.1778)
							(mid -0.249642 0.249642)
							(end -0.1778 0.2794)
						)
						(arc
							(start 0.1778 0.2794)
							(mid 0.249642 0.249642)
							(end 0.2794 0.1778)
						)
						(arc
							(start 0.2794 -0.1778)
							(mid 0.249642 -0.249642)
							(end 0.1778 -0.2794)
						)
					)
					(width 0)
					(fill yes)
				)
			)
		)
	)
	(footprint ""
		(layer "F.Cu")
		(at 29.395928 -68.28028 90)
		(property "Reference" "C285"
			(at 0 0 90)
			(layer "F.SilkS")
			(hide yes)
			(effects
				(font
					(size 1.27 1.27)
				)
			)
		)
		(property "Value" "SC2D2U16V3KX-GP-U"
			(at 0 -2.8194 90)
			(unlocked yes)
			(layer "F.Fab")
			(hide yes)
			(effects
				(font
					(size 1.016 1.016)
					(thickness 0.1524)
				)
			)
		)
		(property "Device Type" "C603H40"
			(at 0 -4.3434 90)
			(unlocked yes)
			(layer "F.Fab")
			(hide yes)
			(effects
				(font
					(size 1.016 1.016)
					(thickness 0.1524)
				)
			)
		)
		(duplicate_pad_numbers_are_jumpers no)
		(fp_line
			(start 0.508 0)
			(end -0.508 0)
			(stroke
				(width 0.2032)
				(type default)
			)
			(layer "F.SilkS")
		)
		(fp_rect
			(start -0.5842 1.3335)
			(end 0.5842 -1.3335)
			(stroke
				(width 0)
				(type default)
			)
			(fill no)
			(layer "F.CrtYd")
		)
		(fp_rect
			(start -0.5842 1.3335)
			(end 0.5842 -1.3335)
			(stroke
				(width 0)
				(type default)
			)
			(fill no)
			(layer "F.Fab")
		)
		(pad "1" smd custom
			(at 0 -0.762 90)
			(size 0.2159 0.2159)
			(layers "F.Cu" "F.Mask" "F.Paste")
			(net "P3V3_STBY")
			(options
				(clearance outline)
				(anchor circle)
			)
			(primitives
				(gr_poly
					(pts
						(arc
							(start -0.3302 -0.4318)
							(mid -0.402042 -0.402042)
							(end -0.4318 -0.3302)
						)
						(arc
							(start -0.4318 0.3302)
							(mid -0.402042 0.402042)
							(end -0.3302 0.4318)
						)
						(arc
							(start 0.3302 0.4318)
							(mid 0.402042 0.402042)
							(end 0.4318 0.3302)
						)
						(arc
							(start 0.4318 -0.3302)
							(mid 0.402042 -0.402042)
							(end 0.3302 -0.4318)
						)
					)
					(width 0)
					(fill yes)
				)
			)
		)
		(pad "2" smd custom
			(at 0 0.762 90)
			(size 0.2159 0.2159)
			(layers "F.Cu" "F.Mask" "F.Paste")
			(net "GND")
			(options
				(clearance outline)
				(anchor circle)
			)
			(primitives
				(gr_poly
					(pts
						(arc
							(start -0.3302 -0.4318)
							(mid -0.402042 -0.402042)
							(end -0.4318 -0.3302)
						)
						(arc
							(start -0.4318 0.3302)
							(mid -0.402042 0.402042)
							(end -0.3302 0.4318)
						)
						(arc
							(start 0.3302 0.4318)
							(mid 0.402042 0.402042)
							(end 0.4318 0.3302)
						)
						(arc
							(start 0.4318 -0.3302)
							(mid 0.402042 -0.402042)
							(end 0.3302 -0.4318)
						)
					)
					(width 0)
					(fill yes)
				)
			)
		)
	)
	(footprint ""
		(layer "F.Cu")
		(at 17.930114 -92.684346)
		(property "Reference" "R2939"
			(at 0 0 0)
			(layer "F.SilkS")
			(hide yes)
			(effects
				(font
					(size 1.27 1.27)
				)
			)
		)
		(property "Value" "470KR2F-1-GP"
			(at 0.064008 -3.993896 0)
			(unlocked yes)
			(layer "F.Fab")
			(hide yes)
			(effects
				(font
					(size 1.016 1.016)
					(thickness 0.1524)
				)
			)
		)
		(property "Device Type" "R402H16"
			(at 0.064008 -5.517896 0)
			(unlocked yes)
			(layer "F.Fab")
			(hide yes)
			(effects
				(font
					(size 1.016 1.016)
					(thickness 0.1524)
				)
			)
		)
		(duplicate_pad_numbers_are_jumpers no)
		(fp_line
			(start -0.508 -0.9398)
			(end -0.508 0.9398)
			(stroke
				(width 0.1524)
				(type default)
			)
			(layer "F.SilkS")
		)
		(fp_line
			(start 0.508 -0.9398)
			(end -0.508 -0.9398)
			(stroke
				(width 0.1524)
				(type default)
			)
			(layer "F.SilkS")
		)
		(fp_rect
			(start -0.508 0.9398)
			(end 0.508 -0.9398)
			(stroke
				(width 0)
				(type default)
			)
			(fill no)
			(layer "F.CrtYd")
		)
		(fp_rect
			(start -0.508 0.9398)
			(end 0.508 -0.9398)
			(stroke
				(width 0)
				(type default)
			)
			(fill no)
			(layer "F.Fab")
		)
		(pad "1" smd custom
			(at 0 -0.4445)
			(size 0.1397 0.1397)
			(layers "F.Cu" "F.Mask" "F.Paste")
			(net "BMC_TPM_RST")
			(options
				(clearance outline)
				(anchor circle)
			)
			(primitives
				(gr_poly
					(pts
						(arc
							(start -0.1778 -0.2794)
							(mid -0.249642 -0.249642)
							(end -0.2794 -0.1778)
						)
						(arc
							(start -0.2794 0.1778)
							(mid -0.249642 0.249642)
							(end -0.1778 0.2794)
						)
						(arc
							(start 0.1778 0.2794)
							(mid 0.249642 0.249642)
							(end 0.2794 0.1778)
						)
						(arc
							(start 0.2794 -0.1778)
							(mid 0.249642 -0.249642)
							(end 0.1778 -0.2794)
						)
					)
					(width 0)
					(fill yes)
				)
			)
		)
		(pad "2" smd custom
			(at 0 0.4445)
			(size 0.1397 0.1397)
			(layers "F.Cu" "F.Mask" "F.Paste")
			(net "GND")
			(options
				(clearance outline)
				(anchor circle)
			)
			(primitives
				(gr_poly
					(pts
						(arc
							(start -0.1778 -0.2794)
							(mid -0.249642 -0.249642)
							(end -0.2794 -0.1778)
						)
						(arc
							(start -0.2794 0.1778)
							(mid -0.249642 0.249642)
							(end -0.1778 0.2794)
						)
						(arc
							(start 0.1778 0.2794)
							(mid 0.249642 0.249642)
							(end 0.2794 0.1778)
						)
						(arc
							(start 0.2794 -0.1778)
							(mid 0.249642 -0.249642)
							(end 0.1778 -0.2794)
						)
					)
					(width 0)
					(fill yes)
				)
			)
		)
	)
	(footprint ""
		(layer "F.Cu")
		(at 40.33266 -116.4463 -90)
		(property "Reference" "TP292"
			(at 0 0 270)
			(layer "F.SilkS")
			(hide yes)
			(effects
				(font
					(size 1.27 1.27)
				)
			)
		)
		(property "Value" "TPAD28-2-GP"
			(at -0.0127 -1.6637 270)
			(unlocked yes)
			(layer "F.Fab")
			(hide yes)
			(effects
				(font
					(size 1.016 1.016)
					(thickness 0.1524)
				)
			)
		)
		(property "Device Type" "TPAD28"
			(at -0.0127 -3.1877 270)
			(unlocked yes)
			(layer "F.Fab")
			(hide yes)
			(effects
				(font
					(size 1.016 1.016)
					(thickness 0.1524)
				)
			)
		)
		(duplicate_pad_numbers_are_jumpers no)
		(fp_poly
			(pts
				(arc
					(start 0 -0.3556)
					(mid 0 0.3556)
					(end 0 -0.3556)
				)
			)
			(stroke
				(width 0)
				(type default)
			)
			(fill no)
			(layer "F.CrtYd")
		)
		(fp_poly
			(pts
				(arc
					(start 0 -0.6096)
					(mid 0 0.6096)
					(end 0 -0.6096)
				)
			)
			(stroke
				(width 0)
				(type default)
			)
			(fill no)
			(layer "F.Fab")
		)
		(pad "1" smd circle
			(at 0 0 270)
			(size 0.7112 0.7112)
			(layers "F.Cu" "F.Mask" "F.Paste")
			(net "TP_GPIOV3")
		)
	)
	(footprint ""
		(layer "F.Cu")
		(at 116.6368 -95.0722)
		(property "Reference" "C688"
			(at 0 0 0)
			(layer "F.SilkS")
			(hide yes)
			(effects
				(font
					(size 1.27 1.27)
				)
			)
		)
		(property "Value" "SCD1U16V2KX-3GP"
			(at 1.1811 -2.7051 0)
			(unlocked yes)
			(layer "F.Fab")
			(hide yes)
			(effects
				(font
					(size 1.016 1.016)
					(thickness 0.1524)
				)
			)
		)
		(property "Device Type" "C402H22"
			(at 1.1811 -4.2291 0)
			(unlocked yes)
			(layer "F.Fab")
			(hide yes)
			(effects
				(font
					(size 1.016 1.016)
					(thickness 0.1524)
				)
			)
		)
		(duplicate_pad_numbers_are_jumpers no)
		(fp_rect
			(start -0.4318 0.9525)
			(end 0.4318 -0.9525)
			(stroke
				(width 0)
				(type default)
			)
			(fill no)
			(layer "F.CrtYd")
		)
		(fp_rect
			(start -0.4318 0.9525)
			(end 0.4318 -0.9525)
			(stroke
				(width 0)
				(type default)
			)
			(fill no)
			(layer "F.Fab")
		)
		(pad "1" smd custom
			(at 0 -0.4445)
			(size 0.1524 0.1524)
			(layers "F.Cu" "F.Mask" "F.Paste")
			(net "P3V3_STBY")
			(options
				(clearance outline)
				(anchor circle)
			)
			(primitives
				(gr_poly
					(pts
						(arc
							(start 0.3048 -0.2032)
							(mid 0.275042 -0.275042)
							(end 0.2032 -0.3048)
						)
						(arc
							(start -0.2032 -0.3048)
							(mid -0.275042 -0.275042)
							(end -0.3048 -0.2032)
						)
						(arc
							(start -0.3048 0.2032)
							(mid -0.275042 0.275042)
							(end -0.2032 0.3048)
						)
						(arc
							(start 0.2032 0.3048)
							(mid 0.275042 0.275042)
							(end 0.3048 0.2032)
						)
					)
					(width 0)
					(fill yes)
				)
			)
		)
		(pad "2" smd custom
			(at 0 0.4445)
			(size 0.1524 0.1524)
			(layers "F.Cu" "F.Mask" "F.Paste")
			(net "GND")
			(options
				(clearance outline)
				(anchor circle)
			)
			(primitives
				(gr_poly
					(pts
						(arc
							(start 0.3048 -0.2032)
							(mid 0.275042 -0.275042)
							(end 0.2032 -0.3048)
						)
						(arc
							(start -0.2032 -0.3048)
							(mid -0.275042 -0.275042)
							(end -0.3048 -0.2032)
						)
						(arc
							(start -0.3048 0.2032)
							(mid -0.275042 0.275042)
							(end -0.2032 0.3048)
						)
						(arc
							(start 0.2032 0.3048)
							(mid 0.275042 0.275042)
							(end 0.3048 0.2032)
						)
					)
					(width 0)
					(fill yes)
				)
			)
		)
	)
	(footprint ""
		(layer "F.Cu")
		(at 25.6286 -184.8612 -90)
		(property "Reference" "R965"
			(at 0 0 270)
			(layer "F.SilkS")
			(hide yes)
			(effects
				(font
					(size 1.27 1.27)
				)
			)
		)
		(property "Value" "0R2J-2-GP"
			(at 0.064008 -3.993896 270)
			(unlocked yes)
			(layer "F.Fab")
			(hide yes)
			(effects
				(font
					(size 1.016 1.016)
					(thickness 0.1524)
				)
			)
		)
		(property "Device Type" "R402H16"
			(at 0.064008 -5.517896 270)
			(unlocked yes)
			(layer "F.Fab")
			(hide yes)
			(effects
				(font
					(size 1.016 1.016)
					(thickness 0.1524)
				)
			)
		)
		(duplicate_pad_numbers_are_jumpers no)
		(fp_line
			(start -0.508 -0.9398)
			(end -0.508 0.9398)
			(stroke
				(width 0.1524)
				(type default)
			)
			(layer "F.SilkS")
		)
		(fp_line
			(start 0.508 -0.9398)
			(end -0.508 -0.9398)
			(stroke
				(width 0.1524)
				(type default)
			)
			(layer "F.SilkS")
		)
		(fp_rect
			(start -0.508 0.9398)
			(end 0.508 -0.9398)
			(stroke
				(width 0)
				(type default)
			)
			(fill no)
			(layer "F.CrtYd")
		)
		(fp_rect
			(start -0.508 0.9398)
			(end 0.508 -0.9398)
			(stroke
				(width 0)
				(type default)
			)
			(fill no)
			(layer "F.Fab")
		)
		(pad "1" smd custom
			(at 0 -0.4445 270)
			(size 0.1397 0.1397)
			(layers "F.Cu" "F.Mask" "F.Paste")
			(net "BMC_I2C5_SDA_R")
			(options
				(clearance outline)
				(anchor circle)
			)
			(primitives
				(gr_poly
					(pts
						(arc
							(start -0.1778 -0.2794)
							(mid -0.249642 -0.249642)
							(end -0.2794 -0.1778)
						)
						(arc
							(start -0.2794 0.1778)
							(mid -0.249642 0.249642)
							(end -0.1778 0.2794)
						)
						(arc
							(start 0.1778 0.2794)
							(mid 0.249642 0.249642)
							(end 0.2794 0.1778)
						)
						(arc
							(start 0.2794 -0.1778)
							(mid 0.249642 -0.249642)
							(end 0.1778 -0.2794)
						)
					)
					(width 0)
					(fill yes)
				)
			)
		)
		(pad "2" smd custom
			(at 0 0.4445 270)
			(size 0.1397 0.1397)
			(layers "F.Cu" "F.Mask" "F.Paste")
			(net "BMC_I2C5_D_PEB_SDA")
			(options
				(clearance outline)
				(anchor circle)
			)
			(primitives
				(gr_poly
					(pts
						(arc
							(start -0.1778 -0.2794)
							(mid -0.249642 -0.249642)
							(end -0.2794 -0.1778)
						)
						(arc
							(start -0.2794 0.1778)
							(mid -0.249642 0.249642)
							(end -0.1778 0.2794)
						)
						(arc
							(start 0.1778 0.2794)
							(mid 0.249642 0.249642)
							(end 0.2794 0.1778)
						)
						(arc
							(start 0.2794 -0.1778)
							(mid 0.249642 -0.249642)
							(end 0.1778 -0.2794)
						)
					)
					(width 0)
					(fill yes)
				)
			)
		)
	)
	(footprint ""
		(layer "F.Cu")
		(at 146.74342 -33.52292)
		(property "Reference" "C391"
			(at 0 0 0)
			(layer "F.SilkS")
			(hide yes)
			(effects
				(font
					(size 1.27 1.27)
				)
			)
		)
		(property "Value" "SCD22U10V2KX-1GP"
			(at 1.1811 -2.7051 0)
			(unlocked yes)
			(layer "F.Fab")
			(hide yes)
			(effects
				(font
					(size 1.016 1.016)
					(thickness 0.1524)
				)
			)
		)
		(property "Device Type" "C402H22"
			(at 1.1811 -4.2291 0)
			(unlocked yes)
			(layer "F.Fab")
			(hide yes)
			(effects
				(font
					(size 1.016 1.016)
					(thickness 0.1524)
				)
			)
		)
		(duplicate_pad_numbers_are_jumpers no)
		(fp_rect
			(start -0.4318 0.9525)
			(end 0.4318 -0.9525)
			(stroke
				(width 0)
				(type default)
			)
			(fill no)
			(layer "F.CrtYd")
		)
		(fp_rect
			(start -0.4318 0.9525)
			(end 0.4318 -0.9525)
			(stroke
				(width 0)
				(type default)
			)
			(fill no)
			(layer "F.Fab")
		)
		(pad "1" smd custom
			(at 0 -0.4445)
			(size 0.1524 0.1524)
			(layers "F.Cu" "F.Mask" "F.Paste")
			(net "PCIE_TX_CAP_N85")
			(options
				(clearance outline)
				(anchor circle)
			)
			(primitives
				(gr_poly
					(pts
						(arc
							(start 0.3048 -0.2032)
							(mid 0.275042 -0.275042)
							(end 0.2032 -0.3048)
						)
						(arc
							(start -0.2032 -0.3048)
							(mid -0.275042 -0.275042)
							(end -0.3048 -0.2032)
						)
						(arc
							(start -0.3048 0.2032)
							(mid -0.275042 0.275042)
							(end -0.2032 0.3048)
						)
						(arc
							(start 0.2032 0.3048)
							(mid 0.275042 0.275042)
							(end 0.3048 0.2032)
						)
					)
					(width 0)
					(fill yes)
				)
			)
		)
		(pad "2" smd custom
			(at 0 0.4445)
			(size 0.1524 0.1524)
			(layers "F.Cu" "F.Mask" "F.Paste")
			(net "PCIE_TX_N85")
			(options
				(clearance outline)
				(anchor circle)
			)
			(primitives
				(gr_poly
					(pts
						(arc
							(start 0.3048 -0.2032)
							(mid 0.275042 -0.275042)
							(end 0.2032 -0.3048)
						)
						(arc
							(start -0.2032 -0.3048)
							(mid -0.275042 -0.275042)
							(end -0.3048 -0.2032)
						)
						(arc
							(start -0.3048 0.2032)
							(mid -0.275042 0.275042)
							(end -0.2032 0.3048)
						)
						(arc
							(start 0.2032 0.3048)
							(mid 0.275042 0.275042)
							(end 0.3048 0.2032)
						)
					)
					(width 0)
					(fill yes)
				)
			)
		)
	)
	(footprint ""
		(layer "F.Cu")
		(at 18.9484 -185.2422)
		(property "Reference" "C419"
			(at 0 0 0)
			(layer "F.SilkS")
			(hide yes)
			(effects
				(font
					(size 1.27 1.27)
				)
			)
		)
		(property "Value" "SCD015U25V2KX-GP"
			(at 1.1811 -2.7051 0)
			(unlocked yes)
			(layer "F.Fab")
			(hide yes)
			(effects
				(font
					(size 1.016 1.016)
					(thickness 0.1524)
				)
			)
		)
		(property "Device Type" "C402H22"
			(at 1.1811 -4.2291 0)
			(unlocked yes)
			(layer "F.Fab")
			(hide yes)
			(effects
				(font
					(size 1.016 1.016)
					(thickness 0.1524)
				)
			)
		)
		(duplicate_pad_numbers_are_jumpers no)
		(fp_rect
			(start -0.4318 0.9525)
			(end 0.4318 -0.9525)
			(stroke
				(width 0)
				(type default)
			)
			(fill no)
			(layer "F.CrtYd")
		)
		(fp_rect
			(start -0.4318 0.9525)
			(end 0.4318 -0.9525)
			(stroke
				(width 0)
				(type default)
			)
			(fill no)
			(layer "F.Fab")
		)
		(pad "1" smd custom
			(at 0 -0.4445)
			(size 0.1524 0.1524)
			(layers "F.Cu" "F.Mask" "F.Paste")
			(net "ADM1278_HS_P")
			(options
				(clearance outline)
				(anchor circle)
			)
			(primitives
				(gr_poly
					(pts
						(arc
							(start 0.3048 -0.2032)
							(mid 0.275042 -0.275042)
							(end 0.2032 -0.3048)
						)
						(arc
							(start -0.2032 -0.3048)
							(mid -0.275042 -0.275042)
							(end -0.3048 -0.2032)
						)
						(arc
							(start -0.3048 0.2032)
							(mid -0.275042 0.275042)
							(end -0.2032 0.3048)
						)
						(arc
							(start 0.2032 0.3048)
							(mid 0.275042 0.275042)
							(end 0.3048 0.2032)
						)
					)
					(width 0)
					(fill yes)
				)
			)
		)
		(pad "2" smd custom
			(at 0 0.4445)
			(size 0.1524 0.1524)
			(layers "F.Cu" "F.Mask" "F.Paste")
			(net "ADM1278_HS_N")
			(options
				(clearance outline)
				(anchor circle)
			)
			(primitives
				(gr_poly
					(pts
						(arc
							(start 0.3048 -0.2032)
							(mid 0.275042 -0.275042)
							(end 0.2032 -0.3048)
						)
						(arc
							(start -0.2032 -0.3048)
							(mid -0.275042 -0.275042)
							(end -0.3048 -0.2032)
						)
						(arc
							(start -0.3048 0.2032)
							(mid -0.275042 0.275042)
							(end -0.2032 0.3048)
						)
						(arc
							(start 0.2032 0.3048)
							(mid 0.275042 0.275042)
							(end 0.3048 0.2032)
						)
					)
					(width 0)
					(fill yes)
				)
			)
		)
	)
	(footprint ""
		(layer "F.Cu")
		(at 182.801006 -54.004972 90)
		(property "Reference" "L2"
			(at 0 0 90)
			(layer "F.SilkS")
			(hide yes)
			(effects
				(font
					(size 1.27 1.27)
				)
			)
		)
		(property "Value" "IND-10UH-103-GP"
			(at 0.3048 -12.065 90)
			(unlocked yes)
			(layer "F.Fab")
			(hide yes)
			(effects
				(font
					(size 1.016 1.016)
					(thickness 0.1524)
				)
			)
		)
		(property "Device Type" "L101100H158"
			(at 0.3048 -13.97 90)
			(unlocked yes)
			(layer "F.Fab")
			(hide yes)
			(effects
				(font
					(size 1.016 1.016)
					(thickness 0.1524)
				)
			)
		)
		(duplicate_pad_numbers_are_jumpers no)
		(fp_line
			(start 5.2578 -6.1849)
			(end -5.2578 -6.1849)
			(stroke
				(width 0.1524)
				(type default)
			)
			(layer "F.SilkS")
		)
		(fp_line
			(start -5.2578 -6.1849)
			(end -5.2578 6.1849)
			(stroke
				(width 0.1524)
				(type default)
			)
			(layer "F.SilkS")
		)
		(fp_line
			(start 5.2578 6.1849)
			(end 5.2578 -6.1849)
			(stroke
				(width 0.1524)
				(type default)
			)
			(layer "F.SilkS")
		)
		(fp_line
			(start -5.2578 6.1849)
			(end 5.2578 6.1849)
			(stroke
				(width 0.1524)
				(type default)
			)
			(layer "F.SilkS")
		)
		(fp_rect
			(start -5.5118 6.2738)
			(end 5.5118 -6.2738)
			(stroke
				(width 0)
				(type default)
			)
			(fill no)
			(layer "F.CrtYd")
		)
		(fp_poly
			(pts
				(xy -5.5118 -6.2738) (xy 5.5118 -6.2738) (xy 5.5118 6.2738) (xy -5.5118 6.2738)
			)
			(stroke
				(width 0)
				(type default)
			)
			(fill no)
			(layer "F.Fab")
		)
		(pad "1" smd rect
			(at 0 -4.7625 90)
			(size 3.2512 2.3368)
			(layers "F.Cu" "F.Mask" "F.Paste")
			(net "DUT_AVD_PCIE")
		)
		(pad "2" smd rect
			(at 0 4.7625 90)
			(size 3.2512 2.3368)
			(layers "F.Cu" "F.Mask" "F.Paste")
			(net "DUT_AVD_PCIE_Q")
		)
	)
	(footprint ""
		(layer "F.Cu")
		(at 317.408052 -212.420454 180)
		(property "Reference" "C69"
			(at 0 0 180)
			(layer "F.SilkS")
			(hide yes)
			(effects
				(font
					(size 1.27 1.27)
				)
			)
		)
		(property "Value" "SCD22U10V2KX-1GP"
			(at 1.1811 -2.7051 180)
			(unlocked yes)
			(layer "F.Fab")
			(hide yes)
			(effects
				(font
					(size 1.016 1.016)
					(thickness 0.1524)
				)
			)
		)
		(property "Device Type" "C402H22"
			(at 1.1811 -4.2291 180)
			(unlocked yes)
			(layer "F.Fab")
			(hide yes)
			(effects
				(font
					(size 1.016 1.016)
					(thickness 0.1524)
				)
			)
		)
		(duplicate_pad_numbers_are_jumpers no)
		(fp_rect
			(start -0.4318 0.9525)
			(end 0.4318 -0.9525)
			(stroke
				(width 0)
				(type default)
			)
			(fill no)
			(layer "F.CrtYd")
		)
		(fp_rect
			(start -0.4318 0.9525)
			(end 0.4318 -0.9525)
			(stroke
				(width 0)
				(type default)
			)
			(fill no)
			(layer "F.Fab")
		)
		(pad "1" smd custom
			(at 0 -0.4445 180)
			(size 0.1524 0.1524)
			(layers "F.Cu" "F.Mask" "F.Paste")
			(net "PCIE_TX_CAP_N23")
			(options
				(clearance outline)
				(anchor circle)
			)
			(primitives
				(gr_poly
					(pts
						(arc
							(start 0.3048 -0.2032)
							(mid 0.275042 -0.275042)
							(end 0.2032 -0.3048)
						)
						(arc
							(start -0.2032 -0.3048)
							(mid -0.275042 -0.275042)
							(end -0.3048 -0.2032)
						)
						(arc
							(start -0.3048 0.2032)
							(mid -0.275042 0.275042)
							(end -0.2032 0.3048)
						)
						(arc
							(start 0.2032 0.3048)
							(mid 0.275042 0.275042)
							(end 0.3048 0.2032)
						)
					)
					(width 0)
					(fill yes)
				)
			)
		)
		(pad "2" smd custom
			(at 0 0.4445 180)
			(size 0.1524 0.1524)
			(layers "F.Cu" "F.Mask" "F.Paste")
			(net "PCIE_TX_N23")
			(options
				(clearance outline)
				(anchor circle)
			)
			(primitives
				(gr_poly
					(pts
						(arc
							(start 0.3048 -0.2032)
							(mid 0.275042 -0.275042)
							(end 0.2032 -0.3048)
						)
						(arc
							(start -0.2032 -0.3048)
							(mid -0.275042 -0.275042)
							(end -0.3048 -0.2032)
						)
						(arc
							(start -0.3048 0.2032)
							(mid -0.275042 0.275042)
							(end -0.2032 0.3048)
						)
						(arc
							(start 0.2032 0.3048)
							(mid 0.275042 0.275042)
							(end 0.3048 0.2032)
						)
					)
					(width 0)
					(fill yes)
				)
			)
		)
	)
	(footprint ""
		(layer "F.Cu")
		(at 54.229 -130.048)
		(property "Reference" "C189"
			(at 0 0 0)
			(layer "F.SilkS")
			(hide yes)
			(effects
				(font
					(size 1.27 1.27)
				)
			)
		)
		(property "Value" "SCD1U16V2KX-3GP"
			(at 1.1811 -2.7051 0)
			(unlocked yes)
			(layer "F.Fab")
			(hide yes)
			(effects
				(font
					(size 1.016 1.016)
					(thickness 0.1524)
				)
			)
		)
		(property "Device Type" "C402H22"
			(at 1.1811 -4.2291 0)
			(unlocked yes)
			(layer "F.Fab")
			(hide yes)
			(effects
				(font
					(size 1.016 1.016)
					(thickness 0.1524)
				)
			)
		)
		(duplicate_pad_numbers_are_jumpers no)
		(fp_rect
			(start -0.4318 0.9525)
			(end 0.4318 -0.9525)
			(stroke
				(width 0)
				(type default)
			)
			(fill no)
			(layer "F.CrtYd")
		)
		(fp_rect
			(start -0.4318 0.9525)
			(end 0.4318 -0.9525)
			(stroke
				(width 0)
				(type default)
			)
			(fill no)
			(layer "F.Fab")
		)
		(pad "1" smd custom
			(at 0 -0.4445)
			(size 0.1524 0.1524)
			(layers "F.Cu" "F.Mask" "F.Paste")
			(net "ADCAV33")
			(options
				(clearance outline)
				(anchor circle)
			)
			(primitives
				(gr_poly
					(pts
						(arc
							(start 0.3048 -0.2032)
							(mid 0.275042 -0.275042)
							(end 0.2032 -0.3048)
						)
						(arc
							(start -0.2032 -0.3048)
							(mid -0.275042 -0.275042)
							(end -0.3048 -0.2032)
						)
						(arc
							(start -0.3048 0.2032)
							(mid -0.275042 0.275042)
							(end -0.2032 0.3048)
						)
						(arc
							(start 0.2032 0.3048)
							(mid 0.275042 0.275042)
							(end 0.3048 0.2032)
						)
					)
					(width 0)
					(fill yes)
				)
			)
		)
		(pad "2" smd custom
			(at 0 0.4445)
			(size 0.1524 0.1524)
			(layers "F.Cu" "F.Mask" "F.Paste")
			(net "ADCVREFFP")
			(options
				(clearance outline)
				(anchor circle)
			)
			(primitives
				(gr_poly
					(pts
						(arc
							(start 0.3048 -0.2032)
							(mid 0.275042 -0.275042)
							(end 0.2032 -0.3048)
						)
						(arc
							(start -0.2032 -0.3048)
							(mid -0.275042 -0.275042)
							(end -0.3048 -0.2032)
						)
						(arc
							(start -0.3048 0.2032)
							(mid -0.275042 0.275042)
							(end -0.2032 0.3048)
						)
						(arc
							(start 0.2032 0.3048)
							(mid 0.275042 0.275042)
							(end 0.3048 0.2032)
						)
					)
					(width 0)
					(fill yes)
				)
			)
		)
	)
	(footprint ""
		(layer "F.Cu")
		(at 27.305 -116.713)
		(property "Reference" "R233"
			(at 0 0 0)
			(layer "F.SilkS")
			(hide yes)
			(effects
				(font
					(size 1.27 1.27)
				)
			)
		)
		(property "Value" "100KR2F-L1-GP"
			(at 0.064008 -3.993896 0)
			(unlocked yes)
			(layer "F.Fab")
			(hide yes)
			(effects
				(font
					(size 1.016 1.016)
					(thickness 0.1524)
				)
			)
		)
		(property "Device Type" "R402H16"
			(at 0.064008 -5.517896 0)
			(unlocked yes)
			(layer "F.Fab")
			(hide yes)
			(effects
				(font
					(size 1.016 1.016)
					(thickness 0.1524)
				)
			)
		)
		(duplicate_pad_numbers_are_jumpers no)
		(fp_line
			(start -0.508 -0.9398)
			(end -0.508 0.9398)
			(stroke
				(width 0.1524)
				(type default)
			)
			(layer "F.SilkS")
		)
		(fp_line
			(start 0.508 -0.9398)
			(end -0.508 -0.9398)
			(stroke
				(width 0.1524)
				(type default)
			)
			(layer "F.SilkS")
		)
		(fp_rect
			(start -0.508 0.9398)
			(end 0.508 -0.9398)
			(stroke
				(width 0)
				(type default)
			)
			(fill no)
			(layer "F.CrtYd")
		)
		(fp_rect
			(start -0.508 0.9398)
			(end 0.508 -0.9398)
			(stroke
				(width 0)
				(type default)
			)
			(fill no)
			(layer "F.Fab")
		)
		(pad "1" smd custom
			(at 0 -0.4445)
			(size 0.1397 0.1397)
			(layers "F.Cu" "F.Mask" "F.Paste")
			(net "TP_LPC_CPU_CLKOUT0")
			(options
				(clearance outline)
				(anchor circle)
			)
			(primitives
				(gr_poly
					(pts
						(arc
							(start -0.1778 -0.2794)
							(mid -0.249642 -0.249642)
							(end -0.2794 -0.1778)
						)
						(arc
							(start -0.2794 0.1778)
							(mid -0.249642 0.249642)
							(end -0.1778 0.2794)
						)
						(arc
							(start 0.1778 0.2794)
							(mid 0.249642 0.249642)
							(end 0.2794 0.1778)
						)
						(arc
							(start 0.2794 -0.1778)
							(mid 0.249642 -0.249642)
							(end 0.1778 -0.2794)
						)
					)
					(width 0)
					(fill yes)
				)
			)
		)
		(pad "2" smd custom
			(at 0 0.4445)
			(size 0.1397 0.1397)
			(layers "F.Cu" "F.Mask" "F.Paste")
			(net "GND")
			(options
				(clearance outline)
				(anchor circle)
			)
			(primitives
				(gr_poly
					(pts
						(arc
							(start -0.1778 -0.2794)
							(mid -0.249642 -0.249642)
							(end -0.2794 -0.1778)
						)
						(arc
							(start -0.2794 0.1778)
							(mid -0.249642 0.249642)
							(end -0.1778 0.2794)
						)
						(arc
							(start 0.1778 0.2794)
							(mid 0.249642 0.249642)
							(end 0.2794 0.1778)
						)
						(arc
							(start 0.2794 -0.1778)
							(mid 0.249642 -0.249642)
							(end 0.1778 -0.2794)
						)
					)
					(width 0)
					(fill yes)
				)
			)
		)
	)
	(footprint ""
		(layer "F.Cu")
		(at 6.8072 -182.9816 90)
		(property "Reference" "R688"
			(at 0 0 90)
			(layer "F.SilkS")
			(hide yes)
			(effects
				(font
					(size 1.27 1.27)
				)
			)
		)
		(property "Value" "10KR2J-3-GP"
			(at 0.064008 -3.993896 90)
			(unlocked yes)
			(layer "F.Fab")
			(hide yes)
			(effects
				(font
					(size 1.016 1.016)
					(thickness 0.1524)
				)
			)
		)
		(property "Device Type" "R402H16"
			(at 0.064008 -5.517896 90)
			(unlocked yes)
			(layer "F.Fab")
			(hide yes)
			(effects
				(font
					(size 1.016 1.016)
					(thickness 0.1524)
				)
			)
		)
		(duplicate_pad_numbers_are_jumpers no)
		(fp_line
			(start 0.508 -0.9398)
			(end -0.508 -0.9398)
			(stroke
				(width 0.1524)
				(type default)
			)
			(layer "F.SilkS")
		)
		(fp_line
			(start -0.508 -0.9398)
			(end -0.508 0.9398)
			(stroke
				(width 0.1524)
				(type default)
			)
			(layer "F.SilkS")
		)
		(fp_rect
			(start -0.508 0.9398)
			(end 0.508 -0.9398)
			(stroke
				(width 0)
				(type default)
			)
			(fill no)
			(layer "F.CrtYd")
		)
		(fp_rect
			(start -0.508 0.9398)
			(end 0.508 -0.9398)
			(stroke
				(width 0)
				(type default)
			)
			(fill no)
			(layer "F.Fab")
		)
		(pad "1" smd custom
			(at 0 -0.4445 90)
			(size 0.1397 0.1397)
			(layers "F.Cu" "F.Mask" "F.Paste")
			(net "GND")
			(options
				(clearance outline)
				(anchor circle)
			)
			(primitives
				(gr_poly
					(pts
						(arc
							(start -0.1778 -0.2794)
							(mid -0.249642 -0.249642)
							(end -0.2794 -0.1778)
						)
						(arc
							(start -0.2794 0.1778)
							(mid -0.249642 0.249642)
							(end -0.1778 0.2794)
						)
						(arc
							(start 0.1778 0.2794)
							(mid 0.249642 0.249642)
							(end 0.2794 0.1778)
						)
						(arc
							(start 0.2794 -0.1778)
							(mid 0.249642 -0.249642)
							(end 0.1778 -0.2794)
						)
					)
					(width 0)
					(fill yes)
				)
			)
		)
		(pad "2" smd custom
			(at 0 0.4445 90)
			(size 0.1397 0.1397)
			(layers "F.Cu" "F.Mask" "F.Paste")
			(net "MB0_RETRY_R")
			(options
				(clearance outline)
				(anchor circle)
			)
			(primitives
				(gr_poly
					(pts
						(arc
							(start -0.1778 -0.2794)
							(mid -0.249642 -0.249642)
							(end -0.2794 -0.1778)
						)
						(arc
							(start -0.2794 0.1778)
							(mid -0.249642 0.249642)
							(end -0.1778 0.2794)
						)
						(arc
							(start 0.1778 0.2794)
							(mid 0.249642 0.249642)
							(end 0.2794 0.1778)
						)
						(arc
							(start 0.2794 -0.1778)
							(mid 0.249642 -0.249642)
							(end 0.1778 -0.2794)
						)
					)
					(width 0)
					(fill yes)
				)
			)
		)
	)
	(footprint ""
		(layer "F.Cu")
		(at 49.911 -184.15 -90)
		(property "Reference" "C708"
			(at 0 0 270)
			(layer "F.SilkS")
			(hide yes)
			(effects
				(font
					(size 1.27 1.27)
				)
			)
		)
		(property "Value" "SC220P50V3JN-GP"
			(at 0 -2.8194 270)
			(unlocked yes)
			(layer "F.Fab")
			(hide yes)
			(effects
				(font
					(size 1.016 1.016)
					(thickness 0.1524)
				)
			)
		)
		(property "Device Type" "C603H36"
			(at 0 -4.3434 270)
			(unlocked yes)
			(layer "F.Fab")
			(hide yes)
			(effects
				(font
					(size 1.016 1.016)
					(thickness 0.1524)
				)
			)
		)
		(duplicate_pad_numbers_are_jumpers no)
		(fp_line
			(start 0.508 0)
			(end -0.508 0)
			(stroke
				(width 0.2032)
				(type default)
			)
			(layer "F.SilkS")
		)
		(fp_rect
			(start -0.5842 1.3335)
			(end 0.5842 -1.3335)
			(stroke
				(width 0)
				(type default)
			)
			(fill no)
			(layer "F.CrtYd")
		)
		(fp_rect
			(start -0.5842 1.3335)
			(end 0.5842 -1.3335)
			(stroke
				(width 0)
				(type default)
			)
			(fill no)
			(layer "F.Fab")
		)
		(pad "1" smd custom
			(at 0 -0.762 270)
			(size 0.2159 0.2159)
			(layers "F.Cu" "F.Mask" "F.Paste")
			(net "BUF_I2C8_CLKBUF1_SDA_R")
			(options
				(clearance outline)
				(anchor circle)
			)
			(primitives
				(gr_poly
					(pts
						(arc
							(start -0.3302 -0.4318)
							(mid -0.402042 -0.402042)
							(end -0.4318 -0.3302)
						)
						(arc
							(start -0.4318 0.3302)
							(mid -0.402042 0.402042)
							(end -0.3302 0.4318)
						)
						(arc
							(start 0.3302 0.4318)
							(mid 0.402042 0.402042)
							(end 0.4318 0.3302)
						)
						(arc
							(start 0.4318 -0.3302)
							(mid 0.402042 -0.402042)
							(end 0.3302 -0.4318)
						)
					)
					(width 0)
					(fill yes)
				)
			)
		)
		(pad "2" smd custom
			(at 0 0.762 270)
			(size 0.2159 0.2159)
			(layers "F.Cu" "F.Mask" "F.Paste")
			(net "GND")
			(options
				(clearance outline)
				(anchor circle)
			)
			(primitives
				(gr_poly
					(pts
						(arc
							(start -0.3302 -0.4318)
							(mid -0.402042 -0.402042)
							(end -0.4318 -0.3302)
						)
						(arc
							(start -0.4318 0.3302)
							(mid -0.402042 0.402042)
							(end -0.3302 0.4318)
						)
						(arc
							(start 0.3302 0.4318)
							(mid 0.402042 0.402042)
							(end 0.4318 0.3302)
						)
						(arc
							(start 0.4318 -0.3302)
							(mid 0.402042 -0.402042)
							(end 0.3302 -0.4318)
						)
					)
					(width 0)
					(fill yes)
				)
			)
		)
	)
	(footprint ""
		(layer "F.Cu")
		(at 79.883 -183.261)
		(property "Reference" "R9034"
			(at 0 0 0)
			(layer "F.SilkS")
			(hide yes)
			(effects
				(font
					(size 1.27 1.27)
				)
			)
		)
		(property "Value" "4K7R2F-GP"
			(at 0.064008 -3.993896 0)
			(unlocked yes)
			(layer "F.Fab")
			(hide yes)
			(effects
				(font
					(size 1.016 1.016)
					(thickness 0.1524)
				)
			)
		)
		(property "Device Type" "R402H16"
			(at 0.064008 -5.517896 0)
			(unlocked yes)
			(layer "F.Fab")
			(hide yes)
			(effects
				(font
					(size 1.016 1.016)
					(thickness 0.1524)
				)
			)
		)
		(duplicate_pad_numbers_are_jumpers no)
		(fp_line
			(start -0.508 -0.9398)
			(end -0.508 0.9398)
			(stroke
				(width 0.1524)
				(type default)
			)
			(layer "F.SilkS")
		)
		(fp_line
			(start 0.508 -0.9398)
			(end -0.508 -0.9398)
			(stroke
				(width 0.1524)
				(type default)
			)
			(layer "F.SilkS")
		)
		(fp_rect
			(start -0.508 0.9398)
			(end 0.508 -0.9398)
			(stroke
				(width 0)
				(type default)
			)
			(fill no)
			(layer "F.CrtYd")
		)
		(fp_rect
			(start -0.508 0.9398)
			(end 0.508 -0.9398)
			(stroke
				(width 0)
				(type default)
			)
			(fill no)
			(layer "F.Fab")
		)
		(pad "1" smd custom
			(at 0 -0.4445)
			(size 0.1397 0.1397)
			(layers "F.Cu" "F.Mask" "F.Paste")
			(net "SSD_PERST#5")
			(options
				(clearance outline)
				(anchor circle)
			)
			(primitives
				(gr_poly
					(pts
						(arc
							(start -0.1778 -0.2794)
							(mid -0.249642 -0.249642)
							(end -0.2794 -0.1778)
						)
						(arc
							(start -0.2794 0.1778)
							(mid -0.249642 0.249642)
							(end -0.1778 0.2794)
						)
						(arc
							(start 0.1778 0.2794)
							(mid 0.249642 0.249642)
							(end 0.2794 0.1778)
						)
						(arc
							(start 0.2794 -0.1778)
							(mid 0.249642 -0.249642)
							(end 0.1778 -0.2794)
						)
					)
					(width 0)
					(fill yes)
				)
			)
		)
		(pad "2" smd custom
			(at 0 0.4445)
			(size 0.1397 0.1397)
			(layers "F.Cu" "F.Mask" "F.Paste")
			(net "GND")
			(options
				(clearance outline)
				(anchor circle)
			)
			(primitives
				(gr_poly
					(pts
						(arc
							(start -0.1778 -0.2794)
							(mid -0.249642 -0.249642)
							(end -0.2794 -0.1778)
						)
						(arc
							(start -0.2794 0.1778)
							(mid -0.249642 0.249642)
							(end -0.1778 0.2794)
						)
						(arc
							(start 0.1778 0.2794)
							(mid 0.249642 0.249642)
							(end 0.2794 0.1778)
						)
						(arc
							(start 0.2794 -0.1778)
							(mid 0.249642 -0.249642)
							(end 0.1778 -0.2794)
						)
					)
					(width 0)
					(fill yes)
				)
			)
		)
	)
	(footprint ""
		(layer "F.Cu")
		(at 129.008124 -196.443092)
		(property "Reference" "R7968"
			(at 0 0 0)
			(layer "F.SilkS")
			(hide yes)
			(effects
				(font
					(size 1.27 1.27)
				)
			)
		)
		(property "Value" "0R2J-2-GP"
			(at 0.064008 -3.993896 0)
			(unlocked yes)
			(layer "F.Fab")
			(hide yes)
			(effects
				(font
					(size 1.016 1.016)
					(thickness 0.1524)
				)
			)
		)
		(property "Device Type" "R402H16"
			(at 0.064008 -5.517896 0)
			(unlocked yes)
			(layer "F.Fab")
			(hide yes)
			(effects
				(font
					(size 1.016 1.016)
					(thickness 0.1524)
				)
			)
		)
		(duplicate_pad_numbers_are_jumpers no)
		(fp_line
			(start -0.508 -0.9398)
			(end -0.508 0.9398)
			(stroke
				(width 0.1524)
				(type default)
			)
			(layer "F.SilkS")
		)
		(fp_line
			(start 0.508 -0.9398)
			(end -0.508 -0.9398)
			(stroke
				(width 0.1524)
				(type default)
			)
			(layer "F.SilkS")
		)
		(fp_rect
			(start -0.508 0.9398)
			(end 0.508 -0.9398)
			(stroke
				(width 0)
				(type default)
			)
			(fill no)
			(layer "F.CrtYd")
		)
		(fp_rect
			(start -0.508 0.9398)
			(end 0.508 -0.9398)
			(stroke
				(width 0)
				(type default)
			)
			(fill no)
			(layer "F.Fab")
		)
		(pad "1" smd custom
			(at 0 -0.4445)
			(size 0.1397 0.1397)
			(layers "F.Cu" "F.Mask" "F.Paste")
			(net "SSD_PERST#1")
			(options
				(clearance outline)
				(anchor circle)
			)
			(primitives
				(gr_poly
					(pts
						(arc
							(start -0.1778 -0.2794)
							(mid -0.249642 -0.249642)
							(end -0.2794 -0.1778)
						)
						(arc
							(start -0.2794 0.1778)
							(mid -0.249642 0.249642)
							(end -0.1778 0.2794)
						)
						(arc
							(start 0.1778 0.2794)
							(mid 0.249642 0.249642)
							(end 0.2794 0.1778)
						)
						(arc
							(start 0.2794 -0.1778)
							(mid 0.249642 -0.249642)
							(end 0.1778 -0.2794)
						)
					)
					(width 0)
					(fill yes)
				)
			)
		)
		(pad "2" smd custom
			(at 0 0.4445)
			(size 0.1397 0.1397)
			(layers "F.Cu" "F.Mask" "F.Paste")
			(net "SSD_PERST#1_R")
			(options
				(clearance outline)
				(anchor circle)
			)
			(primitives
				(gr_poly
					(pts
						(arc
							(start -0.1778 -0.2794)
							(mid -0.249642 -0.249642)
							(end -0.2794 -0.1778)
						)
						(arc
							(start -0.2794 0.1778)
							(mid -0.249642 0.249642)
							(end -0.1778 0.2794)
						)
						(arc
							(start 0.1778 0.2794)
							(mid 0.249642 0.249642)
							(end 0.2794 0.1778)
						)
						(arc
							(start 0.2794 -0.1778)
							(mid 0.249642 -0.249642)
							(end 0.1778 -0.2794)
						)
					)
					(width 0)
					(fill yes)
				)
			)
		)
	)
	(footprint ""
		(layer "F.Cu")
		(at 329.213718 -33.433258)
		(property "Reference" "C53"
			(at 0 0 0)
			(layer "F.SilkS")
			(hide yes)
			(effects
				(font
					(size 1.27 1.27)
				)
			)
		)
		(property "Value" "SCD22U10V2KX-1GP"
			(at 1.1811 -2.7051 0)
			(unlocked yes)
			(layer "F.Fab")
			(hide yes)
			(effects
				(font
					(size 1.016 1.016)
					(thickness 0.1524)
				)
			)
		)
		(property "Device Type" "C402H22"
			(at 1.1811 -4.2291 0)
			(unlocked yes)
			(layer "F.Fab")
			(hide yes)
			(effects
				(font
					(size 1.016 1.016)
					(thickness 0.1524)
				)
			)
		)
		(duplicate_pad_numbers_are_jumpers no)
		(fp_rect
			(start -0.4318 0.9525)
			(end 0.4318 -0.9525)
			(stroke
				(width 0)
				(type default)
			)
			(fill no)
			(layer "F.CrtYd")
		)
		(fp_rect
			(start -0.4318 0.9525)
			(end 0.4318 -0.9525)
			(stroke
				(width 0)
				(type default)
			)
			(fill no)
			(layer "F.Fab")
		)
		(pad "1" smd custom
			(at 0 -0.4445)
			(size 0.1524 0.1524)
			(layers "F.Cu" "F.Mask" "F.Paste")
			(net "PCIE_TX_CAP_N15")
			(options
				(clearance outline)
				(anchor circle)
			)
			(primitives
				(gr_poly
					(pts
						(arc
							(start 0.3048 -0.2032)
							(mid 0.275042 -0.275042)
							(end 0.2032 -0.3048)
						)
						(arc
							(start -0.2032 -0.3048)
							(mid -0.275042 -0.275042)
							(end -0.3048 -0.2032)
						)
						(arc
							(start -0.3048 0.2032)
							(mid -0.275042 0.275042)
							(end -0.2032 0.3048)
						)
						(arc
							(start 0.2032 0.3048)
							(mid 0.275042 0.275042)
							(end 0.3048 0.2032)
						)
					)
					(width 0)
					(fill yes)
				)
			)
		)
		(pad "2" smd custom
			(at 0 0.4445)
			(size 0.1524 0.1524)
			(layers "F.Cu" "F.Mask" "F.Paste")
			(net "PCIE_TX_N15")
			(options
				(clearance outline)
				(anchor circle)
			)
			(primitives
				(gr_poly
					(pts
						(arc
							(start 0.3048 -0.2032)
							(mid 0.275042 -0.275042)
							(end 0.2032 -0.3048)
						)
						(arc
							(start -0.2032 -0.3048)
							(mid -0.275042 -0.275042)
							(end -0.3048 -0.2032)
						)
						(arc
							(start -0.3048 0.2032)
							(mid -0.275042 0.275042)
							(end -0.2032 0.3048)
						)
						(arc
							(start 0.2032 0.3048)
							(mid 0.275042 0.275042)
							(end 0.3048 0.2032)
						)
					)
					(width 0)
					(fill yes)
				)
			)
		)
	)
	(footprint ""
		(layer "F.Cu")
		(at 23.4696 -52.2224 180)
		(property "Reference" "R512"
			(at 0 0 180)
			(layer "F.SilkS")
			(hide yes)
			(effects
				(font
					(size 1.27 1.27)
				)
			)
		)
		(property "Value" "0R2J-2-GP"
			(at 0.064008 -3.993896 180)
			(unlocked yes)
			(layer "F.Fab")
			(hide yes)
			(effects
				(font
					(size 1.016 1.016)
					(thickness 0.1524)
				)
			)
		)
		(property "Device Type" "R402H16"
			(at 0.064008 -5.517896 180)
			(unlocked yes)
			(layer "F.Fab")
			(hide yes)
			(effects
				(font
					(size 1.016 1.016)
					(thickness 0.1524)
				)
			)
		)
		(duplicate_pad_numbers_are_jumpers no)
		(fp_line
			(start 0.508 -0.9398)
			(end -0.508 -0.9398)
			(stroke
				(width 0.1524)
				(type default)
			)
			(layer "F.SilkS")
		)
		(fp_line
			(start -0.508 -0.9398)
			(end -0.508 0.9398)
			(stroke
				(width 0.1524)
				(type default)
			)
			(layer "F.SilkS")
		)
		(fp_rect
			(start -0.508 0.9398)
			(end 0.508 -0.9398)
			(stroke
				(width 0)
				(type default)
			)
			(fill no)
			(layer "F.CrtYd")
		)
		(fp_rect
			(start -0.508 0.9398)
			(end 0.508 -0.9398)
			(stroke
				(width 0)
				(type default)
			)
			(fill no)
			(layer "F.Fab")
		)
		(pad "1" smd custom
			(at 0 -0.4445 180)
			(size 0.1397 0.1397)
			(layers "F.Cu" "F.Mask" "F.Paste")
			(net "NIC0_MDI0_P3_R")
			(options
				(clearance outline)
				(anchor circle)
			)
			(primitives
				(gr_poly
					(pts
						(arc
							(start -0.1778 -0.2794)
							(mid -0.249642 -0.249642)
							(end -0.2794 -0.1778)
						)
						(arc
							(start -0.2794 0.1778)
							(mid -0.249642 0.249642)
							(end -0.1778 0.2794)
						)
						(arc
							(start 0.1778 0.2794)
							(mid 0.249642 0.249642)
							(end 0.2794 0.1778)
						)
						(arc
							(start 0.2794 -0.1778)
							(mid 0.249642 -0.249642)
							(end 0.1778 -0.2794)
						)
					)
					(width 0)
					(fill yes)
				)
			)
		)
		(pad "2" smd custom
			(at 0 0.4445 180)
			(size 0.1397 0.1397)
			(layers "F.Cu" "F.Mask" "F.Paste")
			(net "NIC0_MDI0_P3")
			(options
				(clearance outline)
				(anchor circle)
			)
			(primitives
				(gr_poly
					(pts
						(arc
							(start -0.1778 -0.2794)
							(mid -0.249642 -0.249642)
							(end -0.2794 -0.1778)
						)
						(arc
							(start -0.2794 0.1778)
							(mid -0.249642 0.249642)
							(end -0.1778 0.2794)
						)
						(arc
							(start 0.1778 0.2794)
							(mid 0.249642 0.249642)
							(end 0.2794 0.1778)
						)
						(arc
							(start 0.2794 -0.1778)
							(mid 0.249642 -0.249642)
							(end 0.1778 -0.2794)
						)
					)
					(width 0)
					(fill yes)
				)
			)
		)
	)
	(footprint ""
		(layer "F.Cu")
		(at 181.63794 -14.18844 -90)
		(property "Reference" "R304"
			(at 0 0 270)
			(layer "F.SilkS")
			(hide yes)
			(effects
				(font
					(size 1.27 1.27)
				)
			)
		)
		(property "Value" "0R2J-2-GP"
			(at 0.064008 -3.993896 270)
			(unlocked yes)
			(layer "F.Fab")
			(hide yes)
			(effects
				(font
					(size 1.016 1.016)
					(thickness 0.1524)
				)
			)
		)
		(property "Device Type" "R402H16"
			(at 0.064008 -5.517896 270)
			(unlocked yes)
			(layer "F.Fab")
			(hide yes)
			(effects
				(font
					(size 1.016 1.016)
					(thickness 0.1524)
				)
			)
		)
		(duplicate_pad_numbers_are_jumpers no)
		(fp_line
			(start -0.508 -0.9398)
			(end -0.508 0.9398)
			(stroke
				(width 0.1524)
				(type default)
			)
			(layer "F.SilkS")
		)
		(fp_line
			(start 0.508 -0.9398)
			(end -0.508 -0.9398)
			(stroke
				(width 0.1524)
				(type default)
			)
			(layer "F.SilkS")
		)
		(fp_rect
			(start -0.508 0.9398)
			(end 0.508 -0.9398)
			(stroke
				(width 0)
				(type default)
			)
			(fill no)
			(layer "F.CrtYd")
		)
		(fp_rect
			(start -0.508 0.9398)
			(end 0.508 -0.9398)
			(stroke
				(width 0)
				(type default)
			)
			(fill no)
			(layer "F.Fab")
		)
		(pad "1" smd custom
			(at 0 -0.4445 270)
			(size 0.1397 0.1397)
			(layers "F.Cu" "F.Mask" "F.Paste")
			(net "CLK_P_4_R")
			(options
				(clearance outline)
				(anchor circle)
			)
			(primitives
				(gr_poly
					(pts
						(arc
							(start -0.1778 -0.2794)
							(mid -0.249642 -0.249642)
							(end -0.2794 -0.1778)
						)
						(arc
							(start -0.2794 0.1778)
							(mid -0.249642 0.249642)
							(end -0.1778 0.2794)
						)
						(arc
							(start 0.1778 0.2794)
							(mid 0.249642 0.249642)
							(end 0.2794 0.1778)
						)
						(arc
							(start 0.2794 -0.1778)
							(mid 0.249642 -0.249642)
							(end 0.1778 -0.2794)
						)
					)
					(width 0)
					(fill yes)
				)
			)
		)
		(pad "2" smd custom
			(at 0 0.4445 270)
			(size 0.1397 0.1397)
			(layers "F.Cu" "F.Mask" "F.Paste")
			(net "CLK_P_4")
			(options
				(clearance outline)
				(anchor circle)
			)
			(primitives
				(gr_poly
					(pts
						(arc
							(start -0.1778 -0.2794)
							(mid -0.249642 -0.249642)
							(end -0.2794 -0.1778)
						)
						(arc
							(start -0.2794 0.1778)
							(mid -0.249642 0.249642)
							(end -0.1778 0.2794)
						)
						(arc
							(start 0.1778 0.2794)
							(mid 0.249642 0.249642)
							(end 0.2794 0.1778)
						)
						(arc
							(start 0.2794 -0.1778)
							(mid 0.249642 -0.249642)
							(end 0.1778 -0.2794)
						)
					)
					(width 0)
					(fill yes)
				)
			)
		)
	)
	(footprint ""
		(layer "F.Cu")
		(at 257.423412 -12.473686 90)
		(property "Reference" "R30"
			(at 0 0 90)
			(layer "F.SilkS")
			(hide yes)
			(effects
				(font
					(size 1.27 1.27)
				)
			)
		)
		(property "Value" "4K7R2F-GP"
			(at 0.064008 -3.993896 90)
			(unlocked yes)
			(layer "F.Fab")
			(hide yes)
			(effects
				(font
					(size 1.016 1.016)
					(thickness 0.1524)
				)
			)
		)
		(property "Device Type" "R402H16"
			(at 0.064008 -5.517896 90)
			(unlocked yes)
			(layer "F.Fab")
			(hide yes)
			(effects
				(font
					(size 1.016 1.016)
					(thickness 0.1524)
				)
			)
		)
		(duplicate_pad_numbers_are_jumpers no)
		(fp_line
			(start 0.508 -0.9398)
			(end -0.508 -0.9398)
			(stroke
				(width 0.1524)
				(type default)
			)
			(layer "F.SilkS")
		)
		(fp_line
			(start -0.508 -0.9398)
			(end -0.508 0.9398)
			(stroke
				(width 0.1524)
				(type default)
			)
			(layer "F.SilkS")
		)
		(fp_rect
			(start -0.508 0.9398)
			(end 0.508 -0.9398)
			(stroke
				(width 0)
				(type default)
			)
			(fill no)
			(layer "F.CrtYd")
		)
		(fp_rect
			(start -0.508 0.9398)
			(end 0.508 -0.9398)
			(stroke
				(width 0)
				(type default)
			)
			(fill no)
			(layer "F.Fab")
		)
		(pad "1" smd custom
			(at 0 -0.4445 90)
			(size 0.1397 0.1397)
			(layers "F.Cu" "F.Mask" "F.Paste")
			(net "THERM_EMIT")
			(options
				(clearance outline)
				(anchor circle)
			)
			(primitives
				(gr_poly
					(pts
						(arc
							(start -0.1778 -0.2794)
							(mid -0.249642 -0.249642)
							(end -0.2794 -0.1778)
						)
						(arc
							(start -0.2794 0.1778)
							(mid -0.249642 0.249642)
							(end -0.1778 0.2794)
						)
						(arc
							(start 0.1778 0.2794)
							(mid 0.249642 0.249642)
							(end 0.2794 0.1778)
						)
						(arc
							(start 0.2794 -0.1778)
							(mid 0.249642 -0.249642)
							(end 0.1778 -0.2794)
						)
					)
					(width 0)
					(fill yes)
				)
			)
		)
		(pad "2" smd custom
			(at 0 0.4445 90)
			(size 0.1397 0.1397)
			(layers "F.Cu" "F.Mask" "F.Paste")
			(net "GND")
			(options
				(clearance outline)
				(anchor circle)
			)
			(primitives
				(gr_poly
					(pts
						(arc
							(start -0.1778 -0.2794)
							(mid -0.249642 -0.249642)
							(end -0.2794 -0.1778)
						)
						(arc
							(start -0.2794 0.1778)
							(mid -0.249642 0.249642)
							(end -0.1778 0.2794)
						)
						(arc
							(start 0.1778 0.2794)
							(mid 0.249642 0.249642)
							(end 0.2794 0.1778)
						)
						(arc
							(start 0.2794 -0.1778)
							(mid 0.249642 -0.249642)
							(end 0.1778 -0.2794)
						)
					)
					(width 0)
					(fill yes)
				)
			)
		)
	)
	(footprint ""
		(layer "F.Cu")
		(at 152.20823 -212.420454 180)
		(property "Reference" "C260"
			(at 0 0 180)
			(layer "F.SilkS")
			(hide yes)
			(effects
				(font
					(size 1.27 1.27)
				)
			)
		)
		(property "Value" "SCD22U10V2KX-1GP"
			(at 1.1811 -2.7051 180)
			(unlocked yes)
			(layer "F.Fab")
			(hide yes)
			(effects
				(font
					(size 1.016 1.016)
					(thickness 0.1524)
				)
			)
		)
		(property "Device Type" "C402H22"
			(at 1.1811 -4.2291 180)
			(unlocked yes)
			(layer "F.Fab")
			(hide yes)
			(effects
				(font
					(size 1.016 1.016)
					(thickness 0.1524)
				)
			)
		)
		(duplicate_pad_numbers_are_jumpers no)
		(fp_rect
			(start -0.4318 0.9525)
			(end 0.4318 -0.9525)
			(stroke
				(width 0)
				(type default)
			)
			(fill no)
			(layer "F.CrtYd")
		)
		(fp_rect
			(start -0.4318 0.9525)
			(end 0.4318 -0.9525)
			(stroke
				(width 0)
				(type default)
			)
			(fill no)
			(layer "F.Fab")
		)
		(pad "1" smd custom
			(at 0 -0.4445 180)
			(size 0.1524 0.1524)
			(layers "F.Cu" "F.Mask" "F.Paste")
			(net "PCIE_TX_CAP_N55")
			(options
				(clearance outline)
				(anchor circle)
			)
			(primitives
				(gr_poly
					(pts
						(arc
							(start 0.3048 -0.2032)
							(mid 0.275042 -0.275042)
							(end 0.2032 -0.3048)
						)
						(arc
							(start -0.2032 -0.3048)
							(mid -0.275042 -0.275042)
							(end -0.3048 -0.2032)
						)
						(arc
							(start -0.3048 0.2032)
							(mid -0.275042 0.275042)
							(end -0.2032 0.3048)
						)
						(arc
							(start 0.2032 0.3048)
							(mid 0.275042 0.275042)
							(end 0.3048 0.2032)
						)
					)
					(width 0)
					(fill yes)
				)
			)
		)
		(pad "2" smd custom
			(at 0 0.4445 180)
			(size 0.1524 0.1524)
			(layers "F.Cu" "F.Mask" "F.Paste")
			(net "PCIE_TX_N55")
			(options
				(clearance outline)
				(anchor circle)
			)
			(primitives
				(gr_poly
					(pts
						(arc
							(start 0.3048 -0.2032)
							(mid 0.275042 -0.275042)
							(end 0.2032 -0.3048)
						)
						(arc
							(start -0.2032 -0.3048)
							(mid -0.275042 -0.275042)
							(end -0.3048 -0.2032)
						)
						(arc
							(start -0.3048 0.2032)
							(mid -0.275042 0.275042)
							(end -0.2032 0.3048)
						)
						(arc
							(start 0.2032 0.3048)
							(mid 0.275042 0.275042)
							(end 0.3048 0.2032)
						)
					)
					(width 0)
					(fill yes)
				)
			)
		)
	)
	(footprint ""
		(layer "F.Cu")
		(at 71.7042 -127.3048)
		(property "Reference" "C279"
			(at 0 0 0)
			(layer "F.SilkS")
			(hide yes)
			(effects
				(font
					(size 1.27 1.27)
				)
			)
		)
		(property "Value" "SCD1U16V2KX-3GP"
			(at 1.1811 -2.7051 0)
			(unlocked yes)
			(layer "F.Fab")
			(hide yes)
			(effects
				(font
					(size 1.016 1.016)
					(thickness 0.1524)
				)
			)
		)
		(property "Device Type" "C402H22"
			(at 1.1811 -4.2291 0)
			(unlocked yes)
			(layer "F.Fab")
			(hide yes)
			(effects
				(font
					(size 1.016 1.016)
					(thickness 0.1524)
				)
			)
		)
		(duplicate_pad_numbers_are_jumpers no)
		(fp_rect
			(start -0.4318 0.9525)
			(end 0.4318 -0.9525)
			(stroke
				(width 0)
				(type default)
			)
			(fill no)
			(layer "F.CrtYd")
		)
		(fp_rect
			(start -0.4318 0.9525)
			(end 0.4318 -0.9525)
			(stroke
				(width 0)
				(type default)
			)
			(fill no)
			(layer "F.Fab")
		)
		(pad "1" smd custom
			(at 0 -0.4445)
			(size 0.1524 0.1524)
			(layers "F.Cu" "F.Mask" "F.Paste")
			(net "P3V3_STBY")
			(options
				(clearance outline)
				(anchor circle)
			)
			(primitives
				(gr_poly
					(pts
						(arc
							(start 0.3048 -0.2032)
							(mid 0.275042 -0.275042)
							(end 0.2032 -0.3048)
						)
						(arc
							(start -0.2032 -0.3048)
							(mid -0.275042 -0.275042)
							(end -0.3048 -0.2032)
						)
						(arc
							(start -0.3048 0.2032)
							(mid -0.275042 0.275042)
							(end -0.2032 0.3048)
						)
						(arc
							(start 0.2032 0.3048)
							(mid 0.275042 0.275042)
							(end 0.3048 0.2032)
						)
					)
					(width 0)
					(fill yes)
				)
			)
		)
		(pad "2" smd custom
			(at 0 0.4445)
			(size 0.1524 0.1524)
			(layers "F.Cu" "F.Mask" "F.Paste")
			(net "GND")
			(options
				(clearance outline)
				(anchor circle)
			)
			(primitives
				(gr_poly
					(pts
						(arc
							(start 0.3048 -0.2032)
							(mid 0.275042 -0.275042)
							(end 0.2032 -0.3048)
						)
						(arc
							(start -0.2032 -0.3048)
							(mid -0.275042 -0.275042)
							(end -0.3048 -0.2032)
						)
						(arc
							(start -0.3048 0.2032)
							(mid -0.275042 0.275042)
							(end -0.2032 0.3048)
						)
						(arc
							(start 0.2032 0.3048)
							(mid 0.275042 0.275042)
							(end 0.3048 0.2032)
						)
					)
					(width 0)
					(fill yes)
				)
			)
		)
	)
	(footprint ""
		(layer "F.Cu")
		(at 304.673 -33.528)
		(property "Reference" "C26"
			(at 0 0 0)
			(layer "F.SilkS")
			(hide yes)
			(effects
				(font
					(size 1.27 1.27)
				)
			)
		)
		(property "Value" "SCD22U10V2KX-1GP"
			(at 1.1811 -2.7051 0)
			(unlocked yes)
			(layer "F.Fab")
			(hide yes)
			(effects
				(font
					(size 1.016 1.016)
					(thickness 0.1524)
				)
			)
		)
		(property "Device Type" "C402H22"
			(at 1.1811 -4.2291 0)
			(unlocked yes)
			(layer "F.Fab")
			(hide yes)
			(effects
				(font
					(size 1.016 1.016)
					(thickness 0.1524)
				)
			)
		)
		(duplicate_pad_numbers_are_jumpers no)
		(fp_rect
			(start -0.4318 0.9525)
			(end 0.4318 -0.9525)
			(stroke
				(width 0)
				(type default)
			)
			(fill no)
			(layer "F.CrtYd")
		)
		(fp_rect
			(start -0.4318 0.9525)
			(end 0.4318 -0.9525)
			(stroke
				(width 0)
				(type default)
			)
			(fill no)
			(layer "F.Fab")
		)
		(pad "1" smd custom
			(at 0 -0.4445)
			(size 0.1524 0.1524)
			(layers "F.Cu" "F.Mask" "F.Paste")
			(net "PCIE_TX_CAP_N7")
			(options
				(clearance outline)
				(anchor circle)
			)
			(primitives
				(gr_poly
					(pts
						(arc
							(start 0.3048 -0.2032)
							(mid 0.275042 -0.275042)
							(end 0.2032 -0.3048)
						)
						(arc
							(start -0.2032 -0.3048)
							(mid -0.275042 -0.275042)
							(end -0.3048 -0.2032)
						)
						(arc
							(start -0.3048 0.2032)
							(mid -0.275042 0.275042)
							(end -0.2032 0.3048)
						)
						(arc
							(start 0.2032 0.3048)
							(mid 0.275042 0.275042)
							(end 0.3048 0.2032)
						)
					)
					(width 0)
					(fill yes)
				)
			)
		)
		(pad "2" smd custom
			(at 0 0.4445)
			(size 0.1524 0.1524)
			(layers "F.Cu" "F.Mask" "F.Paste")
			(net "PCIE_TX_N7")
			(options
				(clearance outline)
				(anchor circle)
			)
			(primitives
				(gr_poly
					(pts
						(arc
							(start 0.3048 -0.2032)
							(mid 0.275042 -0.275042)
							(end 0.2032 -0.3048)
						)
						(arc
							(start -0.2032 -0.3048)
							(mid -0.275042 -0.275042)
							(end -0.3048 -0.2032)
						)
						(arc
							(start -0.3048 0.2032)
							(mid -0.275042 0.275042)
							(end -0.2032 0.3048)
						)
						(arc
							(start 0.2032 0.3048)
							(mid 0.275042 0.275042)
							(end 0.3048 0.2032)
						)
					)
					(width 0)
					(fill yes)
				)
			)
		)
	)
	(footprint ""
		(layer "F.Cu")
		(at 14.097 -196.9262 -90)
		(property "Reference" "C7278"
			(at 0 0 270)
			(layer "F.SilkS")
			(hide yes)
			(effects
				(font
					(size 1.27 1.27)
				)
			)
		)
		(property "Value" "SCD1U25V3JX-GP"
			(at 0 -2.8194 270)
			(unlocked yes)
			(layer "F.Fab")
			(hide yes)
			(effects
				(font
					(size 1.016 1.016)
					(thickness 0.1524)
				)
			)
		)
		(property "Device Type" "C603H36"
			(at 0 -4.3434 270)
			(unlocked yes)
			(layer "F.Fab")
			(hide yes)
			(effects
				(font
					(size 1.016 1.016)
					(thickness 0.1524)
				)
			)
		)
		(duplicate_pad_numbers_are_jumpers no)
		(fp_line
			(start 0.508 0)
			(end -0.508 0)
			(stroke
				(width 0.2032)
				(type default)
			)
			(layer "F.SilkS")
		)
		(fp_rect
			(start -0.5842 1.3335)
			(end 0.5842 -1.3335)
			(stroke
				(width 0)
				(type default)
			)
			(fill no)
			(layer "F.CrtYd")
		)
		(fp_rect
			(start -0.5842 1.3335)
			(end 0.5842 -1.3335)
			(stroke
				(width 0)
				(type default)
			)
			(fill no)
			(layer "F.Fab")
		)
		(pad "1" smd custom
			(at 0 -0.762 270)
			(size 0.2159 0.2159)
			(layers "F.Cu" "F.Mask" "F.Paste")
			(net "MB0_ISET_R")
			(options
				(clearance outline)
				(anchor circle)
			)
			(primitives
				(gr_poly
					(pts
						(arc
							(start -0.3302 -0.4318)
							(mid -0.402042 -0.402042)
							(end -0.4318 -0.3302)
						)
						(arc
							(start -0.4318 0.3302)
							(mid -0.402042 0.402042)
							(end -0.3302 0.4318)
						)
						(arc
							(start 0.3302 0.4318)
							(mid 0.402042 0.402042)
							(end 0.4318 0.3302)
						)
						(arc
							(start 0.4318 -0.3302)
							(mid 0.402042 -0.402042)
							(end 0.3302 -0.4318)
						)
					)
					(width 0)
					(fill yes)
				)
			)
		)
		(pad "2" smd custom
			(at 0 0.762 270)
			(size 0.2159 0.2159)
			(layers "F.Cu" "F.Mask" "F.Paste")
			(net "AGND_CURRENT_MON")
			(options
				(clearance outline)
				(anchor circle)
			)
			(primitives
				(gr_poly
					(pts
						(arc
							(start -0.3302 -0.4318)
							(mid -0.402042 -0.402042)
							(end -0.4318 -0.3302)
						)
						(arc
							(start -0.4318 0.3302)
							(mid -0.402042 0.402042)
							(end -0.3302 0.4318)
						)
						(arc
							(start 0.3302 0.4318)
							(mid 0.402042 0.402042)
							(end 0.4318 0.3302)
						)
						(arc
							(start 0.4318 -0.3302)
							(mid 0.402042 -0.402042)
							(end 0.3302 -0.4318)
						)
					)
					(width 0)
					(fill yes)
				)
			)
		)
	)
	(footprint ""
		(layer "F.Cu")
		(at 120.1928 -98.7552 -90)
		(property "Reference" "C248"
			(at 0 0 270)
			(layer "F.SilkS")
			(hide yes)
			(effects
				(font
					(size 1.27 1.27)
				)
			)
		)
		(property "Value" "SC220P50V3JN-GP"
			(at 0 -2.8194 270)
			(unlocked yes)
			(layer "F.Fab")
			(hide yes)
			(effects
				(font
					(size 1.016 1.016)
					(thickness 0.1524)
				)
			)
		)
		(property "Device Type" "C603H36"
			(at 0 -4.3434 270)
			(unlocked yes)
			(layer "F.Fab")
			(hide yes)
			(effects
				(font
					(size 1.016 1.016)
					(thickness 0.1524)
				)
			)
		)
		(duplicate_pad_numbers_are_jumpers no)
		(fp_line
			(start 0.508 0)
			(end -0.508 0)
			(stroke
				(width 0.2032)
				(type default)
			)
			(layer "F.SilkS")
		)
		(fp_rect
			(start -0.5842 1.3335)
			(end 0.5842 -1.3335)
			(stroke
				(width 0)
				(type default)
			)
			(fill no)
			(layer "F.CrtYd")
		)
		(fp_rect
			(start -0.5842 1.3335)
			(end 0.5842 -1.3335)
			(stroke
				(width 0)
				(type default)
			)
			(fill no)
			(layer "F.Fab")
		)
		(pad "1" smd custom
			(at 0 -0.762 270)
			(size 0.2159 0.2159)
			(layers "F.Cu" "F.Mask" "F.Paste")
			(net "BUF_I2C_SDA_2_R")
			(options
				(clearance outline)
				(anchor circle)
			)
			(primitives
				(gr_poly
					(pts
						(arc
							(start -0.3302 -0.4318)
							(mid -0.402042 -0.402042)
							(end -0.4318 -0.3302)
						)
						(arc
							(start -0.4318 0.3302)
							(mid -0.402042 0.402042)
							(end -0.3302 0.4318)
						)
						(arc
							(start 0.3302 0.4318)
							(mid 0.402042 0.402042)
							(end 0.4318 0.3302)
						)
						(arc
							(start 0.4318 -0.3302)
							(mid 0.402042 -0.402042)
							(end 0.3302 -0.4318)
						)
					)
					(width 0)
					(fill yes)
				)
			)
		)
		(pad "2" smd custom
			(at 0 0.762 270)
			(size 0.2159 0.2159)
			(layers "F.Cu" "F.Mask" "F.Paste")
			(net "GND")
			(options
				(clearance outline)
				(anchor circle)
			)
			(primitives
				(gr_poly
					(pts
						(arc
							(start -0.3302 -0.4318)
							(mid -0.402042 -0.402042)
							(end -0.4318 -0.3302)
						)
						(arc
							(start -0.4318 0.3302)
							(mid -0.402042 0.402042)
							(end -0.3302 0.4318)
						)
						(arc
							(start 0.3302 0.4318)
							(mid 0.402042 0.402042)
							(end 0.4318 0.3302)
						)
						(arc
							(start 0.4318 -0.3302)
							(mid 0.402042 -0.402042)
							(end 0.3302 -0.4318)
						)
					)
					(width 0)
					(fill yes)
				)
			)
		)
	)
	(footprint ""
		(layer "F.Cu")
		(at 24.765 -160.909)
		(property "Reference" "R504"
			(at 0 0 0)
			(layer "F.SilkS")
			(hide yes)
			(effects
				(font
					(size 1.27 1.27)
				)
			)
		)
		(property "Value" "0R2J-2-GP"
			(at 0.064008 -3.993896 0)
			(unlocked yes)
			(layer "F.Fab")
			(hide yes)
			(effects
				(font
					(size 1.016 1.016)
					(thickness 0.1524)
				)
			)
		)
		(property "Device Type" "R402H16"
			(at 0.064008 -5.517896 0)
			(unlocked yes)
			(layer "F.Fab")
			(hide yes)
			(effects
				(font
					(size 1.016 1.016)
					(thickness 0.1524)
				)
			)
		)
		(duplicate_pad_numbers_are_jumpers no)
		(fp_line
			(start -0.508 -0.9398)
			(end -0.508 0.9398)
			(stroke
				(width 0.1524)
				(type default)
			)
			(layer "F.SilkS")
		)
		(fp_line
			(start 0.508 -0.9398)
			(end -0.508 -0.9398)
			(stroke
				(width 0.1524)
				(type default)
			)
			(layer "F.SilkS")
		)
		(fp_rect
			(start -0.508 0.9398)
			(end 0.508 -0.9398)
			(stroke
				(width 0)
				(type default)
			)
			(fill no)
			(layer "F.CrtYd")
		)
		(fp_rect
			(start -0.508 0.9398)
			(end 0.508 -0.9398)
			(stroke
				(width 0)
				(type default)
			)
			(fill no)
			(layer "F.Fab")
		)
		(pad "1" smd custom
			(at 0 -0.4445)
			(size 0.1397 0.1397)
			(layers "F.Cu" "F.Mask" "F.Paste")
			(net "BMC_RESET#_DDR3_BUF")
			(options
				(clearance outline)
				(anchor circle)
			)
			(primitives
				(gr_poly
					(pts
						(arc
							(start -0.1778 -0.2794)
							(mid -0.249642 -0.249642)
							(end -0.2794 -0.1778)
						)
						(arc
							(start -0.2794 0.1778)
							(mid -0.249642 0.249642)
							(end -0.1778 0.2794)
						)
						(arc
							(start 0.1778 0.2794)
							(mid 0.249642 0.249642)
							(end 0.2794 0.1778)
						)
						(arc
							(start 0.2794 -0.1778)
							(mid 0.249642 -0.249642)
							(end 0.1778 -0.2794)
						)
					)
					(width 0)
					(fill yes)
				)
			)
		)
		(pad "2" smd custom
			(at 0 0.4445)
			(size 0.1397 0.1397)
			(layers "F.Cu" "F.Mask" "F.Paste")
			(net "BMC_DDR3_RST_N")
			(options
				(clearance outline)
				(anchor circle)
			)
			(primitives
				(gr_poly
					(pts
						(arc
							(start -0.1778 -0.2794)
							(mid -0.249642 -0.249642)
							(end -0.2794 -0.1778)
						)
						(arc
							(start -0.2794 0.1778)
							(mid -0.249642 0.249642)
							(end -0.1778 0.2794)
						)
						(arc
							(start 0.1778 0.2794)
							(mid 0.249642 0.249642)
							(end 0.2794 0.1778)
						)
						(arc
							(start 0.2794 -0.1778)
							(mid 0.249642 -0.249642)
							(end 0.1778 -0.2794)
						)
					)
					(width 0)
					(fill yes)
				)
			)
		)
	)
	(footprint ""
		(layer "F.Cu")
		(at 56.261 -118.11 90)
		(property "Reference" "R581"
			(at 0 0 90)
			(layer "F.SilkS")
			(hide yes)
			(effects
				(font
					(size 1.27 1.27)
				)
			)
		)
		(property "Value" "4K7R2F-GP"
			(at 0.064008 -3.993896 90)
			(unlocked yes)
			(layer "F.Fab")
			(hide yes)
			(effects
				(font
					(size 1.016 1.016)
					(thickness 0.1524)
				)
			)
		)
		(property "Device Type" "R402H16"
			(at 0.064008 -5.517896 90)
			(unlocked yes)
			(layer "F.Fab")
			(hide yes)
			(effects
				(font
					(size 1.016 1.016)
					(thickness 0.1524)
				)
			)
		)
		(duplicate_pad_numbers_are_jumpers no)
		(fp_line
			(start 0.508 -0.9398)
			(end -0.508 -0.9398)
			(stroke
				(width 0.1524)
				(type default)
			)
			(layer "F.SilkS")
		)
		(fp_line
			(start -0.508 -0.9398)
			(end -0.508 0.9398)
			(stroke
				(width 0.1524)
				(type default)
			)
			(layer "F.SilkS")
		)
		(fp_rect
			(start -0.508 0.9398)
			(end 0.508 -0.9398)
			(stroke
				(width 0)
				(type default)
			)
			(fill no)
			(layer "F.CrtYd")
		)
		(fp_rect
			(start -0.508 0.9398)
			(end 0.508 -0.9398)
			(stroke
				(width 0)
				(type default)
			)
			(fill no)
			(layer "F.Fab")
		)
		(pad "1" smd custom
			(at 0 -0.4445 90)
			(size 0.1397 0.1397)
			(layers "F.Cu" "F.Mask" "F.Paste")
			(net "BMC_I2C7_B_DPB_SDA")
			(options
				(clearance outline)
				(anchor circle)
			)
			(primitives
				(gr_poly
					(pts
						(arc
							(start -0.1778 -0.2794)
							(mid -0.249642 -0.249642)
							(end -0.2794 -0.1778)
						)
						(arc
							(start -0.2794 0.1778)
							(mid -0.249642 0.249642)
							(end -0.1778 0.2794)
						)
						(arc
							(start 0.1778 0.2794)
							(mid 0.249642 0.249642)
							(end 0.2794 0.1778)
						)
						(arc
							(start 0.2794 -0.1778)
							(mid 0.249642 -0.249642)
							(end 0.1778 -0.2794)
						)
					)
					(width 0)
					(fill yes)
				)
			)
		)
		(pad "2" smd custom
			(at 0 0.4445 90)
			(size 0.1397 0.1397)
			(layers "F.Cu" "F.Mask" "F.Paste")
			(net "P3V3_STBY")
			(options
				(clearance outline)
				(anchor circle)
			)
			(primitives
				(gr_poly
					(pts
						(arc
							(start -0.1778 -0.2794)
							(mid -0.249642 -0.249642)
							(end -0.2794 -0.1778)
						)
						(arc
							(start -0.2794 0.1778)
							(mid -0.249642 0.249642)
							(end -0.1778 0.2794)
						)
						(arc
							(start 0.1778 0.2794)
							(mid 0.249642 0.249642)
							(end 0.2794 0.1778)
						)
						(arc
							(start 0.2794 -0.1778)
							(mid 0.249642 -0.249642)
							(end 0.1778 -0.2794)
						)
					)
					(width 0)
					(fill yes)
				)
			)
		)
	)
	(footprint ""
		(layer "F.Cu")
		(at 124.944124 -208.889092)
		(property "Reference" "R7916"
			(at 0 0 0)
			(layer "F.SilkS")
			(hide yes)
			(effects
				(font
					(size 1.27 1.27)
				)
			)
		)
		(property "Value" "0R2J-2-GP"
			(at 0.064008 -3.993896 0)
			(unlocked yes)
			(layer "F.Fab")
			(hide yes)
			(effects
				(font
					(size 1.016 1.016)
					(thickness 0.1524)
				)
			)
		)
		(property "Device Type" "R402H16"
			(at 0.064008 -5.517896 0)
			(unlocked yes)
			(layer "F.Fab")
			(hide yes)
			(effects
				(font
					(size 1.016 1.016)
					(thickness 0.1524)
				)
			)
		)
		(duplicate_pad_numbers_are_jumpers no)
		(fp_line
			(start -0.508 -0.9398)
			(end -0.508 0.9398)
			(stroke
				(width 0.1524)
				(type default)
			)
			(layer "F.SilkS")
		)
		(fp_line
			(start 0.508 -0.9398)
			(end -0.508 -0.9398)
			(stroke
				(width 0.1524)
				(type default)
			)
			(layer "F.SilkS")
		)
		(fp_rect
			(start -0.508 0.9398)
			(end 0.508 -0.9398)
			(stroke
				(width 0)
				(type default)
			)
			(fill no)
			(layer "F.CrtYd")
		)
		(fp_rect
			(start -0.508 0.9398)
			(end 0.508 -0.9398)
			(stroke
				(width 0)
				(type default)
			)
			(fill no)
			(layer "F.Fab")
		)
		(pad "1" smd custom
			(at 0 -0.4445)
			(size 0.1397 0.1397)
			(layers "F.Cu" "F.Mask" "F.Paste")
			(net "TWI_SCL1")
			(options
				(clearance outline)
				(anchor circle)
			)
			(primitives
				(gr_poly
					(pts
						(arc
							(start -0.1778 -0.2794)
							(mid -0.249642 -0.249642)
							(end -0.2794 -0.1778)
						)
						(arc
							(start -0.2794 0.1778)
							(mid -0.249642 0.249642)
							(end -0.1778 0.2794)
						)
						(arc
							(start 0.1778 0.2794)
							(mid 0.249642 0.249642)
							(end 0.2794 0.1778)
						)
						(arc
							(start 0.2794 -0.1778)
							(mid 0.249642 -0.249642)
							(end 0.1778 -0.2794)
						)
					)
					(width 0)
					(fill yes)
				)
			)
		)
		(pad "2" smd custom
			(at 0 0.4445)
			(size 0.1397 0.1397)
			(layers "F.Cu" "F.Mask" "F.Paste")
			(net "I2C_GPIO_SCL_2")
			(options
				(clearance outline)
				(anchor circle)
			)
			(primitives
				(gr_poly
					(pts
						(arc
							(start -0.1778 -0.2794)
							(mid -0.249642 -0.249642)
							(end -0.2794 -0.1778)
						)
						(arc
							(start -0.2794 0.1778)
							(mid -0.249642 0.249642)
							(end -0.1778 0.2794)
						)
						(arc
							(start 0.1778 0.2794)
							(mid 0.249642 0.249642)
							(end 0.2794 0.1778)
						)
						(arc
							(start 0.2794 -0.1778)
							(mid 0.249642 -0.249642)
							(end 0.1778 -0.2794)
						)
					)
					(width 0)
					(fill yes)
				)
			)
		)
	)
	(footprint ""
		(layer "F.Cu")
		(at 21.0566 -190.3222 90)
		(property "Reference" "C7276"
			(at 0 0 90)
			(layer "F.SilkS")
			(hide yes)
			(effects
				(font
					(size 1.27 1.27)
				)
			)
		)
		(property "Value" "SC1U16V3KX-5GP"
			(at 0 -2.8194 90)
			(unlocked yes)
			(layer "F.Fab")
			(hide yes)
			(effects
				(font
					(size 1.016 1.016)
					(thickness 0.1524)
				)
			)
		)
		(property "Device Type" "C603H36"
			(at 0 -4.3434 90)
			(unlocked yes)
			(layer "F.Fab")
			(hide yes)
			(effects
				(font
					(size 1.016 1.016)
					(thickness 0.1524)
				)
			)
		)
		(duplicate_pad_numbers_are_jumpers no)
		(fp_line
			(start 0.508 0)
			(end -0.508 0)
			(stroke
				(width 0.2032)
				(type default)
			)
			(layer "F.SilkS")
		)
		(fp_rect
			(start -0.5842 1.3335)
			(end 0.5842 -1.3335)
			(stroke
				(width 0)
				(type default)
			)
			(fill no)
			(layer "F.CrtYd")
		)
		(fp_rect
			(start -0.5842 1.3335)
			(end 0.5842 -1.3335)
			(stroke
				(width 0)
				(type default)
			)
			(fill no)
			(layer "F.Fab")
		)
		(pad "1" smd custom
			(at 0 -0.762 90)
			(size 0.2159 0.2159)
			(layers "F.Cu" "F.Mask" "F.Paste")
			(net "MB0_CM_UV_R")
			(options
				(clearance outline)
				(anchor circle)
			)
			(primitives
				(gr_poly
					(pts
						(arc
							(start -0.3302 -0.4318)
							(mid -0.402042 -0.402042)
							(end -0.4318 -0.3302)
						)
						(arc
							(start -0.4318 0.3302)
							(mid -0.402042 0.402042)
							(end -0.3302 0.4318)
						)
						(arc
							(start 0.3302 0.4318)
							(mid 0.402042 0.402042)
							(end 0.4318 0.3302)
						)
						(arc
							(start 0.4318 -0.3302)
							(mid 0.402042 -0.402042)
							(end 0.3302 -0.4318)
						)
					)
					(width 0)
					(fill yes)
				)
			)
		)
		(pad "2" smd custom
			(at 0 0.762 90)
			(size 0.2159 0.2159)
			(layers "F.Cu" "F.Mask" "F.Paste")
			(net "AGND_CURRENT_MON")
			(options
				(clearance outline)
				(anchor circle)
			)
			(primitives
				(gr_poly
					(pts
						(arc
							(start -0.3302 -0.4318)
							(mid -0.402042 -0.402042)
							(end -0.4318 -0.3302)
						)
						(arc
							(start -0.4318 0.3302)
							(mid -0.402042 0.402042)
							(end -0.3302 0.4318)
						)
						(arc
							(start 0.3302 0.4318)
							(mid 0.402042 0.402042)
							(end 0.4318 0.3302)
						)
						(arc
							(start 0.4318 -0.3302)
							(mid 0.402042 -0.402042)
							(end 0.3302 -0.4318)
						)
					)
					(width 0)
					(fill yes)
				)
			)
		)
	)
	(footprint ""
		(layer "F.Cu")
		(at 167.767 -94.5134 90)
		(property "Reference" "TP74"
			(at 0 0 90)
			(layer "F.SilkS")
			(hide yes)
			(effects
				(font
					(size 1.27 1.27)
				)
			)
		)
		(property "Value" "TPAD28-2-GP"
			(at -0.0127 -1.6637 90)
			(unlocked yes)
			(layer "F.Fab")
			(hide yes)
			(effects
				(font
					(size 1.016 1.016)
					(thickness 0.1524)
				)
			)
		)
		(property "Device Type" "TPAD28"
			(at -0.0127 -3.1877 90)
			(unlocked yes)
			(layer "F.Fab")
			(hide yes)
			(effects
				(font
					(size 1.016 1.016)
					(thickness 0.1524)
				)
			)
		)
		(duplicate_pad_numbers_are_jumpers no)
		(fp_poly
			(pts
				(arc
					(start 0 0.3556)
					(mid 0 -0.3556)
					(end 0 0.3556)
				)
			)
			(stroke
				(width 0)
				(type default)
			)
			(fill no)
			(layer "F.CrtYd")
		)
		(fp_poly
			(pts
				(arc
					(start 0 0.6096)
					(mid 0 -0.6096)
					(end 0 0.6096)
				)
			)
			(stroke
				(width 0)
				(type default)
			)
			(fill no)
			(layer "F.Fab")
		)
		(pad "1" smd circle
			(at 0 0 90)
			(size 0.7112 0.7112)
			(layers "F.Cu" "F.Mask" "F.Paste")
			(net "CLKGEN_OE2")
		)
	)
	(footprint ""
		(layer "F.Cu")
		(at 53.200046 -36.471098 90)
		(property "Reference" "R629"
			(at 0 0 90)
			(layer "F.SilkS")
			(hide yes)
			(effects
				(font
					(size 1.27 1.27)
				)
			)
		)
		(property "Value" "10KR2F-2-GP"
			(at 0.064008 -3.993896 90)
			(unlocked yes)
			(layer "F.Fab")
			(hide yes)
			(effects
				(font
					(size 1.016 1.016)
					(thickness 0.1524)
				)
			)
		)
		(property "Device Type" "R402H16"
			(at 0.064008 -5.517896 90)
			(unlocked yes)
			(layer "F.Fab")
			(hide yes)
			(effects
				(font
					(size 1.016 1.016)
					(thickness 0.1524)
				)
			)
		)
		(duplicate_pad_numbers_are_jumpers no)
		(fp_line
			(start 0.508 -0.9398)
			(end -0.508 -0.9398)
			(stroke
				(width 0.1524)
				(type default)
			)
			(layer "F.SilkS")
		)
		(fp_line
			(start -0.508 -0.9398)
			(end -0.508 0.9398)
			(stroke
				(width 0.1524)
				(type default)
			)
			(layer "F.SilkS")
		)
		(fp_rect
			(start -0.508 0.9398)
			(end 0.508 -0.9398)
			(stroke
				(width 0)
				(type default)
			)
			(fill no)
			(layer "F.CrtYd")
		)
		(fp_rect
			(start -0.508 0.9398)
			(end 0.508 -0.9398)
			(stroke
				(width 0)
				(type default)
			)
			(fill no)
			(layer "F.Fab")
		)
		(pad "1" smd custom
			(at 0 -0.4445 90)
			(size 0.1397 0.1397)
			(layers "F.Cu" "F.Mask" "F.Paste")
			(net "Q42_D")
			(options
				(clearance outline)
				(anchor circle)
			)
			(primitives
				(gr_poly
					(pts
						(arc
							(start -0.1778 -0.2794)
							(mid -0.249642 -0.249642)
							(end -0.2794 -0.1778)
						)
						(arc
							(start -0.2794 0.1778)
							(mid -0.249642 0.249642)
							(end -0.1778 0.2794)
						)
						(arc
							(start 0.1778 0.2794)
							(mid 0.249642 0.249642)
							(end 0.2794 0.1778)
						)
						(arc
							(start 0.2794 -0.1778)
							(mid 0.249642 -0.249642)
							(end 0.1778 -0.2794)
						)
					)
					(width 0)
					(fill yes)
				)
			)
		)
		(pad "2" smd custom
			(at 0 0.4445 90)
			(size 0.1397 0.1397)
			(layers "F.Cu" "F.Mask" "F.Paste")
			(net "Q43_B")
			(options
				(clearance outline)
				(anchor circle)
			)
			(primitives
				(gr_poly
					(pts
						(arc
							(start -0.1778 -0.2794)
							(mid -0.249642 -0.249642)
							(end -0.2794 -0.1778)
						)
						(arc
							(start -0.2794 0.1778)
							(mid -0.249642 0.249642)
							(end -0.1778 0.2794)
						)
						(arc
							(start 0.1778 0.2794)
							(mid 0.249642 0.249642)
							(end 0.2794 0.1778)
						)
						(arc
							(start 0.2794 -0.1778)
							(mid 0.249642 -0.249642)
							(end 0.1778 -0.2794)
						)
					)
					(width 0)
					(fill yes)
				)
			)
		)
	)
	(footprint ""
		(layer "F.Cu")
		(at 125.599952 -19.99996 90)
		(property "Reference" "LED8"
			(at 0 0 90)
			(layer "F.SilkS")
			(hide yes)
			(effects
				(font
					(size 1.27 1.27)
				)
			)
		)
		(property "Value" "LED-YG-51-GP"
			(at -2.6924 -1.4224 90)
			(unlocked yes)
			(layer "F.Fab")
			(hide yes)
			(effects
				(font
					(size 1.016 1.016)
					(thickness 0.1524)
				)
			)
		)
		(property "Device Type" "LED1608AKH40"
			(at -2.6924 -2.9464 90)
			(unlocked yes)
			(layer "F.Fab")
			(hide yes)
			(effects
				(font
					(size 1.016 1.016)
					(thickness 0.1524)
				)
			)
		)
		(duplicate_pad_numbers_are_jumpers no)
		(fp_line
			(start 0.6604 -1.3716)
			(end 0.6604 1.3716)
			(stroke
				(width 0.1524)
				(type default)
			)
			(layer "F.SilkS")
		)
		(fp_line
			(start -0.6604 -1.3716)
			(end 0.6604 -1.3716)
			(stroke
				(width 0.1524)
				(type default)
			)
			(layer "F.SilkS")
		)
		(fp_line
			(start 0.6604 1.3716)
			(end -0.6604 1.3716)
			(stroke
				(width 0.1524)
				(type default)
			)
			(layer "F.SilkS")
		)
		(fp_line
			(start -0.6604 1.3716)
			(end -0.6604 -1.3716)
			(stroke
				(width 0.1524)
				(type default)
			)
			(layer "F.SilkS")
		)
		(fp_line
			(start -0.5969 1.5494)
			(end 0.5842 1.5494)
			(stroke
				(width 0.508)
				(type default)
			)
			(layer "F.SilkS")
		)
		(fp_line
			(start 0.7493 1.651)
			(end 0.7493 1.1811)
			(stroke
				(width 0.3302)
				(type default)
			)
			(layer "F.SilkS")
		)
		(fp_line
			(start -0.7493 1.651)
			(end -0.7493 1.1811)
			(stroke
				(width 0.3302)
				(type default)
			)
			(layer "F.SilkS")
		)
		(fp_rect
			(start -0.6223 1.3335)
			(end 0.6223 -1.3335)
			(stroke
				(width 0)
				(type default)
			)
			(fill no)
			(layer "F.CrtYd")
		)
		(fp_rect
			(start -0.6223 1.3335)
			(end 0.6223 -1.3335)
			(stroke
				(width 0)
				(type default)
			)
			(fill no)
			(layer "F.Fab")
		)
		(pad "A" smd custom
			(at 0 -0.762 90)
			(size 0.2159 0.2159)
			(layers "F.Cu" "F.Mask" "F.Paste")
			(net "LED_R_1")
			(options
				(clearance outline)
				(anchor circle)
			)
			(primitives
				(gr_poly
					(pts
						(arc
							(start -0.3302 -0.4318)
							(mid -0.402042 -0.402042)
							(end -0.4318 -0.3302)
						)
						(arc
							(start -0.4318 0.3302)
							(mid -0.402042 0.402042)
							(end -0.3302 0.4318)
						)
						(arc
							(start 0.3302 0.4318)
							(mid 0.402042 0.402042)
							(end 0.4318 0.3302)
						)
						(arc
							(start 0.4318 -0.3302)
							(mid 0.402042 -0.402042)
							(end 0.3302 -0.4318)
						)
					)
					(width 0)
					(fill yes)
				)
			)
		)
		(pad "K" smd custom
			(at 0 0.762 90)
			(size 0.2159 0.2159)
			(layers "F.Cu" "F.Mask" "F.Paste")
			(net "LED_Q_1")
			(options
				(clearance outline)
				(anchor circle)
			)
			(primitives
				(gr_poly
					(pts
						(arc
							(start -0.3302 -0.4318)
							(mid -0.402042 -0.402042)
							(end -0.4318 -0.3302)
						)
						(arc
							(start -0.4318 0.3302)
							(mid -0.402042 0.402042)
							(end -0.3302 0.4318)
						)
						(arc
							(start 0.3302 0.4318)
							(mid 0.402042 0.402042)
							(end 0.4318 0.3302)
						)
						(arc
							(start 0.4318 -0.3302)
							(mid 0.402042 -0.402042)
							(end 0.3302 -0.4318)
						)
					)
					(width 0)
					(fill yes)
				)
			)
		)
	)
	(footprint ""
		(layer "F.Cu")
		(at 55.118 -194.564 180)
		(property "Reference" "R885"
			(at 0 0 180)
			(layer "F.SilkS")
			(hide yes)
			(effects
				(font
					(size 1.27 1.27)
				)
			)
		)
		(property "Value" "10KR2F-2-GP"
			(at 0.064008 -3.993896 180)
			(unlocked yes)
			(layer "F.Fab")
			(hide yes)
			(effects
				(font
					(size 1.016 1.016)
					(thickness 0.1524)
				)
			)
		)
		(property "Device Type" "R402H16"
			(at 0.064008 -5.517896 180)
			(unlocked yes)
			(layer "F.Fab")
			(hide yes)
			(effects
				(font
					(size 1.016 1.016)
					(thickness 0.1524)
				)
			)
		)
		(duplicate_pad_numbers_are_jumpers no)
		(fp_line
			(start 0.508 -0.9398)
			(end -0.508 -0.9398)
			(stroke
				(width 0.1524)
				(type default)
			)
			(layer "F.SilkS")
		)
		(fp_line
			(start -0.508 -0.9398)
			(end -0.508 0.9398)
			(stroke
				(width 0.1524)
				(type default)
			)
			(layer "F.SilkS")
		)
		(fp_rect
			(start -0.508 0.9398)
			(end 0.508 -0.9398)
			(stroke
				(width 0)
				(type default)
			)
			(fill no)
			(layer "F.CrtYd")
		)
		(fp_rect
			(start -0.508 0.9398)
			(end 0.508 -0.9398)
			(stroke
				(width 0)
				(type default)
			)
			(fill no)
			(layer "F.Fab")
		)
		(pad "1" smd custom
			(at 0 -0.4445 180)
			(size 0.1397 0.1397)
			(layers "F.Cu" "F.Mask" "F.Paste")
			(net "P3V3_STBY")
			(options
				(clearance outline)
				(anchor circle)
			)
			(primitives
				(gr_poly
					(pts
						(arc
							(start -0.1778 -0.2794)
							(mid -0.249642 -0.249642)
							(end -0.2794 -0.1778)
						)
						(arc
							(start -0.2794 0.1778)
							(mid -0.249642 0.249642)
							(end -0.1778 0.2794)
						)
						(arc
							(start 0.1778 0.2794)
							(mid 0.249642 0.249642)
							(end 0.2794 0.1778)
						)
						(arc
							(start 0.2794 -0.1778)
							(mid 0.249642 -0.249642)
							(end 0.1778 -0.2794)
						)
					)
					(width 0)
					(fill yes)
				)
			)
		)
		(pad "2" smd custom
			(at 0 0.4445 180)
			(size 0.1397 0.1397)
			(layers "F.Cu" "F.Mask" "F.Paste")
			(net "I2C7_BUFF_EN")
			(options
				(clearance outline)
				(anchor circle)
			)
			(primitives
				(gr_poly
					(pts
						(arc
							(start -0.1778 -0.2794)
							(mid -0.249642 -0.249642)
							(end -0.2794 -0.1778)
						)
						(arc
							(start -0.2794 0.1778)
							(mid -0.249642 0.249642)
							(end -0.1778 0.2794)
						)
						(arc
							(start 0.1778 0.2794)
							(mid 0.249642 0.249642)
							(end 0.2794 0.1778)
						)
						(arc
							(start 0.2794 -0.1778)
							(mid 0.249642 -0.249642)
							(end 0.1778 -0.2794)
						)
					)
					(width 0)
					(fill yes)
				)
			)
		)
	)
	(footprint ""
		(layer "F.Cu")
		(at 52.607972 -212.420454 180)
		(property "Reference" "C364"
			(at 0 0 180)
			(layer "F.SilkS")
			(hide yes)
			(effects
				(font
					(size 1.27 1.27)
				)
			)
		)
		(property "Value" "SCD22U10V2KX-1GP"
			(at 1.1811 -2.7051 180)
			(unlocked yes)
			(layer "F.Fab")
			(hide yes)
			(effects
				(font
					(size 1.016 1.016)
					(thickness 0.1524)
				)
			)
		)
		(property "Device Type" "C402H22"
			(at 1.1811 -4.2291 180)
			(unlocked yes)
			(layer "F.Fab")
			(hide yes)
			(effects
				(font
					(size 1.016 1.016)
					(thickness 0.1524)
				)
			)
		)
		(duplicate_pad_numbers_are_jumpers no)
		(fp_rect
			(start -0.4318 0.9525)
			(end 0.4318 -0.9525)
			(stroke
				(width 0)
				(type default)
			)
			(fill no)
			(layer "F.CrtYd")
		)
		(fp_rect
			(start -0.4318 0.9525)
			(end 0.4318 -0.9525)
			(stroke
				(width 0)
				(type default)
			)
			(fill no)
			(layer "F.Fab")
		)
		(pad "1" smd custom
			(at 0 -0.4445 180)
			(size 0.1524 0.1524)
			(layers "F.Cu" "F.Mask" "F.Paste")
			(net "PCIE_TX_CAP_N74")
			(options
				(clearance outline)
				(anchor circle)
			)
			(primitives
				(gr_poly
					(pts
						(arc
							(start 0.3048 -0.2032)
							(mid 0.275042 -0.275042)
							(end 0.2032 -0.3048)
						)
						(arc
							(start -0.2032 -0.3048)
							(mid -0.275042 -0.275042)
							(end -0.3048 -0.2032)
						)
						(arc
							(start -0.3048 0.2032)
							(mid -0.275042 0.275042)
							(end -0.2032 0.3048)
						)
						(arc
							(start 0.2032 0.3048)
							(mid 0.275042 0.275042)
							(end 0.3048 0.2032)
						)
					)
					(width 0)
					(fill yes)
				)
			)
		)
		(pad "2" smd custom
			(at 0 0.4445 180)
			(size 0.1524 0.1524)
			(layers "F.Cu" "F.Mask" "F.Paste")
			(net "PCIE_TX_N74")
			(options
				(clearance outline)
				(anchor circle)
			)
			(primitives
				(gr_poly
					(pts
						(arc
							(start 0.3048 -0.2032)
							(mid 0.275042 -0.275042)
							(end 0.2032 -0.3048)
						)
						(arc
							(start -0.2032 -0.3048)
							(mid -0.275042 -0.275042)
							(end -0.3048 -0.2032)
						)
						(arc
							(start -0.3048 0.2032)
							(mid -0.275042 0.275042)
							(end -0.2032 0.3048)
						)
						(arc
							(start 0.2032 0.3048)
							(mid 0.275042 0.275042)
							(end 0.3048 0.2032)
						)
					)
					(width 0)
					(fill yes)
				)
			)
		)
	)
	(footprint ""
		(layer "F.Cu")
		(at 160.528 -81.9404 180)
		(property "Reference" "R44"
			(at 0 0 180)
			(layer "F.SilkS")
			(hide yes)
			(effects
				(font
					(size 1.27 1.27)
				)
			)
		)
		(property "Value" "10KR2F-2-GP"
			(at 0.064008 -3.993896 180)
			(unlocked yes)
			(layer "F.Fab")
			(hide yes)
			(effects
				(font
					(size 1.016 1.016)
					(thickness 0.1524)
				)
			)
		)
		(property "Device Type" "R402H16"
			(at 0.064008 -5.517896 180)
			(unlocked yes)
			(layer "F.Fab")
			(hide yes)
			(effects
				(font
					(size 1.016 1.016)
					(thickness 0.1524)
				)
			)
		)
		(duplicate_pad_numbers_are_jumpers no)
		(fp_line
			(start 0.508 -0.9398)
			(end -0.508 -0.9398)
			(stroke
				(width 0.1524)
				(type default)
			)
			(layer "F.SilkS")
		)
		(fp_line
			(start -0.508 -0.9398)
			(end -0.508 0.9398)
			(stroke
				(width 0.1524)
				(type default)
			)
			(layer "F.SilkS")
		)
		(fp_rect
			(start -0.508 0.9398)
			(end 0.508 -0.9398)
			(stroke
				(width 0)
				(type default)
			)
			(fill no)
			(layer "F.CrtYd")
		)
		(fp_rect
			(start -0.508 0.9398)
			(end 0.508 -0.9398)
			(stroke
				(width 0)
				(type default)
			)
			(fill no)
			(layer "F.Fab")
		)
		(pad "1" smd custom
			(at 0 -0.4445 180)
			(size 0.1397 0.1397)
			(layers "F.Cu" "F.Mask" "F.Paste")
			(net "GND")
			(options
				(clearance outline)
				(anchor circle)
			)
			(primitives
				(gr_poly
					(pts
						(arc
							(start -0.1778 -0.2794)
							(mid -0.249642 -0.249642)
							(end -0.2794 -0.1778)
						)
						(arc
							(start -0.2794 0.1778)
							(mid -0.249642 0.249642)
							(end -0.1778 0.2794)
						)
						(arc
							(start 0.1778 0.2794)
							(mid 0.249642 0.249642)
							(end 0.2794 0.1778)
						)
						(arc
							(start 0.2794 -0.1778)
							(mid 0.249642 -0.249642)
							(end 0.1778 -0.2794)
						)
					)
					(width 0)
					(fill yes)
				)
			)
		)
		(pad "2" smd custom
			(at 0 0.4445 180)
			(size 0.1397 0.1397)
			(layers "F.Cu" "F.Mask" "F.Paste")
			(net "PCIE_CLKGEN2_OE0")
			(options
				(clearance outline)
				(anchor circle)
			)
			(primitives
				(gr_poly
					(pts
						(arc
							(start -0.1778 -0.2794)
							(mid -0.249642 -0.249642)
							(end -0.2794 -0.1778)
						)
						(arc
							(start -0.2794 0.1778)
							(mid -0.249642 0.249642)
							(end -0.1778 0.2794)
						)
						(arc
							(start 0.1778 0.2794)
							(mid 0.249642 0.249642)
							(end 0.2794 0.1778)
						)
						(arc
							(start 0.2794 -0.1778)
							(mid 0.249642 -0.249642)
							(end 0.1778 -0.2794)
						)
					)
					(width 0)
					(fill yes)
				)
			)
		)
	)
	(footprint ""
		(layer "F.Cu")
		(at 50.292 -134.493)
		(property "Reference" "TP161"
			(at 0 0 0)
			(layer "F.SilkS")
			(hide yes)
			(effects
				(font
					(size 1.27 1.27)
				)
			)
		)
		(property "Value" "TPAD28-2-GP"
			(at -0.0127 -1.6637 0)
			(unlocked yes)
			(layer "F.Fab")
			(hide yes)
			(effects
				(font
					(size 1.016 1.016)
					(thickness 0.1524)
				)
			)
		)
		(property "Device Type" "TPAD28"
			(at -0.0127 -3.1877 0)
			(unlocked yes)
			(layer "F.Fab")
			(hide yes)
			(effects
				(font
					(size 1.016 1.016)
					(thickness 0.1524)
				)
			)
		)
		(duplicate_pad_numbers_are_jumpers no)
		(fp_poly
			(pts
				(arc
					(start 0.3556 0)
					(mid -0.3556 0)
					(end 0.3556 0)
				)
			)
			(stroke
				(width 0)
				(type default)
			)
			(fill no)
			(layer "F.CrtYd")
		)
		(fp_poly
			(pts
				(arc
					(start 0.6096 0)
					(mid -0.6096 0)
					(end 0.6096 0)
				)
			)
			(stroke
				(width 0)
				(type default)
			)
			(fill no)
			(layer "F.Fab")
		)
		(pad "1" smd circle
			(at 0 0)
			(size 0.7112 0.7112)
			(layers "F.Cu" "F.Mask" "F.Paste")
			(net "TP_BMC_GPIOJ6")
		)
	)
	(footprint ""
		(layer "F.Cu")
		(at 26.416 -72.6948 -90)
		(property "Reference" "TP165"
			(at 0 0 270)
			(layer "F.SilkS")
			(hide yes)
			(effects
				(font
					(size 1.27 1.27)
				)
			)
		)
		(property "Value" "TPAD28-2-GP"
			(at -0.0127 -1.6637 270)
			(unlocked yes)
			(layer "F.Fab")
			(hide yes)
			(effects
				(font
					(size 1.016 1.016)
					(thickness 0.1524)
				)
			)
		)
		(property "Device Type" "TPAD28"
			(at -0.0127 -3.1877 270)
			(unlocked yes)
			(layer "F.Fab")
			(hide yes)
			(effects
				(font
					(size 1.016 1.016)
					(thickness 0.1524)
				)
			)
		)
		(duplicate_pad_numbers_are_jumpers no)
		(fp_poly
			(pts
				(arc
					(start 0 -0.3556)
					(mid 0 0.3556)
					(end 0 -0.3556)
				)
			)
			(stroke
				(width 0)
				(type default)
			)
			(fill no)
			(layer "F.CrtYd")
		)
		(fp_poly
			(pts
				(arc
					(start 0 -0.6096)
					(mid 0 0.6096)
					(end 0 -0.6096)
				)
			)
			(stroke
				(width 0)
				(type default)
			)
			(fill no)
			(layer "F.Fab")
		)
		(pad "1" smd circle
			(at 0 0 270)
			(size 0.7112 0.7112)
			(layers "F.Cu" "F.Mask" "F.Paste")
			(net "NIC_JTDO")
		)
	)
	(footprint ""
		(layer "F.Cu")
		(at 31.6738 -99.6442 90)
		(property "Reference" "R47"
			(at 0 0 90)
			(layer "F.SilkS")
			(hide yes)
			(effects
				(font
					(size 1.27 1.27)
				)
			)
		)
		(property "Value" "0R2J-2-GP"
			(at 0.064008 -3.993896 90)
			(unlocked yes)
			(layer "F.Fab")
			(hide yes)
			(effects
				(font
					(size 1.016 1.016)
					(thickness 0.1524)
				)
			)
		)
		(property "Device Type" "R402H16"
			(at 0.064008 -5.517896 90)
			(unlocked yes)
			(layer "F.Fab")
			(hide yes)
			(effects
				(font
					(size 1.016 1.016)
					(thickness 0.1524)
				)
			)
		)
		(duplicate_pad_numbers_are_jumpers no)
		(fp_line
			(start 0.508 -0.9398)
			(end -0.508 -0.9398)
			(stroke
				(width 0.1524)
				(type default)
			)
			(layer "F.SilkS")
		)
		(fp_line
			(start -0.508 -0.9398)
			(end -0.508 0.9398)
			(stroke
				(width 0.1524)
				(type default)
			)
			(layer "F.SilkS")
		)
		(fp_rect
			(start -0.508 0.9398)
			(end 0.508 -0.9398)
			(stroke
				(width 0)
				(type default)
			)
			(fill no)
			(layer "F.CrtYd")
		)
		(fp_rect
			(start -0.508 0.9398)
			(end 0.508 -0.9398)
			(stroke
				(width 0)
				(type default)
			)
			(fill no)
			(layer "F.Fab")
		)
		(pad "1" smd custom
			(at 0 -0.4445 90)
			(size 0.1397 0.1397)
			(layers "F.Cu" "F.Mask" "F.Paste")
			(net "NVM_CS_N_R")
			(options
				(clearance outline)
				(anchor circle)
			)
			(primitives
				(gr_poly
					(pts
						(arc
							(start -0.1778 -0.2794)
							(mid -0.249642 -0.249642)
							(end -0.2794 -0.1778)
						)
						(arc
							(start -0.2794 0.1778)
							(mid -0.249642 0.249642)
							(end -0.1778 0.2794)
						)
						(arc
							(start 0.1778 0.2794)
							(mid 0.249642 0.249642)
							(end 0.2794 0.1778)
						)
						(arc
							(start 0.2794 -0.1778)
							(mid 0.249642 -0.249642)
							(end 0.1778 -0.2794)
						)
					)
					(width 0)
					(fill yes)
				)
			)
		)
		(pad "2" smd custom
			(at 0 0.4445 90)
			(size 0.1397 0.1397)
			(layers "F.Cu" "F.Mask" "F.Paste")
			(net "I2C_MUX_1A")
			(options
				(clearance outline)
				(anchor circle)
			)
			(primitives
				(gr_poly
					(pts
						(arc
							(start -0.1778 -0.2794)
							(mid -0.249642 -0.249642)
							(end -0.2794 -0.1778)
						)
						(arc
							(start -0.2794 0.1778)
							(mid -0.249642 0.249642)
							(end -0.1778 0.2794)
						)
						(arc
							(start 0.1778 0.2794)
							(mid 0.249642 0.249642)
							(end 0.2794 0.1778)
						)
						(arc
							(start 0.2794 -0.1778)
							(mid 0.249642 -0.249642)
							(end 0.1778 -0.2794)
						)
					)
					(width 0)
					(fill yes)
				)
			)
		)
	)
	(footprint ""
		(layer "F.Cu")
		(at 17.946116 -94.63024)
		(property "Reference" "R2940"
			(at 0 0 0)
			(layer "F.SilkS")
			(hide yes)
			(effects
				(font
					(size 1.27 1.27)
				)
			)
		)
		(property "Value" "100KR2F-L1-GP"
			(at 0.064008 -3.993896 0)
			(unlocked yes)
			(layer "F.Fab")
			(hide yes)
			(effects
				(font
					(size 1.016 1.016)
					(thickness 0.1524)
				)
			)
		)
		(property "Device Type" "R402H16"
			(at 0.064008 -5.517896 0)
			(unlocked yes)
			(layer "F.Fab")
			(hide yes)
			(effects
				(font
					(size 1.016 1.016)
					(thickness 0.1524)
				)
			)
		)
		(duplicate_pad_numbers_are_jumpers no)
		(fp_line
			(start -0.508 -0.9398)
			(end -0.508 0.9398)
			(stroke
				(width 0.1524)
				(type default)
			)
			(layer "F.SilkS")
		)
		(fp_line
			(start 0.508 -0.9398)
			(end -0.508 -0.9398)
			(stroke
				(width 0.1524)
				(type default)
			)
			(layer "F.SilkS")
		)
		(fp_rect
			(start -0.508 0.9398)
			(end 0.508 -0.9398)
			(stroke
				(width 0)
				(type default)
			)
			(fill no)
			(layer "F.CrtYd")
		)
		(fp_rect
			(start -0.508 0.9398)
			(end 0.508 -0.9398)
			(stroke
				(width 0)
				(type default)
			)
			(fill no)
			(layer "F.Fab")
		)
		(pad "1" smd custom
			(at 0 -0.4445)
			(size 0.1397 0.1397)
			(layers "F.Cu" "F.Mask" "F.Paste")
			(net "Q20_G")
			(options
				(clearance outline)
				(anchor circle)
			)
			(primitives
				(gr_poly
					(pts
						(arc
							(start -0.1778 -0.2794)
							(mid -0.249642 -0.249642)
							(end -0.2794 -0.1778)
						)
						(arc
							(start -0.2794 0.1778)
							(mid -0.249642 0.249642)
							(end -0.1778 0.2794)
						)
						(arc
							(start 0.1778 0.2794)
							(mid 0.249642 0.249642)
							(end 0.2794 0.1778)
						)
						(arc
							(start 0.2794 -0.1778)
							(mid 0.249642 -0.249642)
							(end 0.1778 -0.2794)
						)
					)
					(width 0)
					(fill yes)
				)
			)
		)
		(pad "2" smd custom
			(at 0 0.4445)
			(size 0.1397 0.1397)
			(layers "F.Cu" "F.Mask" "F.Paste")
			(net "GND")
			(options
				(clearance outline)
				(anchor circle)
			)
			(primitives
				(gr_poly
					(pts
						(arc
							(start -0.1778 -0.2794)
							(mid -0.249642 -0.249642)
							(end -0.2794 -0.1778)
						)
						(arc
							(start -0.2794 0.1778)
							(mid -0.249642 0.249642)
							(end -0.1778 0.2794)
						)
						(arc
							(start 0.1778 0.2794)
							(mid 0.249642 0.249642)
							(end 0.2794 0.1778)
						)
						(arc
							(start 0.2794 -0.1778)
							(mid 0.249642 -0.249642)
							(end 0.1778 -0.2794)
						)
					)
					(width 0)
					(fill yes)
				)
			)
		)
	)
	(footprint ""
		(layer "F.Cu")
		(at 31.508954 -165.337744 180)
		(property "Reference" "C170"
			(at 0 0 180)
			(layer "F.SilkS")
			(hide yes)
			(effects
				(font
					(size 1.27 1.27)
				)
			)
		)
		(property "Value" "SC10U6D3V5KX-4GP"
			(at -0.0762 -6.1214 180)
			(unlocked yes)
			(layer "F.Fab")
			(hide yes)
			(effects
				(font
					(size 1.016 1.016)
					(thickness 0.1524)
				)
			)
		)
		(property "Device Type" "C805H58"
			(at -0.0762 -8.1534 180)
			(unlocked yes)
			(layer "F.Fab")
			(hide yes)
			(effects
				(font
					(size 1.016 1.016)
					(thickness 0.1524)
				)
			)
		)
		(duplicate_pad_numbers_are_jumpers no)
		(fp_line
			(start 0.635 0)
			(end -0.635 0)
			(stroke
				(width 0.508)
				(type default)
			)
			(layer "F.SilkS")
		)
		(fp_rect
			(start -0.9652 1.778)
			(end 0.9652 -1.778)
			(stroke
				(width 0)
				(type default)
			)
			(fill no)
			(layer "F.CrtYd")
		)
		(fp_poly
			(pts
				(xy -0.9652 -1.778) (xy 0.9652 -1.778) (xy 0.9652 1.778) (xy -0.9652 1.778)
			)
			(stroke
				(width 0)
				(type default)
			)
			(fill no)
			(layer "F.Fab")
		)
		(pad "1" smd rect
			(at 0 -0.9652 180)
			(size 1.397 1.143)
			(layers "F.Cu" "F.Mask" "F.Paste")
			(net "P1V53_STBY")
		)
		(pad "2" smd rect
			(at 0 0.9652 180)
			(size 1.397 1.143)
			(layers "F.Cu" "F.Mask" "F.Paste")
			(net "GND")
		)
	)
	(footprint ""
		(layer "F.Cu")
		(at 161.798 -97.5614 90)
		(property "Reference" "TP81"
			(at 0 0 90)
			(layer "F.SilkS")
			(hide yes)
			(effects
				(font
					(size 1.27 1.27)
				)
			)
		)
		(property "Value" "TPAD28-2-GP"
			(at -0.0127 -1.6637 90)
			(unlocked yes)
			(layer "F.Fab")
			(hide yes)
			(effects
				(font
					(size 1.016 1.016)
					(thickness 0.1524)
				)
			)
		)
		(property "Device Type" "TPAD28"
			(at -0.0127 -3.1877 90)
			(unlocked yes)
			(layer "F.Fab")
			(hide yes)
			(effects
				(font
					(size 1.016 1.016)
					(thickness 0.1524)
				)
			)
		)
		(duplicate_pad_numbers_are_jumpers no)
		(fp_poly
			(pts
				(arc
					(start 0 0.3556)
					(mid 0 -0.3556)
					(end 0 0.3556)
				)
			)
			(stroke
				(width 0)
				(type default)
			)
			(fill no)
			(layer "F.CrtYd")
		)
		(fp_poly
			(pts
				(arc
					(start 0 0.6096)
					(mid 0 -0.6096)
					(end 0 0.6096)
				)
			)
			(stroke
				(width 0)
				(type default)
			)
			(fill no)
			(layer "F.Fab")
		)
		(pad "1" smd circle
			(at 0 0 90)
			(size 0.7112 0.7112)
			(layers "F.Cu" "F.Mask" "F.Paste")
			(net "CLKGEN_N3")
		)
	)
	(footprint ""
		(layer "F.Cu")
		(at 346.33916 -63.022734 90)
		(property "Reference" "PC173"
			(at 0 0 90)
			(layer "F.SilkS")
			(hide yes)
			(effects
				(font
					(size 1.27 1.27)
				)
			)
		)
		(property "Value" "SC10U25V5KX-GP"
			(at -0.0762 -6.1214 90)
			(unlocked yes)
			(layer "F.Fab")
			(hide yes)
			(effects
				(font
					(size 1.016 1.016)
					(thickness 0.1524)
				)
			)
		)
		(property "Device Type" "C805H56"
			(at -0.0762 -8.1534 90)
			(unlocked yes)
			(layer "F.Fab")
			(hide yes)
			(effects
				(font
					(size 1.016 1.016)
					(thickness 0.1524)
				)
			)
		)
		(duplicate_pad_numbers_are_jumpers no)
		(fp_line
			(start 0.635 0)
			(end -0.635 0)
			(stroke
				(width 0.508)
				(type default)
			)
			(layer "F.SilkS")
		)
		(fp_rect
			(start -0.9652 1.778)
			(end 0.9652 -1.778)
			(stroke
				(width 0)
				(type default)
			)
			(fill no)
			(layer "F.CrtYd")
		)
		(fp_poly
			(pts
				(xy -0.9652 -1.778) (xy 0.9652 -1.778) (xy 0.9652 1.778) (xy -0.9652 1.778)
			)
			(stroke
				(width 0)
				(type default)
			)
			(fill no)
			(layer "F.Fab")
		)
		(pad "1" smd rect
			(at 0 -0.9652 90)
			(size 1.397 1.143)
			(layers "F.Cu" "F.Mask" "F.Paste")
			(net "P0V9_E_VIN")
		)
		(pad "2" smd rect
			(at 0 0.9652 90)
			(size 1.397 1.143)
			(layers "F.Cu" "F.Mask" "F.Paste")
			(net "GND")
		)
	)
	(footprint ""
		(layer "F.Cu")
		(at 105.408222 -212.420454 180)
		(property "Reference" "C148"
			(at 0 0 180)
			(layer "F.SilkS")
			(hide yes)
			(effects
				(font
					(size 1.27 1.27)
				)
			)
		)
		(property "Value" "SCD22U10V2KX-1GP"
			(at 1.1811 -2.7051 180)
			(unlocked yes)
			(layer "F.Fab")
			(hide yes)
			(effects
				(font
					(size 1.016 1.016)
					(thickness 0.1524)
				)
			)
		)
		(property "Device Type" "C402H22"
			(at 1.1811 -4.2291 180)
			(unlocked yes)
			(layer "F.Fab")
			(hide yes)
			(effects
				(font
					(size 1.016 1.016)
					(thickness 0.1524)
				)
			)
		)
		(duplicate_pad_numbers_are_jumpers no)
		(fp_rect
			(start -0.4318 0.9525)
			(end 0.4318 -0.9525)
			(stroke
				(width 0)
				(type default)
			)
			(fill no)
			(layer "F.CrtYd")
		)
		(fp_rect
			(start -0.4318 0.9525)
			(end 0.4318 -0.9525)
			(stroke
				(width 0)
				(type default)
			)
			(fill no)
			(layer "F.Fab")
		)
		(pad "1" smd custom
			(at 0 -0.4445 180)
			(size 0.1524 0.1524)
			(layers "F.Cu" "F.Mask" "F.Paste")
			(net "PCIE_TX_CAP_N61")
			(options
				(clearance outline)
				(anchor circle)
			)
			(primitives
				(gr_poly
					(pts
						(arc
							(start 0.3048 -0.2032)
							(mid 0.275042 -0.275042)
							(end 0.2032 -0.3048)
						)
						(arc
							(start -0.2032 -0.3048)
							(mid -0.275042 -0.275042)
							(end -0.3048 -0.2032)
						)
						(arc
							(start -0.3048 0.2032)
							(mid -0.275042 0.275042)
							(end -0.2032 0.3048)
						)
						(arc
							(start 0.2032 0.3048)
							(mid 0.275042 0.275042)
							(end 0.3048 0.2032)
						)
					)
					(width 0)
					(fill yes)
				)
			)
		)
		(pad "2" smd custom
			(at 0 0.4445 180)
			(size 0.1524 0.1524)
			(layers "F.Cu" "F.Mask" "F.Paste")
			(net "PCIE_TX_N61")
			(options
				(clearance outline)
				(anchor circle)
			)
			(primitives
				(gr_poly
					(pts
						(arc
							(start 0.3048 -0.2032)
							(mid 0.275042 -0.275042)
							(end 0.2032 -0.3048)
						)
						(arc
							(start -0.2032 -0.3048)
							(mid -0.275042 -0.275042)
							(end -0.3048 -0.2032)
						)
						(arc
							(start -0.3048 0.2032)
							(mid -0.275042 0.275042)
							(end -0.2032 0.3048)
						)
						(arc
							(start 0.2032 0.3048)
							(mid 0.275042 0.275042)
							(end 0.3048 0.2032)
						)
					)
					(width 0)
					(fill yes)
				)
			)
		)
	)
	(footprint ""
		(layer "F.Cu")
		(at 6.9342 -55.9308)
		(property "Reference" "R511"
			(at 0 0 0)
			(layer "F.SilkS")
			(hide yes)
			(effects
				(font
					(size 1.27 1.27)
				)
			)
		)
		(property "Value" "150R3J-L-GP"
			(at -0.0254 -2.5146 0)
			(unlocked yes)
			(layer "F.Fab")
			(hide yes)
			(effects
				(font
					(size 1.016 1.016)
					(thickness 0.1524)
				)
			)
		)
		(property "Device Type" "R603H22"
			(at -0.0254 -4.0386 0)
			(unlocked yes)
			(layer "F.Fab")
			(hide yes)
			(effects
				(font
					(size 1.016 1.016)
					(thickness 0.1524)
				)
			)
		)
		(duplicate_pad_numbers_are_jumpers no)
		(fp_line
			(start -0.4826 0)
			(end -0.2032 0)
			(stroke
				(width 0.2032)
				(type default)
			)
			(layer "F.SilkS")
		)
		(fp_line
			(start 0.2032 0)
			(end 0.4826 0)
			(stroke
				(width 0.2032)
				(type default)
			)
			(layer "F.SilkS")
		)
		(fp_rect
			(start -0.5842 1.3335)
			(end 0.5842 -1.3335)
			(stroke
				(width 0)
				(type default)
			)
			(fill no)
			(layer "F.CrtYd")
		)
		(fp_rect
			(start -0.5842 1.3335)
			(end 0.5842 -1.3335)
			(stroke
				(width 0)
				(type default)
			)
			(fill no)
			(layer "F.Fab")
		)
		(pad "1" smd custom
			(at 0 -0.762)
			(size 0.2159 0.2159)
			(layers "F.Cu" "F.Mask" "F.Paste")
			(net "P3V3_STBY")
			(options
				(clearance outline)
				(anchor circle)
			)
			(primitives
				(gr_poly
					(pts
						(arc
							(start -0.3302 -0.4318)
							(mid -0.402042 -0.402042)
							(end -0.4318 -0.3302)
						)
						(arc
							(start -0.4318 0.3302)
							(mid -0.402042 0.402042)
							(end -0.3302 0.4318)
						)
						(arc
							(start 0.3302 0.4318)
							(mid 0.402042 0.402042)
							(end 0.4318 0.3302)
						)
						(arc
							(start 0.4318 -0.3302)
							(mid 0.402042 -0.402042)
							(end 0.3302 -0.4318)
						)
					)
					(width 0)
					(fill yes)
				)
			)
		)
		(pad "2" smd custom
			(at 0 0.762)
			(size 0.2159 0.2159)
			(layers "F.Cu" "F.Mask" "F.Paste")
			(net "LED_MDI0_ACT")
			(options
				(clearance outline)
				(anchor circle)
			)
			(primitives
				(gr_poly
					(pts
						(arc
							(start -0.3302 -0.4318)
							(mid -0.402042 -0.402042)
							(end -0.4318 -0.3302)
						)
						(arc
							(start -0.4318 0.3302)
							(mid -0.402042 0.402042)
							(end -0.3302 0.4318)
						)
						(arc
							(start 0.3302 0.4318)
							(mid 0.402042 0.402042)
							(end 0.4318 0.3302)
						)
						(arc
							(start 0.4318 -0.3302)
							(mid 0.402042 -0.402042)
							(end 0.3302 -0.4318)
						)
					)
					(width 0)
					(fill yes)
				)
			)
		)
	)
	(footprint ""
		(layer "F.Cu")
		(at 85.449918 -5.40004)
		(property "Reference" "PAD2"
			(at 0 0 0)
			(layer "F.SilkS")
			(hide yes)
			(effects
				(font
					(size 1.27 1.27)
				)
			)
		)
		(property "Value" "PAD-3P-GP"
			(at -18.082768 -12.6492 0)
			(unlocked yes)
			(layer "F.Fab")
			(hide yes)
			(effects
				(font
					(size 1.016 1.016)
					(thickness 0.1524)
				)
			)
		)
		(property "Device Type" "HT24X28B8R32-3P-S"
			(at -18.082768 -14.1732 0)
			(unlocked yes)
			(layer "F.Fab")
			(hide yes)
			(effects
				(font
					(size 1.016 1.016)
					(thickness 0.1524)
				)
			)
		)
		(duplicate_pad_numbers_are_jumpers no)
		(fp_poly
			(pts
				(arc
					(start -6.694678 -8.800084)
					(mid -15.305278 -8.800084)
					(end -6.694678 -8.800084)
				)
			)
			(stroke
				(width 0)
				(type default)
			)
			(fill no)
			(layer "B.CrtYd")
		)
		(fp_poly
			(pts
				(arc
					(start 4.3053 -17.599914)
					(mid -4.3053 -17.599914)
					(end 4.3053 -17.599914)
				)
			)
			(stroke
				(width 0)
				(type default)
			)
			(fill no)
			(layer "B.CrtYd")
		)
		(fp_poly
			(pts
				(arc
					(start 4.3053 0)
					(mid -4.3053 0)
					(end 4.3053 0)
				)
			)
			(stroke
				(width 0)
				(type default)
			)
			(fill no)
			(layer "B.CrtYd")
		)
		(fp_poly
			(pts
				(xy -16.304768 5.70484) (xy -16.304768 -22.904704) (xy 8.304784 -22.904704) (xy 8.304784 -13.299948)
				(arc
					(start 4.99999 -13.299948)
					(mid 4.646527 -13.153539)
					(end 4.500118 -12.800076)
				)
				(arc
					(start 4.500118 -4.800092)
					(mid 4.646512 -4.446539)
					(end 4.99999 -4.299966)
				)
				(xy 8.304784 -4.299966) (xy 8.304784 5.70484)
			)
			(stroke
				(width 0)
				(type default)
			)
			(fill no)
			(layer "F.CrtYd")
		)
		(fp_poly
			(pts
				(arc
					(start -6.694678 -8.800084)
					(mid -15.305278 -8.800084)
					(end -6.694678 -8.800084)
				)
			)
			(stroke
				(width 0)
				(type default)
			)
			(fill no)
			(layer "B.Fab")
		)
		(fp_poly
			(pts
				(arc
					(start 4.3053 -17.599914)
					(mid -4.3053 -17.599914)
					(end 4.3053 -17.599914)
				)
			)
			(stroke
				(width 0)
				(type default)
			)
			(fill no)
			(layer "B.Fab")
		)
		(fp_poly
			(pts
				(arc
					(start 4.3053 0)
					(mid -4.3053 0)
					(end 4.3053 0)
				)
			)
			(stroke
				(width 0)
				(type default)
			)
			(fill no)
			(layer "B.Fab")
		)
		(fp_poly
			(pts
				(xy -16.304768 5.70484) (xy -16.304768 -22.904704) (xy 8.304784 -22.904704) (xy 8.304784 -13.299948)
				(arc
					(start 4.99999 -13.299948)
					(mid 4.646527 -13.153539)
					(end 4.500118 -12.800076)
				)
				(arc
					(start 4.500118 -4.800092)
					(mid 4.646512 -4.446539)
					(end 4.99999 -4.299966)
				)
				(xy 8.304784 -4.299966) (xy 8.304784 5.70484)
			)
			(stroke
				(width 0)
				(type default)
			)
			(fill no)
			(layer "F.Fab")
		)
		(pad "1" thru_hole custom
			(at 0 0)
			(size 5.999988 5.999988)
			(drill 3.2004)
			(layers "*.Cu" "*.Mask")
			(remove_unused_layers no)
			(net "GND")
			(clearance -9.891776)
			(thermal_gap 0.3048)
			(options
				(clearance outline)
				(anchor circle)
			)
			(primitives
				(gr_poly
					(pts
						(xy -11.999976 13.999972) (xy -11.999976 -13.999972) (xy 11.999976 -13.999972) (xy 11.999976 -5.004816)
						(arc
							(start 8.999982 -5.004816)
							(mid 8.430993 -4.769133)
							(end 8.19531 -4.200144)
						)
						(arc
							(start 8.19531 3.79984)
							(mid 8.430978 4.368919)
							(end 8.999982 4.604766)
						)
						(xy 11.999976 4.604766) (xy 11.999976 13.999972)
					)
					(width 0)
					(fill yes)
				)
			)
			(padstack
				(mode front_inner_back)
				(layer "Inner"
					(shape circle)
					(size 3.6068 3.6068)
					(clearance 0.3048)
				)
				(layer "B.Cu"
					(shape circle)
					(size 8.001 8.001)
					(clearance -1.8923)
				)
			)
		)
		(pad "2" thru_hole circle
			(at -10.999978 -8.800084)
			(size 8.001 8.001)
			(drill 3.2004)
			(layers "*.Cu" "*.Mask")
			(remove_unused_layers no)
			(net "GND")
			(clearance -1.8923)
			(thermal_gap 0.3048)
			(padstack
				(mode front_inner_back)
				(layer "Inner"
					(shape circle)
					(size 3.6068 3.6068)
					(clearance 0.3048)
				)
				(layer "B.Cu"
					(shape circle)
					(size 8.001 8.001)
					(clearance -1.8923)
				)
			)
		)
		(pad "3" thru_hole circle
			(at 0 -17.599914)
			(size 8.001 8.001)
			(drill 3.2004)
			(layers "*.Cu" "*.Mask")
			(remove_unused_layers no)
			(net "GND")
			(clearance -1.8923)
			(thermal_gap 0.3048)
			(padstack
				(mode front_inner_back)
				(layer "Inner"
					(shape circle)
					(size 3.6068 3.6068)
					(clearance 0.3048)
				)
				(layer "B.Cu"
					(shape circle)
					(size 8.001 8.001)
					(clearance -1.8923)
				)
			)
		)
	)
	(footprint ""
		(layer "F.Cu")
		(at 26.544778 -99.170236 180)
		(property "Reference" "R2950"
			(at 0 0 180)
			(layer "F.SilkS")
			(hide yes)
			(effects
				(font
					(size 1.27 1.27)
				)
			)
		)
		(property "Value" "4K75R2F-1-GP"
			(at 0.064008 -3.993896 180)
			(unlocked yes)
			(layer "F.Fab")
			(hide yes)
			(effects
				(font
					(size 1.016 1.016)
					(thickness 0.1524)
				)
			)
		)
		(property "Device Type" "R402H16"
			(at 0.064008 -5.517896 180)
			(unlocked yes)
			(layer "F.Fab")
			(hide yes)
			(effects
				(font
					(size 1.016 1.016)
					(thickness 0.1524)
				)
			)
		)
		(duplicate_pad_numbers_are_jumpers no)
		(fp_line
			(start 0.508 -0.9398)
			(end -0.508 -0.9398)
			(stroke
				(width 0.1524)
				(type default)
			)
			(layer "F.SilkS")
		)
		(fp_line
			(start -0.508 -0.9398)
			(end -0.508 0.9398)
			(stroke
				(width 0.1524)
				(type default)
			)
			(layer "F.SilkS")
		)
		(fp_rect
			(start -0.508 0.9398)
			(end 0.508 -0.9398)
			(stroke
				(width 0)
				(type default)
			)
			(fill no)
			(layer "F.CrtYd")
		)
		(fp_rect
			(start -0.508 0.9398)
			(end 0.508 -0.9398)
			(stroke
				(width 0)
				(type default)
			)
			(fill no)
			(layer "F.Fab")
		)
		(pad "1" smd custom
			(at 0 -0.4445 180)
			(size 0.1397 0.1397)
			(layers "F.Cu" "F.Mask" "F.Paste")
			(net "P3V3_STBY")
			(options
				(clearance outline)
				(anchor circle)
			)
			(primitives
				(gr_poly
					(pts
						(arc
							(start -0.1778 -0.2794)
							(mid -0.249642 -0.249642)
							(end -0.2794 -0.1778)
						)
						(arc
							(start -0.2794 0.1778)
							(mid -0.249642 0.249642)
							(end -0.1778 0.2794)
						)
						(arc
							(start 0.1778 0.2794)
							(mid 0.249642 0.249642)
							(end 0.2794 0.1778)
						)
						(arc
							(start 0.2794 -0.1778)
							(mid 0.249642 -0.249642)
							(end 0.1778 -0.2794)
						)
					)
					(width 0)
					(fill yes)
				)
			)
		)
		(pad "2" smd custom
			(at 0 0.4445 180)
			(size 0.1397 0.1397)
			(layers "F.Cu" "F.Mask" "F.Paste")
			(net "FM_TPM_PRES_RST_N_C")
			(options
				(clearance outline)
				(anchor circle)
			)
			(primitives
				(gr_poly
					(pts
						(arc
							(start -0.1778 -0.2794)
							(mid -0.249642 -0.249642)
							(end -0.2794 -0.1778)
						)
						(arc
							(start -0.2794 0.1778)
							(mid -0.249642 0.249642)
							(end -0.1778 0.2794)
						)
						(arc
							(start 0.1778 0.2794)
							(mid 0.249642 0.249642)
							(end 0.2794 0.1778)
						)
						(arc
							(start 0.2794 -0.1778)
							(mid 0.249642 -0.249642)
							(end 0.1778 -0.2794)
						)
					)
					(width 0)
					(fill yes)
				)
			)
		)
	)
	(footprint ""
		(layer "F.Cu")
		(at 337.852512 -184.878218 180)
		(property "Reference" "R7960"
			(at 0 0 180)
			(layer "F.SilkS")
			(hide yes)
			(effects
				(font
					(size 1.27 1.27)
				)
			)
		)
		(property "Value" "0R2J-2-GP"
			(at 0.064008 -3.993896 180)
			(unlocked yes)
			(layer "F.Fab")
			(hide yes)
			(effects
				(font
					(size 1.016 1.016)
					(thickness 0.1524)
				)
			)
		)
		(property "Device Type" "R402H16"
			(at 0.064008 -5.517896 180)
			(unlocked yes)
			(layer "F.Fab")
			(hide yes)
			(effects
				(font
					(size 1.016 1.016)
					(thickness 0.1524)
				)
			)
		)
		(duplicate_pad_numbers_are_jumpers no)
		(fp_line
			(start 0.508 -0.9398)
			(end -0.508 -0.9398)
			(stroke
				(width 0.1524)
				(type default)
			)
			(layer "F.SilkS")
		)
		(fp_line
			(start -0.508 -0.9398)
			(end -0.508 0.9398)
			(stroke
				(width 0.1524)
				(type default)
			)
			(layer "F.SilkS")
		)
		(fp_rect
			(start -0.508 0.9398)
			(end 0.508 -0.9398)
			(stroke
				(width 0)
				(type default)
			)
			(fill no)
			(layer "F.CrtYd")
		)
		(fp_rect
			(start -0.508 0.9398)
			(end 0.508 -0.9398)
			(stroke
				(width 0)
				(type default)
			)
			(fill no)
			(layer "F.Fab")
		)
		(pad "1" smd custom
			(at 0 -0.4445 180)
			(size 0.1397 0.1397)
			(layers "F.Cu" "F.Mask" "F.Paste")
			(net "SSD_PWREN14")
			(options
				(clearance outline)
				(anchor circle)
			)
			(primitives
				(gr_poly
					(pts
						(arc
							(start -0.1778 -0.2794)
							(mid -0.249642 -0.249642)
							(end -0.2794 -0.1778)
						)
						(arc
							(start -0.2794 0.1778)
							(mid -0.249642 0.249642)
							(end -0.1778 0.2794)
						)
						(arc
							(start 0.1778 0.2794)
							(mid 0.249642 0.249642)
							(end 0.2794 0.1778)
						)
						(arc
							(start 0.2794 -0.1778)
							(mid 0.249642 -0.249642)
							(end 0.1778 -0.2794)
						)
					)
					(width 0)
					(fill yes)
				)
			)
		)
		(pad "2" smd custom
			(at 0 0.4445 180)
			(size 0.1397 0.1397)
			(layers "F.Cu" "F.Mask" "F.Paste")
			(net "SSD_PWREN14_R")
			(options
				(clearance outline)
				(anchor circle)
			)
			(primitives
				(gr_poly
					(pts
						(arc
							(start -0.1778 -0.2794)
							(mid -0.249642 -0.249642)
							(end -0.2794 -0.1778)
						)
						(arc
							(start -0.2794 0.1778)
							(mid -0.249642 0.249642)
							(end -0.1778 0.2794)
						)
						(arc
							(start 0.1778 0.2794)
							(mid 0.249642 0.249642)
							(end 0.2794 0.1778)
						)
						(arc
							(start 0.2794 -0.1778)
							(mid 0.249642 -0.249642)
							(end 0.1778 -0.2794)
						)
					)
					(width 0)
					(fill yes)
				)
			)
		)
	)
	(footprint ""
		(layer "F.Cu")
		(at 332.92288 -34.36874 -90)
		(property "Reference" "Q31"
			(at 0 0 270)
			(layer "F.SilkS")
			(hide yes)
			(effects
				(font
					(size 1.27 1.27)
				)
			)
		)
		(property "Value" "2N7002K-1-GP"
			(at 0.127 -8.9662 270)
			(unlocked yes)
			(layer "F.Fab")
			(hide yes)
			(effects
				(font
					(size 1.016 1.016)
					(thickness 0.1524)
				)
			)
		)
		(property "Device Type" "SOT23DGS2D4H44"
			(at 0.127 -10.4902 270)
			(unlocked yes)
			(layer "F.Fab")
			(hide yes)
			(effects
				(font
					(size 1.016 1.016)
					(thickness 0.1524)
				)
			)
		)
		(duplicate_pad_numbers_are_jumpers no)
		(fp_line
			(start -1.651 1.778)
			(end 1.651 1.778)
			(stroke
				(width 0.1524)
				(type default)
			)
			(layer "F.SilkS")
		)
		(fp_line
			(start 1.651 1.778)
			(end 1.651 -1.778)
			(stroke
				(width 0.1524)
				(type default)
			)
			(layer "F.SilkS")
		)
		(fp_line
			(start -1.651 -1.778)
			(end -1.651 1.778)
			(stroke
				(width 0.1524)
				(type default)
			)
			(layer "F.SilkS")
		)
		(fp_line
			(start 1.651 -1.778)
			(end -1.651 -1.778)
			(stroke
				(width 0.1524)
				(type default)
			)
			(layer "F.SilkS")
		)
		(fp_poly
			(pts
				(xy -1.778 1.8796) (xy -1.778 -1.8796) (xy 1.778 -1.8796) (xy 1.778 1.8796)
			)
			(stroke
				(width 0)
				(type default)
			)
			(fill no)
			(layer "F.CrtYd")
		)
		(fp_poly
			(pts
				(xy -1.778 1.8796) (xy -1.778 -1.8796) (xy 1.778 -1.8796) (xy 1.778 1.8796)
			)
			(stroke
				(width 0)
				(type default)
			)
			(fill no)
			(layer "F.Fab")
		)
		(pad "D" smd custom
			(at 0 -0.9525 270)
			(size 0.1905 0.1905)
			(layers "F.Cu" "F.Mask" "F.Paste")
			(net "LED_Q_6")
			(options
				(clearance outline)
				(anchor circle)
			)
			(primitives
				(gr_poly
					(pts
						(arc
							(start -0.1778 0.5715)
							(mid -0.321484 0.511984)
							(end -0.381 0.3683)
						)
						(arc
							(start -0.381 -0.3683)
							(mid -0.321484 -0.511984)
							(end -0.1778 -0.5715)
						)
						(arc
							(start 0.1778 -0.5715)
							(mid 0.321484 -0.511984)
							(end 0.381 -0.3683)
						)
						(arc
							(start 0.381 0.3683)
							(mid 0.321484 0.511984)
							(end 0.1778 0.5715)
						)
					)
					(width 0)
					(fill yes)
				)
			)
		)
		(pad "G" smd custom
			(at -0.98425 0.9525 270)
			(size 0.1905 0.1905)
			(layers "F.Cu" "F.Mask" "F.Paste")
			(net "UPLINK6_R")
			(options
				(clearance outline)
				(anchor circle)
			)
			(primitives
				(gr_poly
					(pts
						(arc
							(start -0.1778 0.5715)
							(mid -0.321484 0.511984)
							(end -0.381 0.3683)
						)
						(arc
							(start -0.381 -0.3683)
							(mid -0.321484 -0.511984)
							(end -0.1778 -0.5715)
						)
						(arc
							(start 0.1778 -0.5715)
							(mid 0.321484 -0.511984)
							(end 0.381 -0.3683)
						)
						(arc
							(start 0.381 0.3683)
							(mid 0.321484 0.511984)
							(end 0.1778 0.5715)
						)
					)
					(width 0)
					(fill yes)
				)
			)
		)
		(pad "S" smd custom
			(at 0.98425 0.9525 270)
			(size 0.1905 0.1905)
			(layers "F.Cu" "F.Mask" "F.Paste")
			(net "GND")
			(options
				(clearance outline)
				(anchor circle)
			)
			(primitives
				(gr_poly
					(pts
						(arc
							(start -0.1778 0.5715)
							(mid -0.321484 0.511984)
							(end -0.381 0.3683)
						)
						(arc
							(start -0.381 -0.3683)
							(mid -0.321484 -0.511984)
							(end -0.1778 -0.5715)
						)
						(arc
							(start 0.1778 -0.5715)
							(mid 0.321484 -0.511984)
							(end 0.381 -0.3683)
						)
						(arc
							(start 0.381 0.3683)
							(mid 0.321484 0.511984)
							(end 0.1778 0.5715)
						)
					)
					(width 0)
					(fill yes)
				)
			)
		)
	)
	(footprint ""
		(layer "F.Cu")
		(at 37.2872 -67.5894 -90)
		(property "Reference" "L7"
			(at 0 0 270)
			(layer "F.SilkS")
			(hide yes)
			(effects
				(font
					(size 1.27 1.27)
				)
			)
		)
		(property "Value" "BLM21PG300SN-2GP"
			(at 0.0254 -5.6896 270)
			(unlocked yes)
			(layer "F.Fab")
			(hide yes)
			(effects
				(font
					(size 1.016 1.016)
					(thickness 0.1524)
				)
			)
		)
		(property "Device Type" "L20125H42"
			(at 0.0254 -7.5946 270)
			(unlocked yes)
			(layer "F.Fab")
			(hide yes)
			(effects
				(font
					(size 1.016 1.016)
					(thickness 0.1524)
				)
			)
		)
		(duplicate_pad_numbers_are_jumpers no)
		(fp_line
			(start -0.9144 1.7018)
			(end 0.9144 1.7018)
			(stroke
				(width 0.1524)
				(type default)
			)
			(layer "F.SilkS")
		)
		(fp_line
			(start 0.9144 1.7018)
			(end 0.9144 -1.7018)
			(stroke
				(width 0.1524)
				(type default)
			)
			(layer "F.SilkS")
		)
		(fp_line
			(start -0.9144 -1.7018)
			(end -0.9144 1.7018)
			(stroke
				(width 0.1524)
				(type default)
			)
			(layer "F.SilkS")
		)
		(fp_line
			(start 0.9144 -1.7018)
			(end -0.9144 -1.7018)
			(stroke
				(width 0.1524)
				(type default)
			)
			(layer "F.SilkS")
		)
		(fp_rect
			(start -1.0033 1.778)
			(end 1.0033 -1.778)
			(stroke
				(width 0)
				(type default)
			)
			(fill no)
			(layer "F.CrtYd")
		)
		(fp_poly
			(pts
				(xy -1.0033 -1.778) (xy 1.0033 -1.778) (xy 1.0033 1.778) (xy -1.0033 1.778)
			)
			(stroke
				(width 0)
				(type default)
			)
			(fill no)
			(layer "F.Fab")
		)
		(pad "1" smd rect
			(at 0 -0.9652 270)
			(size 1.397 1.143)
			(layers "F.Cu" "F.Mask" "F.Paste")
			(net "P5V_STBY")
		)
		(pad "2" smd rect
			(at 0 0.9652 270)
			(size 1.397 1.143)
			(layers "F.Cu" "F.Mask" "F.Paste")
			(net "P5V_USB_BP1_F")
		)
	)
	(footprint ""
		(layer "F.Cu")
		(at 45.72 -118.364)
		(property "Reference" "TP95"
			(at 0 0 0)
			(layer "F.SilkS")
			(hide yes)
			(effects
				(font
					(size 1.27 1.27)
				)
			)
		)
		(property "Value" "TPAD28-2-GP"
			(at -0.0127 -1.6637 0)
			(unlocked yes)
			(layer "F.Fab")
			(hide yes)
			(effects
				(font
					(size 1.016 1.016)
					(thickness 0.1524)
				)
			)
		)
		(property "Device Type" "TPAD28"
			(at -0.0127 -3.1877 0)
			(unlocked yes)
			(layer "F.Fab")
			(hide yes)
			(effects
				(font
					(size 1.016 1.016)
					(thickness 0.1524)
				)
			)
		)
		(duplicate_pad_numbers_are_jumpers no)
		(fp_poly
			(pts
				(arc
					(start 0.3556 0)
					(mid -0.3556 0)
					(end 0.3556 0)
				)
			)
			(stroke
				(width 0)
				(type default)
			)
			(fill no)
			(layer "F.CrtYd")
		)
		(fp_poly
			(pts
				(arc
					(start 0.6096 0)
					(mid -0.6096 0)
					(end 0.6096 0)
				)
			)
			(stroke
				(width 0)
				(type default)
			)
			(fill no)
			(layer "F.Fab")
		)
		(pad "1" smd circle
			(at 0 0)
			(size 0.7112 0.7112)
			(layers "F.Cu" "F.Mask" "F.Paste")
			(net "TP_GPIOH6")
		)
	)
	(footprint ""
		(layer "F.Cu")
		(at 222.861124 -190.601092)
		(property "Reference" "R7980"
			(at 0 0 0)
			(layer "F.SilkS")
			(hide yes)
			(effects
				(font
					(size 1.27 1.27)
				)
			)
		)
		(property "Value" "0R2J-2-GP"
			(at 0.064008 -3.993896 0)
			(unlocked yes)
			(layer "F.Fab")
			(hide yes)
			(effects
				(font
					(size 1.016 1.016)
					(thickness 0.1524)
				)
			)
		)
		(property "Device Type" "R402H16"
			(at 0.064008 -5.517896 0)
			(unlocked yes)
			(layer "F.Fab")
			(hide yes)
			(effects
				(font
					(size 1.016 1.016)
					(thickness 0.1524)
				)
			)
		)
		(duplicate_pad_numbers_are_jumpers no)
		(fp_line
			(start -0.508 -0.9398)
			(end -0.508 0.9398)
			(stroke
				(width 0.1524)
				(type default)
			)
			(layer "F.SilkS")
		)
		(fp_line
			(start 0.508 -0.9398)
			(end -0.508 -0.9398)
			(stroke
				(width 0.1524)
				(type default)
			)
			(layer "F.SilkS")
		)
		(fp_rect
			(start -0.508 0.9398)
			(end 0.508 -0.9398)
			(stroke
				(width 0)
				(type default)
			)
			(fill no)
			(layer "F.CrtYd")
		)
		(fp_rect
			(start -0.508 0.9398)
			(end 0.508 -0.9398)
			(stroke
				(width 0)
				(type default)
			)
			(fill no)
			(layer "F.Fab")
		)
		(pad "1" smd custom
			(at 0 -0.4445)
			(size 0.1397 0.1397)
			(layers "F.Cu" "F.Mask" "F.Paste")
			(net "SSD_PERST#3")
			(options
				(clearance outline)
				(anchor circle)
			)
			(primitives
				(gr_poly
					(pts
						(arc
							(start -0.1778 -0.2794)
							(mid -0.249642 -0.249642)
							(end -0.2794 -0.1778)
						)
						(arc
							(start -0.2794 0.1778)
							(mid -0.249642 0.249642)
							(end -0.1778 0.2794)
						)
						(arc
							(start 0.1778 0.2794)
							(mid 0.249642 0.249642)
							(end 0.2794 0.1778)
						)
						(arc
							(start 0.2794 -0.1778)
							(mid 0.249642 -0.249642)
							(end 0.1778 -0.2794)
						)
					)
					(width 0)
					(fill yes)
				)
			)
		)
		(pad "2" smd custom
			(at 0 0.4445)
			(size 0.1397 0.1397)
			(layers "F.Cu" "F.Mask" "F.Paste")
			(net "SSD_PERST#3_R")
			(options
				(clearance outline)
				(anchor circle)
			)
			(primitives
				(gr_poly
					(pts
						(arc
							(start -0.1778 -0.2794)
							(mid -0.249642 -0.249642)
							(end -0.2794 -0.1778)
						)
						(arc
							(start -0.2794 0.1778)
							(mid -0.249642 0.249642)
							(end -0.1778 0.2794)
						)
						(arc
							(start 0.1778 0.2794)
							(mid 0.249642 0.249642)
							(end 0.2794 0.1778)
						)
						(arc
							(start 0.2794 -0.1778)
							(mid 0.249642 -0.249642)
							(end 0.1778 -0.2794)
						)
					)
					(width 0)
					(fill yes)
				)
			)
		)
	)
	(footprint ""
		(layer "F.Cu")
		(at 343.00795 -212.420454 180)
		(property "Reference" "C55"
			(at 0 0 180)
			(layer "F.SilkS")
			(hide yes)
			(effects
				(font
					(size 1.27 1.27)
				)
			)
		)
		(property "Value" "SCD22U10V2KX-1GP"
			(at 1.1811 -2.7051 180)
			(unlocked yes)
			(layer "F.Fab")
			(hide yes)
			(effects
				(font
					(size 1.016 1.016)
					(thickness 0.1524)
				)
			)
		)
		(property "Device Type" "C402H22"
			(at 1.1811 -4.2291 180)
			(unlocked yes)
			(layer "F.Fab")
			(hide yes)
			(effects
				(font
					(size 1.016 1.016)
					(thickness 0.1524)
				)
			)
		)
		(duplicate_pad_numbers_are_jumpers no)
		(fp_rect
			(start -0.4318 0.9525)
			(end 0.4318 -0.9525)
			(stroke
				(width 0)
				(type default)
			)
			(fill no)
			(layer "F.CrtYd")
		)
		(fp_rect
			(start -0.4318 0.9525)
			(end 0.4318 -0.9525)
			(stroke
				(width 0)
				(type default)
			)
			(fill no)
			(layer "F.Fab")
		)
		(pad "1" smd custom
			(at 0 -0.4445 180)
			(size 0.1524 0.1524)
			(layers "F.Cu" "F.Mask" "F.Paste")
			(net "PCIE_TX_CAP_N16")
			(options
				(clearance outline)
				(anchor circle)
			)
			(primitives
				(gr_poly
					(pts
						(arc
							(start 0.3048 -0.2032)
							(mid 0.275042 -0.275042)
							(end 0.2032 -0.3048)
						)
						(arc
							(start -0.2032 -0.3048)
							(mid -0.275042 -0.275042)
							(end -0.3048 -0.2032)
						)
						(arc
							(start -0.3048 0.2032)
							(mid -0.275042 0.275042)
							(end -0.2032 0.3048)
						)
						(arc
							(start 0.2032 0.3048)
							(mid 0.275042 0.275042)
							(end 0.3048 0.2032)
						)
					)
					(width 0)
					(fill yes)
				)
			)
		)
		(pad "2" smd custom
			(at 0 0.4445 180)
			(size 0.1524 0.1524)
			(layers "F.Cu" "F.Mask" "F.Paste")
			(net "PCIE_TX_N16")
			(options
				(clearance outline)
				(anchor circle)
			)
			(primitives
				(gr_poly
					(pts
						(arc
							(start 0.3048 -0.2032)
							(mid 0.275042 -0.275042)
							(end 0.2032 -0.3048)
						)
						(arc
							(start -0.2032 -0.3048)
							(mid -0.275042 -0.275042)
							(end -0.3048 -0.2032)
						)
						(arc
							(start -0.3048 0.2032)
							(mid -0.275042 0.275042)
							(end -0.2032 0.3048)
						)
						(arc
							(start 0.2032 0.3048)
							(mid 0.275042 0.275042)
							(end 0.3048 0.2032)
						)
					)
					(width 0)
					(fill yes)
				)
			)
		)
	)
	(footprint ""
		(layer "F.Cu")
		(at 131.9403 -33.54324)
		(property "Reference" "C382"
			(at 0 0 0)
			(layer "F.SilkS")
			(hide yes)
			(effects
				(font
					(size 1.27 1.27)
				)
			)
		)
		(property "Value" "SCD22U10V2KX-1GP"
			(at 1.1811 -2.7051 0)
			(unlocked yes)
			(layer "F.Fab")
			(hide yes)
			(effects
				(font
					(size 1.016 1.016)
					(thickness 0.1524)
				)
			)
		)
		(property "Device Type" "C402H22"
			(at 1.1811 -4.2291 0)
			(unlocked yes)
			(layer "F.Fab")
			(hide yes)
			(effects
				(font
					(size 1.016 1.016)
					(thickness 0.1524)
				)
			)
		)
		(duplicate_pad_numbers_are_jumpers no)
		(fp_rect
			(start -0.4318 0.9525)
			(end 0.4318 -0.9525)
			(stroke
				(width 0)
				(type default)
			)
			(fill no)
			(layer "F.CrtYd")
		)
		(fp_rect
			(start -0.4318 0.9525)
			(end 0.4318 -0.9525)
			(stroke
				(width 0)
				(type default)
			)
			(fill no)
			(layer "F.Fab")
		)
		(pad "1" smd custom
			(at 0 -0.4445)
			(size 0.1524 0.1524)
			(layers "F.Cu" "F.Mask" "F.Paste")
			(net "PCIE_TX_CAP_N81")
			(options
				(clearance outline)
				(anchor circle)
			)
			(primitives
				(gr_poly
					(pts
						(arc
							(start 0.3048 -0.2032)
							(mid 0.275042 -0.275042)
							(end 0.2032 -0.3048)
						)
						(arc
							(start -0.2032 -0.3048)
							(mid -0.275042 -0.275042)
							(end -0.3048 -0.2032)
						)
						(arc
							(start -0.3048 0.2032)
							(mid -0.275042 0.275042)
							(end -0.2032 0.3048)
						)
						(arc
							(start 0.2032 0.3048)
							(mid 0.275042 0.275042)
							(end 0.3048 0.2032)
						)
					)
					(width 0)
					(fill yes)
				)
			)
		)
		(pad "2" smd custom
			(at 0 0.4445)
			(size 0.1524 0.1524)
			(layers "F.Cu" "F.Mask" "F.Paste")
			(net "PCIE_TX_N81")
			(options
				(clearance outline)
				(anchor circle)
			)
			(primitives
				(gr_poly
					(pts
						(arc
							(start 0.3048 -0.2032)
							(mid 0.275042 -0.275042)
							(end 0.2032 -0.3048)
						)
						(arc
							(start -0.2032 -0.3048)
							(mid -0.275042 -0.275042)
							(end -0.3048 -0.2032)
						)
						(arc
							(start -0.3048 0.2032)
							(mid -0.275042 0.275042)
							(end -0.2032 0.3048)
						)
						(arc
							(start 0.2032 0.3048)
							(mid 0.275042 0.275042)
							(end 0.3048 0.2032)
						)
					)
					(width 0)
					(fill yes)
				)
			)
		)
	)
	(footprint ""
		(layer "F.Cu")
		(at 212.217 -25.527 -90)
		(property "Reference" "TP328"
			(at 0 0 270)
			(layer "F.SilkS")
			(hide yes)
			(effects
				(font
					(size 1.27 1.27)
				)
			)
		)
		(property "Value" "TPAD28-2-GP"
			(at -0.0127 -1.6637 270)
			(unlocked yes)
			(layer "F.Fab")
			(hide yes)
			(effects
				(font
					(size 1.016 1.016)
					(thickness 0.1524)
				)
			)
		)
		(property "Device Type" "TPAD28"
			(at -0.0127 -3.1877 270)
			(unlocked yes)
			(layer "F.Fab")
			(hide yes)
			(effects
				(font
					(size 1.016 1.016)
					(thickness 0.1524)
				)
			)
		)
		(duplicate_pad_numbers_are_jumpers no)
		(fp_poly
			(pts
				(arc
					(start 0 -0.3556)
					(mid 0 0.3556)
					(end 0 -0.3556)
				)
			)
			(stroke
				(width 0)
				(type default)
			)
			(fill no)
			(layer "F.CrtYd")
		)
		(fp_poly
			(pts
				(arc
					(start 0 -0.6096)
					(mid 0 0.6096)
					(end 0 -0.6096)
				)
			)
			(stroke
				(width 0)
				(type default)
			)
			(fill no)
			(layer "F.Fab")
		)
		(pad "1" smd circle
			(at 0 0 270)
			(size 0.7112 0.7112)
			(layers "F.Cu" "F.Mask" "F.Paste")
			(net "DUT_TAP_SEL")
		)
	)
	(footprint ""
		(layer "F.Cu")
		(at 335.026 -73.66 -90)
		(property "Reference" "C270"
			(at 0 0 270)
			(layer "F.SilkS")
			(hide yes)
			(effects
				(font
					(size 1.27 1.27)
				)
			)
		)
		(property "Value" "SC100P50V2JN-3GP"
			(at 1.1811 -2.7051 270)
			(unlocked yes)
			(layer "F.Fab")
			(hide yes)
			(effects
				(font
					(size 1.016 1.016)
					(thickness 0.1524)
				)
			)
		)
		(property "Device Type" "C402H22"
			(at 1.1811 -4.2291 270)
			(unlocked yes)
			(layer "F.Fab")
			(hide yes)
			(effects
				(font
					(size 1.016 1.016)
					(thickness 0.1524)
				)
			)
		)
		(duplicate_pad_numbers_are_jumpers no)
		(fp_rect
			(start -0.4318 0.9525)
			(end 0.4318 -0.9525)
			(stroke
				(width 0)
				(type default)
			)
			(fill no)
			(layer "F.CrtYd")
		)
		(fp_rect
			(start -0.4318 0.9525)
			(end 0.4318 -0.9525)
			(stroke
				(width 0)
				(type default)
			)
			(fill no)
			(layer "F.Fab")
		)
		(pad "1" smd custom
			(at 0 -0.4445 270)
			(size 0.1524 0.1524)
			(layers "F.Cu" "F.Mask" "F.Paste")
			(net "P0V9_E_VFB")
			(options
				(clearance outline)
				(anchor circle)
			)
			(primitives
				(gr_poly
					(pts
						(arc
							(start 0.3048 -0.2032)
							(mid 0.275042 -0.275042)
							(end 0.2032 -0.3048)
						)
						(arc
							(start -0.2032 -0.3048)
							(mid -0.275042 -0.275042)
							(end -0.3048 -0.2032)
						)
						(arc
							(start -0.3048 0.2032)
							(mid -0.275042 0.275042)
							(end -0.2032 0.3048)
						)
						(arc
							(start 0.2032 0.3048)
							(mid 0.275042 0.275042)
							(end 0.3048 0.2032)
						)
					)
					(width 0)
					(fill yes)
				)
			)
		)
		(pad "2" smd custom
			(at 0 0.4445 270)
			(size 0.1524 0.1524)
			(layers "F.Cu" "F.Mask" "F.Paste")
			(net "P0V9_E_VFB_R")
			(options
				(clearance outline)
				(anchor circle)
			)
			(primitives
				(gr_poly
					(pts
						(arc
							(start 0.3048 -0.2032)
							(mid 0.275042 -0.275042)
							(end 0.2032 -0.3048)
						)
						(arc
							(start -0.2032 -0.3048)
							(mid -0.275042 -0.275042)
							(end -0.3048 -0.2032)
						)
						(arc
							(start -0.3048 0.2032)
							(mid -0.275042 0.275042)
							(end -0.2032 0.3048)
						)
						(arc
							(start 0.2032 0.3048)
							(mid 0.275042 0.275042)
							(end 0.3048 0.2032)
						)
					)
					(width 0)
					(fill yes)
				)
			)
		)
	)
	(footprint ""
		(layer "F.Cu")
		(at 84.190332 -74.230992 -90)
		(property "Reference" "C274"
			(at 0 0 270)
			(layer "F.SilkS")
			(hide yes)
			(effects
				(font
					(size 1.27 1.27)
				)
			)
		)
		(property "Value" "SCD1U16V2KX-3GP"
			(at 1.1811 -2.7051 270)
			(unlocked yes)
			(layer "F.Fab")
			(hide yes)
			(effects
				(font
					(size 1.016 1.016)
					(thickness 0.1524)
				)
			)
		)
		(property "Device Type" "C402H22"
			(at 1.1811 -4.2291 270)
			(unlocked yes)
			(layer "F.Fab")
			(hide yes)
			(effects
				(font
					(size 1.016 1.016)
					(thickness 0.1524)
				)
			)
		)
		(duplicate_pad_numbers_are_jumpers no)
		(fp_rect
			(start -0.4318 0.9525)
			(end 0.4318 -0.9525)
			(stroke
				(width 0)
				(type default)
			)
			(fill no)
			(layer "F.CrtYd")
		)
		(fp_rect
			(start -0.4318 0.9525)
			(end 0.4318 -0.9525)
			(stroke
				(width 0)
				(type default)
			)
			(fill no)
			(layer "F.Fab")
		)
		(pad "1" smd custom
			(at 0 -0.4445 270)
			(size 0.1524 0.1524)
			(layers "F.Cu" "F.Mask" "F.Paste")
			(net "P3V3_STBY")
			(options
				(clearance outline)
				(anchor circle)
			)
			(primitives
				(gr_poly
					(pts
						(arc
							(start 0.3048 -0.2032)
							(mid 0.275042 -0.275042)
							(end 0.2032 -0.3048)
						)
						(arc
							(start -0.2032 -0.3048)
							(mid -0.275042 -0.275042)
							(end -0.3048 -0.2032)
						)
						(arc
							(start -0.3048 0.2032)
							(mid -0.275042 0.275042)
							(end -0.2032 0.3048)
						)
						(arc
							(start 0.2032 0.3048)
							(mid 0.275042 0.275042)
							(end 0.3048 0.2032)
						)
					)
					(width 0)
					(fill yes)
				)
			)
		)
		(pad "2" smd custom
			(at 0 0.4445 270)
			(size 0.1524 0.1524)
			(layers "F.Cu" "F.Mask" "F.Paste")
			(net "GND")
			(options
				(clearance outline)
				(anchor circle)
			)
			(primitives
				(gr_poly
					(pts
						(arc
							(start 0.3048 -0.2032)
							(mid 0.275042 -0.275042)
							(end 0.2032 -0.3048)
						)
						(arc
							(start -0.2032 -0.3048)
							(mid -0.275042 -0.275042)
							(end -0.3048 -0.2032)
						)
						(arc
							(start -0.3048 0.2032)
							(mid -0.275042 0.275042)
							(end -0.2032 0.3048)
						)
						(arc
							(start 0.2032 0.3048)
							(mid 0.275042 0.275042)
							(end 0.3048 0.2032)
						)
					)
					(width 0)
					(fill yes)
				)
			)
		)
	)
	(footprint ""
		(layer "F.Cu")
		(at 69.699124 -195.681092)
		(property "Reference" "R7912"
			(at 0 0 0)
			(layer "F.SilkS")
			(hide yes)
			(effects
				(font
					(size 1.27 1.27)
				)
			)
		)
		(property "Value" "0R2J-2-GP"
			(at 0.064008 -3.993896 0)
			(unlocked yes)
			(layer "F.Fab")
			(hide yes)
			(effects
				(font
					(size 1.016 1.016)
					(thickness 0.1524)
				)
			)
		)
		(property "Device Type" "R402H16"
			(at 0.064008 -5.517896 0)
			(unlocked yes)
			(layer "F.Fab")
			(hide yes)
			(effects
				(font
					(size 1.016 1.016)
					(thickness 0.1524)
				)
			)
		)
		(duplicate_pad_numbers_are_jumpers no)
		(fp_line
			(start -0.508 -0.9398)
			(end -0.508 0.9398)
			(stroke
				(width 0.1524)
				(type default)
			)
			(layer "F.SilkS")
		)
		(fp_line
			(start 0.508 -0.9398)
			(end -0.508 -0.9398)
			(stroke
				(width 0.1524)
				(type default)
			)
			(layer "F.SilkS")
		)
		(fp_rect
			(start -0.508 0.9398)
			(end 0.508 -0.9398)
			(stroke
				(width 0)
				(type default)
			)
			(fill no)
			(layer "F.CrtYd")
		)
		(fp_rect
			(start -0.508 0.9398)
			(end 0.508 -0.9398)
			(stroke
				(width 0)
				(type default)
			)
			(fill no)
			(layer "F.Fab")
		)
		(pad "1" smd custom
			(at 0 -0.4445)
			(size 0.1397 0.1397)
			(layers "F.Cu" "F.Mask" "F.Paste")
			(net "TWI_SDA1")
			(options
				(clearance outline)
				(anchor circle)
			)
			(primitives
				(gr_poly
					(pts
						(arc
							(start -0.1778 -0.2794)
							(mid -0.249642 -0.249642)
							(end -0.2794 -0.1778)
						)
						(arc
							(start -0.2794 0.1778)
							(mid -0.249642 0.249642)
							(end -0.1778 0.2794)
						)
						(arc
							(start 0.1778 0.2794)
							(mid 0.249642 0.249642)
							(end 0.2794 0.1778)
						)
						(arc
							(start 0.2794 -0.1778)
							(mid 0.249642 -0.249642)
							(end 0.1778 -0.2794)
						)
					)
					(width 0)
					(fill yes)
				)
			)
		)
		(pad "2" smd custom
			(at 0 0.4445)
			(size 0.1397 0.1397)
			(layers "F.Cu" "F.Mask" "F.Paste")
			(net "I2C_GPIO_SDA_1")
			(options
				(clearance outline)
				(anchor circle)
			)
			(primitives
				(gr_poly
					(pts
						(arc
							(start -0.1778 -0.2794)
							(mid -0.249642 -0.249642)
							(end -0.2794 -0.1778)
						)
						(arc
							(start -0.2794 0.1778)
							(mid -0.249642 0.249642)
							(end -0.1778 0.2794)
						)
						(arc
							(start 0.1778 0.2794)
							(mid 0.249642 0.249642)
							(end 0.2794 0.1778)
						)
						(arc
							(start 0.2794 -0.1778)
							(mid 0.249642 -0.249642)
							(end 0.1778 -0.2794)
						)
					)
					(width 0)
					(fill yes)
				)
			)
		)
	)
	(footprint ""
		(layer "F.Cu")
		(at 215.9762 -4.064 180)
		(property "Reference" "R7907"
			(at 0 0 180)
			(layer "F.SilkS")
			(hide yes)
			(effects
				(font
					(size 1.27 1.27)
				)
			)
		)
		(property "Value" "0R2J-2-GP"
			(at 0.064008 -3.993896 180)
			(unlocked yes)
			(layer "F.Fab")
			(hide yes)
			(effects
				(font
					(size 1.016 1.016)
					(thickness 0.1524)
				)
			)
		)
		(property "Device Type" "R402H16"
			(at 0.064008 -5.517896 180)
			(unlocked yes)
			(layer "F.Fab")
			(hide yes)
			(effects
				(font
					(size 1.016 1.016)
					(thickness 0.1524)
				)
			)
		)
		(duplicate_pad_numbers_are_jumpers no)
		(fp_line
			(start 0.508 -0.9398)
			(end -0.508 -0.9398)
			(stroke
				(width 0.1524)
				(type default)
			)
			(layer "F.SilkS")
		)
		(fp_line
			(start -0.508 -0.9398)
			(end -0.508 0.9398)
			(stroke
				(width 0.1524)
				(type default)
			)
			(layer "F.SilkS")
		)
		(fp_rect
			(start -0.508 0.9398)
			(end 0.508 -0.9398)
			(stroke
				(width 0)
				(type default)
			)
			(fill no)
			(layer "F.CrtYd")
		)
		(fp_rect
			(start -0.508 0.9398)
			(end 0.508 -0.9398)
			(stroke
				(width 0)
				(type default)
			)
			(fill no)
			(layer "F.Fab")
		)
		(pad "1" smd custom
			(at 0 -0.4445 180)
			(size 0.1397 0.1397)
			(layers "F.Cu" "F.Mask" "F.Paste")
			(net "HOST1_RST_N_R")
			(options
				(clearance outline)
				(anchor circle)
			)
			(primitives
				(gr_poly
					(pts
						(arc
							(start -0.1778 -0.2794)
							(mid -0.249642 -0.249642)
							(end -0.2794 -0.1778)
						)
						(arc
							(start -0.2794 0.1778)
							(mid -0.249642 0.249642)
							(end -0.1778 0.2794)
						)
						(arc
							(start 0.1778 0.2794)
							(mid 0.249642 0.249642)
							(end 0.2794 0.1778)
						)
						(arc
							(start 0.2794 -0.1778)
							(mid 0.249642 -0.249642)
							(end 0.1778 -0.2794)
						)
					)
					(width 0)
					(fill yes)
				)
			)
		)
		(pad "2" smd custom
			(at 0 0.4445 180)
			(size 0.1397 0.1397)
			(layers "F.Cu" "F.Mask" "F.Paste")
			(net "HOST1_RST_N")
			(options
				(clearance outline)
				(anchor circle)
			)
			(primitives
				(gr_poly
					(pts
						(arc
							(start -0.1778 -0.2794)
							(mid -0.249642 -0.249642)
							(end -0.2794 -0.1778)
						)
						(arc
							(start -0.2794 0.1778)
							(mid -0.249642 0.249642)
							(end -0.1778 0.2794)
						)
						(arc
							(start 0.1778 0.2794)
							(mid 0.249642 0.249642)
							(end 0.2794 0.1778)
						)
						(arc
							(start 0.2794 -0.1778)
							(mid 0.249642 -0.249642)
							(end 0.1778 -0.2794)
						)
					)
					(width 0)
					(fill yes)
				)
			)
		)
	)
	(footprint ""
		(layer "F.Cu")
		(at 169.59199 -212.420454 180)
		(property "Reference" "C140"
			(at 0 0 180)
			(layer "F.SilkS")
			(hide yes)
			(effects
				(font
					(size 1.27 1.27)
				)
			)
		)
		(property "Value" "SCD22U10V2KX-1GP"
			(at 1.1811 -2.7051 180)
			(unlocked yes)
			(layer "F.Fab")
			(hide yes)
			(effects
				(font
					(size 1.016 1.016)
					(thickness 0.1524)
				)
			)
		)
		(property "Device Type" "C402H22"
			(at 1.1811 -4.2291 180)
			(unlocked yes)
			(layer "F.Fab")
			(hide yes)
			(effects
				(font
					(size 1.016 1.016)
					(thickness 0.1524)
				)
			)
		)
		(duplicate_pad_numbers_are_jumpers no)
		(fp_rect
			(start -0.4318 0.9525)
			(end 0.4318 -0.9525)
			(stroke
				(width 0)
				(type default)
			)
			(fill no)
			(layer "F.CrtYd")
		)
		(fp_rect
			(start -0.4318 0.9525)
			(end 0.4318 -0.9525)
			(stroke
				(width 0)
				(type default)
			)
			(fill no)
			(layer "F.Fab")
		)
		(pad "1" smd custom
			(at 0 -0.4445 180)
			(size 0.1524 0.1524)
			(layers "F.Cu" "F.Mask" "F.Paste")
			(net "PCIE_TX_CAP_P50")
			(options
				(clearance outline)
				(anchor circle)
			)
			(primitives
				(gr_poly
					(pts
						(arc
							(start 0.3048 -0.2032)
							(mid 0.275042 -0.275042)
							(end 0.2032 -0.3048)
						)
						(arc
							(start -0.2032 -0.3048)
							(mid -0.275042 -0.275042)
							(end -0.3048 -0.2032)
						)
						(arc
							(start -0.3048 0.2032)
							(mid -0.275042 0.275042)
							(end -0.2032 0.3048)
						)
						(arc
							(start 0.2032 0.3048)
							(mid 0.275042 0.275042)
							(end 0.3048 0.2032)
						)
					)
					(width 0)
					(fill yes)
				)
			)
		)
		(pad "2" smd custom
			(at 0 0.4445 180)
			(size 0.1524 0.1524)
			(layers "F.Cu" "F.Mask" "F.Paste")
			(net "PCIE_TX_P50")
			(options
				(clearance outline)
				(anchor circle)
			)
			(primitives
				(gr_poly
					(pts
						(arc
							(start 0.3048 -0.2032)
							(mid 0.275042 -0.275042)
							(end 0.2032 -0.3048)
						)
						(arc
							(start -0.2032 -0.3048)
							(mid -0.275042 -0.275042)
							(end -0.3048 -0.2032)
						)
						(arc
							(start -0.3048 0.2032)
							(mid -0.275042 0.275042)
							(end -0.2032 0.3048)
						)
						(arc
							(start 0.2032 0.3048)
							(mid 0.275042 0.275042)
							(end 0.3048 0.2032)
						)
					)
					(width 0)
					(fill yes)
				)
			)
		)
	)
	(footprint ""
		(layer "F.Cu")
		(at 19.685 -182.7022 90)
		(property "Reference" "C8099"
			(at 0 0 90)
			(layer "F.SilkS")
			(hide yes)
			(effects
				(font
					(size 1.27 1.27)
				)
			)
		)
		(property "Value" "SC1KP50V2KX-1GP"
			(at 1.1811 -2.7051 90)
			(unlocked yes)
			(layer "F.Fab")
			(hide yes)
			(effects
				(font
					(size 1.016 1.016)
					(thickness 0.1524)
				)
			)
		)
		(property "Device Type" "C402H22"
			(at 1.1811 -4.2291 90)
			(unlocked yes)
			(layer "F.Fab")
			(hide yes)
			(effects
				(font
					(size 1.016 1.016)
					(thickness 0.1524)
				)
			)
		)
		(duplicate_pad_numbers_are_jumpers no)
		(fp_rect
			(start -0.4318 0.9525)
			(end 0.4318 -0.9525)
			(stroke
				(width 0)
				(type default)
			)
			(fill no)
			(layer "F.CrtYd")
		)
		(fp_rect
			(start -0.4318 0.9525)
			(end 0.4318 -0.9525)
			(stroke
				(width 0)
				(type default)
			)
			(fill no)
			(layer "F.Fab")
		)
		(pad "1" smd custom
			(at 0 -0.4445 90)
			(size 0.1524 0.1524)
			(layers "F.Cu" "F.Mask" "F.Paste")
			(net "MB0_TEMP")
			(options
				(clearance outline)
				(anchor circle)
			)
			(primitives
				(gr_poly
					(pts
						(arc
							(start 0.3048 -0.2032)
							(mid 0.275042 -0.275042)
							(end 0.2032 -0.3048)
						)
						(arc
							(start -0.2032 -0.3048)
							(mid -0.275042 -0.275042)
							(end -0.3048 -0.2032)
						)
						(arc
							(start -0.3048 0.2032)
							(mid -0.275042 0.275042)
							(end -0.2032 0.3048)
						)
						(arc
							(start 0.2032 0.3048)
							(mid 0.275042 0.275042)
							(end 0.3048 0.2032)
						)
					)
					(width 0)
					(fill yes)
				)
			)
		)
		(pad "2" smd custom
			(at 0 0.4445 90)
			(size 0.1524 0.1524)
			(layers "F.Cu" "F.Mask" "F.Paste")
			(net "GND")
			(options
				(clearance outline)
				(anchor circle)
			)
			(primitives
				(gr_poly
					(pts
						(arc
							(start 0.3048 -0.2032)
							(mid 0.275042 -0.275042)
							(end 0.2032 -0.3048)
						)
						(arc
							(start -0.2032 -0.3048)
							(mid -0.275042 -0.275042)
							(end -0.3048 -0.2032)
						)
						(arc
							(start -0.3048 0.2032)
							(mid -0.275042 0.275042)
							(end -0.2032 0.3048)
						)
						(arc
							(start 0.2032 0.3048)
							(mid 0.275042 0.275042)
							(end 0.3048 0.2032)
						)
					)
					(width 0)
					(fill yes)
				)
			)
		)
	)
	(footprint ""
		(layer "F.Cu")
		(at 46.765464 -116.91874)
		(property "Reference" "R562"
			(at 0 0 0)
			(layer "F.SilkS")
			(hide yes)
			(effects
				(font
					(size 1.27 1.27)
				)
			)
		)
		(property "Value" "0R2J-2-GP"
			(at 0.064008 -3.993896 0)
			(unlocked yes)
			(layer "F.Fab")
			(hide yes)
			(effects
				(font
					(size 1.016 1.016)
					(thickness 0.1524)
				)
			)
		)
		(property "Device Type" "R402H16"
			(at 0.064008 -5.517896 0)
			(unlocked yes)
			(layer "F.Fab")
			(hide yes)
			(effects
				(font
					(size 1.016 1.016)
					(thickness 0.1524)
				)
			)
		)
		(duplicate_pad_numbers_are_jumpers no)
		(fp_line
			(start -0.508 -0.9398)
			(end -0.508 0.9398)
			(stroke
				(width 0.1524)
				(type default)
			)
			(layer "F.SilkS")
		)
		(fp_line
			(start 0.508 -0.9398)
			(end -0.508 -0.9398)
			(stroke
				(width 0.1524)
				(type default)
			)
			(layer "F.SilkS")
		)
		(fp_rect
			(start -0.508 0.9398)
			(end 0.508 -0.9398)
			(stroke
				(width 0)
				(type default)
			)
			(fill no)
			(layer "F.CrtYd")
		)
		(fp_rect
			(start -0.508 0.9398)
			(end 0.508 -0.9398)
			(stroke
				(width 0)
				(type default)
			)
			(fill no)
			(layer "F.Fab")
		)
		(pad "1" smd custom
			(at 0 -0.4445)
			(size 0.1397 0.1397)
			(layers "F.Cu" "F.Mask" "F.Paste")
			(net "BMC_JTAG_L_EN_R")
			(options
				(clearance outline)
				(anchor circle)
			)
			(primitives
				(gr_poly
					(pts
						(arc
							(start -0.1778 -0.2794)
							(mid -0.249642 -0.249642)
							(end -0.2794 -0.1778)
						)
						(arc
							(start -0.2794 0.1778)
							(mid -0.249642 0.249642)
							(end -0.1778 0.2794)
						)
						(arc
							(start 0.1778 0.2794)
							(mid 0.249642 0.249642)
							(end 0.2794 0.1778)
						)
						(arc
							(start 0.2794 -0.1778)
							(mid 0.249642 -0.249642)
							(end 0.1778 -0.2794)
						)
					)
					(width 0)
					(fill yes)
				)
			)
		)
		(pad "2" smd custom
			(at 0 0.4445)
			(size 0.1397 0.1397)
			(layers "F.Cu" "F.Mask" "F.Paste")
			(net "BMC_JTAG_L_EN")
			(options
				(clearance outline)
				(anchor circle)
			)
			(primitives
				(gr_poly
					(pts
						(arc
							(start -0.1778 -0.2794)
							(mid -0.249642 -0.249642)
							(end -0.2794 -0.1778)
						)
						(arc
							(start -0.2794 0.1778)
							(mid -0.249642 0.249642)
							(end -0.1778 0.2794)
						)
						(arc
							(start 0.1778 0.2794)
							(mid 0.249642 0.249642)
							(end 0.2794 0.1778)
						)
						(arc
							(start 0.2794 -0.1778)
							(mid 0.249642 -0.249642)
							(end 0.1778 -0.2794)
						)
					)
					(width 0)
					(fill yes)
				)
			)
		)
	)
	(footprint ""
		(layer "F.Cu")
		(at 53.213 -130.048)
		(property "Reference" "C191"
			(at 0 0 0)
			(layer "F.SilkS")
			(hide yes)
			(effects
				(font
					(size 1.27 1.27)
				)
			)
		)
		(property "Value" "SCD1U16V2KX-3GP"
			(at 1.1811 -2.7051 0)
			(unlocked yes)
			(layer "F.Fab")
			(hide yes)
			(effects
				(font
					(size 1.016 1.016)
					(thickness 0.1524)
				)
			)
		)
		(property "Device Type" "C402H22"
			(at 1.1811 -4.2291 0)
			(unlocked yes)
			(layer "F.Fab")
			(hide yes)
			(effects
				(font
					(size 1.016 1.016)
					(thickness 0.1524)
				)
			)
		)
		(duplicate_pad_numbers_are_jumpers no)
		(fp_rect
			(start -0.4318 0.9525)
			(end 0.4318 -0.9525)
			(stroke
				(width 0)
				(type default)
			)
			(fill no)
			(layer "F.CrtYd")
		)
		(fp_rect
			(start -0.4318 0.9525)
			(end 0.4318 -0.9525)
			(stroke
				(width 0)
				(type default)
			)
			(fill no)
			(layer "F.Fab")
		)
		(pad "1" smd custom
			(at 0 -0.4445)
			(size 0.1524 0.1524)
			(layers "F.Cu" "F.Mask" "F.Paste")
			(net "ADCVREFFN")
			(options
				(clearance outline)
				(anchor circle)
			)
			(primitives
				(gr_poly
					(pts
						(arc
							(start 0.3048 -0.2032)
							(mid 0.275042 -0.275042)
							(end 0.2032 -0.3048)
						)
						(arc
							(start -0.2032 -0.3048)
							(mid -0.275042 -0.275042)
							(end -0.3048 -0.2032)
						)
						(arc
							(start -0.3048 0.2032)
							(mid -0.275042 0.275042)
							(end -0.2032 0.3048)
						)
						(arc
							(start 0.2032 0.3048)
							(mid 0.275042 0.275042)
							(end 0.3048 0.2032)
						)
					)
					(width 0)
					(fill yes)
				)
			)
		)
		(pad "2" smd custom
			(at 0 0.4445)
			(size 0.1524 0.1524)
			(layers "F.Cu" "F.Mask" "F.Paste")
			(net "ADCVREFFP")
			(options
				(clearance outline)
				(anchor circle)
			)
			(primitives
				(gr_poly
					(pts
						(arc
							(start 0.3048 -0.2032)
							(mid 0.275042 -0.275042)
							(end 0.2032 -0.3048)
						)
						(arc
							(start -0.2032 -0.3048)
							(mid -0.275042 -0.275042)
							(end -0.3048 -0.2032)
						)
						(arc
							(start -0.3048 0.2032)
							(mid -0.275042 0.275042)
							(end -0.2032 0.3048)
						)
						(arc
							(start 0.2032 0.3048)
							(mid 0.275042 0.275042)
							(end 0.3048 0.2032)
						)
					)
					(width 0)
					(fill yes)
				)
			)
		)
	)
	(footprint ""
		(layer "F.Cu")
		(at 136.386062 -74.43724 180)
		(property "Reference" "R958"
			(at 0 0 180)
			(layer "F.SilkS")
			(hide yes)
			(effects
				(font
					(size 1.27 1.27)
				)
			)
		)
		(property "Value" "82R2F-4-GP"
			(at 0.064008 -3.993896 180)
			(unlocked yes)
			(layer "F.Fab")
			(hide yes)
			(effects
				(font
					(size 1.016 1.016)
					(thickness 0.1524)
				)
			)
		)
		(property "Device Type" "R402H16"
			(at 0.064008 -5.517896 180)
			(unlocked yes)
			(layer "F.Fab")
			(hide yes)
			(effects
				(font
					(size 1.016 1.016)
					(thickness 0.1524)
				)
			)
		)
		(duplicate_pad_numbers_are_jumpers no)
		(fp_line
			(start 0.508 -0.9398)
			(end -0.508 -0.9398)
			(stroke
				(width 0.1524)
				(type default)
			)
			(layer "F.SilkS")
		)
		(fp_line
			(start -0.508 -0.9398)
			(end -0.508 0.9398)
			(stroke
				(width 0.1524)
				(type default)
			)
			(layer "F.SilkS")
		)
		(fp_rect
			(start -0.508 0.9398)
			(end 0.508 -0.9398)
			(stroke
				(width 0)
				(type default)
			)
			(fill no)
			(layer "F.CrtYd")
		)
		(fp_rect
			(start -0.508 0.9398)
			(end 0.508 -0.9398)
			(stroke
				(width 0)
				(type default)
			)
			(fill no)
			(layer "F.Fab")
		)
		(pad "1" smd custom
			(at 0 -0.4445 180)
			(size 0.1397 0.1397)
			(layers "F.Cu" "F.Mask" "F.Paste")
			(net "SPI_CLK0_R")
			(options
				(clearance outline)
				(anchor circle)
			)
			(primitives
				(gr_poly
					(pts
						(arc
							(start -0.1778 -0.2794)
							(mid -0.249642 -0.249642)
							(end -0.2794 -0.1778)
						)
						(arc
							(start -0.2794 0.1778)
							(mid -0.249642 0.249642)
							(end -0.1778 0.2794)
						)
						(arc
							(start 0.1778 0.2794)
							(mid 0.249642 0.249642)
							(end 0.2794 0.1778)
						)
						(arc
							(start 0.2794 -0.1778)
							(mid 0.249642 -0.249642)
							(end 0.1778 -0.2794)
						)
					)
					(width 0)
					(fill yes)
				)
			)
		)
		(pad "2" smd custom
			(at 0 0.4445 180)
			(size 0.1397 0.1397)
			(layers "F.Cu" "F.Mask" "F.Paste")
			(net "SPI_CLK0")
			(options
				(clearance outline)
				(anchor circle)
			)
			(primitives
				(gr_poly
					(pts
						(arc
							(start -0.1778 -0.2794)
							(mid -0.249642 -0.249642)
							(end -0.2794 -0.1778)
						)
						(arc
							(start -0.2794 0.1778)
							(mid -0.249642 0.249642)
							(end -0.1778 0.2794)
						)
						(arc
							(start 0.1778 0.2794)
							(mid 0.249642 0.249642)
							(end 0.2794 0.1778)
						)
						(arc
							(start 0.2794 -0.1778)
							(mid 0.249642 -0.249642)
							(end 0.1778 -0.2794)
						)
					)
					(width 0)
					(fill yes)
				)
			)
		)
	)
	(footprint ""
		(layer "F.Cu")
		(at 25.6286 -186.0042 90)
		(property "Reference" "R967"
			(at 0 0 90)
			(layer "F.SilkS")
			(hide yes)
			(effects
				(font
					(size 1.27 1.27)
				)
			)
		)
		(property "Value" "0R2J-2-GP"
			(at 0.064008 -3.993896 90)
			(unlocked yes)
			(layer "F.Fab")
			(hide yes)
			(effects
				(font
					(size 1.016 1.016)
					(thickness 0.1524)
				)
			)
		)
		(property "Device Type" "R402H16"
			(at 0.064008 -5.517896 90)
			(unlocked yes)
			(layer "F.Fab")
			(hide yes)
			(effects
				(font
					(size 1.016 1.016)
					(thickness 0.1524)
				)
			)
		)
		(duplicate_pad_numbers_are_jumpers no)
		(fp_line
			(start 0.508 -0.9398)
			(end -0.508 -0.9398)
			(stroke
				(width 0.1524)
				(type default)
			)
			(layer "F.SilkS")
		)
		(fp_line
			(start -0.508 -0.9398)
			(end -0.508 0.9398)
			(stroke
				(width 0.1524)
				(type default)
			)
			(layer "F.SilkS")
		)
		(fp_rect
			(start -0.508 0.9398)
			(end 0.508 -0.9398)
			(stroke
				(width 0)
				(type default)
			)
			(fill no)
			(layer "F.CrtYd")
		)
		(fp_rect
			(start -0.508 0.9398)
			(end 0.508 -0.9398)
			(stroke
				(width 0)
				(type default)
			)
			(fill no)
			(layer "F.Fab")
		)
		(pad "1" smd custom
			(at 0 -0.4445 90)
			(size 0.1397 0.1397)
			(layers "F.Cu" "F.Mask" "F.Paste")
			(net "BMC_I2C5_D_PEB_SCL")
			(options
				(clearance outline)
				(anchor circle)
			)
			(primitives
				(gr_poly
					(pts
						(arc
							(start -0.1778 -0.2794)
							(mid -0.249642 -0.249642)
							(end -0.2794 -0.1778)
						)
						(arc
							(start -0.2794 0.1778)
							(mid -0.249642 0.249642)
							(end -0.1778 0.2794)
						)
						(arc
							(start 0.1778 0.2794)
							(mid 0.249642 0.249642)
							(end 0.2794 0.1778)
						)
						(arc
							(start 0.2794 -0.1778)
							(mid 0.249642 -0.249642)
							(end 0.1778 -0.2794)
						)
					)
					(width 0)
					(fill yes)
				)
			)
		)
		(pad "2" smd custom
			(at 0 0.4445 90)
			(size 0.1397 0.1397)
			(layers "F.Cu" "F.Mask" "F.Paste")
			(net "BMC_I2C5_SCL_R")
			(options
				(clearance outline)
				(anchor circle)
			)
			(primitives
				(gr_poly
					(pts
						(arc
							(start -0.1778 -0.2794)
							(mid -0.249642 -0.249642)
							(end -0.2794 -0.1778)
						)
						(arc
							(start -0.2794 0.1778)
							(mid -0.249642 0.249642)
							(end -0.1778 0.2794)
						)
						(arc
							(start 0.1778 0.2794)
							(mid 0.249642 0.249642)
							(end 0.2794 0.1778)
						)
						(arc
							(start 0.2794 -0.1778)
							(mid 0.249642 -0.249642)
							(end 0.1778 -0.2794)
						)
					)
					(width 0)
					(fill yes)
				)
			)
		)
	)
	(footprint ""
		(layer "F.Cu")
		(at 7.581392 -78.961488 90)
		(property "Reference" "R397"
			(at 0 0 90)
			(layer "F.SilkS")
			(hide yes)
			(effects
				(font
					(size 1.27 1.27)
				)
			)
		)
		(property "Value" "10KR2F-2-GP"
			(at 0.064008 -3.993896 90)
			(unlocked yes)
			(layer "F.Fab")
			(hide yes)
			(effects
				(font
					(size 1.016 1.016)
					(thickness 0.1524)
				)
			)
		)
		(property "Device Type" "R402H16"
			(at 0.064008 -5.517896 90)
			(unlocked yes)
			(layer "F.Fab")
			(hide yes)
			(effects
				(font
					(size 1.016 1.016)
					(thickness 0.1524)
				)
			)
		)
		(duplicate_pad_numbers_are_jumpers no)
		(fp_line
			(start 0.508 -0.9398)
			(end -0.508 -0.9398)
			(stroke
				(width 0.1524)
				(type default)
			)
			(layer "F.SilkS")
		)
		(fp_line
			(start -0.508 -0.9398)
			(end -0.508 0.9398)
			(stroke
				(width 0.1524)
				(type default)
			)
			(layer "F.SilkS")
		)
		(fp_rect
			(start -0.508 0.9398)
			(end 0.508 -0.9398)
			(stroke
				(width 0)
				(type default)
			)
			(fill no)
			(layer "F.CrtYd")
		)
		(fp_rect
			(start -0.508 0.9398)
			(end 0.508 -0.9398)
			(stroke
				(width 0)
				(type default)
			)
			(fill no)
			(layer "F.Fab")
		)
		(pad "1" smd custom
			(at 0 -0.4445 90)
			(size 0.1397 0.1397)
			(layers "F.Cu" "F.Mask" "F.Paste")
			(net "P3V3_STBY")
			(options
				(clearance outline)
				(anchor circle)
			)
			(primitives
				(gr_poly
					(pts
						(arc
							(start -0.1778 -0.2794)
							(mid -0.249642 -0.249642)
							(end -0.2794 -0.1778)
						)
						(arc
							(start -0.2794 0.1778)
							(mid -0.249642 0.249642)
							(end -0.1778 0.2794)
						)
						(arc
							(start 0.1778 0.2794)
							(mid 0.249642 0.249642)
							(end 0.2794 0.1778)
						)
						(arc
							(start 0.2794 -0.1778)
							(mid 0.249642 -0.249642)
							(end 0.1778 -0.2794)
						)
					)
					(width 0)
					(fill yes)
				)
			)
		)
		(pad "2" smd custom
			(at 0 0.4445 90)
			(size 0.1397 0.1397)
			(layers "F.Cu" "F.Mask" "F.Paste")
			(net "LAN_SMB_CLK")
			(options
				(clearance outline)
				(anchor circle)
			)
			(primitives
				(gr_poly
					(pts
						(arc
							(start -0.1778 -0.2794)
							(mid -0.249642 -0.249642)
							(end -0.2794 -0.1778)
						)
						(arc
							(start -0.2794 0.1778)
							(mid -0.249642 0.249642)
							(end -0.1778 0.2794)
						)
						(arc
							(start 0.1778 0.2794)
							(mid 0.249642 0.249642)
							(end 0.2794 0.1778)
						)
						(arc
							(start 0.2794 -0.1778)
							(mid 0.249642 -0.249642)
							(end 0.1778 -0.2794)
						)
					)
					(width 0)
					(fill yes)
				)
			)
		)
	)
	(footprint ""
		(layer "F.Cu")
		(at 345.60002 -203.499974)
		(property "Reference" ""
			(at 0 0 0)
			(layer "F.SilkS")
			(hide yes)
			(effects
				(font
					(size 1.27 1.27)
				)
			)
		)
		(property "Value" "*"
			(at -0.1524 -7.3914 0)
			(unlocked yes)
			(layer "F.Fab")
			(hide yes)
			(effects
				(font
					(size 1.016 1.016)
					(thickness 0.1524)
				)
			)
		)
		(duplicate_pad_numbers_are_jumpers no)
		(fp_poly
			(pts
				(arc
					(start 4.3053 0)
					(mid -4.3053 0)
					(end 4.3053 0)
				)
			)
			(stroke
				(width 0)
				(type default)
			)
			(fill no)
			(layer "B.CrtYd")
		)
		(fp_poly
			(pts
				(arc
					(start 4.3053 0)
					(mid -4.3053 0)
					(end 4.3053 0)
				)
			)
			(stroke
				(width 0)
				(type default)
			)
			(fill no)
			(layer "F.CrtYd")
		)
		(fp_poly
			(pts
				(arc
					(start 4.3053 0)
					(mid -4.3053 0)
					(end 4.3053 0)
				)
			)
			(stroke
				(width 0)
				(type default)
			)
			(fill no)
			(layer "B.Fab")
		)
		(fp_poly
			(pts
				(arc
					(start 4.3053 0)
					(mid -4.3053 0)
					(end 4.3053 0)
				)
			)
			(stroke
				(width 0)
				(type default)
			)
			(fill no)
			(layer "F.Fab")
		)
		(pad "1" thru_hole circle
			(at 0 0)
			(size 8.001 8.001)
			(drill 3.81)
			(layers "*.Cu" "*.Mask")
			(remove_unused_layers no)
			(net "Net_115")
			(clearance -1.5875)
			(thermal_gap 0.3048)
			(padstack
				(mode front_inner_back)
				(layer "Inner"
					(shape circle)
					(size 4.2164 4.2164)
					(clearance 0.3048)
				)
				(layer "B.Cu"
					(shape circle)
					(size 8.001 8.001)
					(clearance -1.5875)
				)
			)
		)
	)
	(footprint ""
		(layer "F.Cu")
		(at 307.300122 -226.70008 180)
		(property "Reference" "GF10"
			(at 0 0 180)
			(layer "F.SilkS")
			(hide yes)
			(effects
				(font
					(size 1.27 1.27)
				)
			)
		)
		(property "Value" "GF-200P-8-GP-U1"
			(at -43.1673 -7.6327 180)
			(unlocked yes)
			(layer "F.Fab")
			(hide yes)
			(effects
				(font
					(size 1.016 1.016)
					(thickness 0.1524)
				)
			)
		)
		(property "Device Type" "GF-200P-8-U1"
			(at -43.1673 -9.1567 180)
			(unlocked yes)
			(layer "F.Fab")
			(hide yes)
			(effects
				(font
					(size 1.016 1.016)
					(thickness 0.1524)
				)
			)
		)
		(duplicate_pad_numbers_are_jumpers no)
		(fp_rect
			(start -38.7096 2.032)
			(end 48.3108 -4.3434)
			(stroke
				(width 0)
				(type default)
			)
			(fill no)
			(layer "B.CrtYd")
		)
		(fp_rect
			(start -38.7096 2.032)
			(end 48.3108 -4.3434)
			(stroke
				(width 0)
				(type default)
			)
			(fill no)
			(layer "F.CrtYd")
		)
		(fp_rect
			(start -38.7096 2.032)
			(end 48.3108 -4.3434)
			(stroke
				(width 0)
				(type default)
			)
			(fill no)
			(layer "B.Fab")
		)
		(fp_rect
			(start -38.7096 2.032)
			(end 48.3108 -4.3434)
			(stroke
				(width 0)
				(type default)
			)
			(fill no)
			(layer "F.Fab")
		)
		(fp_text user "02 Do not mirror"
			(at -7.62 4.1148 180)
			(unlocked yes)
			(layer "F.Fab")
			(effects
				(font
					(size 1.016 1.016)
					(thickness 0.1524)
				)
				(justify left)
			)
		)
		(pad "A1" smd rect
			(at -36.399978 -1.1557 180)
			(size 0.5588 2.3114)
			(layers "F.Cu" "F.Mask" "F.Paste")
			(net "GND")
		)
		(pad "A2" smd rect
			(at -35.599878 -1.1557 180)
			(size 0.5588 2.3114)
			(layers "F.Cu" "F.Mask" "F.Paste")
			(net "PCIE_TX_N16")
		)
		(pad "A3" smd rect
			(at -34.800032 -1.1557 180)
			(size 0.5588 2.3114)
			(layers "F.Cu" "F.Mask" "F.Paste")
			(net "PCIE_TX_P16")
		)
		(pad "A4" smd rect
			(at -33.999932 -1.1557 180)
			(size 0.5588 2.3114)
			(layers "F.Cu" "F.Mask" "F.Paste")
			(net "GND")
		)
		(pad "A5" smd rect
			(at -33.200086 -1.1557 180)
			(size 0.5588 2.3114)
			(layers "F.Cu" "F.Mask" "F.Paste")
			(net "GND")
		)
		(pad "A6" smd rect
			(at -32.399986 -1.1557 180)
			(size 0.5588 2.3114)
			(layers "F.Cu" "F.Mask" "F.Paste")
			(net "PCIE_TX_N17")
		)
		(pad "A7" smd rect
			(at -31.599886 -1.1557 180)
			(size 0.5588 2.3114)
			(layers "F.Cu" "F.Mask" "F.Paste")
			(net "PCIE_TX_P17")
		)
		(pad "A8" smd rect
			(at -30.80004 -1.1557 180)
			(size 0.5588 2.3114)
			(layers "F.Cu" "F.Mask" "F.Paste")
			(net "GND")
		)
		(pad "A9" smd rect
			(at -29.99994 -1.1557 180)
			(size 0.5588 2.3114)
			(layers "F.Cu" "F.Mask" "F.Paste")
			(net "GND")
		)
		(pad "A10" smd rect
			(at -29.200094 -1.1557 180)
			(size 0.5588 2.3114)
			(layers "F.Cu" "F.Mask" "F.Paste")
			(net "PCIE_TX_N18")
		)
		(pad "A11" smd rect
			(at -28.399994 -1.1557 180)
			(size 0.5588 2.3114)
			(layers "F.Cu" "F.Mask" "F.Paste")
			(net "PCIE_TX_P18")
		)
		(pad "A12" smd rect
			(at -27.599894 -1.1557 180)
			(size 0.5588 2.3114)
			(layers "F.Cu" "F.Mask" "F.Paste")
			(net "GND")
		)
		(pad "A13" smd rect
			(at -26.800048 -1.1557 180)
			(size 0.5588 2.3114)
			(layers "F.Cu" "F.Mask" "F.Paste")
			(net "GND")
		)
		(pad "A14" smd rect
			(at -25.999948 -1.1557 180)
			(size 0.5588 2.3114)
			(layers "F.Cu" "F.Mask" "F.Paste")
			(net "PCIE_TX_N19")
		)
		(pad "A15" smd rect
			(at -25.200102 -1.1557 180)
			(size 0.5588 2.3114)
			(layers "F.Cu" "F.Mask" "F.Paste")
			(net "PCIE_TX_P19")
		)
		(pad "A16" smd rect
			(at -24.400002 -1.1557 180)
			(size 0.5588 2.3114)
			(layers "F.Cu" "F.Mask" "F.Paste")
			(net "GND")
		)
		(pad "A17" smd rect
			(at -23.599902 -1.1557 180)
			(size 0.5588 2.3114)
			(layers "F.Cu" "F.Mask" "F.Paste")
			(net "SSD_PRSNT#14_R")
		)
		(pad "A18" smd rect
			(at -22.800056 -1.1557 180)
			(size 0.5588 2.3114)
			(layers "F.Cu" "F.Mask" "F.Paste")
			(net "SSD_PWREN9_R")
		)
		(pad "A19" smd rect
			(at -21.999956 -1.1557 180)
			(size 0.5588 2.3114)
			(layers "F.Cu" "F.Mask" "F.Paste")
			(net "SSD_ATNLED#9_R")
		)
		(pad "A20" smd rect
			(at -21.20011 -1.1557 180)
			(size 0.5588 2.3114)
			(layers "F.Cu" "F.Mask" "F.Paste")
			(net "SSD_PRSNT#9_R")
		)
		(pad "A21" smd rect
			(at -20.40001 -1.1557 180)
			(size 0.5588 2.3114)
			(layers "F.Cu" "F.Mask" "F.Paste")
			(net "GND")
		)
		(pad "A22" smd rect
			(at -19.59991 -1.1557 180)
			(size 0.5588 2.3114)
			(layers "F.Cu" "F.Mask" "F.Paste")
			(net "PCIE_TX_N20")
		)
		(pad "A23" smd rect
			(at -18.800064 -1.1557 180)
			(size 0.5588 2.3114)
			(layers "F.Cu" "F.Mask" "F.Paste")
			(net "PCIE_TX_P20")
		)
		(pad "A24" smd rect
			(at -17.999964 -1.1557 180)
			(size 0.5588 2.3114)
			(layers "F.Cu" "F.Mask" "F.Paste")
			(net "GND")
		)
		(pad "A25" smd rect
			(at -17.200118 -1.1557 180)
			(size 0.5588 2.3114)
			(layers "F.Cu" "F.Mask" "F.Paste")
			(net "GND")
		)
		(pad "A26" smd rect
			(at -16.400018 -1.1557 180)
			(size 0.5588 2.3114)
			(layers "F.Cu" "F.Mask" "F.Paste")
			(net "PCIE_TX_N21")
		)
		(pad "A27" smd rect
			(at -15.599918 -1.1557 180)
			(size 0.5588 2.3114)
			(layers "F.Cu" "F.Mask" "F.Paste")
			(net "PCIE_TX_P21")
		)
		(pad "A28" smd rect
			(at -14.800072 -1.1557 180)
			(size 0.5588 2.3114)
			(layers "F.Cu" "F.Mask" "F.Paste")
			(net "GND")
		)
		(pad "A29" smd rect
			(at -13.999972 -1.1557 180)
			(size 0.5588 2.3114)
			(layers "F.Cu" "F.Mask" "F.Paste")
			(net "GND")
		)
		(pad "A30" smd rect
			(at -13.200126 -1.1557 180)
			(size 0.5588 2.3114)
			(layers "F.Cu" "F.Mask" "F.Paste")
			(net "PCIE_TX_N22")
		)
		(pad "A31" smd rect
			(at -12.400026 -1.1557 180)
			(size 0.5588 2.3114)
			(layers "F.Cu" "F.Mask" "F.Paste")
			(net "PCIE_TX_P22")
		)
		(pad "A32" smd rect
			(at -11.599926 -1.1557 180)
			(size 0.5588 2.3114)
			(layers "F.Cu" "F.Mask" "F.Paste")
			(net "GND")
		)
		(pad "A33" smd rect
			(at -10.80008 -1.1557 180)
			(size 0.5588 2.3114)
			(layers "F.Cu" "F.Mask" "F.Paste")
			(net "GND")
		)
		(pad "A34" smd rect
			(at -9.99998 -1.1557 180)
			(size 0.5588 2.3114)
			(layers "F.Cu" "F.Mask" "F.Paste")
			(net "PCIE_TX_N23")
		)
		(pad "A35" smd rect
			(at -9.19988 -1.1557 180)
			(size 0.5588 2.3114)
			(layers "F.Cu" "F.Mask" "F.Paste")
			(net "PCIE_TX_P23")
		)
		(pad "A36" smd rect
			(at -8.400034 -1.1557 180)
			(size 0.5588 2.3114)
			(layers "F.Cu" "F.Mask" "F.Paste")
			(net "GND")
		)
		(pad "A37" smd rect
			(at -7.599934 -1.1557 180)
			(size 0.5588 2.3114)
			(layers "F.Cu" "F.Mask" "F.Paste")
			(net "GND")
		)
		(pad "A38" smd rect
			(at -6.800088 -1.1557 180)
			(size 0.5588 2.3114)
			(layers "F.Cu" "F.Mask" "F.Paste")
			(net "PCIE_TX_N24")
		)
		(pad "A39" smd rect
			(at -5.999988 -1.1557 180)
			(size 0.5588 2.3114)
			(layers "F.Cu" "F.Mask" "F.Paste")
			(net "PCIE_TX_P24")
		)
		(pad "A40" smd rect
			(at -5.199888 -1.1557 180)
			(size 0.5588 2.3114)
			(layers "F.Cu" "F.Mask" "F.Paste")
			(net "GND")
		)
		(pad "A41" smd rect
			(at -4.400042 -1.1557 180)
			(size 0.5588 2.3114)
			(layers "F.Cu" "F.Mask" "F.Paste")
			(net "GND")
		)
		(pad "A42" smd rect
			(at -3.599942 -1.1557 180)
			(size 0.5588 2.3114)
			(layers "F.Cu" "F.Mask" "F.Paste")
			(net "PCIE_TX_N25")
		)
		(pad "A43" smd rect
			(at -2.800096 -1.1557 180)
			(size 0.5588 2.3114)
			(layers "F.Cu" "F.Mask" "F.Paste")
			(net "PCIE_TX_P25")
		)
		(pad "A44" smd rect
			(at -1.999996 -1.1557 180)
			(size 0.5588 2.3114)
			(layers "F.Cu" "F.Mask" "F.Paste")
			(net "GND")
		)
		(pad "A45" smd rect
			(at 1.999996 -1.1557 180)
			(size 0.5588 2.3114)
			(layers "F.Cu" "F.Mask" "F.Paste")
			(net "SSD_PERST#9_R")
		)
		(pad "A46" smd rect
			(at 2.800096 -1.1557 180)
			(size 0.5588 1.8796)
			(drill
				(offset 0 -0.2159)
			)
			(layers "F.Cu" "F.Mask" "F.Paste")
			(net "SSD_PERST#13_R")
		)
		(pad "A47" smd rect
			(at 3.599942 -1.1557 180)
			(size 0.5588 2.3114)
			(layers "F.Cu" "F.Mask" "F.Paste")
			(net "GND")
		)
		(pad "A48" smd rect
			(at 4.400042 -1.1557 180)
			(size 0.5588 2.3114)
			(layers "F.Cu" "F.Mask" "F.Paste")
			(net "PCIE_TX_N26")
		)
		(pad "A49" smd rect
			(at 5.199888 -1.1557 180)
			(size 0.5588 2.3114)
			(layers "F.Cu" "F.Mask" "F.Paste")
			(net "PCIE_TX_P26")
		)
		(pad "A50" smd rect
			(at 5.999988 -1.1557 180)
			(size 0.5588 2.3114)
			(layers "F.Cu" "F.Mask" "F.Paste")
			(net "GND")
		)
		(pad "A51" smd rect
			(at 6.800088 -1.1557 180)
			(size 0.5588 2.3114)
			(layers "F.Cu" "F.Mask" "F.Paste")
			(net "GND")
		)
		(pad "A52" smd rect
			(at 7.599934 -1.1557 180)
			(size 0.5588 2.3114)
			(layers "F.Cu" "F.Mask" "F.Paste")
			(net "PCIE_TX_N27")
		)
		(pad "A53" smd rect
			(at 8.400034 -1.1557 180)
			(size 0.5588 2.3114)
			(layers "F.Cu" "F.Mask" "F.Paste")
			(net "PCIE_TX_P27")
		)
		(pad "A54" smd rect
			(at 9.19988 -1.1557 180)
			(size 0.5588 2.3114)
			(layers "F.Cu" "F.Mask" "F.Paste")
			(net "GND")
		)
		(pad "A55" smd rect
			(at 9.99998 -1.1557 180)
			(size 0.5588 2.3114)
			(layers "F.Cu" "F.Mask" "F.Paste")
			(net "SSD_PWREN13_R")
		)
		(pad "A56" smd rect
			(at 10.80008 -1.1557 180)
			(size 0.5588 2.3114)
			(layers "F.Cu" "F.Mask" "F.Paste")
			(net "SSD_ATNLED#13_R")
		)
		(pad "A57" smd rect
			(at 11.599926 -1.1557 180)
			(size 0.5588 2.3114)
			(layers "F.Cu" "F.Mask" "F.Paste")
			(net "SSD_PRSNT#13_R")
		)
		(pad "A58" smd rect
			(at 12.400026 -1.1557 180)
			(size 0.5588 2.3114)
			(layers "F.Cu" "F.Mask" "F.Paste")
			(net "GND")
		)
		(pad "A59" smd rect
			(at 13.200126 -1.1557 180)
			(size 0.5588 2.3114)
			(layers "F.Cu" "F.Mask" "F.Paste")
			(net "PCIE_TX_N28")
		)
		(pad "A60" smd rect
			(at 13.999972 -1.1557 180)
			(size 0.5588 2.3114)
			(layers "F.Cu" "F.Mask" "F.Paste")
			(net "PCIE_TX_P28")
		)
		(pad "A61" smd rect
			(at 14.800072 -1.1557 180)
			(size 0.5588 2.3114)
			(layers "F.Cu" "F.Mask" "F.Paste")
			(net "GND")
		)
		(pad "A62" smd rect
			(at 15.599918 -1.1557 180)
			(size 0.5588 2.3114)
			(layers "F.Cu" "F.Mask" "F.Paste")
			(net "GND")
		)
		(pad "A63" smd rect
			(at 16.400018 -1.1557 180)
			(size 0.5588 2.3114)
			(layers "F.Cu" "F.Mask" "F.Paste")
			(net "PCIE_TX_N29")
		)
		(pad "A64" smd rect
			(at 17.200118 -1.1557 180)
			(size 0.5588 2.3114)
			(layers "F.Cu" "F.Mask" "F.Paste")
			(net "PCIE_TX_P29")
		)
		(pad "A65" smd rect
			(at 17.999964 -1.1557 180)
			(size 0.5588 2.3114)
			(layers "F.Cu" "F.Mask" "F.Paste")
			(net "GND")
		)
		(pad "A66" smd rect
			(at 18.800064 -1.1557 180)
			(size 0.5588 2.3114)
			(layers "F.Cu" "F.Mask" "F.Paste")
			(net "GND")
		)
		(pad "A67" smd rect
			(at 19.59991 -1.1557 180)
			(size 0.5588 2.3114)
			(layers "F.Cu" "F.Mask" "F.Paste")
			(net "PCIE_TX_N30")
		)
		(pad "A68" smd rect
			(at 20.40001 -1.1557 180)
			(size 0.5588 2.3114)
			(layers "F.Cu" "F.Mask" "F.Paste")
			(net "PCIE_TX_P30")
		)
		(pad "A69" smd rect
			(at 21.20011 -1.1557 180)
			(size 0.5588 2.3114)
			(layers "F.Cu" "F.Mask" "F.Paste")
			(net "GND")
		)
		(pad "A70" smd rect
			(at 21.999956 -1.1557 180)
			(size 0.5588 2.3114)
			(layers "F.Cu" "F.Mask" "F.Paste")
			(net "GND")
		)
		(pad "A71" smd rect
			(at 22.800056 -1.1557 180)
			(size 0.5588 2.3114)
			(layers "F.Cu" "F.Mask" "F.Paste")
			(net "PCIE_TX_N31")
		)
		(pad "A72" smd rect
			(at 23.599902 -1.1557 180)
			(size 0.5588 2.3114)
			(layers "F.Cu" "F.Mask" "F.Paste")
			(net "PCIE_TX_P31")
		)
		(pad "A73" smd rect
			(at 24.400002 -1.1557 180)
			(size 0.5588 2.3114)
			(layers "F.Cu" "F.Mask" "F.Paste")
			(net "GND")
		)
		(pad "A74" smd rect
			(at 25.200102 -1.1557 180)
			(size 0.5588 2.3114)
			(layers "F.Cu" "F.Mask" "F.Paste")
			(net "GND")
		)
		(pad "A75" smd rect
			(at 25.999948 -1.1557 180)
			(size 0.5588 2.3114)
			(layers "F.Cu" "F.Mask" "F.Paste")
			(net "PCIE_TX_N32")
		)
		(pad "A76" smd rect
			(at 26.800048 -1.1557 180)
			(size 0.5588 2.3114)
			(layers "F.Cu" "F.Mask" "F.Paste")
			(net "PCIE_TX_P32")
		)
		(pad "A77" smd rect
			(at 27.599894 -1.1557 180)
			(size 0.5588 2.3114)
			(layers "F.Cu" "F.Mask" "F.Paste")
			(net "GND")
		)
		(pad "A78" smd rect
			(at 28.399994 -1.1557 180)
			(size 0.5588 2.3114)
			(layers "F.Cu" "F.Mask" "F.Paste")
			(net "GND")
		)
		(pad "A79" smd rect
			(at 29.200094 -1.1557 180)
			(size 0.5588 2.3114)
			(layers "F.Cu" "F.Mask" "F.Paste")
			(net "PCIE_TX_N33")
		)
		(pad "A80" smd rect
			(at 29.99994 -1.1557 180)
			(size 0.5588 2.3114)
			(layers "F.Cu" "F.Mask" "F.Paste")
			(net "PCIE_TX_P33")
		)
		(pad "A81" smd rect
			(at 30.80004 -1.1557 180)
			(size 0.5588 2.3114)
			(layers "F.Cu" "F.Mask" "F.Paste")
			(net "GND")
		)
		(pad "A82" smd rect
			(at 31.599886 -1.1557 180)
			(size 0.5588 2.3114)
			(layers "F.Cu" "F.Mask" "F.Paste")
			(net "GND")
		)
		(pad "A83" smd rect
			(at 32.399986 -1.1557 180)
			(size 0.5588 2.3114)
			(layers "F.Cu" "F.Mask" "F.Paste")
			(net "PCIE_TX_N34")
		)
		(pad "A84" smd rect
			(at 33.200086 -1.1557 180)
			(size 0.5588 2.3114)
			(layers "F.Cu" "F.Mask" "F.Paste")
			(net "PCIE_TX_P34")
		)
		(pad "A85" smd rect
			(at 33.999932 -1.1557 180)
			(size 0.5588 2.3114)
			(layers "F.Cu" "F.Mask" "F.Paste")
			(net "GND")
		)
		(pad "A86" smd rect
			(at 34.800032 -1.1557 180)
			(size 0.5588 2.3114)
			(layers "F.Cu" "F.Mask" "F.Paste")
			(net "GND")
		)
		(pad "A87" smd rect
			(at 35.599878 -1.1557 180)
			(size 0.5588 2.3114)
			(layers "F.Cu" "F.Mask" "F.Paste")
			(net "PCIE_TX_N35")
		)
		(pad "A88" smd rect
			(at 36.399978 -1.1557 180)
			(size 0.5588 2.3114)
			(layers "F.Cu" "F.Mask" "F.Paste")
			(net "PCIE_TX_P35")
		)
		(pad "A89" smd rect
			(at 37.200078 -1.1557 180)
			(size 0.5588 2.3114)
			(layers "F.Cu" "F.Mask" "F.Paste")
			(net "GND")
		)
		(pad "A90" smd rect
			(at 37.999924 -1.1557 180)
			(size 0.5588 2.3114)
			(layers "F.Cu" "F.Mask" "F.Paste")
			(net "GND")
		)
		(pad "A91" smd rect
			(at 38.800024 -1.1557 180)
			(size 0.5588 2.3114)
			(layers "F.Cu" "F.Mask" "F.Paste")
			(net "PCIE_TX_N36")
		)
		(pad "A92" smd rect
			(at 39.600124 -1.1557 180)
			(size 0.5588 2.3114)
			(layers "F.Cu" "F.Mask" "F.Paste")
			(net "PCIE_TX_P36")
		)
		(pad "A93" smd rect
			(at 40.39997 -1.1557 180)
			(size 0.5588 2.3114)
			(layers "F.Cu" "F.Mask" "F.Paste")
			(net "GND")
		)
		(pad "A94" smd rect
			(at 41.20007 -1.1557 180)
			(size 0.5588 2.3114)
			(layers "F.Cu" "F.Mask" "F.Paste")
			(net "GND")
		)
		(pad "A95" smd rect
			(at 41.999916 -1.1557 180)
			(size 0.5588 2.3114)
			(layers "F.Cu" "F.Mask" "F.Paste")
			(net "PCIE_TX_N37")
		)
		(pad "A96" smd rect
			(at 42.800016 -1.1557 180)
			(size 0.5588 2.3114)
			(layers "F.Cu" "F.Mask" "F.Paste")
			(net "PCIE_TX_P37")
		)
		(pad "A97" smd rect
			(at 43.600116 -1.1557 180)
			(size 0.5588 2.3114)
			(layers "F.Cu" "F.Mask" "F.Paste")
			(net "GND")
		)
		(pad "A98" smd rect
			(at 44.399962 -1.1557 180)
			(size 0.5588 2.3114)
			(layers "F.Cu" "F.Mask" "F.Paste")
			(net "EXP_TRAY_ID")
		)
		(pad "A99" smd rect
			(at 45.200062 -1.1557 180)
			(size 0.5588 2.3114)
			(layers "F.Cu" "F.Mask" "F.Paste")
			(net "SHUTDOWN_RELEASE")
		)
		(pad "A100" smd rect
			(at 45.999908 -1.1557 180)
			(size 0.5588 1.8796)
			(drill
				(offset 0 -0.2159)
			)
			(layers "F.Cu" "F.Mask" "F.Paste")
			(net "PCIE_MATED#_B")
		)
		(pad "B1" smd rect
			(at -36.399978 -0.7747 180)
			(size 0.5588 2.3114)
			(drill
				(offset 0 -0.381)
			)
			(layers "F.Cu" "F.Mask" "F.Paste")
			(net "SSD_ATNLED#14_R")
		)
		(pad "B2" smd rect
			(at -35.599878 -0.7747 180)
			(size 0.5588 2.3114)
			(drill
				(offset 0 -0.381)
			)
			(layers "F.Cu" "F.Mask" "F.Paste")
			(net "SSD_PWREN14_R")
		)
		(pad "B3" smd rect
			(at -34.800032 -0.7747 180)
			(size 0.5588 2.3114)
			(drill
				(offset 0 -0.381)
			)
			(layers "F.Cu" "F.Mask" "F.Paste")
			(net "GND")
		)
		(pad "B4" smd rect
			(at -33.999932 -0.7747 180)
			(size 0.5588 2.3114)
			(drill
				(offset 0 -0.381)
			)
			(layers "F.Cu" "F.Mask" "F.Paste")
			(net "PCIE_RX_N16")
		)
		(pad "B5" smd rect
			(at -33.200086 -0.7747 180)
			(size 0.5588 2.3114)
			(drill
				(offset 0 -0.381)
			)
			(layers "F.Cu" "F.Mask" "F.Paste")
			(net "PCIE_RX_P16")
		)
		(pad "B6" smd rect
			(at -32.399986 -0.7747 180)
			(size 0.5588 2.3114)
			(drill
				(offset 0 -0.381)
			)
			(layers "F.Cu" "F.Mask" "F.Paste")
			(net "GND")
		)
		(pad "B7" smd rect
			(at -31.599886 -0.7747 180)
			(size 0.5588 2.3114)
			(drill
				(offset 0 -0.381)
			)
			(layers "F.Cu" "F.Mask" "F.Paste")
			(net "GND")
		)
		(pad "B8" smd rect
			(at -30.80004 -0.7747 180)
			(size 0.5588 2.3114)
			(drill
				(offset 0 -0.381)
			)
			(layers "F.Cu" "F.Mask" "F.Paste")
			(net "PCIE_RX_N17")
		)
		(pad "B9" smd rect
			(at -29.99994 -0.7747 180)
			(size 0.5588 2.3114)
			(drill
				(offset 0 -0.381)
			)
			(layers "F.Cu" "F.Mask" "F.Paste")
			(net "PCIE_RX_P17")
		)
		(pad "B10" smd rect
			(at -29.200094 -0.7747 180)
			(size 0.5588 2.3114)
			(drill
				(offset 0 -0.381)
			)
			(layers "F.Cu" "F.Mask" "F.Paste")
			(net "GND")
		)
		(pad "B11" smd rect
			(at -28.399994 -0.7747 180)
			(size 0.5588 2.3114)
			(drill
				(offset 0 -0.381)
			)
			(layers "F.Cu" "F.Mask" "F.Paste")
			(net "GND")
		)
		(pad "B12" smd rect
			(at -27.599894 -0.7747 180)
			(size 0.5588 2.3114)
			(drill
				(offset 0 -0.381)
			)
			(layers "F.Cu" "F.Mask" "F.Paste")
			(net "PCIE_RX_N18")
		)
		(pad "B13" smd rect
			(at -26.800048 -0.7747 180)
			(size 0.5588 2.3114)
			(drill
				(offset 0 -0.381)
			)
			(layers "F.Cu" "F.Mask" "F.Paste")
			(net "PCIE_RX_P18")
		)
		(pad "B14" smd rect
			(at -25.999948 -0.7747 180)
			(size 0.5588 2.3114)
			(drill
				(offset 0 -0.381)
			)
			(layers "F.Cu" "F.Mask" "F.Paste")
			(net "GND")
		)
		(pad "B15" smd rect
			(at -25.200102 -0.7747 180)
			(size 0.5588 2.3114)
			(drill
				(offset 0 -0.381)
			)
			(layers "F.Cu" "F.Mask" "F.Paste")
			(net "GND")
		)
		(pad "B16" smd rect
			(at -24.400002 -0.7747 180)
			(size 0.5588 2.3114)
			(drill
				(offset 0 -0.381)
			)
			(layers "F.Cu" "F.Mask" "F.Paste")
			(net "PCIE_RX_N19")
		)
		(pad "B17" smd rect
			(at -23.599902 -0.7747 180)
			(size 0.5588 2.3114)
			(drill
				(offset 0 -0.381)
			)
			(layers "F.Cu" "F.Mask" "F.Paste")
			(net "PCIE_RX_P19")
		)
		(pad "B18" smd rect
			(at -22.800056 -0.7747 180)
			(size 0.5588 2.3114)
			(drill
				(offset 0 -0.381)
			)
			(layers "F.Cu" "F.Mask" "F.Paste")
			(net "GND")
		)
		(pad "B19" smd rect
			(at -21.999956 -0.7747 180)
			(size 0.5588 2.3114)
			(drill
				(offset 0 -0.381)
			)
			(layers "F.Cu" "F.Mask" "F.Paste")
			(net "GND")
		)
		(pad "B20" smd rect
			(at -21.20011 -0.7747 180)
			(size 0.5588 2.3114)
			(drill
				(offset 0 -0.381)
			)
			(layers "F.Cu" "F.Mask" "F.Paste")
			(net "PCIE_RX_N20")
		)
		(pad "B21" smd rect
			(at -20.40001 -0.7747 180)
			(size 0.5588 2.3114)
			(drill
				(offset 0 -0.381)
			)
			(layers "F.Cu" "F.Mask" "F.Paste")
			(net "PCIE_RX_P20")
		)
		(pad "B22" smd rect
			(at -19.59991 -0.7747 180)
			(size 0.5588 2.3114)
			(drill
				(offset 0 -0.381)
			)
			(layers "F.Cu" "F.Mask" "F.Paste")
			(net "GND")
		)
		(pad "B23" smd rect
			(at -18.800064 -0.7747 180)
			(size 0.5588 2.3114)
			(drill
				(offset 0 -0.381)
			)
			(layers "F.Cu" "F.Mask" "F.Paste")
			(net "GND")
		)
		(pad "B24" smd rect
			(at -17.999964 -0.7747 180)
			(size 0.5588 2.3114)
			(drill
				(offset 0 -0.381)
			)
			(layers "F.Cu" "F.Mask" "F.Paste")
			(net "PCIE_RX_N21")
		)
		(pad "B25" smd rect
			(at -17.200118 -0.7747 180)
			(size 0.5588 2.3114)
			(drill
				(offset 0 -0.381)
			)
			(layers "F.Cu" "F.Mask" "F.Paste")
			(net "PCIE_RX_P21")
		)
		(pad "B26" smd rect
			(at -16.400018 -0.7747 180)
			(size 0.5588 2.3114)
			(drill
				(offset 0 -0.381)
			)
			(layers "F.Cu" "F.Mask" "F.Paste")
			(net "GND")
		)
		(pad "B27" smd rect
			(at -15.599918 -0.7747 180)
			(size 0.5588 2.3114)
			(drill
				(offset 0 -0.381)
			)
			(layers "F.Cu" "F.Mask" "F.Paste")
			(net "GND")
		)
		(pad "B28" smd rect
			(at -14.800072 -0.7747 180)
			(size 0.5588 2.3114)
			(drill
				(offset 0 -0.381)
			)
			(layers "F.Cu" "F.Mask" "F.Paste")
			(net "PCIE_RX_N22")
		)
		(pad "B29" smd rect
			(at -13.999972 -0.7747 180)
			(size 0.5588 2.3114)
			(drill
				(offset 0 -0.381)
			)
			(layers "F.Cu" "F.Mask" "F.Paste")
			(net "PCIE_RX_P22")
		)
		(pad "B30" smd rect
			(at -13.200126 -0.7747 180)
			(size 0.5588 2.3114)
			(drill
				(offset 0 -0.381)
			)
			(layers "F.Cu" "F.Mask" "F.Paste")
			(net "GND")
		)
		(pad "B31" smd rect
			(at -12.400026 -0.7747 180)
			(size 0.5588 2.3114)
			(drill
				(offset 0 -0.381)
			)
			(layers "F.Cu" "F.Mask" "F.Paste")
			(net "GND")
		)
		(pad "B32" smd rect
			(at -11.599926 -0.7747 180)
			(size 0.5588 2.3114)
			(drill
				(offset 0 -0.381)
			)
			(layers "F.Cu" "F.Mask" "F.Paste")
			(net "PCIE_RX_N23")
		)
		(pad "B33" smd rect
			(at -10.80008 -0.7747 180)
			(size 0.5588 2.3114)
			(drill
				(offset 0 -0.381)
			)
			(layers "F.Cu" "F.Mask" "F.Paste")
			(net "PCIE_RX_P23")
		)
		(pad "B34" smd rect
			(at -9.99998 -0.7747 180)
			(size 0.5588 2.3114)
			(drill
				(offset 0 -0.381)
			)
			(layers "F.Cu" "F.Mask" "F.Paste")
			(net "GND")
		)
		(pad "B35" smd rect
			(at -9.19988 -0.7747 180)
			(size 0.5588 2.3114)
			(drill
				(offset 0 -0.381)
			)
			(layers "F.Cu" "F.Mask" "F.Paste")
			(net "GND")
		)
		(pad "B36" smd rect
			(at -8.400034 -0.7747 180)
			(size 0.5588 2.3114)
			(drill
				(offset 0 -0.381)
			)
			(layers "F.Cu" "F.Mask" "F.Paste")
			(net "PCIE_RX_N24")
		)
		(pad "B37" smd rect
			(at -7.599934 -0.7747 180)
			(size 0.5588 2.3114)
			(drill
				(offset 0 -0.381)
			)
			(layers "F.Cu" "F.Mask" "F.Paste")
			(net "PCIE_RX_P24")
		)
		(pad "B38" smd rect
			(at -6.800088 -0.7747 180)
			(size 0.5588 2.3114)
			(drill
				(offset 0 -0.381)
			)
			(layers "F.Cu" "F.Mask" "F.Paste")
			(net "GND")
		)
		(pad "B39" smd rect
			(at -5.999988 -0.7747 180)
			(size 0.5588 2.3114)
			(drill
				(offset 0 -0.381)
			)
			(layers "F.Cu" "F.Mask" "F.Paste")
			(net "GND")
		)
		(pad "B40" smd rect
			(at -5.199888 -0.7747 180)
			(size 0.5588 2.3114)
			(drill
				(offset 0 -0.381)
			)
			(layers "F.Cu" "F.Mask" "F.Paste")
			(net "PCIE_RX_N25")
		)
		(pad "B41" smd rect
			(at -4.400042 -0.7747 180)
			(size 0.5588 2.3114)
			(drill
				(offset 0 -0.381)
			)
			(layers "F.Cu" "F.Mask" "F.Paste")
			(net "PCIE_RX_P25")
		)
		(pad "B42" smd rect
			(at -3.599942 -0.7747 180)
			(size 0.5588 2.3114)
			(drill
				(offset 0 -0.381)
			)
			(layers "F.Cu" "F.Mask" "F.Paste")
			(net "GND")
		)
		(pad "B43" smd rect
			(at -2.800096 -0.7747 180)
			(size 0.5588 2.3114)
			(drill
				(offset 0 -0.381)
			)
			(layers "F.Cu" "F.Mask" "F.Paste")
			(net "SSD_PERST#14_R")
		)
		(pad "B44" smd rect
			(at -1.999996 -0.7747 180)
			(size 0.5588 2.3114)
			(drill
				(offset 0 -0.381)
			)
			(layers "F.Cu" "F.Mask" "F.Paste")
			(net "SSD_PERST#4_R")
		)
		(pad "B45" smd rect
			(at 1.999996 -0.7747 180)
			(size 0.5588 2.3114)
			(drill
				(offset 0 -0.381)
			)
			(layers "F.Cu" "F.Mask" "F.Paste")
			(net "GND")
		)
		(pad "B46" smd rect
			(at 2.800096 -0.7747 180)
			(size 0.5588 2.3114)
			(drill
				(offset 0 -0.381)
			)
			(layers "F.Cu" "F.Mask" "F.Paste")
			(net "PCIE_RX_N26")
		)
		(pad "B47" smd rect
			(at 3.599942 -0.7747 180)
			(size 0.5588 2.3114)
			(drill
				(offset 0 -0.381)
			)
			(layers "F.Cu" "F.Mask" "F.Paste")
			(net "PCIE_RX_P26")
		)
		(pad "B48" smd rect
			(at 4.400042 -0.7747 180)
			(size 0.5588 2.3114)
			(drill
				(offset 0 -0.381)
			)
			(layers "F.Cu" "F.Mask" "F.Paste")
			(net "GND")
		)
		(pad "B49" smd rect
			(at 5.199888 -0.7747 180)
			(size 0.5588 2.3114)
			(drill
				(offset 0 -0.381)
			)
			(layers "F.Cu" "F.Mask" "F.Paste")
			(net "GND")
		)
		(pad "B50" smd rect
			(at 5.999988 -0.7747 180)
			(size 0.5588 2.3114)
			(drill
				(offset 0 -0.381)
			)
			(layers "F.Cu" "F.Mask" "F.Paste")
			(net "PCIE_RX_N27")
		)
		(pad "B51" smd rect
			(at 6.800088 -0.7747 180)
			(size 0.5588 2.3114)
			(drill
				(offset 0 -0.381)
			)
			(layers "F.Cu" "F.Mask" "F.Paste")
			(net "PCIE_RX_P27")
		)
		(pad "B52" smd rect
			(at 7.599934 -0.7747 180)
			(size 0.5588 2.3114)
			(drill
				(offset 0 -0.381)
			)
			(layers "F.Cu" "F.Mask" "F.Paste")
			(net "GND")
		)
		(pad "B53" smd rect
			(at 8.400034 -0.7747 180)
			(size 0.5588 2.3114)
			(drill
				(offset 0 -0.381)
			)
			(layers "F.Cu" "F.Mask" "F.Paste")
			(net "SSD_PRSNT#4_R")
		)
		(pad "B54" smd rect
			(at 9.19988 -0.7747 180)
			(size 0.5588 2.3114)
			(drill
				(offset 0 -0.381)
			)
			(layers "F.Cu" "F.Mask" "F.Paste")
			(net "SSD_ATNLED#4_R")
		)
		(pad "B55" smd rect
			(at 9.99998 -0.7747 180)
			(size 0.5588 2.3114)
			(drill
				(offset 0 -0.381)
			)
			(layers "F.Cu" "F.Mask" "F.Paste")
			(net "SSD_PWREN4_R")
		)
		(pad "B56" smd rect
			(at 10.80008 -0.7747 180)
			(size 0.5588 2.3114)
			(drill
				(offset 0 -0.381)
			)
			(layers "F.Cu" "F.Mask" "F.Paste")
			(net "GND")
		)
		(pad "B57" smd rect
			(at 11.599926 -0.7747 180)
			(size 0.5588 2.3114)
			(drill
				(offset 0 -0.381)
			)
			(layers "F.Cu" "F.Mask" "F.Paste")
			(net "PCIE_RX_N28")
		)
		(pad "B58" smd rect
			(at 12.400026 -0.7747 180)
			(size 0.5588 2.3114)
			(drill
				(offset 0 -0.381)
			)
			(layers "F.Cu" "F.Mask" "F.Paste")
			(net "PCIE_RX_P28")
		)
		(pad "B59" smd rect
			(at 13.200126 -0.7747 180)
			(size 0.5588 2.3114)
			(drill
				(offset 0 -0.381)
			)
			(layers "F.Cu" "F.Mask" "F.Paste")
			(net "GND")
		)
		(pad "B60" smd rect
			(at 13.999972 -0.7747 180)
			(size 0.5588 2.3114)
			(drill
				(offset 0 -0.381)
			)
			(layers "F.Cu" "F.Mask" "F.Paste")
			(net "GND")
		)
		(pad "B61" smd rect
			(at 14.800072 -0.7747 180)
			(size 0.5588 2.3114)
			(drill
				(offset 0 -0.381)
			)
			(layers "F.Cu" "F.Mask" "F.Paste")
			(net "PCIE_RX_N29")
		)
		(pad "B62" smd rect
			(at 15.599918 -0.7747 180)
			(size 0.5588 2.3114)
			(drill
				(offset 0 -0.381)
			)
			(layers "F.Cu" "F.Mask" "F.Paste")
			(net "PCIE_RX_P29")
		)
		(pad "B63" smd rect
			(at 16.400018 -0.7747 180)
			(size 0.5588 2.3114)
			(drill
				(offset 0 -0.381)
			)
			(layers "F.Cu" "F.Mask" "F.Paste")
			(net "GND")
		)
		(pad "B64" smd rect
			(at 17.200118 -0.7747 180)
			(size 0.5588 2.3114)
			(drill
				(offset 0 -0.381)
			)
			(layers "F.Cu" "F.Mask" "F.Paste")
			(net "GND")
		)
		(pad "B65" smd rect
			(at 17.999964 -0.7747 180)
			(size 0.5588 2.3114)
			(drill
				(offset 0 -0.381)
			)
			(layers "F.Cu" "F.Mask" "F.Paste")
			(net "PCIE_RX_N30")
		)
		(pad "B66" smd rect
			(at 18.800064 -0.7747 180)
			(size 0.5588 2.3114)
			(drill
				(offset 0 -0.381)
			)
			(layers "F.Cu" "F.Mask" "F.Paste")
			(net "PCIE_RX_P30")
		)
		(pad "B67" smd rect
			(at 19.59991 -0.7747 180)
			(size 0.5588 2.3114)
			(drill
				(offset 0 -0.381)
			)
			(layers "F.Cu" "F.Mask" "F.Paste")
			(net "GND")
		)
		(pad "B68" smd rect
			(at 20.40001 -0.7747 180)
			(size 0.5588 2.3114)
			(drill
				(offset 0 -0.381)
			)
			(layers "F.Cu" "F.Mask" "F.Paste")
			(net "GND")
		)
		(pad "B69" smd rect
			(at 21.20011 -0.7747 180)
			(size 0.5588 2.3114)
			(drill
				(offset 0 -0.381)
			)
			(layers "F.Cu" "F.Mask" "F.Paste")
			(net "PCIE_RX_N31")
		)
		(pad "B70" smd rect
			(at 21.999956 -0.7747 180)
			(size 0.5588 2.3114)
			(drill
				(offset 0 -0.381)
			)
			(layers "F.Cu" "F.Mask" "F.Paste")
			(net "PCIE_RX_P31")
		)
		(pad "B71" smd rect
			(at 22.800056 -0.7747 180)
			(size 0.5588 2.3114)
			(drill
				(offset 0 -0.381)
			)
			(layers "F.Cu" "F.Mask" "F.Paste")
			(net "GND")
		)
		(pad "B72" smd rect
			(at 23.599902 -0.7747 180)
			(size 0.5588 2.3114)
			(drill
				(offset 0 -0.381)
			)
			(layers "F.Cu" "F.Mask" "F.Paste")
			(net "GND")
		)
		(pad "B73" smd rect
			(at 24.400002 -0.7747 180)
			(size 0.5588 2.3114)
			(drill
				(offset 0 -0.381)
			)
			(layers "F.Cu" "F.Mask" "F.Paste")
			(net "PCIE_RX_N32")
		)
		(pad "B74" smd rect
			(at 25.200102 -0.7747 180)
			(size 0.5588 2.3114)
			(drill
				(offset 0 -0.381)
			)
			(layers "F.Cu" "F.Mask" "F.Paste")
			(net "PCIE_RX_P32")
		)
		(pad "B75" smd rect
			(at 25.999948 -0.7747 180)
			(size 0.5588 2.3114)
			(drill
				(offset 0 -0.381)
			)
			(layers "F.Cu" "F.Mask" "F.Paste")
			(net "GND")
		)
		(pad "B76" smd rect
			(at 26.800048 -0.7747 180)
			(size 0.5588 2.3114)
			(drill
				(offset 0 -0.381)
			)
			(layers "F.Cu" "F.Mask" "F.Paste")
			(net "GND")
		)
		(pad "B77" smd rect
			(at 27.599894 -0.7747 180)
			(size 0.5588 2.3114)
			(drill
				(offset 0 -0.381)
			)
			(layers "F.Cu" "F.Mask" "F.Paste")
			(net "PCIE_RX_N33")
		)
		(pad "B78" smd rect
			(at 28.399994 -0.7747 180)
			(size 0.5588 2.3114)
			(drill
				(offset 0 -0.381)
			)
			(layers "F.Cu" "F.Mask" "F.Paste")
			(net "PCIE_RX_P33")
		)
		(pad "B79" smd rect
			(at 29.200094 -0.7747 180)
			(size 0.5588 2.3114)
			(drill
				(offset 0 -0.381)
			)
			(layers "F.Cu" "F.Mask" "F.Paste")
			(net "GND")
		)
		(pad "B80" smd rect
			(at 29.99994 -0.7747 180)
			(size 0.5588 2.3114)
			(drill
				(offset 0 -0.381)
			)
			(layers "F.Cu" "F.Mask" "F.Paste")
			(net "GND")
		)
		(pad "B81" smd rect
			(at 30.80004 -0.7747 180)
			(size 0.5588 2.3114)
			(drill
				(offset 0 -0.381)
			)
			(layers "F.Cu" "F.Mask" "F.Paste")
			(net "PCIE_RX_N34")
		)
		(pad "B82" smd rect
			(at 31.599886 -0.7747 180)
			(size 0.5588 2.3114)
			(drill
				(offset 0 -0.381)
			)
			(layers "F.Cu" "F.Mask" "F.Paste")
			(net "PCIE_RX_P34")
		)
		(pad "B83" smd rect
			(at 32.399986 -0.7747 180)
			(size 0.5588 2.3114)
			(drill
				(offset 0 -0.381)
			)
			(layers "F.Cu" "F.Mask" "F.Paste")
			(net "GND")
		)
		(pad "B84" smd rect
			(at 33.200086 -0.7747 180)
			(size 0.5588 2.3114)
			(drill
				(offset 0 -0.381)
			)
			(layers "F.Cu" "F.Mask" "F.Paste")
			(net "GND")
		)
		(pad "B85" smd rect
			(at 33.999932 -0.7747 180)
			(size 0.5588 2.3114)
			(drill
				(offset 0 -0.381)
			)
			(layers "F.Cu" "F.Mask" "F.Paste")
			(net "PCIE_RX_N35")
		)
		(pad "B86" smd rect
			(at 34.800032 -0.7747 180)
			(size 0.5588 2.3114)
			(drill
				(offset 0 -0.381)
			)
			(layers "F.Cu" "F.Mask" "F.Paste")
			(net "PCIE_RX_P35")
		)
		(pad "B87" smd rect
			(at 35.599878 -0.7747 180)
			(size 0.5588 2.3114)
			(drill
				(offset 0 -0.381)
			)
			(layers "F.Cu" "F.Mask" "F.Paste")
			(net "GND")
		)
		(pad "B88" smd rect
			(at 36.399978 -0.7747 180)
			(size 0.5588 2.3114)
			(drill
				(offset 0 -0.381)
			)
			(layers "F.Cu" "F.Mask" "F.Paste")
			(net "SSD_PRSNT#8_R")
		)
		(pad "B89" smd rect
			(at 37.200078 -0.7747 180)
			(size 0.5588 2.3114)
			(drill
				(offset 0 -0.381)
			)
			(layers "F.Cu" "F.Mask" "F.Paste")
			(net "SSD_ATNLED#8_R")
		)
		(pad "B90" smd rect
			(at 37.999924 -0.7747 180)
			(size 0.5588 2.3114)
			(drill
				(offset 0 -0.381)
			)
			(layers "F.Cu" "F.Mask" "F.Paste")
			(net "SSD_PWREN8_R")
		)
		(pad "B91" smd rect
			(at 38.800024 -0.7747 180)
			(size 0.5588 2.3114)
			(drill
				(offset 0 -0.381)
			)
			(layers "F.Cu" "F.Mask" "F.Paste")
			(net "SSD_PERST#8_R")
		)
		(pad "B92" smd rect
			(at 39.600124 -0.7747 180)
			(size 0.5588 2.3114)
			(drill
				(offset 0 -0.381)
			)
			(layers "F.Cu" "F.Mask" "F.Paste")
			(net "GND")
		)
		(pad "B93" smd rect
			(at 40.39997 -0.7747 180)
			(size 0.5588 2.3114)
			(drill
				(offset 0 -0.381)
			)
			(layers "F.Cu" "F.Mask" "F.Paste")
			(net "PCIE_RX_N36")
		)
		(pad "B94" smd rect
			(at 41.20007 -0.7747 180)
			(size 0.5588 2.3114)
			(drill
				(offset 0 -0.381)
			)
			(layers "F.Cu" "F.Mask" "F.Paste")
			(net "PCIE_RX_P36")
		)
		(pad "B95" smd rect
			(at 41.999916 -0.7747 180)
			(size 0.5588 2.3114)
			(drill
				(offset 0 -0.381)
			)
			(layers "F.Cu" "F.Mask" "F.Paste")
			(net "GND")
		)
		(pad "B96" smd rect
			(at 42.800016 -0.7747 180)
			(size 0.5588 2.3114)
			(drill
				(offset 0 -0.381)
			)
			(layers "F.Cu" "F.Mask" "F.Paste")
			(net "GND")
		)
		(pad "B97" smd rect
			(at 43.600116 -0.7747 180)
			(size 0.5588 2.3114)
			(drill
				(offset 0 -0.381)
			)
			(layers "F.Cu" "F.Mask" "F.Paste")
			(net "PCIE_RX_N37")
		)
		(pad "B98" smd rect
			(at 44.399962 -0.7747 180)
			(size 0.5588 2.3114)
			(drill
				(offset 0 -0.381)
			)
			(layers "F.Cu" "F.Mask" "F.Paste")
			(net "PCIE_RX_P37")
		)
		(pad "B99" smd rect
			(at 45.200062 -0.7747 180)
			(size 0.5588 2.3114)
			(drill
				(offset 0 -0.381)
			)
			(layers "F.Cu" "F.Mask" "F.Paste")
			(net "GND")
		)
		(pad "B100" smd rect
			(at 45.999908 -0.7747 180)
			(size 0.5588 2.3114)
			(drill
				(offset 0 -0.381)
			)
			(layers "F.Cu" "F.Mask" "F.Paste")
			(net "I2C_MUX_RESET_PEB")
		)
		(zone
			(layer "F.Cu")
			(hatch none 0.5)
			(connect_pads
				(clearance 0)
			)
			(min_thickness 0.25)
			(keepout
				(tracks not_allowed)
				(vias allowed)
				(pads allowed)
				(copperpour not_allowed)
				(footprints allowed)
			)
			(placement
				(enabled no)
				(sheetname "")
			)
			(fill
				(thermal_gap 0.5)
				(thermal_bridge_width 0.5)
				(island_removal_mode 0)
			)
			(polygon
				(pts
					(xy 344.993722 -227.71608) (xy 260.005322 -227.71608) (xy 260.005322 -226.70008) (xy 344.993722 -226.70008)
				)
			)
		)
		(zone
			(layer "F.Cu")
			(hatch none 0.5)
			(connect_pads
				(clearance 0)
			)
			(min_thickness 0.25)
			(keepout
				(tracks allowed)
				(vias not_allowed)
				(pads allowed)
				(copperpour not_allowed)
				(footprints allowed)
			)
			(placement
				(enabled no)
				(sheetname "")
			)
			(fill
				(thermal_gap 0.5)
				(thermal_bridge_width 0.5)
				(island_removal_mode 0)
			)
			(polygon
				(pts
					(xy 344.993722 -227.71608) (xy 260.005322 -227.71608) (xy 260.005322 -223.37268) (xy 344.993722 -223.37268)
				)
			)
		)
		(zone
			(layer "B.Cu")
			(hatch none 0.5)
			(connect_pads
				(clearance 0)
			)
			(min_thickness 0.25)
			(keepout
				(tracks not_allowed)
				(vias allowed)
				(pads allowed)
				(copperpour not_allowed)
				(footprints allowed)
			)
			(placement
				(enabled no)
				(sheetname "")
			)
			(fill
				(thermal_gap 0.5)
				(thermal_bridge_width 0.5)
				(island_removal_mode 0)
			)
			(polygon
				(pts
					(xy 344.993722 -227.71608) (xy 260.005322 -227.71608) (xy 260.005322 -226.70008) (xy 344.993722 -226.70008)
				)
			)
		)
		(zone
			(layer "B.Cu")
			(hatch none 0.5)
			(connect_pads
				(clearance 0)
			)
			(min_thickness 0.25)
			(keepout
				(tracks allowed)
				(vias not_allowed)
				(pads allowed)
				(copperpour not_allowed)
				(footprints allowed)
			)
			(placement
				(enabled no)
				(sheetname "")
			)
			(fill
				(thermal_gap 0.5)
				(thermal_bridge_width 0.5)
				(island_removal_mode 0)
			)
			(polygon
				(pts
					(xy 344.993722 -227.71608) (xy 260.005322 -227.71608) (xy 260.005322 -223.37268) (xy 344.993722 -223.37268)
				)
			)
		)
	)
	(footprint ""
		(layer "F.Cu")
		(at 338.868512 -172.432218)
		(property "Reference" "R7954"
			(at 0 0 0)
			(layer "F.SilkS")
			(hide yes)
			(effects
				(font
					(size 1.27 1.27)
				)
			)
		)
		(property "Value" "0R2J-2-GP"
			(at 0.064008 -3.993896 0)
			(unlocked yes)
			(layer "F.Fab")
			(hide yes)
			(effects
				(font
					(size 1.016 1.016)
					(thickness 0.1524)
				)
			)
		)
		(property "Device Type" "R402H16"
			(at 0.064008 -5.517896 0)
			(unlocked yes)
			(layer "F.Fab")
			(hide yes)
			(effects
				(font
					(size 1.016 1.016)
					(thickness 0.1524)
				)
			)
		)
		(duplicate_pad_numbers_are_jumpers no)
		(fp_line
			(start -0.508 -0.9398)
			(end -0.508 0.9398)
			(stroke
				(width 0.1524)
				(type default)
			)
			(layer "F.SilkS")
		)
		(fp_line
			(start 0.508 -0.9398)
			(end -0.508 -0.9398)
			(stroke
				(width 0.1524)
				(type default)
			)
			(layer "F.SilkS")
		)
		(fp_rect
			(start -0.508 0.9398)
			(end 0.508 -0.9398)
			(stroke
				(width 0)
				(type default)
			)
			(fill no)
			(layer "F.CrtYd")
		)
		(fp_rect
			(start -0.508 0.9398)
			(end 0.508 -0.9398)
			(stroke
				(width 0)
				(type default)
			)
			(fill no)
			(layer "F.Fab")
		)
		(pad "1" smd custom
			(at 0 -0.4445)
			(size 0.1397 0.1397)
			(layers "F.Cu" "F.Mask" "F.Paste")
			(net "SSD_PWREN9")
			(options
				(clearance outline)
				(anchor circle)
			)
			(primitives
				(gr_poly
					(pts
						(arc
							(start -0.1778 -0.2794)
							(mid -0.249642 -0.249642)
							(end -0.2794 -0.1778)
						)
						(arc
							(start -0.2794 0.1778)
							(mid -0.249642 0.249642)
							(end -0.1778 0.2794)
						)
						(arc
							(start 0.1778 0.2794)
							(mid 0.249642 0.249642)
							(end 0.2794 0.1778)
						)
						(arc
							(start 0.2794 -0.1778)
							(mid 0.249642 -0.249642)
							(end 0.1778 -0.2794)
						)
					)
					(width 0)
					(fill yes)
				)
			)
		)
		(pad "2" smd custom
			(at 0 0.4445)
			(size 0.1397 0.1397)
			(layers "F.Cu" "F.Mask" "F.Paste")
			(net "SSD_PWREN9_R")
			(options
				(clearance outline)
				(anchor circle)
			)
			(primitives
				(gr_poly
					(pts
						(arc
							(start -0.1778 -0.2794)
							(mid -0.249642 -0.249642)
							(end -0.2794 -0.1778)
						)
						(arc
							(start -0.2794 0.1778)
							(mid -0.249642 0.249642)
							(end -0.1778 0.2794)
						)
						(arc
							(start 0.1778 0.2794)
							(mid 0.249642 0.249642)
							(end 0.2794 0.1778)
						)
						(arc
							(start 0.2794 -0.1778)
							(mid 0.249642 -0.249642)
							(end 0.1778 -0.2794)
						)
					)
					(width 0)
					(fill yes)
				)
			)
		)
	)
	(footprint ""
		(layer "F.Cu")
		(at 226.822 -23.241 180)
		(property "Reference" "R3719"
			(at 0 0 180)
			(layer "F.SilkS")
			(hide yes)
			(effects
				(font
					(size 1.27 1.27)
				)
			)
		)
		(property "Value" "4K7R2F-GP"
			(at 0.064008 -3.993896 180)
			(unlocked yes)
			(layer "F.Fab")
			(hide yes)
			(effects
				(font
					(size 1.016 1.016)
					(thickness 0.1524)
				)
			)
		)
		(property "Device Type" "R402H16"
			(at 0.064008 -5.517896 180)
			(unlocked yes)
			(layer "F.Fab")
			(hide yes)
			(effects
				(font
					(size 1.016 1.016)
					(thickness 0.1524)
				)
			)
		)
		(duplicate_pad_numbers_are_jumpers no)
		(fp_line
			(start 0.508 -0.9398)
			(end -0.508 -0.9398)
			(stroke
				(width 0.1524)
				(type default)
			)
			(layer "F.SilkS")
		)
		(fp_line
			(start -0.508 -0.9398)
			(end -0.508 0.9398)
			(stroke
				(width 0.1524)
				(type default)
			)
			(layer "F.SilkS")
		)
		(fp_rect
			(start -0.508 0.9398)
			(end 0.508 -0.9398)
			(stroke
				(width 0)
				(type default)
			)
			(fill no)
			(layer "F.CrtYd")
		)
		(fp_rect
			(start -0.508 0.9398)
			(end 0.508 -0.9398)
			(stroke
				(width 0)
				(type default)
			)
			(fill no)
			(layer "F.Fab")
		)
		(pad "1" smd custom
			(at 0 -0.4445 180)
			(size 0.1397 0.1397)
			(layers "F.Cu" "F.Mask" "F.Paste")
			(net "HOST4_RST_N_LS")
			(options
				(clearance outline)
				(anchor circle)
			)
			(primitives
				(gr_poly
					(pts
						(arc
							(start -0.1778 -0.2794)
							(mid -0.249642 -0.249642)
							(end -0.2794 -0.1778)
						)
						(arc
							(start -0.2794 0.1778)
							(mid -0.249642 0.249642)
							(end -0.1778 0.2794)
						)
						(arc
							(start 0.1778 0.2794)
							(mid 0.249642 0.249642)
							(end 0.2794 0.1778)
						)
						(arc
							(start 0.2794 -0.1778)
							(mid 0.249642 -0.249642)
							(end 0.1778 -0.2794)
						)
					)
					(width 0)
					(fill yes)
				)
			)
		)
		(pad "2" smd custom
			(at 0 0.4445 180)
			(size 0.1397 0.1397)
			(layers "F.Cu" "F.Mask" "F.Paste")
			(net "GND")
			(options
				(clearance outline)
				(anchor circle)
			)
			(primitives
				(gr_poly
					(pts
						(arc
							(start -0.1778 -0.2794)
							(mid -0.249642 -0.249642)
							(end -0.2794 -0.1778)
						)
						(arc
							(start -0.2794 0.1778)
							(mid -0.249642 0.249642)
							(end -0.1778 0.2794)
						)
						(arc
							(start 0.1778 0.2794)
							(mid 0.249642 0.249642)
							(end 0.2794 0.1778)
						)
						(arc
							(start 0.2794 -0.1778)
							(mid 0.249642 -0.249642)
							(end 0.1778 -0.2794)
						)
					)
					(width 0)
					(fill yes)
				)
			)
		)
	)
	(footprint ""
		(layer "F.Cu")
		(at 25.019 -152.4)
		(property "Reference" "C3217"
			(at 0 0 0)
			(layer "F.SilkS")
			(hide yes)
			(effects
				(font
					(size 1.27 1.27)
				)
			)
		)
		(property "Value" "SCD1U25V2KX-2-GP"
			(at 1.1811 -2.7051 0)
			(unlocked yes)
			(layer "F.Fab")
			(hide yes)
			(effects
				(font
					(size 1.016 1.016)
					(thickness 0.1524)
				)
			)
		)
		(property "Device Type" "C402H22"
			(at 1.1811 -4.2291 0)
			(unlocked yes)
			(layer "F.Fab")
			(hide yes)
			(effects
				(font
					(size 1.016 1.016)
					(thickness 0.1524)
				)
			)
		)
		(duplicate_pad_numbers_are_jumpers no)
		(fp_rect
			(start -0.4318 0.9525)
			(end 0.4318 -0.9525)
			(stroke
				(width 0)
				(type default)
			)
			(fill no)
			(layer "F.CrtYd")
		)
		(fp_rect
			(start -0.4318 0.9525)
			(end 0.4318 -0.9525)
			(stroke
				(width 0)
				(type default)
			)
			(fill no)
			(layer "F.Fab")
		)
		(pad "1" smd custom
			(at 0 -0.4445)
			(size 0.1524 0.1524)
			(layers "F.Cu" "F.Mask" "F.Paste")
			(net "P3V3_STBY")
			(options
				(clearance outline)
				(anchor circle)
			)
			(primitives
				(gr_poly
					(pts
						(arc
							(start 0.3048 -0.2032)
							(mid 0.275042 -0.275042)
							(end 0.2032 -0.3048)
						)
						(arc
							(start -0.2032 -0.3048)
							(mid -0.275042 -0.275042)
							(end -0.3048 -0.2032)
						)
						(arc
							(start -0.3048 0.2032)
							(mid -0.275042 0.275042)
							(end -0.2032 0.3048)
						)
						(arc
							(start 0.2032 0.3048)
							(mid 0.275042 0.275042)
							(end 0.3048 0.2032)
						)
					)
					(width 0)
					(fill yes)
				)
			)
		)
		(pad "2" smd custom
			(at 0 0.4445)
			(size 0.1524 0.1524)
			(layers "F.Cu" "F.Mask" "F.Paste")
			(net "GND")
			(options
				(clearance outline)
				(anchor circle)
			)
			(primitives
				(gr_poly
					(pts
						(arc
							(start 0.3048 -0.2032)
							(mid 0.275042 -0.275042)
							(end 0.2032 -0.3048)
						)
						(arc
							(start -0.2032 -0.3048)
							(mid -0.275042 -0.275042)
							(end -0.3048 -0.2032)
						)
						(arc
							(start -0.3048 0.2032)
							(mid -0.275042 0.275042)
							(end -0.2032 0.3048)
						)
						(arc
							(start 0.2032 0.3048)
							(mid 0.275042 0.275042)
							(end 0.3048 0.2032)
						)
					)
					(width 0)
					(fill yes)
				)
			)
		)
	)
	(footprint ""
		(layer "F.Cu")
		(at 40.64 -197.231)
		(property "Reference" "R879"
			(at 0 0 0)
			(layer "F.SilkS")
			(hide yes)
			(effects
				(font
					(size 1.27 1.27)
				)
			)
		)
		(property "Value" "0R2J-2-GP"
			(at 0.064008 -3.993896 0)
			(unlocked yes)
			(layer "F.Fab")
			(hide yes)
			(effects
				(font
					(size 1.016 1.016)
					(thickness 0.1524)
				)
			)
		)
		(property "Device Type" "R402H16"
			(at 0.064008 -5.517896 0)
			(unlocked yes)
			(layer "F.Fab")
			(hide yes)
			(effects
				(font
					(size 1.016 1.016)
					(thickness 0.1524)
				)
			)
		)
		(duplicate_pad_numbers_are_jumpers no)
		(fp_line
			(start -0.508 -0.9398)
			(end -0.508 0.9398)
			(stroke
				(width 0.1524)
				(type default)
			)
			(layer "F.SilkS")
		)
		(fp_line
			(start 0.508 -0.9398)
			(end -0.508 -0.9398)
			(stroke
				(width 0.1524)
				(type default)
			)
			(layer "F.SilkS")
		)
		(fp_rect
			(start -0.508 0.9398)
			(end 0.508 -0.9398)
			(stroke
				(width 0)
				(type default)
			)
			(fill no)
			(layer "F.CrtYd")
		)
		(fp_rect
			(start -0.508 0.9398)
			(end 0.508 -0.9398)
			(stroke
				(width 0)
				(type default)
			)
			(fill no)
			(layer "F.Fab")
		)
		(pad "1" smd custom
			(at 0 -0.4445)
			(size 0.1397 0.1397)
			(layers "F.Cu" "F.Mask" "F.Paste")
			(net "BMC_I2C6_C_FCB_SDA_R")
			(options
				(clearance outline)
				(anchor circle)
			)
			(primitives
				(gr_poly
					(pts
						(arc
							(start -0.1778 -0.2794)
							(mid -0.249642 -0.249642)
							(end -0.2794 -0.1778)
						)
						(arc
							(start -0.2794 0.1778)
							(mid -0.249642 0.249642)
							(end -0.1778 0.2794)
						)
						(arc
							(start 0.1778 0.2794)
							(mid 0.249642 0.249642)
							(end 0.2794 0.1778)
						)
						(arc
							(start 0.2794 -0.1778)
							(mid 0.249642 -0.249642)
							(end 0.1778 -0.2794)
						)
					)
					(width 0)
					(fill yes)
				)
			)
		)
		(pad "2" smd custom
			(at 0 0.4445)
			(size 0.1397 0.1397)
			(layers "F.Cu" "F.Mask" "F.Paste")
			(net "BMC_I2C6_C_FCB_SDA")
			(options
				(clearance outline)
				(anchor circle)
			)
			(primitives
				(gr_poly
					(pts
						(arc
							(start -0.1778 -0.2794)
							(mid -0.249642 -0.249642)
							(end -0.2794 -0.1778)
						)
						(arc
							(start -0.2794 0.1778)
							(mid -0.249642 0.249642)
							(end -0.1778 0.2794)
						)
						(arc
							(start 0.1778 0.2794)
							(mid 0.249642 0.249642)
							(end 0.2794 0.1778)
						)
						(arc
							(start 0.2794 -0.1778)
							(mid 0.249642 -0.249642)
							(end 0.1778 -0.2794)
						)
					)
					(width 0)
					(fill yes)
				)
			)
		)
	)
	(footprint ""
		(layer "F.Cu")
		(at 134.1882 -42.11701 -90)
		(property "Reference" "R771"
			(at 0 0 270)
			(layer "F.SilkS")
			(hide yes)
			(effects
				(font
					(size 1.27 1.27)
				)
			)
		)
		(property "Value" "4K7R2F-GP"
			(at 0.064008 -3.993896 270)
			(unlocked yes)
			(layer "F.Fab")
			(hide yes)
			(effects
				(font
					(size 1.016 1.016)
					(thickness 0.1524)
				)
			)
		)
		(property "Device Type" "R402H16"
			(at 0.064008 -5.517896 270)
			(unlocked yes)
			(layer "F.Fab")
			(hide yes)
			(effects
				(font
					(size 1.016 1.016)
					(thickness 0.1524)
				)
			)
		)
		(duplicate_pad_numbers_are_jumpers no)
		(fp_line
			(start -0.508 -0.9398)
			(end -0.508 0.9398)
			(stroke
				(width 0.1524)
				(type default)
			)
			(layer "F.SilkS")
		)
		(fp_line
			(start 0.508 -0.9398)
			(end -0.508 -0.9398)
			(stroke
				(width 0.1524)
				(type default)
			)
			(layer "F.SilkS")
		)
		(fp_rect
			(start -0.508 0.9398)
			(end 0.508 -0.9398)
			(stroke
				(width 0)
				(type default)
			)
			(fill no)
			(layer "F.CrtYd")
		)
		(fp_rect
			(start -0.508 0.9398)
			(end 0.508 -0.9398)
			(stroke
				(width 0)
				(type default)
			)
			(fill no)
			(layer "F.Fab")
		)
		(pad "1" smd custom
			(at 0 -0.4445 270)
			(size 0.1397 0.1397)
			(layers "F.Cu" "F.Mask" "F.Paste")
			(net "DUT_VDDO")
			(options
				(clearance outline)
				(anchor circle)
			)
			(primitives
				(gr_poly
					(pts
						(arc
							(start -0.1778 -0.2794)
							(mid -0.249642 -0.249642)
							(end -0.2794 -0.1778)
						)
						(arc
							(start -0.2794 0.1778)
							(mid -0.249642 0.249642)
							(end -0.1778 0.2794)
						)
						(arc
							(start 0.1778 0.2794)
							(mid 0.249642 0.249642)
							(end 0.2794 0.1778)
						)
						(arc
							(start 0.2794 -0.1778)
							(mid 0.249642 -0.249642)
							(end 0.1778 -0.2794)
						)
					)
					(width 0)
					(fill yes)
				)
			)
		)
		(pad "2" smd custom
			(at 0 0.4445 270)
			(size 0.1397 0.1397)
			(layers "F.Cu" "F.Mask" "F.Paste")
			(net "EJTAG_TDI")
			(options
				(clearance outline)
				(anchor circle)
			)
			(primitives
				(gr_poly
					(pts
						(arc
							(start -0.1778 -0.2794)
							(mid -0.249642 -0.249642)
							(end -0.2794 -0.1778)
						)
						(arc
							(start -0.2794 0.1778)
							(mid -0.249642 0.249642)
							(end -0.1778 0.2794)
						)
						(arc
							(start 0.1778 0.2794)
							(mid 0.249642 0.249642)
							(end 0.2794 0.1778)
						)
						(arc
							(start 0.2794 -0.1778)
							(mid 0.249642 -0.249642)
							(end 0.1778 -0.2794)
						)
					)
					(width 0)
					(fill yes)
				)
			)
		)
	)
	(footprint ""
		(layer "F.Cu")
		(at 202.3364 -18.8468 -90)
		(property "Reference" "R702"
			(at 0 0 270)
			(layer "F.SilkS")
			(hide yes)
			(effects
				(font
					(size 1.27 1.27)
				)
			)
		)
		(property "Value" "4K7R2F-GP"
			(at 0.064008 -3.993896 270)
			(unlocked yes)
			(layer "F.Fab")
			(hide yes)
			(effects
				(font
					(size 1.016 1.016)
					(thickness 0.1524)
				)
			)
		)
		(property "Device Type" "R402H16"
			(at 0.064008 -5.517896 270)
			(unlocked yes)
			(layer "F.Fab")
			(hide yes)
			(effects
				(font
					(size 1.016 1.016)
					(thickness 0.1524)
				)
			)
		)
		(duplicate_pad_numbers_are_jumpers no)
		(fp_line
			(start -0.508 -0.9398)
			(end -0.508 0.9398)
			(stroke
				(width 0.1524)
				(type default)
			)
			(layer "F.SilkS")
		)
		(fp_line
			(start 0.508 -0.9398)
			(end -0.508 -0.9398)
			(stroke
				(width 0.1524)
				(type default)
			)
			(layer "F.SilkS")
		)
		(fp_rect
			(start -0.508 0.9398)
			(end 0.508 -0.9398)
			(stroke
				(width 0)
				(type default)
			)
			(fill no)
			(layer "F.CrtYd")
		)
		(fp_rect
			(start -0.508 0.9398)
			(end 0.508 -0.9398)
			(stroke
				(width 0)
				(type default)
			)
			(fill no)
			(layer "F.Fab")
		)
		(pad "1" smd custom
			(at 0 -0.4445 270)
			(size 0.1397 0.1397)
			(layers "F.Cu" "F.Mask" "F.Paste")
			(net "MINISAS_CN16_C_I2C_INT#")
			(options
				(clearance outline)
				(anchor circle)
			)
			(primitives
				(gr_poly
					(pts
						(arc
							(start -0.1778 -0.2794)
							(mid -0.249642 -0.249642)
							(end -0.2794 -0.1778)
						)
						(arc
							(start -0.2794 0.1778)
							(mid -0.249642 0.249642)
							(end -0.1778 0.2794)
						)
						(arc
							(start 0.1778 0.2794)
							(mid 0.249642 0.249642)
							(end 0.2794 0.1778)
						)
						(arc
							(start 0.2794 -0.1778)
							(mid 0.249642 -0.249642)
							(end 0.1778 -0.2794)
						)
					)
					(width 0)
					(fill yes)
				)
			)
		)
		(pad "2" smd custom
			(at 0 0.4445 270)
			(size 0.1397 0.1397)
			(layers "F.Cu" "F.Mask" "F.Paste")
			(net "P3V3_STBY")
			(options
				(clearance outline)
				(anchor circle)
			)
			(primitives
				(gr_poly
					(pts
						(arc
							(start -0.1778 -0.2794)
							(mid -0.249642 -0.249642)
							(end -0.2794 -0.1778)
						)
						(arc
							(start -0.2794 0.1778)
							(mid -0.249642 0.249642)
							(end -0.1778 0.2794)
						)
						(arc
							(start 0.1778 0.2794)
							(mid 0.249642 0.249642)
							(end 0.2794 0.1778)
						)
						(arc
							(start 0.2794 -0.1778)
							(mid 0.249642 -0.249642)
							(end 0.1778 -0.2794)
						)
					)
					(width 0)
					(fill yes)
				)
			)
		)
	)
	(footprint ""
		(layer "F.Cu")
		(at 190.600076 -17.500092 -90)
		(property "Reference" "LED20"
			(at 0 0 270)
			(layer "F.SilkS")
			(hide yes)
			(effects
				(font
					(size 1.27 1.27)
				)
			)
		)
		(property "Value" "LED-YG-51-GP"
			(at -2.6924 -1.4224 270)
			(unlocked yes)
			(layer "F.Fab")
			(hide yes)
			(effects
				(font
					(size 1.016 1.016)
					(thickness 0.1524)
				)
			)
		)
		(property "Device Type" "LED1608AKH40"
			(at -2.6924 -2.9464 270)
			(unlocked yes)
			(layer "F.Fab")
			(hide yes)
			(effects
				(font
					(size 1.016 1.016)
					(thickness 0.1524)
				)
			)
		)
		(duplicate_pad_numbers_are_jumpers no)
		(fp_line
			(start -0.7493 1.651)
			(end -0.7493 1.1811)
			(stroke
				(width 0.3302)
				(type default)
			)
			(layer "F.SilkS")
		)
		(fp_line
			(start 0.7493 1.651)
			(end 0.7493 1.1811)
			(stroke
				(width 0.3302)
				(type default)
			)
			(layer "F.SilkS")
		)
		(fp_line
			(start -0.5969 1.5494)
			(end 0.5842 1.5494)
			(stroke
				(width 0.508)
				(type default)
			)
			(layer "F.SilkS")
		)
		(fp_line
			(start -0.6604 1.3716)
			(end -0.6604 -1.3716)
			(stroke
				(width 0.1524)
				(type default)
			)
			(layer "F.SilkS")
		)
		(fp_line
			(start 0.6604 1.3716)
			(end -0.6604 1.3716)
			(stroke
				(width 0.1524)
				(type default)
			)
			(layer "F.SilkS")
		)
		(fp_line
			(start -0.6604 -1.3716)
			(end 0.6604 -1.3716)
			(stroke
				(width 0.1524)
				(type default)
			)
			(layer "F.SilkS")
		)
		(fp_line
			(start 0.6604 -1.3716)
			(end 0.6604 1.3716)
			(stroke
				(width 0.1524)
				(type default)
			)
			(layer "F.SilkS")
		)
		(fp_rect
			(start -0.6223 1.3335)
			(end 0.6223 -1.3335)
			(stroke
				(width 0)
				(type default)
			)
			(fill no)
			(layer "F.CrtYd")
		)
		(fp_rect
			(start -0.6223 1.3335)
			(end 0.6223 -1.3335)
			(stroke
				(width 0)
				(type default)
			)
			(fill no)
			(layer "F.Fab")
		)
		(pad "A" smd custom
			(at 0 -0.762 270)
			(size 0.2159 0.2159)
			(layers "F.Cu" "F.Mask" "F.Paste")
			(net "LED_R_11")
			(options
				(clearance outline)
				(anchor circle)
			)
			(primitives
				(gr_poly
					(pts
						(arc
							(start -0.3302 -0.4318)
							(mid -0.402042 -0.402042)
							(end -0.4318 -0.3302)
						)
						(arc
							(start -0.4318 0.3302)
							(mid -0.402042 0.402042)
							(end -0.3302 0.4318)
						)
						(arc
							(start 0.3302 0.4318)
							(mid 0.402042 0.402042)
							(end 0.4318 0.3302)
						)
						(arc
							(start 0.4318 -0.3302)
							(mid 0.402042 -0.402042)
							(end 0.3302 -0.4318)
						)
					)
					(width 0)
					(fill yes)
				)
			)
		)
		(pad "K" smd custom
			(at 0 0.762 270)
			(size 0.2159 0.2159)
			(layers "F.Cu" "F.Mask" "F.Paste")
			(net "LED_Q_11")
			(options
				(clearance outline)
				(anchor circle)
			)
			(primitives
				(gr_poly
					(pts
						(arc
							(start -0.3302 -0.4318)
							(mid -0.402042 -0.402042)
							(end -0.4318 -0.3302)
						)
						(arc
							(start -0.4318 0.3302)
							(mid -0.402042 0.402042)
							(end -0.3302 0.4318)
						)
						(arc
							(start 0.3302 0.4318)
							(mid 0.402042 0.402042)
							(end 0.4318 0.3302)
						)
						(arc
							(start 0.4318 -0.3302)
							(mid 0.402042 -0.402042)
							(end 0.3302 -0.4318)
						)
					)
					(width 0)
					(fill yes)
				)
			)
		)
	)
	(footprint ""
		(layer "F.Cu")
		(at 309.055008 -33.48101 180)
		(property "Reference" "R721"
			(at 0 0 180)
			(layer "F.SilkS")
			(hide yes)
			(effects
				(font
					(size 1.27 1.27)
				)
			)
		)
		(property "Value" "0R2J-2-GP"
			(at 0.064008 -3.993896 180)
			(unlocked yes)
			(layer "F.Fab")
			(hide yes)
			(effects
				(font
					(size 1.016 1.016)
					(thickness 0.1524)
				)
			)
		)
		(property "Device Type" "R402H16"
			(at 0.064008 -5.517896 180)
			(unlocked yes)
			(layer "F.Fab")
			(hide yes)
			(effects
				(font
					(size 1.016 1.016)
					(thickness 0.1524)
				)
			)
		)
		(duplicate_pad_numbers_are_jumpers no)
		(fp_line
			(start 0.508 -0.9398)
			(end -0.508 -0.9398)
			(stroke
				(width 0.1524)
				(type default)
			)
			(layer "F.SilkS")
		)
		(fp_line
			(start -0.508 -0.9398)
			(end -0.508 0.9398)
			(stroke
				(width 0.1524)
				(type default)
			)
			(layer "F.SilkS")
		)
		(fp_rect
			(start -0.508 0.9398)
			(end 0.508 -0.9398)
			(stroke
				(width 0)
				(type default)
			)
			(fill no)
			(layer "F.CrtYd")
		)
		(fp_rect
			(start -0.508 0.9398)
			(end 0.508 -0.9398)
			(stroke
				(width 0)
				(type default)
			)
			(fill no)
			(layer "F.Fab")
		)
		(pad "1" smd custom
			(at 0 -0.4445 180)
			(size 0.1397 0.1397)
			(layers "F.Cu" "F.Mask" "F.Paste")
			(net "8644_USB_DP7")
			(options
				(clearance outline)
				(anchor circle)
			)
			(primitives
				(gr_poly
					(pts
						(arc
							(start -0.1778 -0.2794)
							(mid -0.249642 -0.249642)
							(end -0.2794 -0.1778)
						)
						(arc
							(start -0.2794 0.1778)
							(mid -0.249642 0.249642)
							(end -0.1778 0.2794)
						)
						(arc
							(start 0.1778 0.2794)
							(mid 0.249642 0.249642)
							(end 0.2794 0.1778)
						)
						(arc
							(start 0.2794 -0.1778)
							(mid 0.249642 -0.249642)
							(end 0.1778 -0.2794)
						)
					)
					(width 0)
					(fill yes)
				)
			)
		)
		(pad "2" smd custom
			(at 0 0.4445 180)
			(size 0.1397 0.1397)
			(layers "F.Cu" "F.Mask" "F.Paste")
			(net "P3V3_STBY")
			(options
				(clearance outline)
				(anchor circle)
			)
			(primitives
				(gr_poly
					(pts
						(arc
							(start -0.1778 -0.2794)
							(mid -0.249642 -0.249642)
							(end -0.2794 -0.1778)
						)
						(arc
							(start -0.2794 0.1778)
							(mid -0.249642 0.249642)
							(end -0.1778 0.2794)
						)
						(arc
							(start 0.1778 0.2794)
							(mid 0.249642 0.249642)
							(end 0.2794 0.1778)
						)
						(arc
							(start 0.2794 -0.1778)
							(mid 0.249642 -0.249642)
							(end 0.1778 -0.2794)
						)
					)
					(width 0)
					(fill yes)
				)
			)
		)
	)
	(footprint ""
		(layer "F.Cu")
		(at 266.823444 -2.846832 90)
		(property "Reference" "R641"
			(at 0 0 90)
			(layer "F.SilkS")
			(hide yes)
			(effects
				(font
					(size 1.27 1.27)
				)
			)
		)
		(property "Value" "4K7R2F-GP"
			(at 0.064008 -3.993896 90)
			(unlocked yes)
			(layer "F.Fab")
			(hide yes)
			(effects
				(font
					(size 1.016 1.016)
					(thickness 0.1524)
				)
			)
		)
		(property "Device Type" "R402H16"
			(at 0.064008 -5.517896 90)
			(unlocked yes)
			(layer "F.Fab")
			(hide yes)
			(effects
				(font
					(size 1.016 1.016)
					(thickness 0.1524)
				)
			)
		)
		(duplicate_pad_numbers_are_jumpers no)
		(fp_line
			(start 0.508 -0.9398)
			(end -0.508 -0.9398)
			(stroke
				(width 0.1524)
				(type default)
			)
			(layer "F.SilkS")
		)
		(fp_line
			(start -0.508 -0.9398)
			(end -0.508 0.9398)
			(stroke
				(width 0.1524)
				(type default)
			)
			(layer "F.SilkS")
		)
		(fp_rect
			(start -0.508 0.9398)
			(end 0.508 -0.9398)
			(stroke
				(width 0)
				(type default)
			)
			(fill no)
			(layer "F.CrtYd")
		)
		(fp_rect
			(start -0.508 0.9398)
			(end 0.508 -0.9398)
			(stroke
				(width 0)
				(type default)
			)
			(fill no)
			(layer "F.Fab")
		)
		(pad "1" smd custom
			(at 0 -0.4445 90)
			(size 0.1397 0.1397)
			(layers "F.Cu" "F.Mask" "F.Paste")
			(net "SLIDE_SW_PMC_RST#")
			(options
				(clearance outline)
				(anchor circle)
			)
			(primitives
				(gr_poly
					(pts
						(arc
							(start -0.1778 -0.2794)
							(mid -0.249642 -0.249642)
							(end -0.2794 -0.1778)
						)
						(arc
							(start -0.2794 0.1778)
							(mid -0.249642 0.249642)
							(end -0.1778 0.2794)
						)
						(arc
							(start 0.1778 0.2794)
							(mid 0.249642 0.249642)
							(end 0.2794 0.1778)
						)
						(arc
							(start 0.2794 -0.1778)
							(mid 0.249642 -0.249642)
							(end 0.1778 -0.2794)
						)
					)
					(width 0)
					(fill yes)
				)
			)
		)
		(pad "2" smd custom
			(at 0 0.4445 90)
			(size 0.1397 0.1397)
			(layers "F.Cu" "F.Mask" "F.Paste")
			(net "P3V3_STBY")
			(options
				(clearance outline)
				(anchor circle)
			)
			(primitives
				(gr_poly
					(pts
						(arc
							(start -0.1778 -0.2794)
							(mid -0.249642 -0.249642)
							(end -0.2794 -0.1778)
						)
						(arc
							(start -0.2794 0.1778)
							(mid -0.249642 0.249642)
							(end -0.1778 0.2794)
						)
						(arc
							(start 0.1778 0.2794)
							(mid 0.249642 0.249642)
							(end 0.2794 0.1778)
						)
						(arc
							(start 0.2794 -0.1778)
							(mid 0.249642 -0.249642)
							(end 0.1778 -0.2794)
						)
					)
					(width 0)
					(fill yes)
				)
			)
		)
	)
	(footprint ""
		(layer "F.Cu")
		(at 5.588 -43.942)
		(property "Reference" "C330"
			(at 0 0 0)
			(layer "F.SilkS")
			(hide yes)
			(effects
				(font
					(size 1.27 1.27)
				)
			)
		)
		(property "Value" "SCD1U16V2KX-3GP"
			(at 1.1811 -2.7051 0)
			(unlocked yes)
			(layer "F.Fab")
			(hide yes)
			(effects
				(font
					(size 1.016 1.016)
					(thickness 0.1524)
				)
			)
		)
		(property "Device Type" "C402H22"
			(at 1.1811 -4.2291 0)
			(unlocked yes)
			(layer "F.Fab")
			(hide yes)
			(effects
				(font
					(size 1.016 1.016)
					(thickness 0.1524)
				)
			)
		)
		(duplicate_pad_numbers_are_jumpers no)
		(fp_rect
			(start -0.4318 0.9525)
			(end 0.4318 -0.9525)
			(stroke
				(width 0)
				(type default)
			)
			(fill no)
			(layer "F.CrtYd")
		)
		(fp_rect
			(start -0.4318 0.9525)
			(end 0.4318 -0.9525)
			(stroke
				(width 0)
				(type default)
			)
			(fill no)
			(layer "F.Fab")
		)
		(pad "1" smd custom
			(at 0 -0.4445)
			(size 0.1524 0.1524)
			(layers "F.Cu" "F.Mask" "F.Paste")
			(net "NIC0_CT_POWER")
			(options
				(clearance outline)
				(anchor circle)
			)
			(primitives
				(gr_poly
					(pts
						(arc
							(start 0.3048 -0.2032)
							(mid 0.275042 -0.275042)
							(end 0.2032 -0.3048)
						)
						(arc
							(start -0.2032 -0.3048)
							(mid -0.275042 -0.275042)
							(end -0.3048 -0.2032)
						)
						(arc
							(start -0.3048 0.2032)
							(mid -0.275042 0.275042)
							(end -0.2032 0.3048)
						)
						(arc
							(start 0.2032 0.3048)
							(mid 0.275042 0.275042)
							(end 0.3048 0.2032)
						)
					)
					(width 0)
					(fill yes)
				)
			)
		)
		(pad "2" smd custom
			(at 0 0.4445)
			(size 0.1524 0.1524)
			(layers "F.Cu" "F.Mask" "F.Paste")
			(net "GND")
			(options
				(clearance outline)
				(anchor circle)
			)
			(primitives
				(gr_poly
					(pts
						(arc
							(start 0.3048 -0.2032)
							(mid 0.275042 -0.275042)
							(end 0.2032 -0.3048)
						)
						(arc
							(start -0.2032 -0.3048)
							(mid -0.275042 -0.275042)
							(end -0.3048 -0.2032)
						)
						(arc
							(start -0.3048 0.2032)
							(mid -0.275042 0.275042)
							(end -0.2032 0.3048)
						)
						(arc
							(start 0.2032 0.3048)
							(mid 0.275042 0.275042)
							(end 0.3048 0.2032)
						)
					)
					(width 0)
					(fill yes)
				)
			)
		)
	)
	(footprint ""
		(layer "F.Cu")
		(at 25.371298 -87.01405)
		(property "Reference" "R416"
			(at 0 0 0)
			(layer "F.SilkS")
			(hide yes)
			(effects
				(font
					(size 1.27 1.27)
				)
			)
		)
		(property "Value" "0R2J-2-GP"
			(at 0.064008 -3.993896 0)
			(unlocked yes)
			(layer "F.Fab")
			(hide yes)
			(effects
				(font
					(size 1.016 1.016)
					(thickness 0.1524)
				)
			)
		)
		(property "Device Type" "R402H16"
			(at 0.064008 -5.517896 0)
			(unlocked yes)
			(layer "F.Fab")
			(hide yes)
			(effects
				(font
					(size 1.016 1.016)
					(thickness 0.1524)
				)
			)
		)
		(duplicate_pad_numbers_are_jumpers no)
		(fp_line
			(start -0.508 -0.9398)
			(end -0.508 0.9398)
			(stroke
				(width 0.1524)
				(type default)
			)
			(layer "F.SilkS")
		)
		(fp_line
			(start 0.508 -0.9398)
			(end -0.508 -0.9398)
			(stroke
				(width 0.1524)
				(type default)
			)
			(layer "F.SilkS")
		)
		(fp_rect
			(start -0.508 0.9398)
			(end 0.508 -0.9398)
			(stroke
				(width 0)
				(type default)
			)
			(fill no)
			(layer "F.CrtYd")
		)
		(fp_rect
			(start -0.508 0.9398)
			(end 0.508 -0.9398)
			(stroke
				(width 0)
				(type default)
			)
			(fill no)
			(layer "F.Fab")
		)
		(pad "1" smd custom
			(at 0 -0.4445)
			(size 0.1397 0.1397)
			(layers "F.Cu" "F.Mask" "F.Paste")
			(net "BMC_PERST#_R")
			(options
				(clearance outline)
				(anchor circle)
			)
			(primitives
				(gr_poly
					(pts
						(arc
							(start -0.1778 -0.2794)
							(mid -0.249642 -0.249642)
							(end -0.2794 -0.1778)
						)
						(arc
							(start -0.2794 0.1778)
							(mid -0.249642 0.249642)
							(end -0.1778 0.2794)
						)
						(arc
							(start 0.1778 0.2794)
							(mid 0.249642 0.249642)
							(end 0.2794 0.1778)
						)
						(arc
							(start 0.2794 -0.1778)
							(mid 0.249642 -0.249642)
							(end 0.1778 -0.2794)
						)
					)
					(width 0)
					(fill yes)
				)
			)
		)
		(pad "2" smd custom
			(at 0 0.4445)
			(size 0.1397 0.1397)
			(layers "F.Cu" "F.Mask" "F.Paste")
			(net "PHY_RESET_N")
			(options
				(clearance outline)
				(anchor circle)
			)
			(primitives
				(gr_poly
					(pts
						(arc
							(start -0.1778 -0.2794)
							(mid -0.249642 -0.249642)
							(end -0.2794 -0.1778)
						)
						(arc
							(start -0.2794 0.1778)
							(mid -0.249642 0.249642)
							(end -0.1778 0.2794)
						)
						(arc
							(start 0.1778 0.2794)
							(mid 0.249642 0.249642)
							(end 0.2794 0.1778)
						)
						(arc
							(start 0.2794 -0.1778)
							(mid 0.249642 -0.249642)
							(end 0.1778 -0.2794)
						)
					)
					(width 0)
					(fill yes)
				)
			)
		)
	)
	(footprint ""
		(layer "F.Cu")
		(at 341.376 -62.611 -90)
		(property "Reference" "PC172"
			(at 0 0 270)
			(layer "F.SilkS")
			(hide yes)
			(effects
				(font
					(size 1.27 1.27)
				)
			)
		)
		(property "Value" "SCD1U50V3KX-GP"
			(at 0 -2.8194 270)
			(unlocked yes)
			(layer "F.Fab")
			(hide yes)
			(effects
				(font
					(size 1.016 1.016)
					(thickness 0.1524)
				)
			)
		)
		(property "Device Type" "C603H36"
			(at 0 -4.3434 270)
			(unlocked yes)
			(layer "F.Fab")
			(hide yes)
			(effects
				(font
					(size 1.016 1.016)
					(thickness 0.1524)
				)
			)
		)
		(duplicate_pad_numbers_are_jumpers no)
		(fp_line
			(start 0.508 0)
			(end -0.508 0)
			(stroke
				(width 0.2032)
				(type default)
			)
			(layer "F.SilkS")
		)
		(fp_rect
			(start -0.5842 1.3335)
			(end 0.5842 -1.3335)
			(stroke
				(width 0)
				(type default)
			)
			(fill no)
			(layer "F.CrtYd")
		)
		(fp_rect
			(start -0.5842 1.3335)
			(end 0.5842 -1.3335)
			(stroke
				(width 0)
				(type default)
			)
			(fill no)
			(layer "F.Fab")
		)
		(pad "1" smd custom
			(at 0 -0.762 270)
			(size 0.2159 0.2159)
			(layers "F.Cu" "F.Mask" "F.Paste")
			(net "P0V9_E_VIN")
			(options
				(clearance outline)
				(anchor circle)
			)
			(primitives
				(gr_poly
					(pts
						(arc
							(start -0.3302 -0.4318)
							(mid -0.402042 -0.402042)
							(end -0.4318 -0.3302)
						)
						(arc
							(start -0.4318 0.3302)
							(mid -0.402042 0.402042)
							(end -0.3302 0.4318)
						)
						(arc
							(start 0.3302 0.4318)
							(mid 0.402042 0.402042)
							(end 0.4318 0.3302)
						)
						(arc
							(start 0.4318 -0.3302)
							(mid 0.402042 -0.402042)
							(end 0.3302 -0.4318)
						)
					)
					(width 0)
					(fill yes)
				)
			)
		)
		(pad "2" smd custom
			(at 0 0.762 270)
			(size 0.2159 0.2159)
			(layers "F.Cu" "F.Mask" "F.Paste")
			(net "GND")
			(options
				(clearance outline)
				(anchor circle)
			)
			(primitives
				(gr_poly
					(pts
						(arc
							(start -0.3302 -0.4318)
							(mid -0.402042 -0.402042)
							(end -0.4318 -0.3302)
						)
						(arc
							(start -0.4318 0.3302)
							(mid -0.402042 0.402042)
							(end -0.3302 0.4318)
						)
						(arc
							(start 0.3302 0.4318)
							(mid 0.402042 0.402042)
							(end 0.4318 0.3302)
						)
						(arc
							(start 0.4318 -0.3302)
							(mid 0.402042 -0.402042)
							(end 0.3302 -0.4318)
						)
					)
					(width 0)
					(fill yes)
				)
			)
		)
	)
	(footprint ""
		(layer "F.Cu")
		(at 43.6118 -183.2356 180)
		(property "Reference" "R867"
			(at 0 0 180)
			(layer "F.SilkS")
			(hide yes)
			(effects
				(font
					(size 1.27 1.27)
				)
			)
		)
		(property "Value" "0R2J-2-GP"
			(at 0.064008 -3.993896 180)
			(unlocked yes)
			(layer "F.Fab")
			(hide yes)
			(effects
				(font
					(size 1.016 1.016)
					(thickness 0.1524)
				)
			)
		)
		(property "Device Type" "R402H16"
			(at 0.064008 -5.517896 180)
			(unlocked yes)
			(layer "F.Fab")
			(hide yes)
			(effects
				(font
					(size 1.016 1.016)
					(thickness 0.1524)
				)
			)
		)
		(duplicate_pad_numbers_are_jumpers no)
		(fp_line
			(start 0.508 -0.9398)
			(end -0.508 -0.9398)
			(stroke
				(width 0.1524)
				(type default)
			)
			(layer "F.SilkS")
		)
		(fp_line
			(start -0.508 -0.9398)
			(end -0.508 0.9398)
			(stroke
				(width 0.1524)
				(type default)
			)
			(layer "F.SilkS")
		)
		(fp_rect
			(start -0.508 0.9398)
			(end 0.508 -0.9398)
			(stroke
				(width 0)
				(type default)
			)
			(fill no)
			(layer "F.CrtYd")
		)
		(fp_rect
			(start -0.508 0.9398)
			(end 0.508 -0.9398)
			(stroke
				(width 0)
				(type default)
			)
			(fill no)
			(layer "F.Fab")
		)
		(pad "1" smd custom
			(at 0 -0.4445 180)
			(size 0.1397 0.1397)
			(layers "F.Cu" "F.Mask" "F.Paste")
			(net "BMC_I2C9_CLKBUF2_SCL")
			(options
				(clearance outline)
				(anchor circle)
			)
			(primitives
				(gr_poly
					(pts
						(arc
							(start -0.1778 -0.2794)
							(mid -0.249642 -0.249642)
							(end -0.2794 -0.1778)
						)
						(arc
							(start -0.2794 0.1778)
							(mid -0.249642 0.249642)
							(end -0.1778 0.2794)
						)
						(arc
							(start 0.1778 0.2794)
							(mid 0.249642 0.249642)
							(end 0.2794 0.1778)
						)
						(arc
							(start 0.2794 -0.1778)
							(mid 0.249642 -0.249642)
							(end 0.1778 -0.2794)
						)
					)
					(width 0)
					(fill yes)
				)
			)
		)
		(pad "2" smd custom
			(at 0 0.4445 180)
			(size 0.1397 0.1397)
			(layers "F.Cu" "F.Mask" "F.Paste")
			(net "BMC_I2C9_CLKBUF2_SCL_R")
			(options
				(clearance outline)
				(anchor circle)
			)
			(primitives
				(gr_poly
					(pts
						(arc
							(start -0.1778 -0.2794)
							(mid -0.249642 -0.249642)
							(end -0.2794 -0.1778)
						)
						(arc
							(start -0.2794 0.1778)
							(mid -0.249642 0.249642)
							(end -0.1778 0.2794)
						)
						(arc
							(start 0.1778 0.2794)
							(mid 0.249642 0.249642)
							(end 0.2794 0.1778)
						)
						(arc
							(start 0.2794 -0.1778)
							(mid 0.249642 -0.249642)
							(end 0.1778 -0.2794)
						)
					)
					(width 0)
					(fill yes)
				)
			)
		)
	)
	(footprint ""
		(layer "F.Cu")
		(at 231.394 -23.241)
		(property "Reference" "R820"
			(at 0 0 0)
			(layer "F.SilkS")
			(hide yes)
			(effects
				(font
					(size 1.27 1.27)
				)
			)
		)
		(property "Value" "4K7R2F-GP"
			(at 0.064008 -3.993896 0)
			(unlocked yes)
			(layer "F.Fab")
			(hide yes)
			(effects
				(font
					(size 1.016 1.016)
					(thickness 0.1524)
				)
			)
		)
		(property "Device Type" "R402H16"
			(at 0.064008 -5.517896 0)
			(unlocked yes)
			(layer "F.Fab")
			(hide yes)
			(effects
				(font
					(size 1.016 1.016)
					(thickness 0.1524)
				)
			)
		)
		(duplicate_pad_numbers_are_jumpers no)
		(fp_line
			(start -0.508 -0.9398)
			(end -0.508 0.9398)
			(stroke
				(width 0.1524)
				(type default)
			)
			(layer "F.SilkS")
		)
		(fp_line
			(start 0.508 -0.9398)
			(end -0.508 -0.9398)
			(stroke
				(width 0.1524)
				(type default)
			)
			(layer "F.SilkS")
		)
		(fp_rect
			(start -0.508 0.9398)
			(end 0.508 -0.9398)
			(stroke
				(width 0)
				(type default)
			)
			(fill no)
			(layer "F.CrtYd")
		)
		(fp_rect
			(start -0.508 0.9398)
			(end 0.508 -0.9398)
			(stroke
				(width 0)
				(type default)
			)
			(fill no)
			(layer "F.Fab")
		)
		(pad "1" smd custom
			(at 0 -0.4445)
			(size 0.1397 0.1397)
			(layers "F.Cu" "F.Mask" "F.Paste")
			(net "GND")
			(options
				(clearance outline)
				(anchor circle)
			)
			(primitives
				(gr_poly
					(pts
						(arc
							(start -0.1778 -0.2794)
							(mid -0.249642 -0.249642)
							(end -0.2794 -0.1778)
						)
						(arc
							(start -0.2794 0.1778)
							(mid -0.249642 0.249642)
							(end -0.1778 0.2794)
						)
						(arc
							(start 0.1778 0.2794)
							(mid 0.249642 0.249642)
							(end 0.2794 0.1778)
						)
						(arc
							(start 0.2794 -0.1778)
							(mid 0.249642 -0.249642)
							(end 0.1778 -0.2794)
						)
					)
					(width 0)
					(fill yes)
				)
			)
		)
		(pad "2" smd custom
			(at 0 0.4445)
			(size 0.1397 0.1397)
			(layers "F.Cu" "F.Mask" "F.Paste")
			(net "BOOTSTRAP10")
			(options
				(clearance outline)
				(anchor circle)
			)
			(primitives
				(gr_poly
					(pts
						(arc
							(start -0.1778 -0.2794)
							(mid -0.249642 -0.249642)
							(end -0.2794 -0.1778)
						)
						(arc
							(start -0.2794 0.1778)
							(mid -0.249642 0.249642)
							(end -0.1778 0.2794)
						)
						(arc
							(start 0.1778 0.2794)
							(mid 0.249642 0.249642)
							(end 0.2794 0.1778)
						)
						(arc
							(start 0.2794 -0.1778)
							(mid 0.249642 -0.249642)
							(end 0.1778 -0.2794)
						)
					)
					(width 0)
					(fill yes)
				)
			)
		)
	)
	(footprint ""
		(layer "F.Cu")
		(at 143.982186 -79.309214)
		(property "Reference" "PL10"
			(at 0 0 0)
			(layer "F.SilkS")
			(hide yes)
			(effects
				(font
					(size 1.27 1.27)
				)
			)
		)
		(property "Value" "BLM41PG600-GP"
			(at -3.690874 -7.441184 0)
			(unlocked yes)
			(layer "F.Fab")
			(hide yes)
			(effects
				(font
					(size 1.016 1.016)
					(thickness 0.1524)
				)
			)
		)
		(property "Device Type" "L451616H71"
			(at -3.690874 -5.917184 0)
			(unlocked yes)
			(layer "F.Fab")
			(hide yes)
			(effects
				(font
					(size 1.016 1.016)
					(thickness 0.1524)
				)
			)
		)
		(duplicate_pad_numbers_are_jumpers no)
		(fp_line
			(start -2.8702 -1.2954)
			(end -2.8702 1.2954)
			(stroke
				(width 0.1524)
				(type default)
			)
			(layer "F.SilkS")
		)
		(fp_line
			(start -2.8702 -1.2954)
			(end -2.8702 1.2954)
			(stroke
				(width 0.1524)
				(type default)
			)
			(layer "F.SilkS")
		)
		(fp_line
			(start -2.8702 1.2954)
			(end 2.8702 1.2954)
			(stroke
				(width 0.1524)
				(type default)
			)
			(layer "F.SilkS")
		)
		(fp_line
			(start -2.8702 1.2954)
			(end 2.8702 1.2954)
			(stroke
				(width 0.1524)
				(type default)
			)
			(layer "F.SilkS")
		)
		(fp_line
			(start 2.8702 -1.2954)
			(end -2.8702 -1.2954)
			(stroke
				(width 0.1524)
				(type default)
			)
			(layer "F.SilkS")
		)
		(fp_line
			(start 2.8702 -1.2954)
			(end -2.8702 -1.2954)
			(stroke
				(width 0.1524)
				(type default)
			)
			(layer "F.SilkS")
		)
		(fp_line
			(start 2.8702 1.2954)
			(end 2.8702 -1.2954)
			(stroke
				(width 0.1524)
				(type default)
			)
			(layer "F.SilkS")
		)
		(fp_line
			(start 2.8702 1.2954)
			(end 2.8702 -1.2954)
			(stroke
				(width 0.1524)
				(type default)
			)
			(layer "F.SilkS")
		)
		(fp_poly
			(pts
				(xy -2.8702 1.2954) (xy 2.8702 1.2954) (xy 2.8702 -1.2954) (xy -2.8702 -1.2954)
			)
			(stroke
				(width 0)
				(type default)
			)
			(fill no)
			(layer "F.CrtYd")
		)
		(fp_poly
			(pts
				(xy -2.8702 1.2954) (xy 2.8702 1.2954) (xy 2.8702 -1.2954) (xy -2.8702 -1.2954)
			)
			(stroke
				(width 0)
				(type default)
			)
			(fill no)
			(layer "F.Fab")
		)
		(pad "1" smd rect
			(at -1.9685 0)
			(size 1.3716 1.8796)
			(layers "F.Cu" "F.Mask" "F.Paste")
			(net "P12V")
		)
		(pad "2" smd rect
			(at 1.9685 0)
			(size 1.3716 1.8796)
			(layers "F.Cu" "F.Mask" "F.Paste")
			(net "P0V9_VIN")
		)
	)
	(footprint ""
		(layer "F.Cu")
		(at 281.408124 -212.420454 180)
		(property "Reference" "C96"
			(at 0 0 180)
			(layer "F.SilkS")
			(hide yes)
			(effects
				(font
					(size 1.27 1.27)
				)
			)
		)
		(property "Value" "SCD22U10V2KX-1GP"
			(at 1.1811 -2.7051 180)
			(unlocked yes)
			(layer "F.Fab")
			(hide yes)
			(effects
				(font
					(size 1.016 1.016)
					(thickness 0.1524)
				)
			)
		)
		(property "Device Type" "C402H22"
			(at 1.1811 -4.2291 180)
			(unlocked yes)
			(layer "F.Fab")
			(hide yes)
			(effects
				(font
					(size 1.016 1.016)
					(thickness 0.1524)
				)
			)
		)
		(duplicate_pad_numbers_are_jumpers no)
		(fp_rect
			(start -0.4318 0.9525)
			(end 0.4318 -0.9525)
			(stroke
				(width 0)
				(type default)
			)
			(fill no)
			(layer "F.CrtYd")
		)
		(fp_rect
			(start -0.4318 0.9525)
			(end 0.4318 -0.9525)
			(stroke
				(width 0)
				(type default)
			)
			(fill no)
			(layer "F.Fab")
		)
		(pad "1" smd custom
			(at 0 -0.4445 180)
			(size 0.1524 0.1524)
			(layers "F.Cu" "F.Mask" "F.Paste")
			(net "PCIE_TX_CAP_N32")
			(options
				(clearance outline)
				(anchor circle)
			)
			(primitives
				(gr_poly
					(pts
						(arc
							(start 0.3048 -0.2032)
							(mid 0.275042 -0.275042)
							(end 0.2032 -0.3048)
						)
						(arc
							(start -0.2032 -0.3048)
							(mid -0.275042 -0.275042)
							(end -0.3048 -0.2032)
						)
						(arc
							(start -0.3048 0.2032)
							(mid -0.275042 0.275042)
							(end -0.2032 0.3048)
						)
						(arc
							(start 0.2032 0.3048)
							(mid 0.275042 0.275042)
							(end 0.3048 0.2032)
						)
					)
					(width 0)
					(fill yes)
				)
			)
		)
		(pad "2" smd custom
			(at 0 0.4445 180)
			(size 0.1524 0.1524)
			(layers "F.Cu" "F.Mask" "F.Paste")
			(net "PCIE_TX_N32")
			(options
				(clearance outline)
				(anchor circle)
			)
			(primitives
				(gr_poly
					(pts
						(arc
							(start 0.3048 -0.2032)
							(mid 0.275042 -0.275042)
							(end 0.2032 -0.3048)
						)
						(arc
							(start -0.2032 -0.3048)
							(mid -0.275042 -0.275042)
							(end -0.3048 -0.2032)
						)
						(arc
							(start -0.3048 0.2032)
							(mid -0.275042 0.275042)
							(end -0.2032 0.3048)
						)
						(arc
							(start 0.2032 0.3048)
							(mid 0.275042 0.275042)
							(end 0.3048 0.2032)
						)
					)
					(width 0)
					(fill yes)
				)
			)
		)
	)
	(footprint ""
		(layer "F.Cu")
		(at 251.680726 -5.872734 -90)
		(property "Reference" "R269"
			(at 0 0 270)
			(layer "F.SilkS")
			(hide yes)
			(effects
				(font
					(size 1.27 1.27)
				)
			)
		)
		(property "Value" "0R2J-2-GP"
			(at 0.064008 -3.993896 270)
			(unlocked yes)
			(layer "F.Fab")
			(hide yes)
			(effects
				(font
					(size 1.016 1.016)
					(thickness 0.1524)
				)
			)
		)
		(property "Device Type" "R402H16"
			(at 0.064008 -5.517896 270)
			(unlocked yes)
			(layer "F.Fab")
			(hide yes)
			(effects
				(font
					(size 1.016 1.016)
					(thickness 0.1524)
				)
			)
		)
		(duplicate_pad_numbers_are_jumpers no)
		(fp_line
			(start -0.508 -0.9398)
			(end -0.508 0.9398)
			(stroke
				(width 0.1524)
				(type default)
			)
			(layer "F.SilkS")
		)
		(fp_line
			(start 0.508 -0.9398)
			(end -0.508 -0.9398)
			(stroke
				(width 0.1524)
				(type default)
			)
			(layer "F.SilkS")
		)
		(fp_rect
			(start -0.508 0.9398)
			(end 0.508 -0.9398)
			(stroke
				(width 0)
				(type default)
			)
			(fill no)
			(layer "F.CrtYd")
		)
		(fp_rect
			(start -0.508 0.9398)
			(end 0.508 -0.9398)
			(stroke
				(width 0)
				(type default)
			)
			(fill no)
			(layer "F.Fab")
		)
		(pad "1" smd custom
			(at 0 -0.4445 270)
			(size 0.1397 0.1397)
			(layers "F.Cu" "F.Mask" "F.Paste")
			(net "I2C_MAX6654_DAT")
			(options
				(clearance outline)
				(anchor circle)
			)
			(primitives
				(gr_poly
					(pts
						(arc
							(start -0.1778 -0.2794)
							(mid -0.249642 -0.249642)
							(end -0.2794 -0.1778)
						)
						(arc
							(start -0.2794 0.1778)
							(mid -0.249642 0.249642)
							(end -0.1778 0.2794)
						)
						(arc
							(start 0.1778 0.2794)
							(mid 0.249642 0.249642)
							(end 0.2794 0.1778)
						)
						(arc
							(start 0.2794 -0.1778)
							(mid 0.249642 -0.249642)
							(end 0.1778 -0.2794)
						)
					)
					(width 0)
					(fill yes)
				)
			)
		)
		(pad "2" smd custom
			(at 0 0.4445 270)
			(size 0.1397 0.1397)
			(layers "F.Cu" "F.Mask" "F.Paste")
			(net "BMC_I2C5_D_PEB_SDA")
			(options
				(clearance outline)
				(anchor circle)
			)
			(primitives
				(gr_poly
					(pts
						(arc
							(start -0.1778 -0.2794)
							(mid -0.249642 -0.249642)
							(end -0.2794 -0.1778)
						)
						(arc
							(start -0.2794 0.1778)
							(mid -0.249642 0.249642)
							(end -0.1778 0.2794)
						)
						(arc
							(start 0.1778 0.2794)
							(mid 0.249642 0.249642)
							(end 0.2794 0.1778)
						)
						(arc
							(start 0.2794 -0.1778)
							(mid 0.249642 -0.249642)
							(end 0.1778 -0.2794)
						)
					)
					(width 0)
					(fill yes)
				)
			)
		)
	)
	(footprint ""
		(layer "F.Cu")
		(at 5.969 -107.696 90)
		(property "Reference" "PR71"
			(at 0 0 90)
			(layer "F.SilkS")
			(hide yes)
			(effects
				(font
					(size 1.27 1.27)
				)
			)
		)
		(property "Value" "0R2J-2-GP"
			(at 0.064008 -3.993896 90)
			(unlocked yes)
			(layer "F.Fab")
			(hide yes)
			(effects
				(font
					(size 1.016 1.016)
					(thickness 0.1524)
				)
			)
		)
		(property "Device Type" "R402H16"
			(at 0.064008 -5.517896 90)
			(unlocked yes)
			(layer "F.Fab")
			(hide yes)
			(effects
				(font
					(size 1.016 1.016)
					(thickness 0.1524)
				)
			)
		)
		(duplicate_pad_numbers_are_jumpers no)
		(fp_line
			(start 0.508 -0.9398)
			(end -0.508 -0.9398)
			(stroke
				(width 0.1524)
				(type default)
			)
			(layer "F.SilkS")
		)
		(fp_line
			(start -0.508 -0.9398)
			(end -0.508 0.9398)
			(stroke
				(width 0.1524)
				(type default)
			)
			(layer "F.SilkS")
		)
		(fp_rect
			(start -0.508 0.9398)
			(end 0.508 -0.9398)
			(stroke
				(width 0)
				(type default)
			)
			(fill no)
			(layer "F.CrtYd")
		)
		(fp_rect
			(start -0.508 0.9398)
			(end 0.508 -0.9398)
			(stroke
				(width 0)
				(type default)
			)
			(fill no)
			(layer "F.Fab")
		)
		(pad "1" smd custom
			(at 0 -0.4445 90)
			(size 0.1397 0.1397)
			(layers "F.Cu" "F.Mask" "F.Paste")
			(net "P5V_STBY")
			(options
				(clearance outline)
				(anchor circle)
			)
			(primitives
				(gr_poly
					(pts
						(arc
							(start -0.1778 -0.2794)
							(mid -0.249642 -0.249642)
							(end -0.2794 -0.1778)
						)
						(arc
							(start -0.2794 0.1778)
							(mid -0.249642 0.249642)
							(end -0.1778 0.2794)
						)
						(arc
							(start 0.1778 0.2794)
							(mid 0.249642 0.249642)
							(end 0.2794 0.1778)
						)
						(arc
							(start 0.2794 -0.1778)
							(mid 0.249642 -0.249642)
							(end 0.1778 -0.2794)
						)
					)
					(width 0)
					(fill yes)
				)
			)
		)
		(pad "2" smd custom
			(at 0 0.4445 90)
			(size 0.1397 0.1397)
			(layers "F.Cu" "F.Mask" "F.Paste")
			(net "VR_P1V26_STBY_BIAS")
			(options
				(clearance outline)
				(anchor circle)
			)
			(primitives
				(gr_poly
					(pts
						(arc
							(start -0.1778 -0.2794)
							(mid -0.249642 -0.249642)
							(end -0.2794 -0.1778)
						)
						(arc
							(start -0.2794 0.1778)
							(mid -0.249642 0.249642)
							(end -0.1778 0.2794)
						)
						(arc
							(start 0.1778 0.2794)
							(mid 0.249642 0.249642)
							(end 0.2794 0.1778)
						)
						(arc
							(start 0.2794 -0.1778)
							(mid 0.249642 -0.249642)
							(end 0.1778 -0.2794)
						)
					)
					(width 0)
					(fill yes)
				)
			)
		)
	)
	(footprint ""
		(layer "F.Cu")
		(at 57.0484 -30.9372)
		(property "Reference" "R570"
			(at 0 0 0)
			(layer "F.SilkS")
			(hide yes)
			(effects
				(font
					(size 1.27 1.27)
				)
			)
		)
		(property "Value" "10KR2F-2-GP"
			(at 0.064008 -3.993896 0)
			(unlocked yes)
			(layer "F.Fab")
			(hide yes)
			(effects
				(font
					(size 1.016 1.016)
					(thickness 0.1524)
				)
			)
		)
		(property "Device Type" "R402H16"
			(at 0.064008 -5.517896 0)
			(unlocked yes)
			(layer "F.Fab")
			(hide yes)
			(effects
				(font
					(size 1.016 1.016)
					(thickness 0.1524)
				)
			)
		)
		(duplicate_pad_numbers_are_jumpers no)
		(fp_line
			(start -0.508 -0.9398)
			(end -0.508 0.9398)
			(stroke
				(width 0.1524)
				(type default)
			)
			(layer "F.SilkS")
		)
		(fp_line
			(start 0.508 -0.9398)
			(end -0.508 -0.9398)
			(stroke
				(width 0.1524)
				(type default)
			)
			(layer "F.SilkS")
		)
		(fp_rect
			(start -0.508 0.9398)
			(end 0.508 -0.9398)
			(stroke
				(width 0)
				(type default)
			)
			(fill no)
			(layer "F.CrtYd")
		)
		(fp_rect
			(start -0.508 0.9398)
			(end 0.508 -0.9398)
			(stroke
				(width 0)
				(type default)
			)
			(fill no)
			(layer "F.Fab")
		)
		(pad "1" smd custom
			(at 0 -0.4445)
			(size 0.1397 0.1397)
			(layers "F.Cu" "F.Mask" "F.Paste")
			(net "P3V3_STBY")
			(options
				(clearance outline)
				(anchor circle)
			)
			(primitives
				(gr_poly
					(pts
						(arc
							(start -0.1778 -0.2794)
							(mid -0.249642 -0.249642)
							(end -0.2794 -0.1778)
						)
						(arc
							(start -0.2794 0.1778)
							(mid -0.249642 0.249642)
							(end -0.1778 0.2794)
						)
						(arc
							(start 0.1778 0.2794)
							(mid 0.249642 0.249642)
							(end 0.2794 0.1778)
						)
						(arc
							(start 0.2794 -0.1778)
							(mid 0.249642 -0.249642)
							(end 0.1778 -0.2794)
						)
					)
					(width 0)
					(fill yes)
				)
			)
		)
		(pad "2" smd custom
			(at 0 0.4445)
			(size 0.1397 0.1397)
			(layers "F.Cu" "F.Mask" "F.Paste")
			(net "TRAY_POWER_CRIT_N")
			(options
				(clearance outline)
				(anchor circle)
			)
			(primitives
				(gr_poly
					(pts
						(arc
							(start -0.1778 -0.2794)
							(mid -0.249642 -0.249642)
							(end -0.2794 -0.1778)
						)
						(arc
							(start -0.2794 0.1778)
							(mid -0.249642 0.249642)
							(end -0.1778 0.2794)
						)
						(arc
							(start 0.1778 0.2794)
							(mid 0.249642 0.249642)
							(end 0.2794 0.1778)
						)
						(arc
							(start 0.2794 -0.1778)
							(mid 0.249642 -0.249642)
							(end 0.1778 -0.2794)
						)
					)
					(width 0)
					(fill yes)
				)
			)
		)
	)
	(footprint ""
		(layer "F.Cu")
		(at 24.30018 -86.997794)
		(property "Reference" "R405"
			(at 0 0 0)
			(layer "F.SilkS")
			(hide yes)
			(effects
				(font
					(size 1.27 1.27)
				)
			)
		)
		(property "Value" "3K3R2F-2-GP"
			(at 0.064008 -3.993896 0)
			(unlocked yes)
			(layer "F.Fab")
			(hide yes)
			(effects
				(font
					(size 1.016 1.016)
					(thickness 0.1524)
				)
			)
		)
		(property "Device Type" "R402H16"
			(at 0.064008 -5.517896 0)
			(unlocked yes)
			(layer "F.Fab")
			(hide yes)
			(effects
				(font
					(size 1.016 1.016)
					(thickness 0.1524)
				)
			)
		)
		(duplicate_pad_numbers_are_jumpers no)
		(fp_line
			(start -0.508 -0.9398)
			(end -0.508 0.9398)
			(stroke
				(width 0.1524)
				(type default)
			)
			(layer "F.SilkS")
		)
		(fp_line
			(start 0.508 -0.9398)
			(end -0.508 -0.9398)
			(stroke
				(width 0.1524)
				(type default)
			)
			(layer "F.SilkS")
		)
		(fp_rect
			(start -0.508 0.9398)
			(end 0.508 -0.9398)
			(stroke
				(width 0)
				(type default)
			)
			(fill no)
			(layer "F.CrtYd")
		)
		(fp_rect
			(start -0.508 0.9398)
			(end 0.508 -0.9398)
			(stroke
				(width 0)
				(type default)
			)
			(fill no)
			(layer "F.Fab")
		)
		(pad "1" smd custom
			(at 0 -0.4445)
			(size 0.1397 0.1397)
			(layers "F.Cu" "F.Mask" "F.Paste")
			(net "P3V3_STBY")
			(options
				(clearance outline)
				(anchor circle)
			)
			(primitives
				(gr_poly
					(pts
						(arc
							(start -0.1778 -0.2794)
							(mid -0.249642 -0.249642)
							(end -0.2794 -0.1778)
						)
						(arc
							(start -0.2794 0.1778)
							(mid -0.249642 0.249642)
							(end -0.1778 0.2794)
						)
						(arc
							(start 0.1778 0.2794)
							(mid 0.249642 0.249642)
							(end 0.2794 0.1778)
						)
						(arc
							(start 0.2794 -0.1778)
							(mid 0.249642 -0.249642)
							(end 0.1778 -0.2794)
						)
					)
					(width 0)
					(fill yes)
				)
			)
		)
		(pad "2" smd custom
			(at 0 0.4445)
			(size 0.1397 0.1397)
			(layers "F.Cu" "F.Mask" "F.Paste")
			(net "NIC_JTMS")
			(options
				(clearance outline)
				(anchor circle)
			)
			(primitives
				(gr_poly
					(pts
						(arc
							(start -0.1778 -0.2794)
							(mid -0.249642 -0.249642)
							(end -0.2794 -0.1778)
						)
						(arc
							(start -0.2794 0.1778)
							(mid -0.249642 0.249642)
							(end -0.1778 0.2794)
						)
						(arc
							(start 0.1778 0.2794)
							(mid 0.249642 0.249642)
							(end 0.2794 0.1778)
						)
						(arc
							(start 0.2794 -0.1778)
							(mid 0.249642 -0.249642)
							(end 0.1778 -0.2794)
						)
					)
					(width 0)
					(fill yes)
				)
			)
		)
	)
	(footprint ""
		(layer "F.Cu")
		(at 256.711704 -10.988548)
		(property "Reference" "R4"
			(at 0 0 0)
			(layer "F.SilkS")
			(hide yes)
			(effects
				(font
					(size 1.27 1.27)
				)
			)
		)
		(property "Value" "0R2J-2-GP"
			(at 0.064008 -3.993896 0)
			(unlocked yes)
			(layer "F.Fab")
			(hide yes)
			(effects
				(font
					(size 1.016 1.016)
					(thickness 0.1524)
				)
			)
		)
		(property "Device Type" "R402H16"
			(at 0.064008 -5.517896 0)
			(unlocked yes)
			(layer "F.Fab")
			(hide yes)
			(effects
				(font
					(size 1.016 1.016)
					(thickness 0.1524)
				)
			)
		)
		(duplicate_pad_numbers_are_jumpers no)
		(fp_line
			(start -0.508 -0.9398)
			(end -0.508 0.9398)
			(stroke
				(width 0.1524)
				(type default)
			)
			(layer "F.SilkS")
		)
		(fp_line
			(start 0.508 -0.9398)
			(end -0.508 -0.9398)
			(stroke
				(width 0.1524)
				(type default)
			)
			(layer "F.SilkS")
		)
		(fp_rect
			(start -0.508 0.9398)
			(end 0.508 -0.9398)
			(stroke
				(width 0)
				(type default)
			)
			(fill no)
			(layer "F.CrtYd")
		)
		(fp_rect
			(start -0.508 0.9398)
			(end 0.508 -0.9398)
			(stroke
				(width 0)
				(type default)
			)
			(fill no)
			(layer "F.Fab")
		)
		(pad "1" smd custom
			(at 0 -0.4445)
			(size 0.1397 0.1397)
			(layers "F.Cu" "F.Mask" "F.Paste")
			(net "THERM_EMIT")
			(options
				(clearance outline)
				(anchor circle)
			)
			(primitives
				(gr_poly
					(pts
						(arc
							(start -0.1778 -0.2794)
							(mid -0.249642 -0.249642)
							(end -0.2794 -0.1778)
						)
						(arc
							(start -0.2794 0.1778)
							(mid -0.249642 0.249642)
							(end -0.1778 0.2794)
						)
						(arc
							(start 0.1778 0.2794)
							(mid 0.249642 0.249642)
							(end 0.2794 0.1778)
						)
						(arc
							(start 0.2794 -0.1778)
							(mid 0.249642 -0.249642)
							(end 0.1778 -0.2794)
						)
					)
					(width 0)
					(fill yes)
				)
			)
		)
		(pad "2" smd custom
			(at 0 0.4445)
			(size 0.1397 0.1397)
			(layers "F.Cu" "F.Mask" "F.Paste")
			(net "THERM_EMIT_R")
			(options
				(clearance outline)
				(anchor circle)
			)
			(primitives
				(gr_poly
					(pts
						(arc
							(start -0.1778 -0.2794)
							(mid -0.249642 -0.249642)
							(end -0.2794 -0.1778)
						)
						(arc
							(start -0.2794 0.1778)
							(mid -0.249642 0.249642)
							(end -0.1778 0.2794)
						)
						(arc
							(start 0.1778 0.2794)
							(mid 0.249642 0.249642)
							(end 0.2794 0.1778)
						)
						(arc
							(start 0.2794 -0.1778)
							(mid 0.249642 -0.249642)
							(end 0.1778 -0.2794)
						)
					)
					(width 0)
					(fill yes)
				)
			)
		)
	)
	(footprint ""
		(layer "F.Cu")
		(at 122.557286 -86.116414 -90)
		(property "Reference" "R5201"
			(at 0 0 270)
			(layer "F.SilkS")
			(hide yes)
			(effects
				(font
					(size 1.27 1.27)
				)
			)
		)
		(property "Value" "0R2J-2-GP"
			(at 0.064008 -3.993896 270)
			(unlocked yes)
			(layer "F.Fab")
			(hide yes)
			(effects
				(font
					(size 1.016 1.016)
					(thickness 0.1524)
				)
			)
		)
		(property "Device Type" "R402H16"
			(at 0.064008 -5.517896 270)
			(unlocked yes)
			(layer "F.Fab")
			(hide yes)
			(effects
				(font
					(size 1.016 1.016)
					(thickness 0.1524)
				)
			)
		)
		(duplicate_pad_numbers_are_jumpers no)
		(fp_line
			(start -0.508 -0.9398)
			(end -0.508 0.9398)
			(stroke
				(width 0.1524)
				(type default)
			)
			(layer "F.SilkS")
		)
		(fp_line
			(start 0.508 -0.9398)
			(end -0.508 -0.9398)
			(stroke
				(width 0.1524)
				(type default)
			)
			(layer "F.SilkS")
		)
		(fp_rect
			(start -0.508 0.9398)
			(end 0.508 -0.9398)
			(stroke
				(width 0)
				(type default)
			)
			(fill no)
			(layer "F.CrtYd")
		)
		(fp_rect
			(start -0.508 0.9398)
			(end 0.508 -0.9398)
			(stroke
				(width 0)
				(type default)
			)
			(fill no)
			(layer "F.Fab")
		)
		(pad "1" smd custom
			(at 0 -0.4445 270)
			(size 0.1397 0.1397)
			(layers "F.Cu" "F.Mask" "F.Paste")
			(net "RTC_I2C_SDA")
			(options
				(clearance outline)
				(anchor circle)
			)
			(primitives
				(gr_poly
					(pts
						(arc
							(start -0.1778 -0.2794)
							(mid -0.249642 -0.249642)
							(end -0.2794 -0.1778)
						)
						(arc
							(start -0.2794 0.1778)
							(mid -0.249642 0.249642)
							(end -0.1778 0.2794)
						)
						(arc
							(start 0.1778 0.2794)
							(mid 0.249642 0.249642)
							(end 0.2794 0.1778)
						)
						(arc
							(start 0.2794 -0.1778)
							(mid 0.249642 -0.249642)
							(end 0.1778 -0.2794)
						)
					)
					(width 0)
					(fill yes)
				)
			)
		)
		(pad "2" smd custom
			(at 0 0.4445 270)
			(size 0.1397 0.1397)
			(layers "F.Cu" "F.Mask" "F.Paste")
			(net "BMC_I2C5_D_PEB_SDA")
			(options
				(clearance outline)
				(anchor circle)
			)
			(primitives
				(gr_poly
					(pts
						(arc
							(start -0.1778 -0.2794)
							(mid -0.249642 -0.249642)
							(end -0.2794 -0.1778)
						)
						(arc
							(start -0.2794 0.1778)
							(mid -0.249642 0.249642)
							(end -0.1778 0.2794)
						)
						(arc
							(start 0.1778 0.2794)
							(mid 0.249642 0.249642)
							(end 0.2794 0.1778)
						)
						(arc
							(start 0.2794 -0.1778)
							(mid 0.249642 -0.249642)
							(end 0.1778 -0.2794)
						)
					)
					(width 0)
					(fill yes)
				)
			)
		)
	)
	(footprint ""
		(layer "F.Cu")
		(at 116.2558 -17.0688)
		(property "Reference" "R750"
			(at 0 0 0)
			(layer "F.SilkS")
			(hide yes)
			(effects
				(font
					(size 1.27 1.27)
				)
			)
		)
		(property "Value" "4K7R2F-GP"
			(at 0.064008 -3.993896 0)
			(unlocked yes)
			(layer "F.Fab")
			(hide yes)
			(effects
				(font
					(size 1.016 1.016)
					(thickness 0.1524)
				)
			)
		)
		(property "Device Type" "R402H16"
			(at 0.064008 -5.517896 0)
			(unlocked yes)
			(layer "F.Fab")
			(hide yes)
			(effects
				(font
					(size 1.016 1.016)
					(thickness 0.1524)
				)
			)
		)
		(duplicate_pad_numbers_are_jumpers no)
		(fp_line
			(start -0.508 -0.9398)
			(end -0.508 0.9398)
			(stroke
				(width 0.1524)
				(type default)
			)
			(layer "F.SilkS")
		)
		(fp_line
			(start 0.508 -0.9398)
			(end -0.508 -0.9398)
			(stroke
				(width 0.1524)
				(type default)
			)
			(layer "F.SilkS")
		)
		(fp_rect
			(start -0.508 0.9398)
			(end 0.508 -0.9398)
			(stroke
				(width 0)
				(type default)
			)
			(fill no)
			(layer "F.CrtYd")
		)
		(fp_rect
			(start -0.508 0.9398)
			(end 0.508 -0.9398)
			(stroke
				(width 0)
				(type default)
			)
			(fill no)
			(layer "F.Fab")
		)
		(pad "1" smd custom
			(at 0 -0.4445)
			(size 0.1397 0.1397)
			(layers "F.Cu" "F.Mask" "F.Paste")
			(net "U54_A0")
			(options
				(clearance outline)
				(anchor circle)
			)
			(primitives
				(gr_poly
					(pts
						(arc
							(start -0.1778 -0.2794)
							(mid -0.249642 -0.249642)
							(end -0.2794 -0.1778)
						)
						(arc
							(start -0.2794 0.1778)
							(mid -0.249642 0.249642)
							(end -0.1778 0.2794)
						)
						(arc
							(start 0.1778 0.2794)
							(mid 0.249642 0.249642)
							(end 0.2794 0.1778)
						)
						(arc
							(start 0.2794 -0.1778)
							(mid 0.249642 -0.249642)
							(end 0.1778 -0.2794)
						)
					)
					(width 0)
					(fill yes)
				)
			)
		)
		(pad "2" smd custom
			(at 0 0.4445)
			(size 0.1397 0.1397)
			(layers "F.Cu" "F.Mask" "F.Paste")
			(net "P3V3_STBY")
			(options
				(clearance outline)
				(anchor circle)
			)
			(primitives
				(gr_poly
					(pts
						(arc
							(start -0.1778 -0.2794)
							(mid -0.249642 -0.249642)
							(end -0.2794 -0.1778)
						)
						(arc
							(start -0.2794 0.1778)
							(mid -0.249642 0.249642)
							(end -0.1778 0.2794)
						)
						(arc
							(start 0.1778 0.2794)
							(mid 0.249642 0.249642)
							(end 0.2794 0.1778)
						)
						(arc
							(start 0.2794 -0.1778)
							(mid 0.249642 -0.249642)
							(end 0.1778 -0.2794)
						)
					)
					(width 0)
					(fill yes)
				)
			)
		)
	)
	(footprint ""
		(layer "F.Cu")
		(at 259.299202 -4.419092 90)
		(property "Reference" "SC1302"
			(at 0 0 90)
			(layer "F.SilkS")
			(hide yes)
			(effects
				(font
					(size 1.27 1.27)
				)
			)
		)
		(property "Value" "SCD1U16V2KX-3GP"
			(at 1.1811 -2.7051 90)
			(unlocked yes)
			(layer "F.Fab")
			(hide yes)
			(effects
				(font
					(size 1.016 1.016)
					(thickness 0.1524)
				)
			)
		)
		(property "Device Type" "C402H22"
			(at 1.1811 -4.2291 90)
			(unlocked yes)
			(layer "F.Fab")
			(hide yes)
			(effects
				(font
					(size 1.016 1.016)
					(thickness 0.1524)
				)
			)
		)
		(duplicate_pad_numbers_are_jumpers no)
		(fp_rect
			(start -0.4318 0.9525)
			(end 0.4318 -0.9525)
			(stroke
				(width 0)
				(type default)
			)
			(fill no)
			(layer "F.CrtYd")
		)
		(fp_rect
			(start -0.4318 0.9525)
			(end 0.4318 -0.9525)
			(stroke
				(width 0)
				(type default)
			)
			(fill no)
			(layer "F.Fab")
		)
		(pad "1" smd custom
			(at 0 -0.4445 90)
			(size 0.1524 0.1524)
			(layers "F.Cu" "F.Mask" "F.Paste")
			(net "P3V3_STBY")
			(options
				(clearance outline)
				(anchor circle)
			)
			(primitives
				(gr_poly
					(pts
						(arc
							(start 0.3048 -0.2032)
							(mid 0.275042 -0.275042)
							(end 0.2032 -0.3048)
						)
						(arc
							(start -0.2032 -0.3048)
							(mid -0.275042 -0.275042)
							(end -0.3048 -0.2032)
						)
						(arc
							(start -0.3048 0.2032)
							(mid -0.275042 0.275042)
							(end -0.2032 0.3048)
						)
						(arc
							(start 0.2032 0.3048)
							(mid 0.275042 0.275042)
							(end 0.3048 0.2032)
						)
					)
					(width 0)
					(fill yes)
				)
			)
		)
		(pad "2" smd custom
			(at 0 0.4445 90)
			(size 0.1524 0.1524)
			(layers "F.Cu" "F.Mask" "F.Paste")
			(net "GND")
			(options
				(clearance outline)
				(anchor circle)
			)
			(primitives
				(gr_poly
					(pts
						(arc
							(start 0.3048 -0.2032)
							(mid 0.275042 -0.275042)
							(end 0.2032 -0.3048)
						)
						(arc
							(start -0.2032 -0.3048)
							(mid -0.275042 -0.275042)
							(end -0.3048 -0.2032)
						)
						(arc
							(start -0.3048 0.2032)
							(mid -0.275042 0.275042)
							(end -0.2032 0.3048)
						)
						(arc
							(start 0.2032 0.3048)
							(mid 0.275042 0.275042)
							(end 0.3048 0.2032)
						)
					)
					(width 0)
					(fill yes)
				)
			)
		)
	)
	(footprint ""
		(layer "F.Cu")
		(at 27.1526 -184.4802 180)
		(property "Reference" "R468"
			(at 0 0 180)
			(layer "F.SilkS")
			(hide yes)
			(effects
				(font
					(size 1.27 1.27)
				)
			)
		)
		(property "Value" "2KR2F-3-GP"
			(at 0.064008 -3.993896 180)
			(unlocked yes)
			(layer "F.Fab")
			(hide yes)
			(effects
				(font
					(size 1.016 1.016)
					(thickness 0.1524)
				)
			)
		)
		(property "Device Type" "R402H16"
			(at 0.064008 -5.517896 180)
			(unlocked yes)
			(layer "F.Fab")
			(hide yes)
			(effects
				(font
					(size 1.016 1.016)
					(thickness 0.1524)
				)
			)
		)
		(duplicate_pad_numbers_are_jumpers no)
		(fp_line
			(start 0.508 -0.9398)
			(end -0.508 -0.9398)
			(stroke
				(width 0.1524)
				(type default)
			)
			(layer "F.SilkS")
		)
		(fp_line
			(start -0.508 -0.9398)
			(end -0.508 0.9398)
			(stroke
				(width 0.1524)
				(type default)
			)
			(layer "F.SilkS")
		)
		(fp_rect
			(start -0.508 0.9398)
			(end 0.508 -0.9398)
			(stroke
				(width 0)
				(type default)
			)
			(fill no)
			(layer "F.CrtYd")
		)
		(fp_rect
			(start -0.508 0.9398)
			(end 0.508 -0.9398)
			(stroke
				(width 0)
				(type default)
			)
			(fill no)
			(layer "F.Fab")
		)
		(pad "1" smd custom
			(at 0 -0.4445 180)
			(size 0.1397 0.1397)
			(layers "F.Cu" "F.Mask" "F.Paste")
			(net "P3V3_STBY")
			(options
				(clearance outline)
				(anchor circle)
			)
			(primitives
				(gr_poly
					(pts
						(arc
							(start -0.1778 -0.2794)
							(mid -0.249642 -0.249642)
							(end -0.2794 -0.1778)
						)
						(arc
							(start -0.2794 0.1778)
							(mid -0.249642 0.249642)
							(end -0.1778 0.2794)
						)
						(arc
							(start 0.1778 0.2794)
							(mid 0.249642 0.249642)
							(end 0.2794 0.1778)
						)
						(arc
							(start 0.2794 -0.1778)
							(mid 0.249642 -0.249642)
							(end 0.1778 -0.2794)
						)
					)
					(width 0)
					(fill yes)
				)
			)
		)
		(pad "2" smd custom
			(at 0 0.4445 180)
			(size 0.1397 0.1397)
			(layers "F.Cu" "F.Mask" "F.Paste")
			(net "BMC_I2C5_SDA_R")
			(options
				(clearance outline)
				(anchor circle)
			)
			(primitives
				(gr_poly
					(pts
						(arc
							(start -0.1778 -0.2794)
							(mid -0.249642 -0.249642)
							(end -0.2794 -0.1778)
						)
						(arc
							(start -0.2794 0.1778)
							(mid -0.249642 0.249642)
							(end -0.1778 0.2794)
						)
						(arc
							(start 0.1778 0.2794)
							(mid 0.249642 0.249642)
							(end 0.2794 0.1778)
						)
						(arc
							(start 0.2794 -0.1778)
							(mid 0.249642 -0.249642)
							(end 0.1778 -0.2794)
						)
					)
					(width 0)
					(fill yes)
				)
			)
		)
	)
	(footprint ""
		(layer "F.Cu")
		(at 155.829 -90.267282 180)
		(property "Reference" "R78"
			(at 0 0 180)
			(layer "F.SilkS")
			(hide yes)
			(effects
				(font
					(size 1.27 1.27)
				)
			)
		)
		(property "Value" "0R2J-2-GP"
			(at 0.064008 -3.993896 180)
			(unlocked yes)
			(layer "F.Fab")
			(hide yes)
			(effects
				(font
					(size 1.016 1.016)
					(thickness 0.1524)
				)
			)
		)
		(property "Device Type" "R402H16"
			(at 0.064008 -5.517896 180)
			(unlocked yes)
			(layer "F.Fab")
			(hide yes)
			(effects
				(font
					(size 1.016 1.016)
					(thickness 0.1524)
				)
			)
		)
		(duplicate_pad_numbers_are_jumpers no)
		(fp_line
			(start 0.508 -0.9398)
			(end -0.508 -0.9398)
			(stroke
				(width 0.1524)
				(type default)
			)
			(layer "F.SilkS")
		)
		(fp_line
			(start -0.508 -0.9398)
			(end -0.508 0.9398)
			(stroke
				(width 0.1524)
				(type default)
			)
			(layer "F.SilkS")
		)
		(fp_rect
			(start -0.508 0.9398)
			(end 0.508 -0.9398)
			(stroke
				(width 0)
				(type default)
			)
			(fill no)
			(layer "F.CrtYd")
		)
		(fp_rect
			(start -0.508 0.9398)
			(end 0.508 -0.9398)
			(stroke
				(width 0)
				(type default)
			)
			(fill no)
			(layer "F.Fab")
		)
		(pad "1" smd custom
			(at 0 -0.4445 180)
			(size 0.1397 0.1397)
			(layers "F.Cu" "F.Mask" "F.Paste")
			(net "XTAL_X2")
			(options
				(clearance outline)
				(anchor circle)
			)
			(primitives
				(gr_poly
					(pts
						(arc
							(start -0.1778 -0.2794)
							(mid -0.249642 -0.249642)
							(end -0.2794 -0.1778)
						)
						(arc
							(start -0.2794 0.1778)
							(mid -0.249642 0.249642)
							(end -0.1778 0.2794)
						)
						(arc
							(start 0.1778 0.2794)
							(mid 0.249642 0.249642)
							(end 0.2794 0.1778)
						)
						(arc
							(start 0.2794 -0.1778)
							(mid 0.249642 -0.249642)
							(end 0.1778 -0.2794)
						)
					)
					(width 0)
					(fill yes)
				)
			)
		)
		(pad "2" smd custom
			(at 0 0.4445 180)
			(size 0.1397 0.1397)
			(layers "F.Cu" "F.Mask" "F.Paste")
			(net "XTAL_X2_CLKGEN")
			(options
				(clearance outline)
				(anchor circle)
			)
			(primitives
				(gr_poly
					(pts
						(arc
							(start -0.1778 -0.2794)
							(mid -0.249642 -0.249642)
							(end -0.2794 -0.1778)
						)
						(arc
							(start -0.2794 0.1778)
							(mid -0.249642 0.249642)
							(end -0.1778 0.2794)
						)
						(arc
							(start 0.1778 0.2794)
							(mid 0.249642 0.249642)
							(end 0.2794 0.1778)
						)
						(arc
							(start 0.2794 -0.1778)
							(mid 0.249642 -0.249642)
							(end 0.1778 -0.2794)
						)
					)
					(width 0)
					(fill yes)
				)
			)
		)
	)
	(footprint ""
		(layer "F.Cu")
		(at 261.9756 -28.575)
		(property "Reference" "TP291"
			(at 0 0 0)
			(layer "F.SilkS")
			(hide yes)
			(effects
				(font
					(size 1.27 1.27)
				)
			)
		)
		(property "Value" "TPAD28-2-GP"
			(at -0.0127 -1.6637 0)
			(unlocked yes)
			(layer "F.Fab")
			(hide yes)
			(effects
				(font
					(size 1.016 1.016)
					(thickness 0.1524)
				)
			)
		)
		(property "Device Type" "TPAD28"
			(at -0.0127 -3.1877 0)
			(unlocked yes)
			(layer "F.Fab")
			(hide yes)
			(effects
				(font
					(size 1.016 1.016)
					(thickness 0.1524)
				)
			)
		)
		(duplicate_pad_numbers_are_jumpers no)
		(fp_poly
			(pts
				(arc
					(start 0.3556 0)
					(mid -0.3556 0)
					(end 0.3556 0)
				)
			)
			(stroke
				(width 0)
				(type default)
			)
			(fill no)
			(layer "F.CrtYd")
		)
		(fp_poly
			(pts
				(arc
					(start 0.6096 0)
					(mid -0.6096 0)
					(end 0.6096 0)
				)
			)
			(stroke
				(width 0)
				(type default)
			)
			(fill no)
			(layer "F.Fab")
		)
		(pad "1" smd circle
			(at 0 0)
			(size 0.7112 0.7112)
			(layers "F.Cu" "F.Mask" "F.Paste")
			(net "TWI_SRST#6")
		)
	)
	(footprint ""
		(layer "F.Cu")
		(at 332.39202 -212.420454 180)
		(property "Reference" "C60"
			(at 0 0 180)
			(layer "F.SilkS")
			(hide yes)
			(effects
				(font
					(size 1.27 1.27)
				)
			)
		)
		(property "Value" "SCD22U10V2KX-1GP"
			(at 1.1811 -2.7051 180)
			(unlocked yes)
			(layer "F.Fab")
			(hide yes)
			(effects
				(font
					(size 1.016 1.016)
					(thickness 0.1524)
				)
			)
		)
		(property "Device Type" "C402H22"
			(at 1.1811 -4.2291 180)
			(unlocked yes)
			(layer "F.Fab")
			(hide yes)
			(effects
				(font
					(size 1.016 1.016)
					(thickness 0.1524)
				)
			)
		)
		(duplicate_pad_numbers_are_jumpers no)
		(fp_rect
			(start -0.4318 0.9525)
			(end 0.4318 -0.9525)
			(stroke
				(width 0)
				(type default)
			)
			(fill no)
			(layer "F.CrtYd")
		)
		(fp_rect
			(start -0.4318 0.9525)
			(end 0.4318 -0.9525)
			(stroke
				(width 0)
				(type default)
			)
			(fill no)
			(layer "F.Fab")
		)
		(pad "1" smd custom
			(at 0 -0.4445 180)
			(size 0.1524 0.1524)
			(layers "F.Cu" "F.Mask" "F.Paste")
			(net "PCIE_TX_CAP_P19")
			(options
				(clearance outline)
				(anchor circle)
			)
			(primitives
				(gr_poly
					(pts
						(arc
							(start 0.3048 -0.2032)
							(mid 0.275042 -0.275042)
							(end 0.2032 -0.3048)
						)
						(arc
							(start -0.2032 -0.3048)
							(mid -0.275042 -0.275042)
							(end -0.3048 -0.2032)
						)
						(arc
							(start -0.3048 0.2032)
							(mid -0.275042 0.275042)
							(end -0.2032 0.3048)
						)
						(arc
							(start 0.2032 0.3048)
							(mid 0.275042 0.275042)
							(end 0.3048 0.2032)
						)
					)
					(width 0)
					(fill yes)
				)
			)
		)
		(pad "2" smd custom
			(at 0 0.4445 180)
			(size 0.1524 0.1524)
			(layers "F.Cu" "F.Mask" "F.Paste")
			(net "PCIE_TX_P19")
			(options
				(clearance outline)
				(anchor circle)
			)
			(primitives
				(gr_poly
					(pts
						(arc
							(start 0.3048 -0.2032)
							(mid 0.275042 -0.275042)
							(end 0.2032 -0.3048)
						)
						(arc
							(start -0.2032 -0.3048)
							(mid -0.275042 -0.275042)
							(end -0.3048 -0.2032)
						)
						(arc
							(start -0.3048 0.2032)
							(mid -0.275042 0.275042)
							(end -0.2032 0.3048)
						)
						(arc
							(start 0.2032 0.3048)
							(mid 0.275042 0.275042)
							(end 0.3048 0.2032)
						)
					)
					(width 0)
					(fill yes)
				)
			)
		)
	)
	(footprint ""
		(layer "F.Cu")
		(at 23.495 -119.761)
		(property "Reference" "R234"
			(at 0 0 0)
			(layer "F.SilkS")
			(hide yes)
			(effects
				(font
					(size 1.27 1.27)
				)
			)
		)
		(property "Value" "100KR2F-L1-GP"
			(at 0.064008 -3.993896 0)
			(unlocked yes)
			(layer "F.Fab")
			(hide yes)
			(effects
				(font
					(size 1.016 1.016)
					(thickness 0.1524)
				)
			)
		)
		(property "Device Type" "R402H16"
			(at 0.064008 -5.517896 0)
			(unlocked yes)
			(layer "F.Fab")
			(hide yes)
			(effects
				(font
					(size 1.016 1.016)
					(thickness 0.1524)
				)
			)
		)
		(duplicate_pad_numbers_are_jumpers no)
		(fp_line
			(start -0.508 -0.9398)
			(end -0.508 0.9398)
			(stroke
				(width 0.1524)
				(type default)
			)
			(layer "F.SilkS")
		)
		(fp_line
			(start 0.508 -0.9398)
			(end -0.508 -0.9398)
			(stroke
				(width 0.1524)
				(type default)
			)
			(layer "F.SilkS")
		)
		(fp_rect
			(start -0.508 0.9398)
			(end 0.508 -0.9398)
			(stroke
				(width 0)
				(type default)
			)
			(fill no)
			(layer "F.CrtYd")
		)
		(fp_rect
			(start -0.508 0.9398)
			(end 0.508 -0.9398)
			(stroke
				(width 0)
				(type default)
			)
			(fill no)
			(layer "F.Fab")
		)
		(pad "1" smd custom
			(at 0 -0.4445)
			(size 0.1397 0.1397)
			(layers "F.Cu" "F.Mask" "F.Paste")
			(net "GND")
			(options
				(clearance outline)
				(anchor circle)
			)
			(primitives
				(gr_poly
					(pts
						(arc
							(start -0.1778 -0.2794)
							(mid -0.249642 -0.249642)
							(end -0.2794 -0.1778)
						)
						(arc
							(start -0.2794 0.1778)
							(mid -0.249642 0.249642)
							(end -0.1778 0.2794)
						)
						(arc
							(start 0.1778 0.2794)
							(mid 0.249642 0.249642)
							(end 0.2794 0.1778)
						)
						(arc
							(start 0.2794 -0.1778)
							(mid 0.249642 -0.249642)
							(end 0.1778 -0.2794)
						)
					)
					(width 0)
					(fill yes)
				)
			)
		)
		(pad "2" smd custom
			(at 0 0.4445)
			(size 0.1397 0.1397)
			(layers "F.Cu" "F.Mask" "F.Paste")
			(net "TP_BMC0_LPC_LAD0")
			(options
				(clearance outline)
				(anchor circle)
			)
			(primitives
				(gr_poly
					(pts
						(arc
							(start -0.1778 -0.2794)
							(mid -0.249642 -0.249642)
							(end -0.2794 -0.1778)
						)
						(arc
							(start -0.2794 0.1778)
							(mid -0.249642 0.249642)
							(end -0.1778 0.2794)
						)
						(arc
							(start 0.1778 0.2794)
							(mid 0.249642 0.249642)
							(end 0.2794 0.1778)
						)
						(arc
							(start 0.2794 -0.1778)
							(mid 0.249642 -0.249642)
							(end 0.1778 -0.2794)
						)
					)
					(width 0)
					(fill yes)
				)
			)
		)
	)
	(footprint ""
		(layer "F.Cu")
		(at 315.722 -33.528)
		(property "Reference" "C45"
			(at 0 0 0)
			(layer "F.SilkS")
			(hide yes)
			(effects
				(font
					(size 1.27 1.27)
				)
			)
		)
		(property "Value" "SCD22U10V2KX-1GP"
			(at 1.1811 -2.7051 0)
			(unlocked yes)
			(layer "F.Fab")
			(hide yes)
			(effects
				(font
					(size 1.016 1.016)
					(thickness 0.1524)
				)
			)
		)
		(property "Device Type" "C402H22"
			(at 1.1811 -4.2291 0)
			(unlocked yes)
			(layer "F.Fab")
			(hide yes)
			(effects
				(font
					(size 1.016 1.016)
					(thickness 0.1524)
				)
			)
		)
		(duplicate_pad_numbers_are_jumpers no)
		(fp_rect
			(start -0.4318 0.9525)
			(end 0.4318 -0.9525)
			(stroke
				(width 0)
				(type default)
			)
			(fill no)
			(layer "F.CrtYd")
		)
		(fp_rect
			(start -0.4318 0.9525)
			(end 0.4318 -0.9525)
			(stroke
				(width 0)
				(type default)
			)
			(fill no)
			(layer "F.Fab")
		)
		(pad "1" smd custom
			(at 0 -0.4445)
			(size 0.1524 0.1524)
			(layers "F.Cu" "F.Mask" "F.Paste")
			(net "PCIE_TX_CAP_N11")
			(options
				(clearance outline)
				(anchor circle)
			)
			(primitives
				(gr_poly
					(pts
						(arc
							(start 0.3048 -0.2032)
							(mid 0.275042 -0.275042)
							(end 0.2032 -0.3048)
						)
						(arc
							(start -0.2032 -0.3048)
							(mid -0.275042 -0.275042)
							(end -0.3048 -0.2032)
						)
						(arc
							(start -0.3048 0.2032)
							(mid -0.275042 0.275042)
							(end -0.2032 0.3048)
						)
						(arc
							(start 0.2032 0.3048)
							(mid 0.275042 0.275042)
							(end 0.3048 0.2032)
						)
					)
					(width 0)
					(fill yes)
				)
			)
		)
		(pad "2" smd custom
			(at 0 0.4445)
			(size 0.1524 0.1524)
			(layers "F.Cu" "F.Mask" "F.Paste")
			(net "PCIE_TX_N11")
			(options
				(clearance outline)
				(anchor circle)
			)
			(primitives
				(gr_poly
					(pts
						(arc
							(start 0.3048 -0.2032)
							(mid 0.275042 -0.275042)
							(end 0.2032 -0.3048)
						)
						(arc
							(start -0.2032 -0.3048)
							(mid -0.275042 -0.275042)
							(end -0.3048 -0.2032)
						)
						(arc
							(start -0.3048 0.2032)
							(mid -0.275042 0.275042)
							(end -0.2032 0.3048)
						)
						(arc
							(start 0.2032 0.3048)
							(mid 0.275042 0.275042)
							(end 0.3048 0.2032)
						)
					)
					(width 0)
					(fill yes)
				)
			)
		)
	)
	(footprint ""
		(layer "F.Cu")
		(at 34.429954 -164.702744 90)
		(property "Reference" "R231"
			(at 0 0 90)
			(layer "F.SilkS")
			(hide yes)
			(effects
				(font
					(size 1.27 1.27)
				)
			)
		)
		(property "Value" "1KR2F-3-GP"
			(at 0.064008 -3.993896 90)
			(unlocked yes)
			(layer "F.Fab")
			(hide yes)
			(effects
				(font
					(size 1.016 1.016)
					(thickness 0.1524)
				)
			)
		)
		(property "Device Type" "R402H16"
			(at 0.064008 -5.517896 90)
			(unlocked yes)
			(layer "F.Fab")
			(hide yes)
			(effects
				(font
					(size 1.016 1.016)
					(thickness 0.1524)
				)
			)
		)
		(duplicate_pad_numbers_are_jumpers no)
		(fp_line
			(start 0.508 -0.9398)
			(end -0.508 -0.9398)
			(stroke
				(width 0.1524)
				(type default)
			)
			(layer "F.SilkS")
		)
		(fp_line
			(start -0.508 -0.9398)
			(end -0.508 0.9398)
			(stroke
				(width 0.1524)
				(type default)
			)
			(layer "F.SilkS")
		)
		(fp_rect
			(start -0.508 0.9398)
			(end 0.508 -0.9398)
			(stroke
				(width 0)
				(type default)
			)
			(fill no)
			(layer "F.CrtYd")
		)
		(fp_rect
			(start -0.508 0.9398)
			(end 0.508 -0.9398)
			(stroke
				(width 0)
				(type default)
			)
			(fill no)
			(layer "F.Fab")
		)
		(pad "1" smd custom
			(at 0 -0.4445 90)
			(size 0.1397 0.1397)
			(layers "F.Cu" "F.Mask" "F.Paste")
			(net "P1V53_STBY")
			(options
				(clearance outline)
				(anchor circle)
			)
			(primitives
				(gr_poly
					(pts
						(arc
							(start -0.1778 -0.2794)
							(mid -0.249642 -0.249642)
							(end -0.2794 -0.1778)
						)
						(arc
							(start -0.2794 0.1778)
							(mid -0.249642 0.249642)
							(end -0.1778 0.2794)
						)
						(arc
							(start 0.1778 0.2794)
							(mid 0.249642 0.249642)
							(end 0.2794 0.1778)
						)
						(arc
							(start 0.2794 -0.1778)
							(mid 0.249642 -0.249642)
							(end 0.1778 -0.2794)
						)
					)
					(width 0)
					(fill yes)
				)
			)
		)
		(pad "2" smd custom
			(at 0 0.4445 90)
			(size 0.1397 0.1397)
			(layers "F.Cu" "F.Mask" "F.Paste")
			(net "DDR_VREF")
			(options
				(clearance outline)
				(anchor circle)
			)
			(primitives
				(gr_poly
					(pts
						(arc
							(start -0.1778 -0.2794)
							(mid -0.249642 -0.249642)
							(end -0.2794 -0.1778)
						)
						(arc
							(start -0.2794 0.1778)
							(mid -0.249642 0.249642)
							(end -0.1778 0.2794)
						)
						(arc
							(start 0.1778 0.2794)
							(mid 0.249642 0.249642)
							(end 0.2794 0.1778)
						)
						(arc
							(start 0.2794 -0.1778)
							(mid 0.249642 -0.249642)
							(end 0.1778 -0.2794)
						)
					)
					(width 0)
					(fill yes)
				)
			)
		)
	)
	(footprint ""
		(layer "F.Cu")
		(at 265.684 -26.289 180)
		(property "Reference" "R764"
			(at 0 0 180)
			(layer "F.SilkS")
			(hide yes)
			(effects
				(font
					(size 1.27 1.27)
				)
			)
		)
		(property "Value" "1KR2F-3-GP"
			(at 0.064008 -3.993896 180)
			(unlocked yes)
			(layer "F.Fab")
			(hide yes)
			(effects
				(font
					(size 1.016 1.016)
					(thickness 0.1524)
				)
			)
		)
		(property "Device Type" "R402H16"
			(at 0.064008 -5.517896 180)
			(unlocked yes)
			(layer "F.Fab")
			(hide yes)
			(effects
				(font
					(size 1.016 1.016)
					(thickness 0.1524)
				)
			)
		)
		(duplicate_pad_numbers_are_jumpers no)
		(fp_line
			(start 0.508 -0.9398)
			(end -0.508 -0.9398)
			(stroke
				(width 0.1524)
				(type default)
			)
			(layer "F.SilkS")
		)
		(fp_line
			(start -0.508 -0.9398)
			(end -0.508 0.9398)
			(stroke
				(width 0.1524)
				(type default)
			)
			(layer "F.SilkS")
		)
		(fp_rect
			(start -0.508 0.9398)
			(end 0.508 -0.9398)
			(stroke
				(width 0)
				(type default)
			)
			(fill no)
			(layer "F.CrtYd")
		)
		(fp_rect
			(start -0.508 0.9398)
			(end 0.508 -0.9398)
			(stroke
				(width 0)
				(type default)
			)
			(fill no)
			(layer "F.Fab")
		)
		(pad "1" smd custom
			(at 0 -0.4445 180)
			(size 0.1397 0.1397)
			(layers "F.Cu" "F.Mask" "F.Paste")
			(net "P3V3_GPIO")
			(options
				(clearance outline)
				(anchor circle)
			)
			(primitives
				(gr_poly
					(pts
						(arc
							(start -0.1778 -0.2794)
							(mid -0.249642 -0.249642)
							(end -0.2794 -0.1778)
						)
						(arc
							(start -0.2794 0.1778)
							(mid -0.249642 0.249642)
							(end -0.1778 0.2794)
						)
						(arc
							(start 0.1778 0.2794)
							(mid 0.249642 0.249642)
							(end 0.2794 0.1778)
						)
						(arc
							(start 0.2794 -0.1778)
							(mid 0.249642 -0.249642)
							(end 0.1778 -0.2794)
						)
					)
					(width 0)
					(fill yes)
				)
			)
		)
		(pad "2" smd custom
			(at 0 0.4445 180)
			(size 0.1397 0.1397)
			(layers "F.Cu" "F.Mask" "F.Paste")
			(net "TWI_SDA1")
			(options
				(clearance outline)
				(anchor circle)
			)
			(primitives
				(gr_poly
					(pts
						(arc
							(start -0.1778 -0.2794)
							(mid -0.249642 -0.249642)
							(end -0.2794 -0.1778)
						)
						(arc
							(start -0.2794 0.1778)
							(mid -0.249642 0.249642)
							(end -0.1778 0.2794)
						)
						(arc
							(start 0.1778 0.2794)
							(mid 0.249642 0.249642)
							(end 0.2794 0.1778)
						)
						(arc
							(start 0.2794 -0.1778)
							(mid 0.249642 -0.249642)
							(end 0.1778 -0.2794)
						)
					)
					(width 0)
					(fill yes)
				)
			)
		)
	)
	(footprint ""
		(layer "F.Cu")
		(at 55.88 -123.5964 90)
		(property "Reference" "R279"
			(at 0 0 90)
			(layer "F.SilkS")
			(hide yes)
			(effects
				(font
					(size 1.27 1.27)
				)
			)
		)
		(property "Value" "0R2J-2-GP"
			(at 0.064008 -3.993896 90)
			(unlocked yes)
			(layer "F.Fab")
			(hide yes)
			(effects
				(font
					(size 1.016 1.016)
					(thickness 0.1524)
				)
			)
		)
		(property "Device Type" "R402H16"
			(at 0.064008 -5.517896 90)
			(unlocked yes)
			(layer "F.Fab")
			(hide yes)
			(effects
				(font
					(size 1.016 1.016)
					(thickness 0.1524)
				)
			)
		)
		(duplicate_pad_numbers_are_jumpers no)
		(fp_line
			(start 0.508 -0.9398)
			(end -0.508 -0.9398)
			(stroke
				(width 0.1524)
				(type default)
			)
			(layer "F.SilkS")
		)
		(fp_line
			(start -0.508 -0.9398)
			(end -0.508 0.9398)
			(stroke
				(width 0.1524)
				(type default)
			)
			(layer "F.SilkS")
		)
		(fp_rect
			(start -0.508 0.9398)
			(end 0.508 -0.9398)
			(stroke
				(width 0)
				(type default)
			)
			(fill no)
			(layer "F.CrtYd")
		)
		(fp_rect
			(start -0.508 0.9398)
			(end 0.508 -0.9398)
			(stroke
				(width 0)
				(type default)
			)
			(fill no)
			(layer "F.Fab")
		)
		(pad "1" smd custom
			(at 0 -0.4445 90)
			(size 0.1397 0.1397)
			(layers "F.Cu" "F.Mask" "F.Paste")
			(net "BMC_RXD5_R")
			(options
				(clearance outline)
				(anchor circle)
			)
			(primitives
				(gr_poly
					(pts
						(arc
							(start -0.1778 -0.2794)
							(mid -0.249642 -0.249642)
							(end -0.2794 -0.1778)
						)
						(arc
							(start -0.2794 0.1778)
							(mid -0.249642 0.249642)
							(end -0.1778 0.2794)
						)
						(arc
							(start 0.1778 0.2794)
							(mid 0.249642 0.249642)
							(end 0.2794 0.1778)
						)
						(arc
							(start 0.2794 -0.1778)
							(mid 0.249642 -0.249642)
							(end 0.1778 -0.2794)
						)
					)
					(width 0)
					(fill yes)
				)
			)
		)
		(pad "2" smd custom
			(at 0 0.4445 90)
			(size 0.1397 0.1397)
			(layers "F.Cu" "F.Mask" "F.Paste")
			(net "BMC_RXD5")
			(options
				(clearance outline)
				(anchor circle)
			)
			(primitives
				(gr_poly
					(pts
						(arc
							(start -0.1778 -0.2794)
							(mid -0.249642 -0.249642)
							(end -0.2794 -0.1778)
						)
						(arc
							(start -0.2794 0.1778)
							(mid -0.249642 0.249642)
							(end -0.1778 0.2794)
						)
						(arc
							(start 0.1778 0.2794)
							(mid 0.249642 0.249642)
							(end 0.2794 0.1778)
						)
						(arc
							(start 0.2794 -0.1778)
							(mid 0.249642 -0.249642)
							(end 0.1778 -0.2794)
						)
					)
					(width 0)
					(fill yes)
				)
			)
		)
	)
	(footprint ""
		(layer "F.Cu")
		(at 57.15 -133.985 180)
		(property "Reference" "R5767"
			(at 0 0 180)
			(layer "F.SilkS")
			(hide yes)
			(effects
				(font
					(size 1.27 1.27)
				)
			)
		)
		(property "Value" "1KR2F-3-GP"
			(at 0.064008 -3.993896 180)
			(unlocked yes)
			(layer "F.Fab")
			(hide yes)
			(effects
				(font
					(size 1.016 1.016)
					(thickness 0.1524)
				)
			)
		)
		(property "Device Type" "R402H16"
			(at 0.064008 -5.517896 180)
			(unlocked yes)
			(layer "F.Fab")
			(hide yes)
			(effects
				(font
					(size 1.016 1.016)
					(thickness 0.1524)
				)
			)
		)
		(duplicate_pad_numbers_are_jumpers no)
		(fp_line
			(start 0.508 -0.9398)
			(end -0.508 -0.9398)
			(stroke
				(width 0.1524)
				(type default)
			)
			(layer "F.SilkS")
		)
		(fp_line
			(start -0.508 -0.9398)
			(end -0.508 0.9398)
			(stroke
				(width 0.1524)
				(type default)
			)
			(layer "F.SilkS")
		)
		(fp_rect
			(start -0.508 0.9398)
			(end 0.508 -0.9398)
			(stroke
				(width 0)
				(type default)
			)
			(fill no)
			(layer "F.CrtYd")
		)
		(fp_rect
			(start -0.508 0.9398)
			(end 0.508 -0.9398)
			(stroke
				(width 0)
				(type default)
			)
			(fill no)
			(layer "F.Fab")
		)
		(pad "1" smd custom
			(at 0 -0.4445 180)
			(size 0.1397 0.1397)
			(layers "F.Cu" "F.Mask" "F.Paste")
			(net "ADC_P1V8_STBY")
			(options
				(clearance outline)
				(anchor circle)
			)
			(primitives
				(gr_poly
					(pts
						(arc
							(start -0.1778 -0.2794)
							(mid -0.249642 -0.249642)
							(end -0.2794 -0.1778)
						)
						(arc
							(start -0.2794 0.1778)
							(mid -0.249642 0.249642)
							(end -0.1778 0.2794)
						)
						(arc
							(start 0.1778 0.2794)
							(mid 0.249642 0.249642)
							(end 0.2794 0.1778)
						)
						(arc
							(start 0.2794 -0.1778)
							(mid 0.249642 -0.249642)
							(end 0.1778 -0.2794)
						)
					)
					(width 0)
					(fill yes)
				)
			)
		)
		(pad "2" smd custom
			(at 0 0.4445 180)
			(size 0.1397 0.1397)
			(layers "F.Cu" "F.Mask" "F.Paste")
			(net "GND")
			(options
				(clearance outline)
				(anchor circle)
			)
			(primitives
				(gr_poly
					(pts
						(arc
							(start -0.1778 -0.2794)
							(mid -0.249642 -0.249642)
							(end -0.2794 -0.1778)
						)
						(arc
							(start -0.2794 0.1778)
							(mid -0.249642 0.249642)
							(end -0.1778 0.2794)
						)
						(arc
							(start 0.1778 0.2794)
							(mid 0.249642 0.249642)
							(end 0.2794 0.1778)
						)
						(arc
							(start 0.2794 -0.1778)
							(mid 0.249642 -0.249642)
							(end 0.1778 -0.2794)
						)
					)
					(width 0)
					(fill yes)
				)
			)
		)
	)
	(footprint ""
		(layer "F.Cu")
		(at 15.1257 -92.083382)
		(property "Reference" "D1404"
			(at 0 0 0)
			(layer "F.SilkS")
			(hide yes)
			(effects
				(font
					(size 1.27 1.27)
				)
			)
		)
		(property "Value" "BAT54WS-7-F-GP"
			(at 0 -6.7818 0)
			(unlocked yes)
			(layer "F.Fab")
			(hide yes)
			(effects
				(font
					(size 1.016 1.016)
					(thickness 0.1524)
				)
			)
		)
		(property "Device Type" "SOD323AKH42"
			(at 0 -8.6868 0)
			(unlocked yes)
			(layer "F.Fab")
			(hide yes)
			(effects
				(font
					(size 1.016 1.016)
					(thickness 0.1524)
				)
			)
		)
		(duplicate_pad_numbers_are_jumpers no)
		(fp_line
			(start -0.889 -1.9304)
			(end 0.889 -1.9304)
			(stroke
				(width 0.1524)
				(type default)
			)
			(layer "F.SilkS")
		)
		(fp_line
			(start -0.889 2.159)
			(end -0.889 -1.9304)
			(stroke
				(width 0.1524)
				(type default)
			)
			(layer "F.SilkS")
		)
		(fp_line
			(start 0.762 2.0574)
			(end -0.762 2.0574)
			(stroke
				(width 0.508)
				(type default)
			)
			(layer "F.SilkS")
		)
		(fp_line
			(start 0.889 -1.9304)
			(end 0.889 2.159)
			(stroke
				(width 0.1524)
				(type default)
			)
			(layer "F.SilkS")
		)
		(fp_line
			(start 0.889 2.159)
			(end -0.889 2.159)
			(stroke
				(width 0.1524)
				(type default)
			)
			(layer "F.SilkS")
		)
		(fp_rect
			(start -1.016 2.3114)
			(end 1.016 -2.0066)
			(stroke
				(width 0)
				(type default)
			)
			(fill no)
			(layer "F.CrtYd")
		)
		(fp_poly
			(pts
				(xy -1.016 -2.0066) (xy 1.016 -2.0066) (xy 1.016 2.3114) (xy -1.016 2.3114)
			)
			(stroke
				(width 0)
				(type default)
			)
			(fill no)
			(layer "F.Fab")
		)
		(pad "A" smd rect
			(at 0 -1.143)
			(size 0.5588 1.016)
			(layers "F.Cu" "F.Mask" "F.Paste")
			(net "BMC_SELF_HW_RST")
		)
		(pad "K" smd rect
			(at 0 1.143)
			(size 0.5588 1.016)
			(layers "F.Cu" "F.Mask" "F.Paste")
			(net "BMC_TPM_RST")
		)
	)
	(footprint ""
		(layer "F.Cu")
		(at 85.991954 -212.420454 180)
		(property "Reference" "C347"
			(at 0 0 180)
			(layer "F.SilkS")
			(hide yes)
			(effects
				(font
					(size 1.27 1.27)
				)
			)
		)
		(property "Value" "SCD22U10V2KX-1GP"
			(at 1.1811 -2.7051 180)
			(unlocked yes)
			(layer "F.Fab")
			(hide yes)
			(effects
				(font
					(size 1.016 1.016)
					(thickness 0.1524)
				)
			)
		)
		(property "Device Type" "C402H22"
			(at 1.1811 -4.2291 180)
			(unlocked yes)
			(layer "F.Fab")
			(hide yes)
			(effects
				(font
					(size 1.016 1.016)
					(thickness 0.1524)
				)
			)
		)
		(duplicate_pad_numbers_are_jumpers no)
		(fp_rect
			(start -0.4318 0.9525)
			(end 0.4318 -0.9525)
			(stroke
				(width 0)
				(type default)
			)
			(fill no)
			(layer "F.CrtYd")
		)
		(fp_rect
			(start -0.4318 0.9525)
			(end 0.4318 -0.9525)
			(stroke
				(width 0)
				(type default)
			)
			(fill no)
			(layer "F.Fab")
		)
		(pad "1" smd custom
			(at 0 -0.4445 180)
			(size 0.1524 0.1524)
			(layers "F.Cu" "F.Mask" "F.Paste")
			(net "PCIE_TX_CAP_P66")
			(options
				(clearance outline)
				(anchor circle)
			)
			(primitives
				(gr_poly
					(pts
						(arc
							(start 0.3048 -0.2032)
							(mid 0.275042 -0.275042)
							(end 0.2032 -0.3048)
						)
						(arc
							(start -0.2032 -0.3048)
							(mid -0.275042 -0.275042)
							(end -0.3048 -0.2032)
						)
						(arc
							(start -0.3048 0.2032)
							(mid -0.275042 0.275042)
							(end -0.2032 0.3048)
						)
						(arc
							(start 0.2032 0.3048)
							(mid 0.275042 0.275042)
							(end 0.3048 0.2032)
						)
					)
					(width 0)
					(fill yes)
				)
			)
		)
		(pad "2" smd custom
			(at 0 0.4445 180)
			(size 0.1524 0.1524)
			(layers "F.Cu" "F.Mask" "F.Paste")
			(net "PCIE_TX_P66")
			(options
				(clearance outline)
				(anchor circle)
			)
			(primitives
				(gr_poly
					(pts
						(arc
							(start 0.3048 -0.2032)
							(mid 0.275042 -0.275042)
							(end 0.2032 -0.3048)
						)
						(arc
							(start -0.2032 -0.3048)
							(mid -0.275042 -0.275042)
							(end -0.3048 -0.2032)
						)
						(arc
							(start -0.3048 0.2032)
							(mid -0.275042 0.275042)
							(end -0.2032 0.3048)
						)
						(arc
							(start 0.2032 0.3048)
							(mid 0.275042 0.275042)
							(end 0.3048 0.2032)
						)
					)
					(width 0)
					(fill yes)
				)
			)
		)
	)
	(footprint ""
		(layer "F.Cu")
		(at 36.847526 -162.66668 90)
		(property "Reference" "C239"
			(at 0 0 90)
			(layer "F.SilkS")
			(hide yes)
			(effects
				(font
					(size 1.27 1.27)
				)
			)
		)
		(property "Value" "SCD1U16V2KX-3GP"
			(at 1.1811 -2.7051 90)
			(unlocked yes)
			(layer "F.Fab")
			(hide yes)
			(effects
				(font
					(size 1.016 1.016)
					(thickness 0.1524)
				)
			)
		)
		(property "Device Type" "C402H22"
			(at 1.1811 -4.2291 90)
			(unlocked yes)
			(layer "F.Fab")
			(hide yes)
			(effects
				(font
					(size 1.016 1.016)
					(thickness 0.1524)
				)
			)
		)
		(duplicate_pad_numbers_are_jumpers no)
		(fp_rect
			(start -0.4318 0.9525)
			(end 0.4318 -0.9525)
			(stroke
				(width 0)
				(type default)
			)
			(fill no)
			(layer "F.CrtYd")
		)
		(fp_rect
			(start -0.4318 0.9525)
			(end 0.4318 -0.9525)
			(stroke
				(width 0)
				(type default)
			)
			(fill no)
			(layer "F.Fab")
		)
		(pad "1" smd custom
			(at 0 -0.4445 90)
			(size 0.1524 0.1524)
			(layers "F.Cu" "F.Mask" "F.Paste")
			(net "DDR_VREF")
			(options
				(clearance outline)
				(anchor circle)
			)
			(primitives
				(gr_poly
					(pts
						(arc
							(start 0.3048 -0.2032)
							(mid 0.275042 -0.275042)
							(end 0.2032 -0.3048)
						)
						(arc
							(start -0.2032 -0.3048)
							(mid -0.275042 -0.275042)
							(end -0.3048 -0.2032)
						)
						(arc
							(start -0.3048 0.2032)
							(mid -0.275042 0.275042)
							(end -0.2032 0.3048)
						)
						(arc
							(start 0.2032 0.3048)
							(mid 0.275042 0.275042)
							(end 0.3048 0.2032)
						)
					)
					(width 0)
					(fill yes)
				)
			)
		)
		(pad "2" smd custom
			(at 0 0.4445 90)
			(size 0.1524 0.1524)
			(layers "F.Cu" "F.Mask" "F.Paste")
			(net "GND")
			(options
				(clearance outline)
				(anchor circle)
			)
			(primitives
				(gr_poly
					(pts
						(arc
							(start 0.3048 -0.2032)
							(mid 0.275042 -0.275042)
							(end 0.2032 -0.3048)
						)
						(arc
							(start -0.2032 -0.3048)
							(mid -0.275042 -0.275042)
							(end -0.3048 -0.2032)
						)
						(arc
							(start -0.3048 0.2032)
							(mid -0.275042 0.275042)
							(end -0.2032 0.3048)
						)
						(arc
							(start 0.2032 0.3048)
							(mid 0.275042 0.275042)
							(end 0.3048 0.2032)
						)
					)
					(width 0)
					(fill yes)
				)
			)
		)
	)
	(footprint ""
		(layer "F.Cu")
		(at 258.050792 -26.289 180)
		(property "Reference" "R741"
			(at 0 0 180)
			(layer "F.SilkS")
			(hide yes)
			(effects
				(font
					(size 1.27 1.27)
				)
			)
		)
		(property "Value" "4K7R2F-GP"
			(at 0.064008 -3.993896 180)
			(unlocked yes)
			(layer "F.Fab")
			(hide yes)
			(effects
				(font
					(size 1.016 1.016)
					(thickness 0.1524)
				)
			)
		)
		(property "Device Type" "R402H16"
			(at 0.064008 -5.517896 180)
			(unlocked yes)
			(layer "F.Fab")
			(hide yes)
			(effects
				(font
					(size 1.016 1.016)
					(thickness 0.1524)
				)
			)
		)
		(duplicate_pad_numbers_are_jumpers no)
		(fp_line
			(start 0.508 -0.9398)
			(end -0.508 -0.9398)
			(stroke
				(width 0.1524)
				(type default)
			)
			(layer "F.SilkS")
		)
		(fp_line
			(start -0.508 -0.9398)
			(end -0.508 0.9398)
			(stroke
				(width 0.1524)
				(type default)
			)
			(layer "F.SilkS")
		)
		(fp_rect
			(start -0.508 0.9398)
			(end 0.508 -0.9398)
			(stroke
				(width 0)
				(type default)
			)
			(fill no)
			(layer "F.CrtYd")
		)
		(fp_rect
			(start -0.508 0.9398)
			(end 0.508 -0.9398)
			(stroke
				(width 0)
				(type default)
			)
			(fill no)
			(layer "F.Fab")
		)
		(pad "1" smd custom
			(at 0 -0.4445 180)
			(size 0.1397 0.1397)
			(layers "F.Cu" "F.Mask" "F.Paste")
			(net "P3V3_GPIO")
			(options
				(clearance outline)
				(anchor circle)
			)
			(primitives
				(gr_poly
					(pts
						(arc
							(start -0.1778 -0.2794)
							(mid -0.249642 -0.249642)
							(end -0.2794 -0.1778)
						)
						(arc
							(start -0.2794 0.1778)
							(mid -0.249642 0.249642)
							(end -0.1778 0.2794)
						)
						(arc
							(start 0.1778 0.2794)
							(mid 0.249642 0.249642)
							(end 0.2794 0.1778)
						)
						(arc
							(start 0.2794 -0.1778)
							(mid 0.249642 -0.249642)
							(end 0.1778 -0.2794)
						)
					)
					(width 0)
					(fill yes)
				)
			)
		)
		(pad "2" smd custom
			(at 0 0.4445 180)
			(size 0.1397 0.1397)
			(layers "F.Cu" "F.Mask" "F.Paste")
			(net "IOEXP_INT#_2")
			(options
				(clearance outline)
				(anchor circle)
			)
			(primitives
				(gr_poly
					(pts
						(arc
							(start -0.1778 -0.2794)
							(mid -0.249642 -0.249642)
							(end -0.2794 -0.1778)
						)
						(arc
							(start -0.2794 0.1778)
							(mid -0.249642 0.249642)
							(end -0.1778 0.2794)
						)
						(arc
							(start 0.1778 0.2794)
							(mid 0.249642 0.249642)
							(end 0.2794 0.1778)
						)
						(arc
							(start 0.2794 -0.1778)
							(mid 0.249642 -0.249642)
							(end 0.1778 -0.2794)
						)
					)
					(width 0)
					(fill yes)
				)
			)
		)
	)
	(footprint ""
		(layer "F.Cu")
		(at 53.721 -135.763 90)
		(property "Reference" "R151"
			(at 0 0 90)
			(layer "F.SilkS")
			(hide yes)
			(effects
				(font
					(size 1.27 1.27)
				)
			)
		)
		(property "Value" "4K7R2F-GP"
			(at 0.064008 -3.993896 90)
			(unlocked yes)
			(layer "F.Fab")
			(hide yes)
			(effects
				(font
					(size 1.016 1.016)
					(thickness 0.1524)
				)
			)
		)
		(property "Device Type" "R402H16"
			(at 0.064008 -5.517896 90)
			(unlocked yes)
			(layer "F.Fab")
			(hide yes)
			(effects
				(font
					(size 1.016 1.016)
					(thickness 0.1524)
				)
			)
		)
		(duplicate_pad_numbers_are_jumpers no)
		(fp_line
			(start 0.508 -0.9398)
			(end -0.508 -0.9398)
			(stroke
				(width 0.1524)
				(type default)
			)
			(layer "F.SilkS")
		)
		(fp_line
			(start -0.508 -0.9398)
			(end -0.508 0.9398)
			(stroke
				(width 0.1524)
				(type default)
			)
			(layer "F.SilkS")
		)
		(fp_rect
			(start -0.508 0.9398)
			(end 0.508 -0.9398)
			(stroke
				(width 0)
				(type default)
			)
			(fill no)
			(layer "F.CrtYd")
		)
		(fp_rect
			(start -0.508 0.9398)
			(end 0.508 -0.9398)
			(stroke
				(width 0)
				(type default)
			)
			(fill no)
			(layer "F.Fab")
		)
		(pad "1" smd custom
			(at 0 -0.4445 90)
			(size 0.1397 0.1397)
			(layers "F.Cu" "F.Mask" "F.Paste")
			(net "CBL_PRSNT_N_1")
			(options
				(clearance outline)
				(anchor circle)
			)
			(primitives
				(gr_poly
					(pts
						(arc
							(start -0.1778 -0.2794)
							(mid -0.249642 -0.249642)
							(end -0.2794 -0.1778)
						)
						(arc
							(start -0.2794 0.1778)
							(mid -0.249642 0.249642)
							(end -0.1778 0.2794)
						)
						(arc
							(start 0.1778 0.2794)
							(mid 0.249642 0.249642)
							(end 0.2794 0.1778)
						)
						(arc
							(start 0.2794 -0.1778)
							(mid 0.249642 -0.249642)
							(end 0.1778 -0.2794)
						)
					)
					(width 0)
					(fill yes)
				)
			)
		)
		(pad "2" smd custom
			(at 0 0.4445 90)
			(size 0.1397 0.1397)
			(layers "F.Cu" "F.Mask" "F.Paste")
			(net "P3V3_STBY")
			(options
				(clearance outline)
				(anchor circle)
			)
			(primitives
				(gr_poly
					(pts
						(arc
							(start -0.1778 -0.2794)
							(mid -0.249642 -0.249642)
							(end -0.2794 -0.1778)
						)
						(arc
							(start -0.2794 0.1778)
							(mid -0.249642 0.249642)
							(end -0.1778 0.2794)
						)
						(arc
							(start 0.1778 0.2794)
							(mid 0.249642 0.249642)
							(end 0.2794 0.1778)
						)
						(arc
							(start 0.2794 -0.1778)
							(mid 0.249642 -0.249642)
							(end 0.1778 -0.2794)
						)
					)
					(width 0)
					(fill yes)
				)
			)
		)
	)
	(footprint ""
		(layer "F.Cu")
		(at 17.399 -107.315)
		(property "Reference" "PC78"
			(at 0 0 0)
			(layer "F.SilkS")
			(hide yes)
			(effects
				(font
					(size 1.27 1.27)
				)
			)
		)
		(property "Value" "SCD01U25V2KX-3GP"
			(at 1.1811 -2.7051 0)
			(unlocked yes)
			(layer "F.Fab")
			(hide yes)
			(effects
				(font
					(size 1.016 1.016)
					(thickness 0.1524)
				)
			)
		)
		(property "Device Type" "C402H22"
			(at 1.1811 -4.2291 0)
			(unlocked yes)
			(layer "F.Fab")
			(hide yes)
			(effects
				(font
					(size 1.016 1.016)
					(thickness 0.1524)
				)
			)
		)
		(duplicate_pad_numbers_are_jumpers no)
		(fp_rect
			(start -0.4318 0.9525)
			(end 0.4318 -0.9525)
			(stroke
				(width 0)
				(type default)
			)
			(fill no)
			(layer "F.CrtYd")
		)
		(fp_rect
			(start -0.4318 0.9525)
			(end 0.4318 -0.9525)
			(stroke
				(width 0)
				(type default)
			)
			(fill no)
			(layer "F.Fab")
		)
		(pad "1" smd custom
			(at 0 -0.4445)
			(size 0.1524 0.1524)
			(layers "F.Cu" "F.Mask" "F.Paste")
			(net "P1V26_PWR")
			(options
				(clearance outline)
				(anchor circle)
			)
			(primitives
				(gr_poly
					(pts
						(arc
							(start 0.3048 -0.2032)
							(mid 0.275042 -0.275042)
							(end 0.2032 -0.3048)
						)
						(arc
							(start -0.2032 -0.3048)
							(mid -0.275042 -0.275042)
							(end -0.3048 -0.2032)
						)
						(arc
							(start -0.3048 0.2032)
							(mid -0.275042 0.275042)
							(end -0.2032 0.3048)
						)
						(arc
							(start 0.2032 0.3048)
							(mid 0.275042 0.275042)
							(end 0.3048 0.2032)
						)
					)
					(width 0)
					(fill yes)
				)
			)
		)
		(pad "2" smd custom
			(at 0 0.4445)
			(size 0.1524 0.1524)
			(layers "F.Cu" "F.Mask" "F.Paste")
			(net "VR_P1V26_STBY_FB")
			(options
				(clearance outline)
				(anchor circle)
			)
			(primitives
				(gr_poly
					(pts
						(arc
							(start 0.3048 -0.2032)
							(mid 0.275042 -0.275042)
							(end 0.2032 -0.3048)
						)
						(arc
							(start -0.2032 -0.3048)
							(mid -0.275042 -0.275042)
							(end -0.3048 -0.2032)
						)
						(arc
							(start -0.3048 0.2032)
							(mid -0.275042 0.275042)
							(end -0.2032 0.3048)
						)
						(arc
							(start 0.2032 0.3048)
							(mid 0.275042 0.275042)
							(end 0.3048 0.2032)
						)
					)
					(width 0)
					(fill yes)
				)
			)
		)
	)
	(footprint ""
		(layer "F.Cu")
		(at 142.247874 -87.11692 90)
		(property "Reference" "PR9034"
			(at 0 0 90)
			(layer "F.SilkS")
			(hide yes)
			(effects
				(font
					(size 1.27 1.27)
				)
			)
		)
		(property "Value" "2K87R2F-1-GP"
			(at 0.064008 -3.993896 90)
			(unlocked yes)
			(layer "F.Fab")
			(hide yes)
			(effects
				(font
					(size 1.016 1.016)
					(thickness 0.1524)
				)
			)
		)
		(property "Device Type" "R402H16"
			(at 0.064008 -5.517896 90)
			(unlocked yes)
			(layer "F.Fab")
			(hide yes)
			(effects
				(font
					(size 1.016 1.016)
					(thickness 0.1524)
				)
			)
		)
		(duplicate_pad_numbers_are_jumpers no)
		(fp_line
			(start 0.508 -0.9398)
			(end -0.508 -0.9398)
			(stroke
				(width 0.1524)
				(type default)
			)
			(layer "F.SilkS")
		)
		(fp_line
			(start -0.508 -0.9398)
			(end -0.508 0.9398)
			(stroke
				(width 0.1524)
				(type default)
			)
			(layer "F.SilkS")
		)
		(fp_rect
			(start -0.508 0.9398)
			(end 0.508 -0.9398)
			(stroke
				(width 0)
				(type default)
			)
			(fill no)
			(layer "F.CrtYd")
		)
		(fp_rect
			(start -0.508 0.9398)
			(end 0.508 -0.9398)
			(stroke
				(width 0)
				(type default)
			)
			(fill no)
			(layer "F.Fab")
		)
		(pad "1" smd custom
			(at 0 -0.4445 90)
			(size 0.1397 0.1397)
			(layers "F.Cu" "F.Mask" "F.Paste")
			(net "VR_P1V8_STBY_FB")
			(options
				(clearance outline)
				(anchor circle)
			)
			(primitives
				(gr_poly
					(pts
						(arc
							(start -0.1778 -0.2794)
							(mid -0.249642 -0.249642)
							(end -0.2794 -0.1778)
						)
						(arc
							(start -0.2794 0.1778)
							(mid -0.249642 0.249642)
							(end -0.1778 0.2794)
						)
						(arc
							(start 0.1778 0.2794)
							(mid 0.249642 0.249642)
							(end 0.2794 0.1778)
						)
						(arc
							(start 0.2794 -0.1778)
							(mid 0.249642 -0.249642)
							(end 0.1778 -0.2794)
						)
					)
					(width 0)
					(fill yes)
				)
			)
		)
		(pad "2" smd custom
			(at 0 0.4445 90)
			(size 0.1397 0.1397)
			(layers "F.Cu" "F.Mask" "F.Paste")
			(net "GND")
			(options
				(clearance outline)
				(anchor circle)
			)
			(primitives
				(gr_poly
					(pts
						(arc
							(start -0.1778 -0.2794)
							(mid -0.249642 -0.249642)
							(end -0.2794 -0.1778)
						)
						(arc
							(start -0.2794 0.1778)
							(mid -0.249642 0.249642)
							(end -0.1778 0.2794)
						)
						(arc
							(start 0.1778 0.2794)
							(mid 0.249642 0.249642)
							(end 0.2794 0.1778)
						)
						(arc
							(start 0.2794 -0.1778)
							(mid 0.249642 -0.249642)
							(end 0.1778 -0.2794)
						)
					)
					(width 0)
					(fill yes)
				)
			)
		)
	)
	(footprint ""
		(layer "F.Cu")
		(at 20.3454 -185.7502 -90)
		(property "Reference" "R2120"
			(at 0 0 270)
			(layer "F.SilkS")
			(hide yes)
			(effects
				(font
					(size 1.27 1.27)
				)
			)
		)
		(property "Value" "10R2F-L-GP"
			(at 0.064008 -3.993896 270)
			(unlocked yes)
			(layer "F.Fab")
			(hide yes)
			(effects
				(font
					(size 1.016 1.016)
					(thickness 0.1524)
				)
			)
		)
		(property "Device Type" "R402H14"
			(at 0.064008 -5.517896 270)
			(unlocked yes)
			(layer "F.Fab")
			(hide yes)
			(effects
				(font
					(size 1.016 1.016)
					(thickness 0.1524)
				)
			)
		)
		(duplicate_pad_numbers_are_jumpers no)
		(fp_line
			(start -0.508 -0.9398)
			(end -0.508 0.9398)
			(stroke
				(width 0.1524)
				(type default)
			)
			(layer "F.SilkS")
		)
		(fp_line
			(start 0.508 -0.9398)
			(end -0.508 -0.9398)
			(stroke
				(width 0.1524)
				(type default)
			)
			(layer "F.SilkS")
		)
		(fp_rect
			(start -0.508 0.9398)
			(end 0.508 -0.9398)
			(stroke
				(width 0)
				(type default)
			)
			(fill no)
			(layer "F.CrtYd")
		)
		(fp_rect
			(start -0.508 0.9398)
			(end 0.508 -0.9398)
			(stroke
				(width 0)
				(type default)
			)
			(fill no)
			(layer "F.Fab")
		)
		(pad "1" smd custom
			(at 0 -0.4445 270)
			(size 0.1397 0.1397)
			(layers "F.Cu" "F.Mask" "F.Paste")
			(net "MB0_CM_SENSE_R1_P")
			(options
				(clearance outline)
				(anchor circle)
			)
			(primitives
				(gr_poly
					(pts
						(arc
							(start -0.1778 -0.2794)
							(mid -0.249642 -0.249642)
							(end -0.2794 -0.1778)
						)
						(arc
							(start -0.2794 0.1778)
							(mid -0.249642 0.249642)
							(end -0.1778 0.2794)
						)
						(arc
							(start 0.1778 0.2794)
							(mid 0.249642 0.249642)
							(end 0.2794 0.1778)
						)
						(arc
							(start 0.2794 -0.1778)
							(mid 0.249642 -0.249642)
							(end 0.1778 -0.2794)
						)
					)
					(width 0)
					(fill yes)
				)
			)
		)
		(pad "2" smd custom
			(at 0 0.4445 270)
			(size 0.1397 0.1397)
			(layers "F.Cu" "F.Mask" "F.Paste")
			(net "ADM1278_HS_P")
			(options
				(clearance outline)
				(anchor circle)
			)
			(primitives
				(gr_poly
					(pts
						(arc
							(start -0.1778 -0.2794)
							(mid -0.249642 -0.249642)
							(end -0.2794 -0.1778)
						)
						(arc
							(start -0.2794 0.1778)
							(mid -0.249642 0.249642)
							(end -0.1778 0.2794)
						)
						(arc
							(start 0.1778 0.2794)
							(mid 0.249642 0.249642)
							(end 0.2794 0.1778)
						)
						(arc
							(start 0.2794 -0.1778)
							(mid 0.249642 -0.249642)
							(end 0.1778 -0.2794)
						)
					)
					(width 0)
					(fill yes)
				)
			)
		)
	)
	(footprint ""
		(layer "F.Cu")
		(at 15.9512 -83.5406)
		(property "Reference" "R401"
			(at 0 0 0)
			(layer "F.SilkS")
			(hide yes)
			(effects
				(font
					(size 1.27 1.27)
				)
			)
		)
		(property "Value" "10KR2F-2-GP"
			(at 0.064008 -3.993896 0)
			(unlocked yes)
			(layer "F.Fab")
			(hide yes)
			(effects
				(font
					(size 1.016 1.016)
					(thickness 0.1524)
				)
			)
		)
		(property "Device Type" "R402H16"
			(at 0.064008 -5.517896 0)
			(unlocked yes)
			(layer "F.Fab")
			(hide yes)
			(effects
				(font
					(size 1.016 1.016)
					(thickness 0.1524)
				)
			)
		)
		(duplicate_pad_numbers_are_jumpers no)
		(fp_line
			(start -0.508 -0.9398)
			(end -0.508 0.9398)
			(stroke
				(width 0.1524)
				(type default)
			)
			(layer "F.SilkS")
		)
		(fp_line
			(start 0.508 -0.9398)
			(end -0.508 -0.9398)
			(stroke
				(width 0.1524)
				(type default)
			)
			(layer "F.SilkS")
		)
		(fp_rect
			(start -0.508 0.9398)
			(end 0.508 -0.9398)
			(stroke
				(width 0)
				(type default)
			)
			(fill no)
			(layer "F.CrtYd")
		)
		(fp_rect
			(start -0.508 0.9398)
			(end 0.508 -0.9398)
			(stroke
				(width 0)
				(type default)
			)
			(fill no)
			(layer "F.Fab")
		)
		(pad "1" smd custom
			(at 0 -0.4445)
			(size 0.1397 0.1397)
			(layers "F.Cu" "F.Mask" "F.Paste")
			(net "P3V3_STBY")
			(options
				(clearance outline)
				(anchor circle)
			)
			(primitives
				(gr_poly
					(pts
						(arc
							(start -0.1778 -0.2794)
							(mid -0.249642 -0.249642)
							(end -0.2794 -0.1778)
						)
						(arc
							(start -0.2794 0.1778)
							(mid -0.249642 0.249642)
							(end -0.1778 0.2794)
						)
						(arc
							(start 0.1778 0.2794)
							(mid 0.249642 0.249642)
							(end 0.2794 0.1778)
						)
						(arc
							(start 0.2794 -0.1778)
							(mid 0.249642 -0.249642)
							(end 0.1778 -0.2794)
						)
					)
					(width 0)
					(fill yes)
				)
			)
		)
		(pad "2" smd custom
			(at 0 0.4445)
			(size 0.1397 0.1397)
			(layers "F.Cu" "F.Mask" "F.Paste")
			(net "FM_PCH_LAN1_DISABLE_N")
			(options
				(clearance outline)
				(anchor circle)
			)
			(primitives
				(gr_poly
					(pts
						(arc
							(start -0.1778 -0.2794)
							(mid -0.249642 -0.249642)
							(end -0.2794 -0.1778)
						)
						(arc
							(start -0.2794 0.1778)
							(mid -0.249642 0.249642)
							(end -0.1778 0.2794)
						)
						(arc
							(start 0.1778 0.2794)
							(mid 0.249642 0.249642)
							(end 0.2794 0.1778)
						)
						(arc
							(start 0.2794 -0.1778)
							(mid 0.249642 -0.249642)
							(end 0.1778 -0.2794)
						)
					)
					(width 0)
					(fill yes)
				)
			)
		)
	)
	(footprint ""
		(layer "F.Cu")
		(at 85.0392 -81.0006 90)
		(property "Reference" "SR947"
			(at 0 0 90)
			(layer "F.SilkS")
			(hide yes)
			(effects
				(font
					(size 1.27 1.27)
				)
			)
		)
		(property "Value" "0R2J-2-GP"
			(at 0.064008 -3.993896 90)
			(unlocked yes)
			(layer "F.Fab")
			(hide yes)
			(effects
				(font
					(size 1.016 1.016)
					(thickness 0.1524)
				)
			)
		)
		(property "Device Type" "R402H16"
			(at 0.064008 -5.517896 90)
			(unlocked yes)
			(layer "F.Fab")
			(hide yes)
			(effects
				(font
					(size 1.016 1.016)
					(thickness 0.1524)
				)
			)
		)
		(duplicate_pad_numbers_are_jumpers no)
		(fp_line
			(start 0.508 -0.9398)
			(end -0.508 -0.9398)
			(stroke
				(width 0.1524)
				(type default)
			)
			(layer "F.SilkS")
		)
		(fp_line
			(start -0.508 -0.9398)
			(end -0.508 0.9398)
			(stroke
				(width 0.1524)
				(type default)
			)
			(layer "F.SilkS")
		)
		(fp_rect
			(start -0.508 0.9398)
			(end 0.508 -0.9398)
			(stroke
				(width 0)
				(type default)
			)
			(fill no)
			(layer "F.CrtYd")
		)
		(fp_rect
			(start -0.508 0.9398)
			(end 0.508 -0.9398)
			(stroke
				(width 0)
				(type default)
			)
			(fill no)
			(layer "F.Fab")
		)
		(pad "1" smd custom
			(at 0 -0.4445 90)
			(size 0.1397 0.1397)
			(layers "F.Cu" "F.Mask" "F.Paste")
			(net "SAS_SMART_R_RX")
			(options
				(clearance outline)
				(anchor circle)
			)
			(primitives
				(gr_poly
					(pts
						(arc
							(start -0.1778 -0.2794)
							(mid -0.249642 -0.249642)
							(end -0.2794 -0.1778)
						)
						(arc
							(start -0.2794 0.1778)
							(mid -0.249642 0.249642)
							(end -0.1778 0.2794)
						)
						(arc
							(start 0.1778 0.2794)
							(mid 0.249642 0.249642)
							(end 0.2794 0.1778)
						)
						(arc
							(start 0.2794 -0.1778)
							(mid 0.249642 -0.249642)
							(end 0.1778 -0.2794)
						)
					)
					(width 0)
					(fill yes)
				)
			)
		)
		(pad "2" smd custom
			(at 0 0.4445 90)
			(size 0.1397 0.1397)
			(layers "F.Cu" "F.Mask" "F.Paste")
			(net "UART_USIN")
			(options
				(clearance outline)
				(anchor circle)
			)
			(primitives
				(gr_poly
					(pts
						(arc
							(start -0.1778 -0.2794)
							(mid -0.249642 -0.249642)
							(end -0.2794 -0.1778)
						)
						(arc
							(start -0.2794 0.1778)
							(mid -0.249642 0.249642)
							(end -0.1778 0.2794)
						)
						(arc
							(start 0.1778 0.2794)
							(mid 0.249642 0.249642)
							(end 0.2794 0.1778)
						)
						(arc
							(start 0.2794 -0.1778)
							(mid 0.249642 -0.249642)
							(end 0.1778 -0.2794)
						)
					)
					(width 0)
					(fill yes)
				)
			)
		)
	)
	(footprint ""
		(layer "F.Cu")
		(at 133.140958 -74.40676 180)
		(property "Reference" "R650"
			(at 0 0 180)
			(layer "F.SilkS")
			(hide yes)
			(effects
				(font
					(size 1.27 1.27)
				)
			)
		)
		(property "Value" "100KR2F-L1-GP"
			(at 0.064008 -3.993896 180)
			(unlocked yes)
			(layer "F.Fab")
			(hide yes)
			(effects
				(font
					(size 1.016 1.016)
					(thickness 0.1524)
				)
			)
		)
		(property "Device Type" "R402H16"
			(at 0.064008 -5.517896 180)
			(unlocked yes)
			(layer "F.Fab")
			(hide yes)
			(effects
				(font
					(size 1.016 1.016)
					(thickness 0.1524)
				)
			)
		)
		(duplicate_pad_numbers_are_jumpers no)
		(fp_line
			(start 0.508 -0.9398)
			(end -0.508 -0.9398)
			(stroke
				(width 0.1524)
				(type default)
			)
			(layer "F.SilkS")
		)
		(fp_line
			(start -0.508 -0.9398)
			(end -0.508 0.9398)
			(stroke
				(width 0.1524)
				(type default)
			)
			(layer "F.SilkS")
		)
		(fp_rect
			(start -0.508 0.9398)
			(end 0.508 -0.9398)
			(stroke
				(width 0)
				(type default)
			)
			(fill no)
			(layer "F.CrtYd")
		)
		(fp_rect
			(start -0.508 0.9398)
			(end 0.508 -0.9398)
			(stroke
				(width 0)
				(type default)
			)
			(fill no)
			(layer "F.Fab")
		)
		(pad "1" smd custom
			(at 0 -0.4445 180)
			(size 0.1397 0.1397)
			(layers "F.Cu" "F.Mask" "F.Paste")
			(net "DUT_VDDO")
			(options
				(clearance outline)
				(anchor circle)
			)
			(primitives
				(gr_poly
					(pts
						(arc
							(start -0.1778 -0.2794)
							(mid -0.249642 -0.249642)
							(end -0.2794 -0.1778)
						)
						(arc
							(start -0.2794 0.1778)
							(mid -0.249642 0.249642)
							(end -0.1778 0.2794)
						)
						(arc
							(start 0.1778 0.2794)
							(mid 0.249642 0.249642)
							(end 0.2794 0.1778)
						)
						(arc
							(start 0.2794 -0.1778)
							(mid 0.249642 -0.249642)
							(end 0.1778 -0.2794)
						)
					)
					(width 0)
					(fill yes)
				)
			)
		)
		(pad "2" smd custom
			(at 0 0.4445 180)
			(size 0.1397 0.1397)
			(layers "F.Cu" "F.Mask" "F.Paste")
			(net "SPI_DATA0_3_R")
			(options
				(clearance outline)
				(anchor circle)
			)
			(primitives
				(gr_poly
					(pts
						(arc
							(start -0.1778 -0.2794)
							(mid -0.249642 -0.249642)
							(end -0.2794 -0.1778)
						)
						(arc
							(start -0.2794 0.1778)
							(mid -0.249642 0.249642)
							(end -0.1778 0.2794)
						)
						(arc
							(start 0.1778 0.2794)
							(mid 0.249642 0.249642)
							(end 0.2794 0.1778)
						)
						(arc
							(start 0.2794 -0.1778)
							(mid 0.249642 -0.249642)
							(end 0.1778 -0.2794)
						)
					)
					(width 0)
					(fill yes)
				)
			)
		)
	)
	(footprint ""
		(layer "F.Cu")
		(at 34.181034 -103.656384 180)
		(property "Reference" "R53"
			(at 0 0 180)
			(layer "F.SilkS")
			(hide yes)
			(effects
				(font
					(size 1.27 1.27)
				)
			)
		)
		(property "Value" "0R2J-2-GP"
			(at 0.064008 -3.993896 180)
			(unlocked yes)
			(layer "F.Fab")
			(hide yes)
			(effects
				(font
					(size 1.016 1.016)
					(thickness 0.1524)
				)
			)
		)
		(property "Device Type" "R402H16"
			(at 0.064008 -5.517896 180)
			(unlocked yes)
			(layer "F.Fab")
			(hide yes)
			(effects
				(font
					(size 1.016 1.016)
					(thickness 0.1524)
				)
			)
		)
		(duplicate_pad_numbers_are_jumpers no)
		(fp_line
			(start 0.508 -0.9398)
			(end -0.508 -0.9398)
			(stroke
				(width 0.1524)
				(type default)
			)
			(layer "F.SilkS")
		)
		(fp_line
			(start -0.508 -0.9398)
			(end -0.508 0.9398)
			(stroke
				(width 0.1524)
				(type default)
			)
			(layer "F.SilkS")
		)
		(fp_rect
			(start -0.508 0.9398)
			(end 0.508 -0.9398)
			(stroke
				(width 0)
				(type default)
			)
			(fill no)
			(layer "F.CrtYd")
		)
		(fp_rect
			(start -0.508 0.9398)
			(end 0.508 -0.9398)
			(stroke
				(width 0)
				(type default)
			)
			(fill no)
			(layer "F.Fab")
		)
		(pad "1" smd custom
			(at 0 -0.4445 180)
			(size 0.1397 0.1397)
			(layers "F.Cu" "F.Mask" "F.Paste")
			(net "SPI_FLASH_SELECT_R")
			(options
				(clearance outline)
				(anchor circle)
			)
			(primitives
				(gr_poly
					(pts
						(arc
							(start -0.1778 -0.2794)
							(mid -0.249642 -0.249642)
							(end -0.2794 -0.1778)
						)
						(arc
							(start -0.2794 0.1778)
							(mid -0.249642 0.249642)
							(end -0.1778 0.2794)
						)
						(arc
							(start 0.1778 0.2794)
							(mid 0.249642 0.249642)
							(end 0.2794 0.1778)
						)
						(arc
							(start 0.2794 -0.1778)
							(mid 0.249642 -0.249642)
							(end 0.1778 -0.2794)
						)
					)
					(width 0)
					(fill yes)
				)
			)
		)
		(pad "2" smd custom
			(at 0 0.4445 180)
			(size 0.1397 0.1397)
			(layers "F.Cu" "F.Mask" "F.Paste")
			(net "SPI_FLASH_SELECT")
			(options
				(clearance outline)
				(anchor circle)
			)
			(primitives
				(gr_poly
					(pts
						(arc
							(start -0.1778 -0.2794)
							(mid -0.249642 -0.249642)
							(end -0.2794 -0.1778)
						)
						(arc
							(start -0.2794 0.1778)
							(mid -0.249642 0.249642)
							(end -0.1778 0.2794)
						)
						(arc
							(start 0.1778 0.2794)
							(mid 0.249642 0.249642)
							(end 0.2794 0.1778)
						)
						(arc
							(start 0.2794 -0.1778)
							(mid 0.249642 -0.249642)
							(end 0.1778 -0.2794)
						)
					)
					(width 0)
					(fill yes)
				)
			)
		)
	)
	(footprint ""
		(layer "F.Cu")
		(at 66.003678 -130.034792 180)
		(property "Reference" "C280"
			(at 0 0 180)
			(layer "F.SilkS")
			(hide yes)
			(effects
				(font
					(size 1.27 1.27)
				)
			)
		)
		(property "Value" "SCD1U16V2KX-3GP"
			(at 1.1811 -2.7051 180)
			(unlocked yes)
			(layer "F.Fab")
			(hide yes)
			(effects
				(font
					(size 1.016 1.016)
					(thickness 0.1524)
				)
			)
		)
		(property "Device Type" "C402H22"
			(at 1.1811 -4.2291 180)
			(unlocked yes)
			(layer "F.Fab")
			(hide yes)
			(effects
				(font
					(size 1.016 1.016)
					(thickness 0.1524)
				)
			)
		)
		(duplicate_pad_numbers_are_jumpers no)
		(fp_rect
			(start -0.4318 0.9525)
			(end 0.4318 -0.9525)
			(stroke
				(width 0)
				(type default)
			)
			(fill no)
			(layer "F.CrtYd")
		)
		(fp_rect
			(start -0.4318 0.9525)
			(end 0.4318 -0.9525)
			(stroke
				(width 0)
				(type default)
			)
			(fill no)
			(layer "F.Fab")
		)
		(pad "1" smd custom
			(at 0 -0.4445 180)
			(size 0.1524 0.1524)
			(layers "F.Cu" "F.Mask" "F.Paste")
			(net "P3V3_STBY")
			(options
				(clearance outline)
				(anchor circle)
			)
			(primitives
				(gr_poly
					(pts
						(arc
							(start 0.3048 -0.2032)
							(mid 0.275042 -0.275042)
							(end 0.2032 -0.3048)
						)
						(arc
							(start -0.2032 -0.3048)
							(mid -0.275042 -0.275042)
							(end -0.3048 -0.2032)
						)
						(arc
							(start -0.3048 0.2032)
							(mid -0.275042 0.275042)
							(end -0.2032 0.3048)
						)
						(arc
							(start 0.2032 0.3048)
							(mid 0.275042 0.275042)
							(end 0.3048 0.2032)
						)
					)
					(width 0)
					(fill yes)
				)
			)
		)
		(pad "2" smd custom
			(at 0 0.4445 180)
			(size 0.1524 0.1524)
			(layers "F.Cu" "F.Mask" "F.Paste")
			(net "GND")
			(options
				(clearance outline)
				(anchor circle)
			)
			(primitives
				(gr_poly
					(pts
						(arc
							(start 0.3048 -0.2032)
							(mid 0.275042 -0.275042)
							(end 0.2032 -0.3048)
						)
						(arc
							(start -0.2032 -0.3048)
							(mid -0.275042 -0.275042)
							(end -0.3048 -0.2032)
						)
						(arc
							(start -0.3048 0.2032)
							(mid -0.275042 0.275042)
							(end -0.2032 0.3048)
						)
						(arc
							(start 0.2032 0.3048)
							(mid 0.275042 0.275042)
							(end 0.3048 0.2032)
						)
					)
					(width 0)
					(fill yes)
				)
			)
		)
	)
	(footprint ""
		(layer "F.Cu")
		(at 52.959 -143.129)
		(property "Reference" "TP269"
			(at 0 0 0)
			(layer "F.SilkS")
			(hide yes)
			(effects
				(font
					(size 1.27 1.27)
				)
			)
		)
		(property "Value" "TPAD28-2-GP"
			(at -0.0127 -1.6637 0)
			(unlocked yes)
			(layer "F.Fab")
			(hide yes)
			(effects
				(font
					(size 1.016 1.016)
					(thickness 0.1524)
				)
			)
		)
		(property "Device Type" "TPAD28"
			(at -0.0127 -3.1877 0)
			(unlocked yes)
			(layer "F.Fab")
			(hide yes)
			(effects
				(font
					(size 1.016 1.016)
					(thickness 0.1524)
				)
			)
		)
		(duplicate_pad_numbers_are_jumpers no)
		(fp_poly
			(pts
				(arc
					(start 0.3556 0)
					(mid -0.3556 0)
					(end 0.3556 0)
				)
			)
			(stroke
				(width 0)
				(type default)
			)
			(fill no)
			(layer "F.CrtYd")
		)
		(fp_poly
			(pts
				(arc
					(start 0.6096 0)
					(mid -0.6096 0)
					(end 0.6096 0)
				)
			)
			(stroke
				(width 0)
				(type default)
			)
			(fill no)
			(layer "F.Fab")
		)
		(pad "1" smd circle
			(at 0 0)
			(size 0.7112 0.7112)
			(layers "F.Cu" "F.Mask" "F.Paste")
			(net "LED_DR_LED0")
		)
	)
	(footprint ""
		(layer "F.Cu")
		(at 255.314704 -10.988548)
		(property "Reference" "R31"
			(at 0 0 0)
			(layer "F.SilkS")
			(hide yes)
			(effects
				(font
					(size 1.27 1.27)
				)
			)
		)
		(property "Value" "4K7R2F-GP"
			(at 0.064008 -3.993896 0)
			(unlocked yes)
			(layer "F.Fab")
			(hide yes)
			(effects
				(font
					(size 1.016 1.016)
					(thickness 0.1524)
				)
			)
		)
		(property "Device Type" "R402H16"
			(at 0.064008 -5.517896 0)
			(unlocked yes)
			(layer "F.Fab")
			(hide yes)
			(effects
				(font
					(size 1.016 1.016)
					(thickness 0.1524)
				)
			)
		)
		(duplicate_pad_numbers_are_jumpers no)
		(fp_line
			(start -0.508 -0.9398)
			(end -0.508 0.9398)
			(stroke
				(width 0.1524)
				(type default)
			)
			(layer "F.SilkS")
		)
		(fp_line
			(start 0.508 -0.9398)
			(end -0.508 -0.9398)
			(stroke
				(width 0.1524)
				(type default)
			)
			(layer "F.SilkS")
		)
		(fp_rect
			(start -0.508 0.9398)
			(end 0.508 -0.9398)
			(stroke
				(width 0)
				(type default)
			)
			(fill no)
			(layer "F.CrtYd")
		)
		(fp_rect
			(start -0.508 0.9398)
			(end 0.508 -0.9398)
			(stroke
				(width 0)
				(type default)
			)
			(fill no)
			(layer "F.Fab")
		)
		(pad "1" smd custom
			(at 0 -0.4445)
			(size 0.1397 0.1397)
			(layers "F.Cu" "F.Mask" "F.Paste")
			(net "THERM_BASE")
			(options
				(clearance outline)
				(anchor circle)
			)
			(primitives
				(gr_poly
					(pts
						(arc
							(start -0.1778 -0.2794)
							(mid -0.249642 -0.249642)
							(end -0.2794 -0.1778)
						)
						(arc
							(start -0.2794 0.1778)
							(mid -0.249642 0.249642)
							(end -0.1778 0.2794)
						)
						(arc
							(start 0.1778 0.2794)
							(mid 0.249642 0.249642)
							(end 0.2794 0.1778)
						)
						(arc
							(start 0.2794 -0.1778)
							(mid 0.249642 -0.249642)
							(end 0.1778 -0.2794)
						)
					)
					(width 0)
					(fill yes)
				)
			)
		)
		(pad "2" smd custom
			(at 0 0.4445)
			(size 0.1397 0.1397)
			(layers "F.Cu" "F.Mask" "F.Paste")
			(net "GND")
			(options
				(clearance outline)
				(anchor circle)
			)
			(primitives
				(gr_poly
					(pts
						(arc
							(start -0.1778 -0.2794)
							(mid -0.249642 -0.249642)
							(end -0.2794 -0.1778)
						)
						(arc
							(start -0.2794 0.1778)
							(mid -0.249642 0.249642)
							(end -0.1778 0.2794)
						)
						(arc
							(start 0.1778 0.2794)
							(mid 0.249642 0.249642)
							(end 0.2794 0.1778)
						)
						(arc
							(start 0.2794 -0.1778)
							(mid 0.249642 -0.249642)
							(end 0.1778 -0.2794)
						)
					)
					(width 0)
					(fill yes)
				)
			)
		)
	)
	(footprint ""
		(layer "F.Cu")
		(at 53.721 -144.907 90)
		(property "Reference" "R257"
			(at 0 0 90)
			(layer "F.SilkS")
			(hide yes)
			(effects
				(font
					(size 1.27 1.27)
				)
			)
		)
		(property "Value" "4K7R2F-GP"
			(at 0.064008 -3.993896 90)
			(unlocked yes)
			(layer "F.Fab")
			(hide yes)
			(effects
				(font
					(size 1.016 1.016)
					(thickness 0.1524)
				)
			)
		)
		(property "Device Type" "R402H16"
			(at 0.064008 -5.517896 90)
			(unlocked yes)
			(layer "F.Fab")
			(hide yes)
			(effects
				(font
					(size 1.016 1.016)
					(thickness 0.1524)
				)
			)
		)
		(duplicate_pad_numbers_are_jumpers no)
		(fp_line
			(start 0.508 -0.9398)
			(end -0.508 -0.9398)
			(stroke
				(width 0.1524)
				(type default)
			)
			(layer "F.SilkS")
		)
		(fp_line
			(start -0.508 -0.9398)
			(end -0.508 0.9398)
			(stroke
				(width 0.1524)
				(type default)
			)
			(layer "F.SilkS")
		)
		(fp_rect
			(start -0.508 0.9398)
			(end 0.508 -0.9398)
			(stroke
				(width 0)
				(type default)
			)
			(fill no)
			(layer "F.CrtYd")
		)
		(fp_rect
			(start -0.508 0.9398)
			(end 0.508 -0.9398)
			(stroke
				(width 0)
				(type default)
			)
			(fill no)
			(layer "F.Fab")
		)
		(pad "1" smd custom
			(at 0 -0.4445 90)
			(size 0.1397 0.1397)
			(layers "F.Cu" "F.Mask" "F.Paste")
			(net "LED_DR_LED1")
			(options
				(clearance outline)
				(anchor circle)
			)
			(primitives
				(gr_poly
					(pts
						(arc
							(start -0.1778 -0.2794)
							(mid -0.249642 -0.249642)
							(end -0.2794 -0.1778)
						)
						(arc
							(start -0.2794 0.1778)
							(mid -0.249642 0.249642)
							(end -0.1778 0.2794)
						)
						(arc
							(start 0.1778 0.2794)
							(mid 0.249642 0.249642)
							(end 0.2794 0.1778)
						)
						(arc
							(start 0.2794 -0.1778)
							(mid 0.249642 -0.249642)
							(end 0.1778 -0.2794)
						)
					)
					(width 0)
					(fill yes)
				)
			)
		)
		(pad "2" smd custom
			(at 0 0.4445 90)
			(size 0.1397 0.1397)
			(layers "F.Cu" "F.Mask" "F.Paste")
			(net "P3V3_STBY")
			(options
				(clearance outline)
				(anchor circle)
			)
			(primitives
				(gr_poly
					(pts
						(arc
							(start -0.1778 -0.2794)
							(mid -0.249642 -0.249642)
							(end -0.2794 -0.1778)
						)
						(arc
							(start -0.2794 0.1778)
							(mid -0.249642 0.249642)
							(end -0.1778 0.2794)
						)
						(arc
							(start 0.1778 0.2794)
							(mid 0.249642 0.249642)
							(end 0.2794 0.1778)
						)
						(arc
							(start 0.2794 -0.1778)
							(mid 0.249642 -0.249642)
							(end 0.1778 -0.2794)
						)
					)
					(width 0)
					(fill yes)
				)
			)
		)
	)
	(footprint ""
		(layer "F.Cu")
		(at 55.808118 -212.420454 180)
		(property "Reference" "C362"
			(at 0 0 180)
			(layer "F.SilkS")
			(hide yes)
			(effects
				(font
					(size 1.27 1.27)
				)
			)
		)
		(property "Value" "SCD22U10V2KX-1GP"
			(at 1.1811 -2.7051 180)
			(unlocked yes)
			(layer "F.Fab")
			(hide yes)
			(effects
				(font
					(size 1.016 1.016)
					(thickness 0.1524)
				)
			)
		)
		(property "Device Type" "C402H22"
			(at 1.1811 -4.2291 180)
			(unlocked yes)
			(layer "F.Fab")
			(hide yes)
			(effects
				(font
					(size 1.016 1.016)
					(thickness 0.1524)
				)
			)
		)
		(duplicate_pad_numbers_are_jumpers no)
		(fp_rect
			(start -0.4318 0.9525)
			(end 0.4318 -0.9525)
			(stroke
				(width 0)
				(type default)
			)
			(fill no)
			(layer "F.CrtYd")
		)
		(fp_rect
			(start -0.4318 0.9525)
			(end 0.4318 -0.9525)
			(stroke
				(width 0)
				(type default)
			)
			(fill no)
			(layer "F.Fab")
		)
		(pad "1" smd custom
			(at 0 -0.4445 180)
			(size 0.1524 0.1524)
			(layers "F.Cu" "F.Mask" "F.Paste")
			(net "PCIE_TX_CAP_N73")
			(options
				(clearance outline)
				(anchor circle)
			)
			(primitives
				(gr_poly
					(pts
						(arc
							(start 0.3048 -0.2032)
							(mid 0.275042 -0.275042)
							(end 0.2032 -0.3048)
						)
						(arc
							(start -0.2032 -0.3048)
							(mid -0.275042 -0.275042)
							(end -0.3048 -0.2032)
						)
						(arc
							(start -0.3048 0.2032)
							(mid -0.275042 0.275042)
							(end -0.2032 0.3048)
						)
						(arc
							(start 0.2032 0.3048)
							(mid 0.275042 0.275042)
							(end 0.3048 0.2032)
						)
					)
					(width 0)
					(fill yes)
				)
			)
		)
		(pad "2" smd custom
			(at 0 0.4445 180)
			(size 0.1524 0.1524)
			(layers "F.Cu" "F.Mask" "F.Paste")
			(net "PCIE_TX_N73")
			(options
				(clearance outline)
				(anchor circle)
			)
			(primitives
				(gr_poly
					(pts
						(arc
							(start 0.3048 -0.2032)
							(mid 0.275042 -0.275042)
							(end 0.2032 -0.3048)
						)
						(arc
							(start -0.2032 -0.3048)
							(mid -0.275042 -0.275042)
							(end -0.3048 -0.2032)
						)
						(arc
							(start -0.3048 0.2032)
							(mid -0.275042 0.275042)
							(end -0.2032 0.3048)
						)
						(arc
							(start 0.2032 0.3048)
							(mid 0.275042 0.275042)
							(end 0.3048 0.2032)
						)
					)
					(width 0)
					(fill yes)
				)
			)
		)
	)
	(footprint ""
		(layer "F.Cu")
		(at 276.460458 -4.70535 90)
		(property "Reference" "R332"
			(at 0 0 90)
			(layer "F.SilkS")
			(hide yes)
			(effects
				(font
					(size 1.27 1.27)
				)
			)
		)
		(property "Value" "0R2J-2-GP"
			(at 0.064008 -3.993896 90)
			(unlocked yes)
			(layer "F.Fab")
			(hide yes)
			(effects
				(font
					(size 1.016 1.016)
					(thickness 0.1524)
				)
			)
		)
		(property "Device Type" "R402H16"
			(at 0.064008 -5.517896 90)
			(unlocked yes)
			(layer "F.Fab")
			(hide yes)
			(effects
				(font
					(size 1.016 1.016)
					(thickness 0.1524)
				)
			)
		)
		(duplicate_pad_numbers_are_jumpers no)
		(fp_line
			(start 0.508 -0.9398)
			(end -0.508 -0.9398)
			(stroke
				(width 0.1524)
				(type default)
			)
			(layer "F.SilkS")
		)
		(fp_line
			(start -0.508 -0.9398)
			(end -0.508 0.9398)
			(stroke
				(width 0.1524)
				(type default)
			)
			(layer "F.SilkS")
		)
		(fp_rect
			(start -0.508 0.9398)
			(end 0.508 -0.9398)
			(stroke
				(width 0)
				(type default)
			)
			(fill no)
			(layer "F.CrtYd")
		)
		(fp_rect
			(start -0.508 0.9398)
			(end 0.508 -0.9398)
			(stroke
				(width 0)
				(type default)
			)
			(fill no)
			(layer "F.Fab")
		)
		(pad "1" smd custom
			(at 0 -0.4445 90)
			(size 0.1397 0.1397)
			(layers "F.Cu" "F.Mask" "F.Paste")
			(net "CLK_P_6_R")
			(options
				(clearance outline)
				(anchor circle)
			)
			(primitives
				(gr_poly
					(pts
						(arc
							(start -0.1778 -0.2794)
							(mid -0.249642 -0.249642)
							(end -0.2794 -0.1778)
						)
						(arc
							(start -0.2794 0.1778)
							(mid -0.249642 0.249642)
							(end -0.1778 0.2794)
						)
						(arc
							(start 0.1778 0.2794)
							(mid 0.249642 0.249642)
							(end 0.2794 0.1778)
						)
						(arc
							(start 0.2794 -0.1778)
							(mid 0.249642 -0.249642)
							(end 0.1778 -0.2794)
						)
					)
					(width 0)
					(fill yes)
				)
			)
		)
		(pad "2" smd custom
			(at 0 0.4445 90)
			(size 0.1397 0.1397)
			(layers "F.Cu" "F.Mask" "F.Paste")
			(net "CLK_P_6")
			(options
				(clearance outline)
				(anchor circle)
			)
			(primitives
				(gr_poly
					(pts
						(arc
							(start -0.1778 -0.2794)
							(mid -0.249642 -0.249642)
							(end -0.2794 -0.1778)
						)
						(arc
							(start -0.2794 0.1778)
							(mid -0.249642 0.249642)
							(end -0.1778 0.2794)
						)
						(arc
							(start 0.1778 0.2794)
							(mid 0.249642 0.249642)
							(end 0.2794 0.1778)
						)
						(arc
							(start 0.2794 -0.1778)
							(mid 0.249642 -0.249642)
							(end 0.1778 -0.2794)
						)
					)
					(width 0)
					(fill yes)
				)
			)
		)
	)
	(footprint ""
		(layer "F.Cu")
		(at 23.876 -134.747 90)
		(property "Reference" "R354"
			(at 0 0 90)
			(layer "F.SilkS")
			(hide yes)
			(effects
				(font
					(size 1.27 1.27)
				)
			)
		)
		(property "Value" "3K3R2F-2-GP"
			(at 0.064008 -3.993896 90)
			(unlocked yes)
			(layer "F.Fab")
			(hide yes)
			(effects
				(font
					(size 1.016 1.016)
					(thickness 0.1524)
				)
			)
		)
		(property "Device Type" "R402H16"
			(at 0.064008 -5.517896 90)
			(unlocked yes)
			(layer "F.Fab")
			(hide yes)
			(effects
				(font
					(size 1.016 1.016)
					(thickness 0.1524)
				)
			)
		)
		(duplicate_pad_numbers_are_jumpers no)
		(fp_line
			(start 0.508 -0.9398)
			(end -0.508 -0.9398)
			(stroke
				(width 0.1524)
				(type default)
			)
			(layer "F.SilkS")
		)
		(fp_line
			(start -0.508 -0.9398)
			(end -0.508 0.9398)
			(stroke
				(width 0.1524)
				(type default)
			)
			(layer "F.SilkS")
		)
		(fp_rect
			(start -0.508 0.9398)
			(end 0.508 -0.9398)
			(stroke
				(width 0)
				(type default)
			)
			(fill no)
			(layer "F.CrtYd")
		)
		(fp_rect
			(start -0.508 0.9398)
			(end 0.508 -0.9398)
			(stroke
				(width 0)
				(type default)
			)
			(fill no)
			(layer "F.Fab")
		)
		(pad "1" smd custom
			(at 0 -0.4445 90)
			(size 0.1397 0.1397)
			(layers "F.Cu" "F.Mask" "F.Paste")
			(net "P3V3_STBY")
			(options
				(clearance outline)
				(anchor circle)
			)
			(primitives
				(gr_poly
					(pts
						(arc
							(start -0.1778 -0.2794)
							(mid -0.249642 -0.249642)
							(end -0.2794 -0.1778)
						)
						(arc
							(start -0.2794 0.1778)
							(mid -0.249642 0.249642)
							(end -0.1778 0.2794)
						)
						(arc
							(start 0.1778 0.2794)
							(mid 0.249642 0.249642)
							(end 0.2794 0.1778)
						)
						(arc
							(start 0.2794 -0.1778)
							(mid 0.249642 -0.249642)
							(end 0.1778 -0.2794)
						)
					)
					(width 0)
					(fill yes)
				)
			)
		)
		(pad "2" smd custom
			(at 0 0.4445 90)
			(size 0.1397 0.1397)
			(layers "F.Cu" "F.Mask" "F.Paste")
			(net "ROMD3")
			(options
				(clearance outline)
				(anchor circle)
			)
			(primitives
				(gr_poly
					(pts
						(arc
							(start -0.1778 -0.2794)
							(mid -0.249642 -0.249642)
							(end -0.2794 -0.1778)
						)
						(arc
							(start -0.2794 0.1778)
							(mid -0.249642 0.249642)
							(end -0.1778 0.2794)
						)
						(arc
							(start 0.1778 0.2794)
							(mid 0.249642 0.249642)
							(end 0.2794 0.1778)
						)
						(arc
							(start 0.2794 -0.1778)
							(mid 0.249642 -0.249642)
							(end 0.1778 -0.2794)
						)
					)
					(width 0)
					(fill yes)
				)
			)
		)
	)
	(footprint ""
		(layer "F.Cu")
		(at 284.988 -59.69 -90)
		(property "Reference" "R609"
			(at 0 0 270)
			(layer "F.SilkS")
			(hide yes)
			(effects
				(font
					(size 1.27 1.27)
				)
			)
		)
		(property "Value" "0R2J-2-GP"
			(at 0.064008 -3.993896 270)
			(unlocked yes)
			(layer "F.Fab")
			(hide yes)
			(effects
				(font
					(size 1.016 1.016)
					(thickness 0.1524)
				)
			)
		)
		(property "Device Type" "R402H16"
			(at 0.064008 -5.517896 270)
			(unlocked yes)
			(layer "F.Fab")
			(hide yes)
			(effects
				(font
					(size 1.016 1.016)
					(thickness 0.1524)
				)
			)
		)
		(duplicate_pad_numbers_are_jumpers no)
		(fp_line
			(start -0.508 -0.9398)
			(end -0.508 0.9398)
			(stroke
				(width 0.1524)
				(type default)
			)
			(layer "F.SilkS")
		)
		(fp_line
			(start 0.508 -0.9398)
			(end -0.508 -0.9398)
			(stroke
				(width 0.1524)
				(type default)
			)
			(layer "F.SilkS")
		)
		(fp_rect
			(start -0.508 0.9398)
			(end 0.508 -0.9398)
			(stroke
				(width 0)
				(type default)
			)
			(fill no)
			(layer "F.CrtYd")
		)
		(fp_rect
			(start -0.508 0.9398)
			(end 0.508 -0.9398)
			(stroke
				(width 0)
				(type default)
			)
			(fill no)
			(layer "F.Fab")
		)
		(pad "1" smd custom
			(at 0 -0.4445 270)
			(size 0.1397 0.1397)
			(layers "F.Cu" "F.Mask" "F.Paste")
			(net "VS4_LED_R")
			(options
				(clearance outline)
				(anchor circle)
			)
			(primitives
				(gr_poly
					(pts
						(arc
							(start -0.1778 -0.2794)
							(mid -0.249642 -0.249642)
							(end -0.2794 -0.1778)
						)
						(arc
							(start -0.2794 0.1778)
							(mid -0.249642 0.249642)
							(end -0.1778 0.2794)
						)
						(arc
							(start 0.1778 0.2794)
							(mid 0.249642 0.249642)
							(end 0.2794 0.1778)
						)
						(arc
							(start 0.2794 -0.1778)
							(mid 0.249642 -0.249642)
							(end 0.1778 -0.2794)
						)
					)
					(width 0)
					(fill yes)
				)
			)
		)
		(pad "2" smd custom
			(at 0 0.4445 270)
			(size 0.1397 0.1397)
			(layers "F.Cu" "F.Mask" "F.Paste")
			(net "VS4_LED")
			(options
				(clearance outline)
				(anchor circle)
			)
			(primitives
				(gr_poly
					(pts
						(arc
							(start -0.1778 -0.2794)
							(mid -0.249642 -0.249642)
							(end -0.2794 -0.1778)
						)
						(arc
							(start -0.2794 0.1778)
							(mid -0.249642 0.249642)
							(end -0.1778 0.2794)
						)
						(arc
							(start 0.1778 0.2794)
							(mid 0.249642 0.249642)
							(end 0.2794 0.1778)
						)
						(arc
							(start 0.2794 -0.1778)
							(mid 0.249642 -0.249642)
							(end 0.1778 -0.2794)
						)
					)
					(width 0)
					(fill yes)
				)
			)
		)
	)
	(footprint ""
		(layer "F.Cu")
		(at 296.672 -68.834 180)
		(property "Reference" "C454"
			(at 0 0 180)
			(layer "F.SilkS")
			(hide yes)
			(effects
				(font
					(size 1.27 1.27)
				)
			)
		)
		(property "Value" "SC100U4V5MX-1-GP"
			(at -0.0762 -6.1214 180)
			(unlocked yes)
			(layer "F.Fab")
			(hide yes)
			(effects
				(font
					(size 1.016 1.016)
					(thickness 0.1524)
				)
			)
		)
		(property "Device Type" "C805H58"
			(at -0.0762 -8.1534 180)
			(unlocked yes)
			(layer "F.Fab")
			(hide yes)
			(effects
				(font
					(size 1.016 1.016)
					(thickness 0.1524)
				)
			)
		)
		(duplicate_pad_numbers_are_jumpers no)
		(fp_line
			(start 0.635 0)
			(end -0.635 0)
			(stroke
				(width 0.508)
				(type default)
			)
			(layer "F.SilkS")
		)
		(fp_rect
			(start -0.9652 1.778)
			(end 0.9652 -1.778)
			(stroke
				(width 0)
				(type default)
			)
			(fill no)
			(layer "F.CrtYd")
		)
		(fp_poly
			(pts
				(xy -0.9652 -1.778) (xy 0.9652 -1.778) (xy 0.9652 1.778) (xy -0.9652 1.778)
			)
			(stroke
				(width 0)
				(type default)
			)
			(fill no)
			(layer "F.Fab")
		)
		(pad "1" smd rect
			(at 0 -0.9652 180)
			(size 1.397 1.143)
			(layers "F.Cu" "F.Mask" "F.Paste")
			(net "DUT_VDD")
		)
		(pad "2" smd rect
			(at 0 0.9652 180)
			(size 1.397 1.143)
			(layers "F.Cu" "F.Mask" "F.Paste")
			(net "GND")
		)
	)
	(footprint ""
		(layer "F.Cu")
		(at 43.8912 -116.713)
		(property "Reference" "R473"
			(at 0 0 0)
			(layer "F.SilkS")
			(hide yes)
			(effects
				(font
					(size 1.27 1.27)
				)
			)
		)
		(property "Value" "0R2J-2-GP"
			(at 0.064008 -3.993896 0)
			(unlocked yes)
			(layer "F.Fab")
			(hide yes)
			(effects
				(font
					(size 1.016 1.016)
					(thickness 0.1524)
				)
			)
		)
		(property "Device Type" "R402H16"
			(at 0.064008 -5.517896 0)
			(unlocked yes)
			(layer "F.Fab")
			(hide yes)
			(effects
				(font
					(size 1.016 1.016)
					(thickness 0.1524)
				)
			)
		)
		(duplicate_pad_numbers_are_jumpers no)
		(fp_line
			(start -0.508 -0.9398)
			(end -0.508 0.9398)
			(stroke
				(width 0.1524)
				(type default)
			)
			(layer "F.SilkS")
		)
		(fp_line
			(start 0.508 -0.9398)
			(end -0.508 -0.9398)
			(stroke
				(width 0.1524)
				(type default)
			)
			(layer "F.SilkS")
		)
		(fp_rect
			(start -0.508 0.9398)
			(end 0.508 -0.9398)
			(stroke
				(width 0)
				(type default)
			)
			(fill no)
			(layer "F.CrtYd")
		)
		(fp_rect
			(start -0.508 0.9398)
			(end 0.508 -0.9398)
			(stroke
				(width 0)
				(type default)
			)
			(fill no)
			(layer "F.Fab")
		)
		(pad "1" smd custom
			(at 0 -0.4445)
			(size 0.1397 0.1397)
			(layers "F.Cu" "F.Mask" "F.Paste")
			(net "GPIOH2_R")
			(options
				(clearance outline)
				(anchor circle)
			)
			(primitives
				(gr_poly
					(pts
						(arc
							(start -0.1778 -0.2794)
							(mid -0.249642 -0.249642)
							(end -0.2794 -0.1778)
						)
						(arc
							(start -0.2794 0.1778)
							(mid -0.249642 0.249642)
							(end -0.1778 0.2794)
						)
						(arc
							(start 0.1778 0.2794)
							(mid 0.249642 0.249642)
							(end 0.2794 0.1778)
						)
						(arc
							(start 0.2794 -0.1778)
							(mid 0.249642 -0.249642)
							(end 0.1778 -0.2794)
						)
					)
					(width 0)
					(fill yes)
				)
			)
		)
		(pad "2" smd custom
			(at 0 0.4445)
			(size 0.1397 0.1397)
			(layers "F.Cu" "F.Mask" "F.Paste")
			(net "GPIOH2")
			(options
				(clearance outline)
				(anchor circle)
			)
			(primitives
				(gr_poly
					(pts
						(arc
							(start -0.1778 -0.2794)
							(mid -0.249642 -0.249642)
							(end -0.2794 -0.1778)
						)
						(arc
							(start -0.2794 0.1778)
							(mid -0.249642 0.249642)
							(end -0.1778 0.2794)
						)
						(arc
							(start 0.1778 0.2794)
							(mid 0.249642 0.249642)
							(end 0.2794 0.1778)
						)
						(arc
							(start 0.2794 -0.1778)
							(mid 0.249642 -0.249642)
							(end 0.1778 -0.2794)
						)
					)
					(width 0)
					(fill yes)
				)
			)
		)
	)
	(footprint ""
		(layer "F.Cu")
		(at 6.8072 -185.2676 -90)
		(property "Reference" "PR9004"
			(at 0 0 270)
			(layer "F.SilkS")
			(hide yes)
			(effects
				(font
					(size 1.27 1.27)
				)
			)
		)
		(property "Value" "0R2J-2-GP"
			(at 0.064008 -3.993896 270)
			(unlocked yes)
			(layer "F.Fab")
			(hide yes)
			(effects
				(font
					(size 1.016 1.016)
					(thickness 0.1524)
				)
			)
		)
		(property "Device Type" "R402H16"
			(at 0.064008 -5.517896 270)
			(unlocked yes)
			(layer "F.Fab")
			(hide yes)
			(effects
				(font
					(size 1.016 1.016)
					(thickness 0.1524)
				)
			)
		)
		(duplicate_pad_numbers_are_jumpers no)
		(fp_line
			(start -0.508 -0.9398)
			(end -0.508 0.9398)
			(stroke
				(width 0.1524)
				(type default)
			)
			(layer "F.SilkS")
		)
		(fp_line
			(start 0.508 -0.9398)
			(end -0.508 -0.9398)
			(stroke
				(width 0.1524)
				(type default)
			)
			(layer "F.SilkS")
		)
		(fp_rect
			(start -0.508 0.9398)
			(end 0.508 -0.9398)
			(stroke
				(width 0)
				(type default)
			)
			(fill no)
			(layer "F.CrtYd")
		)
		(fp_rect
			(start -0.508 0.9398)
			(end 0.508 -0.9398)
			(stroke
				(width 0)
				(type default)
			)
			(fill no)
			(layer "F.Fab")
		)
		(pad "1" smd custom
			(at 0 -0.4445 270)
			(size 0.1397 0.1397)
			(layers "F.Cu" "F.Mask" "F.Paste")
			(net "HSW_SCL_2")
			(options
				(clearance outline)
				(anchor circle)
			)
			(primitives
				(gr_poly
					(pts
						(arc
							(start -0.1778 -0.2794)
							(mid -0.249642 -0.249642)
							(end -0.2794 -0.1778)
						)
						(arc
							(start -0.2794 0.1778)
							(mid -0.249642 0.249642)
							(end -0.1778 0.2794)
						)
						(arc
							(start 0.1778 0.2794)
							(mid 0.249642 0.249642)
							(end 0.2794 0.1778)
						)
						(arc
							(start 0.2794 -0.1778)
							(mid 0.249642 -0.249642)
							(end 0.1778 -0.2794)
						)
					)
					(width 0)
					(fill yes)
				)
			)
		)
		(pad "2" smd custom
			(at 0 0.4445 270)
			(size 0.1397 0.1397)
			(layers "F.Cu" "F.Mask" "F.Paste")
			(net "BMC_I2C5_D_PEB_SCL")
			(options
				(clearance outline)
				(anchor circle)
			)
			(primitives
				(gr_poly
					(pts
						(arc
							(start -0.1778 -0.2794)
							(mid -0.249642 -0.249642)
							(end -0.2794 -0.1778)
						)
						(arc
							(start -0.2794 0.1778)
							(mid -0.249642 0.249642)
							(end -0.1778 0.2794)
						)
						(arc
							(start 0.1778 0.2794)
							(mid 0.249642 0.249642)
							(end 0.2794 0.1778)
						)
						(arc
							(start 0.2794 -0.1778)
							(mid 0.249642 -0.249642)
							(end 0.1778 -0.2794)
						)
					)
					(width 0)
					(fill yes)
				)
			)
		)
	)
	(footprint ""
		(layer "F.Cu")
		(at 18.3642 -66.9798)
		(property "Reference" "C637"
			(at 0 0 0)
			(layer "F.SilkS")
			(hide yes)
			(effects
				(font
					(size 1.27 1.27)
				)
			)
		)
		(property "Value" "SCD1U16V2KX-3GP"
			(at 1.1811 -2.7051 0)
			(unlocked yes)
			(layer "F.Fab")
			(hide yes)
			(effects
				(font
					(size 1.016 1.016)
					(thickness 0.1524)
				)
			)
		)
		(property "Device Type" "C402H22"
			(at 1.1811 -4.2291 0)
			(unlocked yes)
			(layer "F.Fab")
			(hide yes)
			(effects
				(font
					(size 1.016 1.016)
					(thickness 0.1524)
				)
			)
		)
		(duplicate_pad_numbers_are_jumpers no)
		(fp_rect
			(start -0.4318 0.9525)
			(end 0.4318 -0.9525)
			(stroke
				(width 0)
				(type default)
			)
			(fill no)
			(layer "F.CrtYd")
		)
		(fp_rect
			(start -0.4318 0.9525)
			(end 0.4318 -0.9525)
			(stroke
				(width 0)
				(type default)
			)
			(fill no)
			(layer "F.Fab")
		)
		(pad "1" smd custom
			(at 0 -0.4445)
			(size 0.1524 0.1524)
			(layers "F.Cu" "F.Mask" "F.Paste")
			(net "P0V9_I210")
			(options
				(clearance outline)
				(anchor circle)
			)
			(primitives
				(gr_poly
					(pts
						(arc
							(start 0.3048 -0.2032)
							(mid 0.275042 -0.275042)
							(end 0.2032 -0.3048)
						)
						(arc
							(start -0.2032 -0.3048)
							(mid -0.275042 -0.275042)
							(end -0.3048 -0.2032)
						)
						(arc
							(start -0.3048 0.2032)
							(mid -0.275042 0.275042)
							(end -0.2032 0.3048)
						)
						(arc
							(start 0.2032 0.3048)
							(mid 0.275042 0.275042)
							(end 0.3048 0.2032)
						)
					)
					(width 0)
					(fill yes)
				)
			)
		)
		(pad "2" smd custom
			(at 0 0.4445)
			(size 0.1524 0.1524)
			(layers "F.Cu" "F.Mask" "F.Paste")
			(net "GND")
			(options
				(clearance outline)
				(anchor circle)
			)
			(primitives
				(gr_poly
					(pts
						(arc
							(start 0.3048 -0.2032)
							(mid 0.275042 -0.275042)
							(end 0.2032 -0.3048)
						)
						(arc
							(start -0.2032 -0.3048)
							(mid -0.275042 -0.275042)
							(end -0.3048 -0.2032)
						)
						(arc
							(start -0.3048 0.2032)
							(mid -0.275042 0.275042)
							(end -0.2032 0.3048)
						)
						(arc
							(start 0.2032 0.3048)
							(mid 0.275042 0.275042)
							(end 0.3048 0.2032)
						)
					)
					(width 0)
					(fill yes)
				)
			)
		)
	)
	(footprint ""
		(layer "F.Cu")
		(at 218.9988 -0.9906 90)
		(property "Reference" "R412"
			(at 0 0 90)
			(layer "F.SilkS")
			(hide yes)
			(effects
				(font
					(size 1.27 1.27)
				)
			)
		)
		(property "Value" "0R2J-2-GP"
			(at 0.064008 -3.993896 90)
			(unlocked yes)
			(layer "F.Fab")
			(hide yes)
			(effects
				(font
					(size 1.016 1.016)
					(thickness 0.1524)
				)
			)
		)
		(property "Device Type" "R402H16"
			(at 0.064008 -5.517896 90)
			(unlocked yes)
			(layer "F.Fab")
			(hide yes)
			(effects
				(font
					(size 1.016 1.016)
					(thickness 0.1524)
				)
			)
		)
		(duplicate_pad_numbers_are_jumpers no)
		(fp_line
			(start 0.508 -0.9398)
			(end -0.508 -0.9398)
			(stroke
				(width 0.1524)
				(type default)
			)
			(layer "F.SilkS")
		)
		(fp_line
			(start -0.508 -0.9398)
			(end -0.508 0.9398)
			(stroke
				(width 0.1524)
				(type default)
			)
			(layer "F.SilkS")
		)
		(fp_rect
			(start -0.508 0.9398)
			(end 0.508 -0.9398)
			(stroke
				(width 0)
				(type default)
			)
			(fill no)
			(layer "F.CrtYd")
		)
		(fp_rect
			(start -0.508 0.9398)
			(end 0.508 -0.9398)
			(stroke
				(width 0)
				(type default)
			)
			(fill no)
			(layer "F.Fab")
		)
		(pad "1" smd custom
			(at 0 -0.4445 90)
			(size 0.1397 0.1397)
			(layers "F.Cu" "F.Mask" "F.Paste")
			(net "EXP_SMART_RX")
			(options
				(clearance outline)
				(anchor circle)
			)
			(primitives
				(gr_poly
					(pts
						(arc
							(start -0.1778 -0.2794)
							(mid -0.249642 -0.249642)
							(end -0.2794 -0.1778)
						)
						(arc
							(start -0.2794 0.1778)
							(mid -0.249642 0.249642)
							(end -0.1778 0.2794)
						)
						(arc
							(start 0.1778 0.2794)
							(mid 0.249642 0.249642)
							(end 0.2794 0.1778)
						)
						(arc
							(start 0.2794 -0.1778)
							(mid 0.249642 -0.249642)
							(end 0.1778 -0.2794)
						)
					)
					(width 0)
					(fill yes)
				)
			)
		)
		(pad "2" smd custom
			(at 0 0.4445 90)
			(size 0.1397 0.1397)
			(layers "F.Cu" "F.Mask" "F.Paste")
			(net "EXP_UART_RX_R")
			(options
				(clearance outline)
				(anchor circle)
			)
			(primitives
				(gr_poly
					(pts
						(arc
							(start -0.1778 -0.2794)
							(mid -0.249642 -0.249642)
							(end -0.2794 -0.1778)
						)
						(arc
							(start -0.2794 0.1778)
							(mid -0.249642 0.249642)
							(end -0.1778 0.2794)
						)
						(arc
							(start 0.1778 0.2794)
							(mid 0.249642 0.249642)
							(end 0.2794 0.1778)
						)
						(arc
							(start 0.2794 -0.1778)
							(mid 0.249642 -0.249642)
							(end 0.1778 -0.2794)
						)
					)
					(width 0)
					(fill yes)
				)
			)
		)
	)
	(footprint ""
		(layer "F.Cu")
		(at 331.756512 -184.878218)
		(property "Reference" "R7966"
			(at 0 0 0)
			(layer "F.SilkS")
			(hide yes)
			(effects
				(font
					(size 1.27 1.27)
				)
			)
		)
		(property "Value" "0R2J-2-GP"
			(at 0.064008 -3.993896 0)
			(unlocked yes)
			(layer "F.Fab")
			(hide yes)
			(effects
				(font
					(size 1.016 1.016)
					(thickness 0.1524)
				)
			)
		)
		(property "Device Type" "R402H16"
			(at 0.064008 -5.517896 0)
			(unlocked yes)
			(layer "F.Fab")
			(hide yes)
			(effects
				(font
					(size 1.016 1.016)
					(thickness 0.1524)
				)
			)
		)
		(duplicate_pad_numbers_are_jumpers no)
		(fp_line
			(start -0.508 -0.9398)
			(end -0.508 0.9398)
			(stroke
				(width 0.1524)
				(type default)
			)
			(layer "F.SilkS")
		)
		(fp_line
			(start 0.508 -0.9398)
			(end -0.508 -0.9398)
			(stroke
				(width 0.1524)
				(type default)
			)
			(layer "F.SilkS")
		)
		(fp_rect
			(start -0.508 0.9398)
			(end 0.508 -0.9398)
			(stroke
				(width 0)
				(type default)
			)
			(fill no)
			(layer "F.CrtYd")
		)
		(fp_rect
			(start -0.508 0.9398)
			(end 0.508 -0.9398)
			(stroke
				(width 0)
				(type default)
			)
			(fill no)
			(layer "F.Fab")
		)
		(pad "1" smd custom
			(at 0 -0.4445)
			(size 0.1397 0.1397)
			(layers "F.Cu" "F.Mask" "F.Paste")
			(net "TWI_SCL1")
			(options
				(clearance outline)
				(anchor circle)
			)
			(primitives
				(gr_poly
					(pts
						(arc
							(start -0.1778 -0.2794)
							(mid -0.249642 -0.249642)
							(end -0.2794 -0.1778)
						)
						(arc
							(start -0.2794 0.1778)
							(mid -0.249642 0.249642)
							(end -0.1778 0.2794)
						)
						(arc
							(start 0.1778 0.2794)
							(mid 0.249642 0.249642)
							(end 0.2794 0.1778)
						)
						(arc
							(start 0.2794 -0.1778)
							(mid 0.249642 -0.249642)
							(end 0.1778 -0.2794)
						)
					)
					(width 0)
					(fill yes)
				)
			)
		)
		(pad "2" smd custom
			(at 0 0.4445)
			(size 0.1397 0.1397)
			(layers "F.Cu" "F.Mask" "F.Paste")
			(net "I2C_GPIO_SCL_4")
			(options
				(clearance outline)
				(anchor circle)
			)
			(primitives
				(gr_poly
					(pts
						(arc
							(start -0.1778 -0.2794)
							(mid -0.249642 -0.249642)
							(end -0.2794 -0.1778)
						)
						(arc
							(start -0.2794 0.1778)
							(mid -0.249642 0.249642)
							(end -0.1778 0.2794)
						)
						(arc
							(start 0.1778 0.2794)
							(mid 0.249642 0.249642)
							(end 0.2794 0.1778)
						)
						(arc
							(start 0.2794 -0.1778)
							(mid 0.249642 -0.249642)
							(end 0.1778 -0.2794)
						)
					)
					(width 0)
					(fill yes)
				)
			)
		)
	)
	(footprint ""
		(layer "F.Cu")
		(at 92.391992 -212.420454 180)
		(property "Reference" "C378"
			(at 0 0 180)
			(layer "F.SilkS")
			(hide yes)
			(effects
				(font
					(size 1.27 1.27)
				)
			)
		)
		(property "Value" "SCD22U10V2KX-1GP"
			(at 1.1811 -2.7051 180)
			(unlocked yes)
			(layer "F.Fab")
			(hide yes)
			(effects
				(font
					(size 1.016 1.016)
					(thickness 0.1524)
				)
			)
		)
		(property "Device Type" "C402H22"
			(at 1.1811 -4.2291 180)
			(unlocked yes)
			(layer "F.Fab")
			(hide yes)
			(effects
				(font
					(size 1.016 1.016)
					(thickness 0.1524)
				)
			)
		)
		(duplicate_pad_numbers_are_jumpers no)
		(fp_rect
			(start -0.4318 0.9525)
			(end 0.4318 -0.9525)
			(stroke
				(width 0)
				(type default)
			)
			(fill no)
			(layer "F.CrtYd")
		)
		(fp_rect
			(start -0.4318 0.9525)
			(end 0.4318 -0.9525)
			(stroke
				(width 0)
				(type default)
			)
			(fill no)
			(layer "F.Fab")
		)
		(pad "1" smd custom
			(at 0 -0.4445 180)
			(size 0.1524 0.1524)
			(layers "F.Cu" "F.Mask" "F.Paste")
			(net "PCIE_TX_CAP_P64")
			(options
				(clearance outline)
				(anchor circle)
			)
			(primitives
				(gr_poly
					(pts
						(arc
							(start 0.3048 -0.2032)
							(mid 0.275042 -0.275042)
							(end 0.2032 -0.3048)
						)
						(arc
							(start -0.2032 -0.3048)
							(mid -0.275042 -0.275042)
							(end -0.3048 -0.2032)
						)
						(arc
							(start -0.3048 0.2032)
							(mid -0.275042 0.275042)
							(end -0.2032 0.3048)
						)
						(arc
							(start 0.2032 0.3048)
							(mid 0.275042 0.275042)
							(end 0.3048 0.2032)
						)
					)
					(width 0)
					(fill yes)
				)
			)
		)
		(pad "2" smd custom
			(at 0 0.4445 180)
			(size 0.1524 0.1524)
			(layers "F.Cu" "F.Mask" "F.Paste")
			(net "PCIE_TX_P64")
			(options
				(clearance outline)
				(anchor circle)
			)
			(primitives
				(gr_poly
					(pts
						(arc
							(start 0.3048 -0.2032)
							(mid 0.275042 -0.275042)
							(end 0.2032 -0.3048)
						)
						(arc
							(start -0.2032 -0.3048)
							(mid -0.275042 -0.275042)
							(end -0.3048 -0.2032)
						)
						(arc
							(start -0.3048 0.2032)
							(mid -0.275042 0.275042)
							(end -0.2032 0.3048)
						)
						(arc
							(start 0.2032 0.3048)
							(mid 0.275042 0.275042)
							(end 0.3048 0.2032)
						)
					)
					(width 0)
					(fill yes)
				)
			)
		)
	)
	(footprint ""
		(layer "F.Cu")
		(at 187.192158 -212.420454 180)
		(property "Reference" "C125"
			(at 0 0 180)
			(layer "F.SilkS")
			(hide yes)
			(effects
				(font
					(size 1.27 1.27)
				)
			)
		)
		(property "Value" "SCD22U10V2KX-1GP"
			(at 1.1811 -2.7051 180)
			(unlocked yes)
			(layer "F.Fab")
			(hide yes)
			(effects
				(font
					(size 1.016 1.016)
					(thickness 0.1524)
				)
			)
		)
		(property "Device Type" "C402H22"
			(at 1.1811 -4.2291 180)
			(unlocked yes)
			(layer "F.Fab")
			(hide yes)
			(effects
				(font
					(size 1.016 1.016)
					(thickness 0.1524)
				)
			)
		)
		(duplicate_pad_numbers_are_jumpers no)
		(fp_rect
			(start -0.4318 0.9525)
			(end 0.4318 -0.9525)
			(stroke
				(width 0)
				(type default)
			)
			(fill no)
			(layer "F.CrtYd")
		)
		(fp_rect
			(start -0.4318 0.9525)
			(end 0.4318 -0.9525)
			(stroke
				(width 0)
				(type default)
			)
			(fill no)
			(layer "F.Fab")
		)
		(pad "1" smd custom
			(at 0 -0.4445 180)
			(size 0.1524 0.1524)
			(layers "F.Cu" "F.Mask" "F.Paste")
			(net "PCIE_TX_CAP_P46")
			(options
				(clearance outline)
				(anchor circle)
			)
			(primitives
				(gr_poly
					(pts
						(arc
							(start 0.3048 -0.2032)
							(mid 0.275042 -0.275042)
							(end 0.2032 -0.3048)
						)
						(arc
							(start -0.2032 -0.3048)
							(mid -0.275042 -0.275042)
							(end -0.3048 -0.2032)
						)
						(arc
							(start -0.3048 0.2032)
							(mid -0.275042 0.275042)
							(end -0.2032 0.3048)
						)
						(arc
							(start 0.2032 0.3048)
							(mid 0.275042 0.275042)
							(end 0.3048 0.2032)
						)
					)
					(width 0)
					(fill yes)
				)
			)
		)
		(pad "2" smd custom
			(at 0 0.4445 180)
			(size 0.1524 0.1524)
			(layers "F.Cu" "F.Mask" "F.Paste")
			(net "PCIE_TX_P46")
			(options
				(clearance outline)
				(anchor circle)
			)
			(primitives
				(gr_poly
					(pts
						(arc
							(start 0.3048 -0.2032)
							(mid 0.275042 -0.275042)
							(end 0.2032 -0.3048)
						)
						(arc
							(start -0.2032 -0.3048)
							(mid -0.275042 -0.275042)
							(end -0.3048 -0.2032)
						)
						(arc
							(start -0.3048 0.2032)
							(mid -0.275042 0.275042)
							(end -0.2032 0.3048)
						)
						(arc
							(start 0.2032 0.3048)
							(mid 0.275042 0.275042)
							(end 0.3048 0.2032)
						)
					)
					(width 0)
					(fill yes)
				)
			)
		)
	)
	(footprint ""
		(layer "F.Cu")
		(at 25.96896 -80.1751 90)
		(property "Reference" "R383"
			(at 0 0 90)
			(layer "F.SilkS")
			(hide yes)
			(effects
				(font
					(size 1.27 1.27)
				)
			)
		)
		(property "Value" "0R2J-2-GP"
			(at 0.064008 -3.993896 90)
			(unlocked yes)
			(layer "F.Fab")
			(hide yes)
			(effects
				(font
					(size 1.016 1.016)
					(thickness 0.1524)
				)
			)
		)
		(property "Device Type" "R402H16"
			(at 0.064008 -5.517896 90)
			(unlocked yes)
			(layer "F.Fab")
			(hide yes)
			(effects
				(font
					(size 1.016 1.016)
					(thickness 0.1524)
				)
			)
		)
		(duplicate_pad_numbers_are_jumpers no)
		(fp_line
			(start 0.508 -0.9398)
			(end -0.508 -0.9398)
			(stroke
				(width 0.1524)
				(type default)
			)
			(layer "F.SilkS")
		)
		(fp_line
			(start -0.508 -0.9398)
			(end -0.508 0.9398)
			(stroke
				(width 0.1524)
				(type default)
			)
			(layer "F.SilkS")
		)
		(fp_rect
			(start -0.508 0.9398)
			(end 0.508 -0.9398)
			(stroke
				(width 0)
				(type default)
			)
			(fill no)
			(layer "F.CrtYd")
		)
		(fp_rect
			(start -0.508 0.9398)
			(end 0.508 -0.9398)
			(stroke
				(width 0)
				(type default)
			)
			(fill no)
			(layer "F.Fab")
		)
		(pad "1" smd custom
			(at 0 -0.4445 90)
			(size 0.1397 0.1397)
			(layers "F.Cu" "F.Mask" "F.Paste")
			(net "NVM_SI")
			(options
				(clearance outline)
				(anchor circle)
			)
			(primitives
				(gr_poly
					(pts
						(arc
							(start -0.1778 -0.2794)
							(mid -0.249642 -0.249642)
							(end -0.2794 -0.1778)
						)
						(arc
							(start -0.2794 0.1778)
							(mid -0.249642 0.249642)
							(end -0.1778 0.2794)
						)
						(arc
							(start 0.1778 0.2794)
							(mid 0.249642 0.249642)
							(end 0.2794 0.1778)
						)
						(arc
							(start 0.2794 -0.1778)
							(mid 0.249642 -0.249642)
							(end 0.1778 -0.2794)
						)
					)
					(width 0)
					(fill yes)
				)
			)
		)
		(pad "2" smd custom
			(at 0 0.4445 90)
			(size 0.1397 0.1397)
			(layers "F.Cu" "F.Mask" "F.Paste")
			(net "I210_SI_R")
			(options
				(clearance outline)
				(anchor circle)
			)
			(primitives
				(gr_poly
					(pts
						(arc
							(start -0.1778 -0.2794)
							(mid -0.249642 -0.249642)
							(end -0.2794 -0.1778)
						)
						(arc
							(start -0.2794 0.1778)
							(mid -0.249642 0.249642)
							(end -0.1778 0.2794)
						)
						(arc
							(start 0.1778 0.2794)
							(mid 0.249642 0.249642)
							(end 0.2794 0.1778)
						)
						(arc
							(start 0.2794 -0.1778)
							(mid 0.249642 -0.249642)
							(end 0.1778 -0.2794)
						)
					)
					(width 0)
					(fill yes)
				)
			)
		)
	)
	(footprint ""
		(layer "F.Cu")
		(at 14.4018 -194.2592 180)
		(property "Reference" "R2117"
			(at 0 0 180)
			(layer "F.SilkS")
			(hide yes)
			(effects
				(font
					(size 1.27 1.27)
				)
			)
		)
		(property "Value" "100KR2J-4-GP"
			(at 0.064008 -3.993896 180)
			(unlocked yes)
			(layer "F.Fab")
			(hide yes)
			(effects
				(font
					(size 1.016 1.016)
					(thickness 0.1524)
				)
			)
		)
		(property "Device Type" "R402H15"
			(at 0.064008 -5.517896 180)
			(unlocked yes)
			(layer "F.Fab")
			(hide yes)
			(effects
				(font
					(size 1.016 1.016)
					(thickness 0.1524)
				)
			)
		)
		(duplicate_pad_numbers_are_jumpers no)
		(fp_line
			(start 0.508 -0.9398)
			(end -0.508 -0.9398)
			(stroke
				(width 0.1524)
				(type default)
			)
			(layer "F.SilkS")
		)
		(fp_line
			(start -0.508 -0.9398)
			(end -0.508 0.9398)
			(stroke
				(width 0.1524)
				(type default)
			)
			(layer "F.SilkS")
		)
		(fp_rect
			(start -0.508 0.9398)
			(end 0.508 -0.9398)
			(stroke
				(width 0)
				(type default)
			)
			(fill no)
			(layer "F.CrtYd")
		)
		(fp_rect
			(start -0.508 0.9398)
			(end 0.508 -0.9398)
			(stroke
				(width 0)
				(type default)
			)
			(fill no)
			(layer "F.Fab")
		)
		(pad "1" smd custom
			(at 0 -0.4445 180)
			(size 0.1397 0.1397)
			(layers "F.Cu" "F.Mask" "F.Paste")
			(net "MB0_VCAP_R")
			(options
				(clearance outline)
				(anchor circle)
			)
			(primitives
				(gr_poly
					(pts
						(arc
							(start -0.1778 -0.2794)
							(mid -0.249642 -0.249642)
							(end -0.2794 -0.1778)
						)
						(arc
							(start -0.2794 0.1778)
							(mid -0.249642 0.249642)
							(end -0.1778 0.2794)
						)
						(arc
							(start 0.1778 0.2794)
							(mid 0.249642 0.249642)
							(end 0.2794 0.1778)
						)
						(arc
							(start 0.2794 -0.1778)
							(mid 0.249642 -0.249642)
							(end 0.1778 -0.2794)
						)
					)
					(width 0)
					(fill yes)
				)
			)
		)
		(pad "2" smd custom
			(at 0 0.4445 180)
			(size 0.1397 0.1397)
			(layers "F.Cu" "F.Mask" "F.Paste")
			(net "MB0_ISET_R")
			(options
				(clearance outline)
				(anchor circle)
			)
			(primitives
				(gr_poly
					(pts
						(arc
							(start -0.1778 -0.2794)
							(mid -0.249642 -0.249642)
							(end -0.2794 -0.1778)
						)
						(arc
							(start -0.2794 0.1778)
							(mid -0.249642 0.249642)
							(end -0.1778 0.2794)
						)
						(arc
							(start 0.1778 0.2794)
							(mid 0.249642 0.249642)
							(end 0.2794 0.1778)
						)
						(arc
							(start 0.2794 -0.1778)
							(mid 0.249642 -0.249642)
							(end 0.1778 -0.2794)
						)
					)
					(width 0)
					(fill yes)
				)
			)
		)
	)
	(footprint ""
		(layer "F.Cu")
		(at 273.702526 -6.8453 -90)
		(property "Reference" "R2903"
			(at 0 0 270)
			(layer "F.SilkS")
			(hide yes)
			(effects
				(font
					(size 1.27 1.27)
				)
			)
		)
		(property "Value" "0R2J-2-GP"
			(at 0.064008 -3.993896 270)
			(unlocked yes)
			(layer "F.Fab")
			(hide yes)
			(effects
				(font
					(size 1.016 1.016)
					(thickness 0.1524)
				)
			)
		)
		(property "Device Type" "R402H16"
			(at 0.064008 -5.517896 270)
			(unlocked yes)
			(layer "F.Fab")
			(hide yes)
			(effects
				(font
					(size 1.016 1.016)
					(thickness 0.1524)
				)
			)
		)
		(duplicate_pad_numbers_are_jumpers no)
		(fp_line
			(start -0.508 -0.9398)
			(end -0.508 0.9398)
			(stroke
				(width 0.1524)
				(type default)
			)
			(layer "F.SilkS")
		)
		(fp_line
			(start 0.508 -0.9398)
			(end -0.508 -0.9398)
			(stroke
				(width 0.1524)
				(type default)
			)
			(layer "F.SilkS")
		)
		(fp_rect
			(start -0.508 0.9398)
			(end 0.508 -0.9398)
			(stroke
				(width 0)
				(type default)
			)
			(fill no)
			(layer "F.CrtYd")
		)
		(fp_rect
			(start -0.508 0.9398)
			(end 0.508 -0.9398)
			(stroke
				(width 0)
				(type default)
			)
			(fill no)
			(layer "F.Fab")
		)
		(pad "1" smd custom
			(at 0 -0.4445 270)
			(size 0.1397 0.1397)
			(layers "F.Cu" "F.Mask" "F.Paste")
			(net "BMC_I2C12_MINI6_SDA")
			(options
				(clearance outline)
				(anchor circle)
			)
			(primitives
				(gr_poly
					(pts
						(arc
							(start -0.1778 -0.2794)
							(mid -0.249642 -0.249642)
							(end -0.2794 -0.1778)
						)
						(arc
							(start -0.2794 0.1778)
							(mid -0.249642 0.249642)
							(end -0.1778 0.2794)
						)
						(arc
							(start 0.1778 0.2794)
							(mid 0.249642 0.249642)
							(end 0.2794 0.1778)
						)
						(arc
							(start 0.2794 -0.1778)
							(mid 0.249642 -0.249642)
							(end 0.1778 -0.2794)
						)
					)
					(width 0)
					(fill yes)
				)
			)
		)
		(pad "2" smd custom
			(at 0 0.4445 270)
			(size 0.1397 0.1397)
			(layers "F.Cu" "F.Mask" "F.Paste")
			(net "8644_SDA_R_6")
			(options
				(clearance outline)
				(anchor circle)
			)
			(primitives
				(gr_poly
					(pts
						(arc
							(start -0.1778 -0.2794)
							(mid -0.249642 -0.249642)
							(end -0.2794 -0.1778)
						)
						(arc
							(start -0.2794 0.1778)
							(mid -0.249642 0.249642)
							(end -0.1778 0.2794)
						)
						(arc
							(start 0.1778 0.2794)
							(mid 0.249642 0.249642)
							(end 0.2794 0.1778)
						)
						(arc
							(start 0.2794 -0.1778)
							(mid 0.249642 -0.249642)
							(end 0.1778 -0.2794)
						)
					)
					(width 0)
					(fill yes)
				)
			)
		)
	)
	(footprint ""
		(layer "F.Cu")
		(at 162.56 -85.2424)
		(property "Reference" "R3103"
			(at 0 0 0)
			(layer "F.SilkS")
			(hide yes)
			(effects
				(font
					(size 1.27 1.27)
				)
			)
		)
		(property "Value" "27R2F-GP"
			(at 0.064008 -3.993896 0)
			(unlocked yes)
			(layer "F.Fab")
			(hide yes)
			(effects
				(font
					(size 1.016 1.016)
					(thickness 0.1524)
				)
			)
		)
		(property "Device Type" "R402H16"
			(at 0.064008 -5.517896 0)
			(unlocked yes)
			(layer "F.Fab")
			(hide yes)
			(effects
				(font
					(size 1.016 1.016)
					(thickness 0.1524)
				)
			)
		)
		(duplicate_pad_numbers_are_jumpers no)
		(fp_line
			(start -0.508 -0.9398)
			(end -0.508 0.9398)
			(stroke
				(width 0.1524)
				(type default)
			)
			(layer "F.SilkS")
		)
		(fp_line
			(start 0.508 -0.9398)
			(end -0.508 -0.9398)
			(stroke
				(width 0.1524)
				(type default)
			)
			(layer "F.SilkS")
		)
		(fp_rect
			(start -0.508 0.9398)
			(end 0.508 -0.9398)
			(stroke
				(width 0)
				(type default)
			)
			(fill no)
			(layer "F.CrtYd")
		)
		(fp_rect
			(start -0.508 0.9398)
			(end 0.508 -0.9398)
			(stroke
				(width 0)
				(type default)
			)
			(fill no)
			(layer "F.Fab")
		)
		(pad "1" smd custom
			(at 0 -0.4445)
			(size 0.1397 0.1397)
			(layers "F.Cu" "F.Mask" "F.Paste")
			(net "PCIE_REFCLK_D_N_R")
			(options
				(clearance outline)
				(anchor circle)
			)
			(primitives
				(gr_poly
					(pts
						(arc
							(start -0.1778 -0.2794)
							(mid -0.249642 -0.249642)
							(end -0.2794 -0.1778)
						)
						(arc
							(start -0.2794 0.1778)
							(mid -0.249642 0.249642)
							(end -0.1778 0.2794)
						)
						(arc
							(start 0.1778 0.2794)
							(mid 0.249642 0.249642)
							(end 0.2794 0.1778)
						)
						(arc
							(start 0.2794 -0.1778)
							(mid 0.249642 -0.249642)
							(end 0.1778 -0.2794)
						)
					)
					(width 0)
					(fill yes)
				)
			)
		)
		(pad "2" smd custom
			(at 0 0.4445)
			(size 0.1397 0.1397)
			(layers "F.Cu" "F.Mask" "F.Paste")
			(net "PCIE_REFCLK_D_N")
			(options
				(clearance outline)
				(anchor circle)
			)
			(primitives
				(gr_poly
					(pts
						(arc
							(start -0.1778 -0.2794)
							(mid -0.249642 -0.249642)
							(end -0.2794 -0.1778)
						)
						(arc
							(start -0.2794 0.1778)
							(mid -0.249642 0.249642)
							(end -0.1778 0.2794)
						)
						(arc
							(start 0.1778 0.2794)
							(mid 0.249642 0.249642)
							(end 0.2794 0.1778)
						)
						(arc
							(start 0.2794 -0.1778)
							(mid 0.249642 -0.249642)
							(end 0.1778 -0.2794)
						)
					)
					(width 0)
					(fill yes)
				)
			)
		)
	)
	(footprint ""
		(layer "F.Cu")
		(at 32.004 -197.866)
		(property "Reference" "R2111"
			(at 0 0 0)
			(layer "F.SilkS")
			(hide yes)
			(effects
				(font
					(size 1.27 1.27)
				)
			)
		)
		(property "Value" "10R2J-2-GP"
			(at 0.064008 -3.993896 0)
			(unlocked yes)
			(layer "F.Fab")
			(hide yes)
			(effects
				(font
					(size 1.016 1.016)
					(thickness 0.1524)
				)
			)
		)
		(property "Device Type" "R402H14"
			(at 0.064008 -5.517896 0)
			(unlocked yes)
			(layer "F.Fab")
			(hide yes)
			(effects
				(font
					(size 1.016 1.016)
					(thickness 0.1524)
				)
			)
		)
		(duplicate_pad_numbers_are_jumpers no)
		(fp_line
			(start -0.508 -0.9398)
			(end -0.508 0.9398)
			(stroke
				(width 0.1524)
				(type default)
			)
			(layer "F.SilkS")
		)
		(fp_line
			(start 0.508 -0.9398)
			(end -0.508 -0.9398)
			(stroke
				(width 0.1524)
				(type default)
			)
			(layer "F.SilkS")
		)
		(fp_rect
			(start -0.508 0.9398)
			(end 0.508 -0.9398)
			(stroke
				(width 0)
				(type default)
			)
			(fill no)
			(layer "F.CrtYd")
		)
		(fp_rect
			(start -0.508 0.9398)
			(end 0.508 -0.9398)
			(stroke
				(width 0)
				(type default)
			)
			(fill no)
			(layer "F.Fab")
		)
		(pad "1" smd custom
			(at 0 -0.4445)
			(size 0.1397 0.1397)
			(layers "F.Cu" "F.Mask" "F.Paste")
			(net "MB0_12V_CTRL_GATE1")
			(options
				(clearance outline)
				(anchor circle)
			)
			(primitives
				(gr_poly
					(pts
						(arc
							(start -0.1778 -0.2794)
							(mid -0.249642 -0.249642)
							(end -0.2794 -0.1778)
						)
						(arc
							(start -0.2794 0.1778)
							(mid -0.249642 0.249642)
							(end -0.1778 0.2794)
						)
						(arc
							(start 0.1778 0.2794)
							(mid 0.249642 0.249642)
							(end 0.2794 0.1778)
						)
						(arc
							(start 0.2794 -0.1778)
							(mid 0.249642 -0.249642)
							(end 0.1778 -0.2794)
						)
					)
					(width 0)
					(fill yes)
				)
			)
		)
		(pad "2" smd custom
			(at 0 0.4445)
			(size 0.1397 0.1397)
			(layers "F.Cu" "F.Mask" "F.Paste")
			(net "MB0_CM_GATE_R")
			(options
				(clearance outline)
				(anchor circle)
			)
			(primitives
				(gr_poly
					(pts
						(arc
							(start -0.1778 -0.2794)
							(mid -0.249642 -0.249642)
							(end -0.2794 -0.1778)
						)
						(arc
							(start -0.2794 0.1778)
							(mid -0.249642 0.249642)
							(end -0.1778 0.2794)
						)
						(arc
							(start 0.1778 0.2794)
							(mid 0.249642 0.249642)
							(end 0.2794 0.1778)
						)
						(arc
							(start 0.2794 -0.1778)
							(mid 0.249642 -0.249642)
							(end 0.1778 -0.2794)
						)
					)
					(width 0)
					(fill yes)
				)
			)
		)
	)
	(footprint ""
		(layer "F.Cu")
		(at 303.53 -57.0992)
		(property "Reference" "C427"
			(at 0 0 0)
			(layer "F.SilkS")
			(hide yes)
			(effects
				(font
					(size 1.27 1.27)
				)
			)
		)
		(property "Value" "SC10U16V5KX-1-GP"
			(at -0.0762 -6.1214 0)
			(unlocked yes)
			(layer "F.Fab")
			(hide yes)
			(effects
				(font
					(size 1.016 1.016)
					(thickness 0.1524)
				)
			)
		)
		(property "Device Type" "C805H54"
			(at -0.0762 -8.1534 0)
			(unlocked yes)
			(layer "F.Fab")
			(hide yes)
			(effects
				(font
					(size 1.016 1.016)
					(thickness 0.1524)
				)
			)
		)
		(duplicate_pad_numbers_are_jumpers no)
		(fp_line
			(start 0.635 0)
			(end -0.635 0)
			(stroke
				(width 0.508)
				(type default)
			)
			(layer "F.SilkS")
		)
		(fp_rect
			(start -0.9652 1.778)
			(end 0.9652 -1.778)
			(stroke
				(width 0)
				(type default)
			)
			(fill no)
			(layer "F.CrtYd")
		)
		(fp_poly
			(pts
				(xy -0.9652 -1.778) (xy 0.9652 -1.778) (xy 0.9652 1.778) (xy -0.9652 1.778)
			)
			(stroke
				(width 0)
				(type default)
			)
			(fill no)
			(layer "F.Fab")
		)
		(pad "1" smd rect
			(at 0 -0.9652)
			(size 1.397 1.143)
			(layers "F.Cu" "F.Mask" "F.Paste")
			(net "DUT_VDD")
		)
		(pad "2" smd rect
			(at 0 0.9652)
			(size 1.397 1.143)
			(layers "F.Cu" "F.Mask" "F.Paste")
			(net "GND")
		)
	)
	(footprint ""
		(layer "F.Cu")
		(at 311.008014 -212.420454 180)
		(property "Reference" "C73"
			(at 0 0 180)
			(layer "F.SilkS")
			(hide yes)
			(effects
				(font
					(size 1.27 1.27)
				)
			)
		)
		(property "Value" "SCD22U10V2KX-1GP"
			(at 1.1811 -2.7051 180)
			(unlocked yes)
			(layer "F.Fab")
			(hide yes)
			(effects
				(font
					(size 1.016 1.016)
					(thickness 0.1524)
				)
			)
		)
		(property "Device Type" "C402H22"
			(at 1.1811 -4.2291 180)
			(unlocked yes)
			(layer "F.Fab")
			(hide yes)
			(effects
				(font
					(size 1.016 1.016)
					(thickness 0.1524)
				)
			)
		)
		(duplicate_pad_numbers_are_jumpers no)
		(fp_rect
			(start -0.4318 0.9525)
			(end 0.4318 -0.9525)
			(stroke
				(width 0)
				(type default)
			)
			(fill no)
			(layer "F.CrtYd")
		)
		(fp_rect
			(start -0.4318 0.9525)
			(end 0.4318 -0.9525)
			(stroke
				(width 0)
				(type default)
			)
			(fill no)
			(layer "F.Fab")
		)
		(pad "1" smd custom
			(at 0 -0.4445 180)
			(size 0.1524 0.1524)
			(layers "F.Cu" "F.Mask" "F.Paste")
			(net "PCIE_TX_CAP_N25")
			(options
				(clearance outline)
				(anchor circle)
			)
			(primitives
				(gr_poly
					(pts
						(arc
							(start 0.3048 -0.2032)
							(mid 0.275042 -0.275042)
							(end 0.2032 -0.3048)
						)
						(arc
							(start -0.2032 -0.3048)
							(mid -0.275042 -0.275042)
							(end -0.3048 -0.2032)
						)
						(arc
							(start -0.3048 0.2032)
							(mid -0.275042 0.275042)
							(end -0.2032 0.3048)
						)
						(arc
							(start 0.2032 0.3048)
							(mid 0.275042 0.275042)
							(end 0.3048 0.2032)
						)
					)
					(width 0)
					(fill yes)
				)
			)
		)
		(pad "2" smd custom
			(at 0 0.4445 180)
			(size 0.1524 0.1524)
			(layers "F.Cu" "F.Mask" "F.Paste")
			(net "PCIE_TX_N25")
			(options
				(clearance outline)
				(anchor circle)
			)
			(primitives
				(gr_poly
					(pts
						(arc
							(start 0.3048 -0.2032)
							(mid 0.275042 -0.275042)
							(end 0.2032 -0.3048)
						)
						(arc
							(start -0.2032 -0.3048)
							(mid -0.275042 -0.275042)
							(end -0.3048 -0.2032)
						)
						(arc
							(start -0.3048 0.2032)
							(mid -0.275042 0.275042)
							(end -0.2032 0.3048)
						)
						(arc
							(start 0.2032 0.3048)
							(mid 0.275042 0.275042)
							(end 0.3048 0.2032)
						)
					)
					(width 0)
					(fill yes)
				)
			)
		)
	)
	(footprint ""
		(layer "F.Cu")
		(at 181.63794 -13.156184 -90)
		(property "Reference" "R292"
			(at 0 0 270)
			(layer "F.SilkS")
			(hide yes)
			(effects
				(font
					(size 1.27 1.27)
				)
			)
		)
		(property "Value" "0R2J-2-GP"
			(at 0.064008 -3.993896 270)
			(unlocked yes)
			(layer "F.Fab")
			(hide yes)
			(effects
				(font
					(size 1.016 1.016)
					(thickness 0.1524)
				)
			)
		)
		(property "Device Type" "R402H16"
			(at 0.064008 -5.517896 270)
			(unlocked yes)
			(layer "F.Fab")
			(hide yes)
			(effects
				(font
					(size 1.016 1.016)
					(thickness 0.1524)
				)
			)
		)
		(duplicate_pad_numbers_are_jumpers no)
		(fp_line
			(start -0.508 -0.9398)
			(end -0.508 0.9398)
			(stroke
				(width 0.1524)
				(type default)
			)
			(layer "F.SilkS")
		)
		(fp_line
			(start 0.508 -0.9398)
			(end -0.508 -0.9398)
			(stroke
				(width 0.1524)
				(type default)
			)
			(layer "F.SilkS")
		)
		(fp_rect
			(start -0.508 0.9398)
			(end 0.508 -0.9398)
			(stroke
				(width 0)
				(type default)
			)
			(fill no)
			(layer "F.CrtYd")
		)
		(fp_rect
			(start -0.508 0.9398)
			(end 0.508 -0.9398)
			(stroke
				(width 0)
				(type default)
			)
			(fill no)
			(layer "F.Fab")
		)
		(pad "1" smd custom
			(at 0 -0.4445 270)
			(size 0.1397 0.1397)
			(layers "F.Cu" "F.Mask" "F.Paste")
			(net "MINISAS_CN15_D_I2C_INT#")
			(options
				(clearance outline)
				(anchor circle)
			)
			(primitives
				(gr_poly
					(pts
						(arc
							(start -0.1778 -0.2794)
							(mid -0.249642 -0.249642)
							(end -0.2794 -0.1778)
						)
						(arc
							(start -0.2794 0.1778)
							(mid -0.249642 0.249642)
							(end -0.1778 0.2794)
						)
						(arc
							(start 0.1778 0.2794)
							(mid 0.249642 0.249642)
							(end 0.2794 0.1778)
						)
						(arc
							(start 0.2794 -0.1778)
							(mid 0.249642 -0.249642)
							(end 0.1778 -0.2794)
						)
					)
					(width 0)
					(fill yes)
				)
			)
		)
		(pad "2" smd custom
			(at 0 0.4445 270)
			(size 0.1397 0.1397)
			(layers "F.Cu" "F.Mask" "F.Paste")
			(net "CLK_N_4")
			(options
				(clearance outline)
				(anchor circle)
			)
			(primitives
				(gr_poly
					(pts
						(arc
							(start -0.1778 -0.2794)
							(mid -0.249642 -0.249642)
							(end -0.2794 -0.1778)
						)
						(arc
							(start -0.2794 0.1778)
							(mid -0.249642 0.249642)
							(end -0.1778 0.2794)
						)
						(arc
							(start 0.1778 0.2794)
							(mid 0.249642 0.249642)
							(end 0.2794 0.1778)
						)
						(arc
							(start 0.2794 -0.1778)
							(mid 0.249642 -0.249642)
							(end 0.1778 -0.2794)
						)
					)
					(width 0)
					(fill yes)
				)
			)
		)
	)
	(footprint ""
		(layer "F.Cu")
		(at 133.2103 -33.54324)
		(property "Reference" "C385"
			(at 0 0 0)
			(layer "F.SilkS")
			(hide yes)
			(effects
				(font
					(size 1.27 1.27)
				)
			)
		)
		(property "Value" "SCD22U10V2KX-1GP"
			(at 1.1811 -2.7051 0)
			(unlocked yes)
			(layer "F.Fab")
			(hide yes)
			(effects
				(font
					(size 1.016 1.016)
					(thickness 0.1524)
				)
			)
		)
		(property "Device Type" "C402H22"
			(at 1.1811 -4.2291 0)
			(unlocked yes)
			(layer "F.Fab")
			(hide yes)
			(effects
				(font
					(size 1.016 1.016)
					(thickness 0.1524)
				)
			)
		)
		(duplicate_pad_numbers_are_jumpers no)
		(fp_rect
			(start -0.4318 0.9525)
			(end 0.4318 -0.9525)
			(stroke
				(width 0)
				(type default)
			)
			(fill no)
			(layer "F.CrtYd")
		)
		(fp_rect
			(start -0.4318 0.9525)
			(end 0.4318 -0.9525)
			(stroke
				(width 0)
				(type default)
			)
			(fill no)
			(layer "F.Fab")
		)
		(pad "1" smd custom
			(at 0 -0.4445)
			(size 0.1524 0.1524)
			(layers "F.Cu" "F.Mask" "F.Paste")
			(net "PCIE_TX_CAP_P82")
			(options
				(clearance outline)
				(anchor circle)
			)
			(primitives
				(gr_poly
					(pts
						(arc
							(start 0.3048 -0.2032)
							(mid 0.275042 -0.275042)
							(end 0.2032 -0.3048)
						)
						(arc
							(start -0.2032 -0.3048)
							(mid -0.275042 -0.275042)
							(end -0.3048 -0.2032)
						)
						(arc
							(start -0.3048 0.2032)
							(mid -0.275042 0.275042)
							(end -0.2032 0.3048)
						)
						(arc
							(start 0.2032 0.3048)
							(mid 0.275042 0.275042)
							(end 0.3048 0.2032)
						)
					)
					(width 0)
					(fill yes)
				)
			)
		)
		(pad "2" smd custom
			(at 0 0.4445)
			(size 0.1524 0.1524)
			(layers "F.Cu" "F.Mask" "F.Paste")
			(net "PCIE_TX_P82")
			(options
				(clearance outline)
				(anchor circle)
			)
			(primitives
				(gr_poly
					(pts
						(arc
							(start 0.3048 -0.2032)
							(mid 0.275042 -0.275042)
							(end 0.2032 -0.3048)
						)
						(arc
							(start -0.2032 -0.3048)
							(mid -0.275042 -0.275042)
							(end -0.3048 -0.2032)
						)
						(arc
							(start -0.3048 0.2032)
							(mid -0.275042 0.275042)
							(end -0.2032 0.3048)
						)
						(arc
							(start 0.2032 0.3048)
							(mid 0.275042 0.275042)
							(end 0.3048 0.2032)
						)
					)
					(width 0)
					(fill yes)
				)
			)
		)
	)
	(footprint ""
		(layer "F.Cu")
		(at 50.8762 -50.3174 180)
		(property "Reference" "R500"
			(at 0 0 180)
			(layer "F.SilkS")
			(hide yes)
			(effects
				(font
					(size 1.27 1.27)
				)
			)
		)
		(property "Value" "3K3R2F-2-GP"
			(at 0.064008 -3.993896 180)
			(unlocked yes)
			(layer "F.Fab")
			(hide yes)
			(effects
				(font
					(size 1.016 1.016)
					(thickness 0.1524)
				)
			)
		)
		(property "Device Type" "R402H16"
			(at 0.064008 -5.517896 180)
			(unlocked yes)
			(layer "F.Fab")
			(hide yes)
			(effects
				(font
					(size 1.016 1.016)
					(thickness 0.1524)
				)
			)
		)
		(duplicate_pad_numbers_are_jumpers no)
		(fp_line
			(start 0.508 -0.9398)
			(end -0.508 -0.9398)
			(stroke
				(width 0.1524)
				(type default)
			)
			(layer "F.SilkS")
		)
		(fp_line
			(start -0.508 -0.9398)
			(end -0.508 0.9398)
			(stroke
				(width 0.1524)
				(type default)
			)
			(layer "F.SilkS")
		)
		(fp_rect
			(start -0.508 0.9398)
			(end 0.508 -0.9398)
			(stroke
				(width 0)
				(type default)
			)
			(fill no)
			(layer "F.CrtYd")
		)
		(fp_rect
			(start -0.508 0.9398)
			(end 0.508 -0.9398)
			(stroke
				(width 0)
				(type default)
			)
			(fill no)
			(layer "F.Fab")
		)
		(pad "1" smd custom
			(at 0 -0.4445 180)
			(size 0.1397 0.1397)
			(layers "F.Cu" "F.Mask" "F.Paste")
			(net "P3V3_STBY")
			(options
				(clearance outline)
				(anchor circle)
			)
			(primitives
				(gr_poly
					(pts
						(arc
							(start -0.1778 -0.2794)
							(mid -0.249642 -0.249642)
							(end -0.2794 -0.1778)
						)
						(arc
							(start -0.2794 0.1778)
							(mid -0.249642 0.249642)
							(end -0.1778 0.2794)
						)
						(arc
							(start 0.1778 0.2794)
							(mid 0.249642 0.249642)
							(end 0.2794 0.1778)
						)
						(arc
							(start 0.2794 -0.1778)
							(mid 0.249642 -0.249642)
							(end 0.1778 -0.2794)
						)
					)
					(width 0)
					(fill yes)
				)
			)
		)
		(pad "2" smd custom
			(at 0 0.4445 180)
			(size 0.1397 0.1397)
			(layers "F.Cu" "F.Mask" "F.Paste")
			(net "U44_HOLD_N")
			(options
				(clearance outline)
				(anchor circle)
			)
			(primitives
				(gr_poly
					(pts
						(arc
							(start -0.1778 -0.2794)
							(mid -0.249642 -0.249642)
							(end -0.2794 -0.1778)
						)
						(arc
							(start -0.2794 0.1778)
							(mid -0.249642 0.249642)
							(end -0.1778 0.2794)
						)
						(arc
							(start 0.1778 0.2794)
							(mid 0.249642 0.249642)
							(end 0.2794 0.1778)
						)
						(arc
							(start 0.2794 -0.1778)
							(mid 0.249642 -0.249642)
							(end 0.1778 -0.2794)
						)
					)
					(width 0)
					(fill yes)
				)
			)
		)
	)
	(footprint ""
		(layer "F.Cu")
		(at 7.2136 -70.9676 -90)
		(property "Reference" "X11"
			(at 0 0 270)
			(layer "F.SilkS")
			(hide yes)
			(effects
				(font
					(size 1.27 1.27)
				)
			)
		)
		(property "Value" "XTAL-25MHZ-96GP"
			(at 0 -7.5692 270)
			(unlocked yes)
			(layer "F.Fab")
			(hide yes)
			(effects
				(font
					(size 1.016 1.016)
					(thickness 0.1524)
				)
			)
		)
		(property "Device Type" "SMD49-4H56"
			(at 0 -9.0932 270)
			(unlocked yes)
			(layer "F.Fab")
			(hide yes)
			(effects
				(font
					(size 1.016 1.016)
					(thickness 0.1524)
				)
			)
		)
		(duplicate_pad_numbers_are_jumpers no)
		(fp_line
			(start -3.6322 1.8542)
			(end -3.6322 -1.8542)
			(stroke
				(width 0.1524)
				(type default)
			)
			(layer "F.SilkS")
		)
		(fp_line
			(start 3.6322 1.8542)
			(end -3.6322 1.8542)
			(stroke
				(width 0.1524)
				(type default)
			)
			(layer "F.SilkS")
		)
		(fp_line
			(start -3.6322 -1.8542)
			(end 3.6322 -1.8542)
			(stroke
				(width 0.1524)
				(type default)
			)
			(layer "F.SilkS")
		)
		(fp_line
			(start 3.6322 -1.8542)
			(end 3.6322 1.8542)
			(stroke
				(width 0.1524)
				(type default)
			)
			(layer "F.SilkS")
		)
		(fp_poly
			(pts
				(xy -3.8862 2.1082) (xy 3.8862 2.1082) (xy 3.8862 -2.1082) (xy -3.8862 -2.1082)
			)
			(stroke
				(width 0)
				(type default)
			)
			(fill no)
			(layer "F.CrtYd")
		)
		(fp_poly
			(pts
				(xy -3.8862 -2.1082) (xy 3.8862 -2.1082) (xy 3.8862 2.1082) (xy -3.8862 2.1082)
			)
			(stroke
				(width 0)
				(type default)
			)
			(fill no)
			(layer "F.Fab")
		)
		(pad "1" smd rect
			(at -2.16535 0 270)
			(size 2.4384 2.2606)
			(layers "F.Cu" "F.Mask" "F.Paste")
			(net "XTAL_OUT_I210_R")
		)
		(pad "2" smd rect
			(at 2.16535 0 270)
			(size 2.4384 2.2606)
			(layers "F.Cu" "F.Mask" "F.Paste")
			(net "XTAL_IN_I210_R")
		)
		(zone
			(layer "F.Cu")
			(hatch none 0.5)
			(connect_pads
				(clearance 0)
			)
			(min_thickness 0.25)
			(keepout
				(tracks not_allowed)
				(vias allowed)
				(pads allowed)
				(copperpour not_allowed)
				(footprints allowed)
			)
			(placement
				(enabled no)
				(sheetname "")
			)
			(fill
				(thermal_gap 0.5)
				(thermal_bridge_width 0.5)
				(island_removal_mode 0)
			)
			(polygon
				(pts
					(xy 5.4356 -74.35215) (xy 5.4356 -73.13295) (xy 6.0833 -73.13295) (xy 6.0833 -74.35215)
				)
			)
		)
		(zone
			(layer "F.Cu")
			(hatch none 0.5)
			(connect_pads
				(clearance 0)
			)
			(min_thickness 0.25)
			(keepout
				(tracks allowed)
				(vias not_allowed)
				(pads allowed)
				(copperpour not_allowed)
				(footprints allowed)
			)
			(placement
				(enabled no)
				(sheetname "")
			)
			(fill
				(thermal_gap 0.5)
				(thermal_bridge_width 0.5)
				(island_removal_mode 0)
			)
			(polygon
				(pts
					(xy 5.4356 -74.35215) (xy 5.4356 -73.13295) (xy 6.0833 -73.13295) (xy 6.0833 -74.35215)
				)
			)
		)
		(zone
			(layer "F.Cu")
			(hatch none 0.5)
			(connect_pads
				(clearance 0)
			)
			(min_thickness 0.25)
			(keepout
				(tracks not_allowed)
				(vias allowed)
				(pads allowed)
				(copperpour not_allowed)
				(footprints allowed)
			)
			(placement
				(enabled no)
				(sheetname "")
			)
			(fill
				(thermal_gap 0.5)
				(thermal_bridge_width 0.5)
				(island_removal_mode 0)
			)
			(polygon
				(pts
					(xy 5.4356 -68.80225) (xy 5.4356 -67.58305) (xy 6.0833 -67.58305) (xy 6.0833 -68.80225)
				)
			)
		)
		(zone
			(layer "F.Cu")
			(hatch none 0.5)
			(connect_pads
				(clearance 0)
			)
			(min_thickness 0.25)
			(keepout
				(tracks allowed)
				(vias not_allowed)
				(pads allowed)
				(copperpour not_allowed)
				(footprints allowed)
			)
			(placement
				(enabled no)
				(sheetname "")
			)
			(fill
				(thermal_gap 0.5)
				(thermal_bridge_width 0.5)
				(island_removal_mode 0)
			)
			(polygon
				(pts
					(xy 5.4356 -68.80225) (xy 5.4356 -67.58305) (xy 6.0833 -67.58305) (xy 6.0833 -68.80225)
				)
			)
		)
		(zone
			(layer "F.Cu")
			(hatch none 0.5)
			(connect_pads
				(clearance 0)
			)
			(min_thickness 0.25)
			(keepout
				(tracks allowed)
				(vias not_allowed)
				(pads allowed)
				(copperpour not_allowed)
				(footprints allowed)
			)
			(placement
				(enabled no)
				(sheetname "")
			)
			(fill
				(thermal_gap 0.5)
				(thermal_bridge_width 0.5)
				(island_removal_mode 0)
			)
			(polygon
				(pts
					(xy 8.3439 -74.35215) (xy 8.3439 -73.13295) (xy 8.9916 -73.1393) (xy 8.9916 -74.35215)
				)
			)
		)
		(zone
			(layer "F.Cu")
			(hatch none 0.5)
			(connect_pads
				(clearance 0)
			)
			(min_thickness 0.25)
			(keepout
				(tracks not_allowed)
				(vias allowed)
				(pads allowed)
				(copperpour not_allowed)
				(footprints allowed)
			)
			(placement
				(enabled no)
				(sheetname "")
			)
			(fill
				(thermal_gap 0.5)
				(thermal_bridge_width 0.5)
				(island_removal_mode 0)
			)
			(polygon
				(pts
					(xy 8.3439 -74.35215) (xy 8.3439 -73.13295) (xy 8.9916 -73.1393) (xy 8.9916 -74.35215)
				)
			)
		)
		(zone
			(layer "F.Cu")
			(hatch none 0.5)
			(connect_pads
				(clearance 0)
			)
			(min_thickness 0.25)
			(keepout
				(tracks not_allowed)
				(vias allowed)
				(pads allowed)
				(copperpour not_allowed)
				(footprints allowed)
			)
			(placement
				(enabled no)
				(sheetname "")
			)
			(fill
				(thermal_gap 0.5)
				(thermal_bridge_width 0.5)
				(island_removal_mode 0)
			)
			(polygon
				(pts
					(xy 8.3439 -68.80225) (xy 8.3439 -67.58305) (xy 8.9916 -67.58305) (xy 8.9916 -68.7959)
				)
			)
		)
		(zone
			(layer "F.Cu")
			(hatch none 0.5)
			(connect_pads
				(clearance 0)
			)
			(min_thickness 0.25)
			(keepout
				(tracks allowed)
				(vias not_allowed)
				(pads allowed)
				(copperpour not_allowed)
				(footprints allowed)
			)
			(placement
				(enabled no)
				(sheetname "")
			)
			(fill
				(thermal_gap 0.5)
				(thermal_bridge_width 0.5)
				(island_removal_mode 0)
			)
			(polygon
				(pts
					(xy 8.3439 -68.80225) (xy 8.3439 -67.58305) (xy 8.9916 -67.58305) (xy 8.9916 -68.7959)
				)
			)
		)
	)
	(footprint ""
		(layer "F.Cu")
		(at 56.515 -130.048 180)
		(property "Reference" "C192"
			(at 0 0 180)
			(layer "F.SilkS")
			(hide yes)
			(effects
				(font
					(size 1.27 1.27)
				)
			)
		)
		(property "Value" "SC1U10V2KX-4-GP"
			(at 1.1811 -2.7051 180)
			(unlocked yes)
			(layer "F.Fab")
			(hide yes)
			(effects
				(font
					(size 1.016 1.016)
					(thickness 0.1524)
				)
			)
		)
		(property "Device Type" "C402H22"
			(at 1.1811 -4.2291 180)
			(unlocked yes)
			(layer "F.Fab")
			(hide yes)
			(effects
				(font
					(size 1.016 1.016)
					(thickness 0.1524)
				)
			)
		)
		(duplicate_pad_numbers_are_jumpers no)
		(fp_rect
			(start -0.4318 0.9525)
			(end 0.4318 -0.9525)
			(stroke
				(width 0)
				(type default)
			)
			(fill no)
			(layer "F.CrtYd")
		)
		(fp_rect
			(start -0.4318 0.9525)
			(end 0.4318 -0.9525)
			(stroke
				(width 0)
				(type default)
			)
			(fill no)
			(layer "F.Fab")
		)
		(pad "1" smd custom
			(at 0 -0.4445 180)
			(size 0.1524 0.1524)
			(layers "F.Cu" "F.Mask" "F.Paste")
			(net "ADCAV33")
			(options
				(clearance outline)
				(anchor circle)
			)
			(primitives
				(gr_poly
					(pts
						(arc
							(start 0.3048 -0.2032)
							(mid 0.275042 -0.275042)
							(end 0.2032 -0.3048)
						)
						(arc
							(start -0.2032 -0.3048)
							(mid -0.275042 -0.275042)
							(end -0.3048 -0.2032)
						)
						(arc
							(start -0.3048 0.2032)
							(mid -0.275042 0.275042)
							(end -0.2032 0.3048)
						)
						(arc
							(start 0.2032 0.3048)
							(mid 0.275042 0.275042)
							(end 0.3048 0.2032)
						)
					)
					(width 0)
					(fill yes)
				)
			)
		)
		(pad "2" smd custom
			(at 0 0.4445 180)
			(size 0.1524 0.1524)
			(layers "F.Cu" "F.Mask" "F.Paste")
			(net "GND")
			(options
				(clearance outline)
				(anchor circle)
			)
			(primitives
				(gr_poly
					(pts
						(arc
							(start 0.3048 -0.2032)
							(mid 0.275042 -0.275042)
							(end 0.2032 -0.3048)
						)
						(arc
							(start -0.2032 -0.3048)
							(mid -0.275042 -0.275042)
							(end -0.3048 -0.2032)
						)
						(arc
							(start -0.3048 0.2032)
							(mid -0.275042 0.275042)
							(end -0.2032 0.3048)
						)
						(arc
							(start 0.2032 0.3048)
							(mid 0.275042 0.275042)
							(end 0.3048 0.2032)
						)
					)
					(width 0)
					(fill yes)
				)
			)
		)
	)
	(footprint ""
		(layer "F.Cu")
		(at 314.20816 -212.420454 180)
		(property "Reference" "C71"
			(at 0 0 180)
			(layer "F.SilkS")
			(hide yes)
			(effects
				(font
					(size 1.27 1.27)
				)
			)
		)
		(property "Value" "SCD22U10V2KX-1GP"
			(at 1.1811 -2.7051 180)
			(unlocked yes)
			(layer "F.Fab")
			(hide yes)
			(effects
				(font
					(size 1.016 1.016)
					(thickness 0.1524)
				)
			)
		)
		(property "Device Type" "C402H22"
			(at 1.1811 -4.2291 180)
			(unlocked yes)
			(layer "F.Fab")
			(hide yes)
			(effects
				(font
					(size 1.016 1.016)
					(thickness 0.1524)
				)
			)
		)
		(duplicate_pad_numbers_are_jumpers no)
		(fp_rect
			(start -0.4318 0.9525)
			(end 0.4318 -0.9525)
			(stroke
				(width 0)
				(type default)
			)
			(fill no)
			(layer "F.CrtYd")
		)
		(fp_rect
			(start -0.4318 0.9525)
			(end 0.4318 -0.9525)
			(stroke
				(width 0)
				(type default)
			)
			(fill no)
			(layer "F.Fab")
		)
		(pad "1" smd custom
			(at 0 -0.4445 180)
			(size 0.1524 0.1524)
			(layers "F.Cu" "F.Mask" "F.Paste")
			(net "PCIE_TX_CAP_N24")
			(options
				(clearance outline)
				(anchor circle)
			)
			(primitives
				(gr_poly
					(pts
						(arc
							(start 0.3048 -0.2032)
							(mid 0.275042 -0.275042)
							(end 0.2032 -0.3048)
						)
						(arc
							(start -0.2032 -0.3048)
							(mid -0.275042 -0.275042)
							(end -0.3048 -0.2032)
						)
						(arc
							(start -0.3048 0.2032)
							(mid -0.275042 0.275042)
							(end -0.2032 0.3048)
						)
						(arc
							(start 0.2032 0.3048)
							(mid 0.275042 0.275042)
							(end 0.3048 0.2032)
						)
					)
					(width 0)
					(fill yes)
				)
			)
		)
		(pad "2" smd custom
			(at 0 0.4445 180)
			(size 0.1524 0.1524)
			(layers "F.Cu" "F.Mask" "F.Paste")
			(net "PCIE_TX_N24")
			(options
				(clearance outline)
				(anchor circle)
			)
			(primitives
				(gr_poly
					(pts
						(arc
							(start 0.3048 -0.2032)
							(mid 0.275042 -0.275042)
							(end 0.2032 -0.3048)
						)
						(arc
							(start -0.2032 -0.3048)
							(mid -0.275042 -0.275042)
							(end -0.3048 -0.2032)
						)
						(arc
							(start -0.3048 0.2032)
							(mid -0.275042 0.275042)
							(end -0.2032 0.3048)
						)
						(arc
							(start 0.2032 0.3048)
							(mid 0.275042 0.275042)
							(end 0.3048 0.2032)
						)
					)
					(width 0)
					(fill yes)
				)
			)
		)
	)
	(footprint ""
		(layer "F.Cu")
		(at 122.547126 -79.269082 -90)
		(property "Reference" "D13"
			(at 0 0 270)
			(layer "F.SilkS")
			(hide yes)
			(effects
				(font
					(size 1.27 1.27)
				)
			)
		)
		(property "Value" "BAT54C-7-F-3-GP"
			(at 0 -5.0292 270)
			(unlocked yes)
			(layer "F.Fab")
			(hide yes)
			(effects
				(font
					(size 1.016 1.016)
					(thickness 0.1524)
				)
			)
		)
		(property "Device Type" "SOT23-2D4-312H48"
			(at 0 -6.5532 270)
			(unlocked yes)
			(layer "F.Fab")
			(hide yes)
			(effects
				(font
					(size 1.016 1.016)
					(thickness 0.1524)
				)
			)
		)
		(duplicate_pad_numbers_are_jumpers no)
		(fp_line
			(start -1.7018 1.778)
			(end -1.7018 -0.9017)
			(stroke
				(width 0.1524)
				(type default)
			)
			(layer "F.SilkS")
		)
		(fp_line
			(start 1.7018 1.778)
			(end -1.7018 1.778)
			(stroke
				(width 0.1524)
				(type default)
			)
			(layer "F.SilkS")
		)
		(fp_line
			(start -1.7018 -0.9017)
			(end -0.635 -0.9017)
			(stroke
				(width 0.1524)
				(type default)
			)
			(layer "F.SilkS")
		)
		(fp_line
			(start -0.635 -0.9017)
			(end -0.635 -1.778)
			(stroke
				(width 0.1524)
				(type default)
			)
			(layer "F.SilkS")
		)
		(fp_line
			(start 0.635 -0.9017)
			(end 1.7018 -0.9017)
			(stroke
				(width 0.1524)
				(type default)
			)
			(layer "F.SilkS")
		)
		(fp_line
			(start 1.7018 -0.9017)
			(end 1.7018 1.778)
			(stroke
				(width 0.1524)
				(type default)
			)
			(layer "F.SilkS")
		)
		(fp_line
			(start -0.635 -1.778)
			(end 0.635 -1.778)
			(stroke
				(width 0.1524)
				(type default)
			)
			(layer "F.SilkS")
		)
		(fp_line
			(start 0.635 -1.778)
			(end 0.635 -0.9017)
			(stroke
				(width 0.1524)
				(type default)
			)
			(layer "F.SilkS")
		)
		(fp_poly
			(pts
				(xy 0.2159 -1.1938) (xy -0.2159 -1.1938) (xy -0.2159 -0.6477) (xy -1.4478 -0.6477) (xy -1.4478 1.1938)
				(xy 1.4478 1.1938) (xy 1.4478 -0.6477) (xy 0.2159 -0.6477)
			)
			(stroke
				(width 0)
				(type default)
			)
			(fill no)
			(layer "F.CrtYd")
		)
		(fp_poly
			(pts
				(xy 1.9558 2.032) (xy 1.9558 -0.1905) (xy 1.4478 -0.1905) (xy 1.4478 1.1938) (xy -1.4478 1.1938)
				(xy -1.4478 -0.6477) (xy -0.2159 -0.6477) (xy -0.2159 -1.1938) (xy 0.2159 -1.1938) (xy 0.2159 -0.6477)
				(xy 1.4478 -0.6477) (xy 1.4478 -0.2032) (xy 1.9558 -0.2032) (xy 1.9558 -1.1557) (xy 0.889 -1.1557)
				(xy 0.889 -2.032) (xy -0.889 -2.032) (xy -0.889 -1.1557) (xy -1.9558 -1.1557) (xy -1.9558 2.032)
			)
			(stroke
				(width 0)
				(type default)
			)
			(fill no)
			(layer "F.CrtYd")
		)
		(fp_poly
			(pts
				(xy -1.9558 2.032) (xy -1.9558 -1.1557) (xy -0.889 -1.1557) (xy -0.889 -2.032) (xy 0.889 -2.032)
				(xy 0.889 -1.1557) (xy 1.9558 -1.1557) (xy 1.9558 2.032)
			)
			(stroke
				(width 0)
				(type default)
			)
			(fill no)
			(layer "F.Fab")
		)
		(pad "1" smd custom
			(at -0.98425 0.9525 270)
			(size 0.1905 0.1905)
			(layers "F.Cu" "F.Mask" "F.Paste")
			(net "P3V3_STBY")
			(options
				(clearance outline)
				(anchor circle)
			)
			(primitives
				(gr_poly
					(pts
						(arc
							(start -0.1778 0.5715)
							(mid -0.321484 0.511984)
							(end -0.381 0.3683)
						)
						(arc
							(start -0.381 -0.3683)
							(mid -0.321484 -0.511984)
							(end -0.1778 -0.5715)
						)
						(arc
							(start 0.1778 -0.5715)
							(mid 0.321484 -0.511984)
							(end 0.381 -0.3683)
						)
						(arc
							(start 0.381 0.3683)
							(mid 0.321484 0.511984)
							(end 0.1778 0.5715)
						)
					)
					(width 0)
					(fill yes)
				)
			)
		)
		(pad "2" smd custom
			(at 0.98425 0.9525 270)
			(size 0.1905 0.1905)
			(layers "F.Cu" "F.Mask" "F.Paste")
			(net "P3V0_BAT_R")
			(options
				(clearance outline)
				(anchor circle)
			)
			(primitives
				(gr_poly
					(pts
						(arc
							(start -0.1778 0.5715)
							(mid -0.321484 0.511984)
							(end -0.381 0.3683)
						)
						(arc
							(start -0.381 -0.3683)
							(mid -0.321484 -0.511984)
							(end -0.1778 -0.5715)
						)
						(arc
							(start 0.1778 -0.5715)
							(mid 0.321484 -0.511984)
							(end 0.381 -0.3683)
						)
						(arc
							(start 0.381 0.3683)
							(mid 0.321484 0.511984)
							(end 0.1778 0.5715)
						)
					)
					(width 0)
					(fill yes)
				)
			)
		)
		(pad "3" smd custom
			(at 0 -0.9525 270)
			(size 0.1905 0.1905)
			(layers "F.Cu" "F.Mask" "F.Paste")
			(net "P3V3_RTC")
			(options
				(clearance outline)
				(anchor circle)
			)
			(primitives
				(gr_poly
					(pts
						(arc
							(start -0.1778 0.5715)
							(mid -0.321484 0.511984)
							(end -0.381 0.3683)
						)
						(arc
							(start -0.381 -0.3683)
							(mid -0.321484 -0.511984)
							(end -0.1778 -0.5715)
						)
						(arc
							(start 0.1778 -0.5715)
							(mid 0.321484 -0.511984)
							(end 0.381 -0.3683)
						)
						(arc
							(start 0.381 0.3683)
							(mid 0.321484 0.511984)
							(end 0.1778 0.5715)
						)
					)
					(width 0)
					(fill yes)
				)
			)
		)
	)
	(footprint ""
		(layer "F.Cu")
		(at 233.68 -23.241)
		(property "Reference" "R816"
			(at 0 0 0)
			(layer "F.SilkS")
			(hide yes)
			(effects
				(font
					(size 1.27 1.27)
				)
			)
		)
		(property "Value" "4K7R2F-GP"
			(at 0.064008 -3.993896 0)
			(unlocked yes)
			(layer "F.Fab")
			(hide yes)
			(effects
				(font
					(size 1.016 1.016)
					(thickness 0.1524)
				)
			)
		)
		(property "Device Type" "R402H16"
			(at 0.064008 -5.517896 0)
			(unlocked yes)
			(layer "F.Fab")
			(hide yes)
			(effects
				(font
					(size 1.016 1.016)
					(thickness 0.1524)
				)
			)
		)
		(duplicate_pad_numbers_are_jumpers no)
		(fp_line
			(start -0.508 -0.9398)
			(end -0.508 0.9398)
			(stroke
				(width 0.1524)
				(type default)
			)
			(layer "F.SilkS")
		)
		(fp_line
			(start 0.508 -0.9398)
			(end -0.508 -0.9398)
			(stroke
				(width 0.1524)
				(type default)
			)
			(layer "F.SilkS")
		)
		(fp_rect
			(start -0.508 0.9398)
			(end 0.508 -0.9398)
			(stroke
				(width 0)
				(type default)
			)
			(fill no)
			(layer "F.CrtYd")
		)
		(fp_rect
			(start -0.508 0.9398)
			(end 0.508 -0.9398)
			(stroke
				(width 0)
				(type default)
			)
			(fill no)
			(layer "F.Fab")
		)
		(pad "1" smd custom
			(at 0 -0.4445)
			(size 0.1397 0.1397)
			(layers "F.Cu" "F.Mask" "F.Paste")
			(net "GND")
			(options
				(clearance outline)
				(anchor circle)
			)
			(primitives
				(gr_poly
					(pts
						(arc
							(start -0.1778 -0.2794)
							(mid -0.249642 -0.249642)
							(end -0.2794 -0.1778)
						)
						(arc
							(start -0.2794 0.1778)
							(mid -0.249642 0.249642)
							(end -0.1778 0.2794)
						)
						(arc
							(start 0.1778 0.2794)
							(mid 0.249642 0.249642)
							(end 0.2794 0.1778)
						)
						(arc
							(start 0.2794 -0.1778)
							(mid 0.249642 -0.249642)
							(end 0.1778 -0.2794)
						)
					)
					(width 0)
					(fill yes)
				)
			)
		)
		(pad "2" smd custom
			(at 0 0.4445)
			(size 0.1397 0.1397)
			(layers "F.Cu" "F.Mask" "F.Paste")
			(net "BOOTSTRAP8")
			(options
				(clearance outline)
				(anchor circle)
			)
			(primitives
				(gr_poly
					(pts
						(arc
							(start -0.1778 -0.2794)
							(mid -0.249642 -0.249642)
							(end -0.2794 -0.1778)
						)
						(arc
							(start -0.2794 0.1778)
							(mid -0.249642 0.249642)
							(end -0.1778 0.2794)
						)
						(arc
							(start 0.1778 0.2794)
							(mid 0.249642 0.249642)
							(end 0.2794 0.1778)
						)
						(arc
							(start 0.2794 -0.1778)
							(mid 0.249642 -0.249642)
							(end 0.1778 -0.2794)
						)
					)
					(width 0)
					(fill yes)
				)
			)
		)
	)
	(footprint ""
		(layer "F.Cu")
		(at 283.592016 -212.420454 180)
		(property "Reference" "C94"
			(at 0 0 180)
			(layer "F.SilkS")
			(hide yes)
			(effects
				(font
					(size 1.27 1.27)
				)
			)
		)
		(property "Value" "SCD22U10V2KX-1GP"
			(at 1.1811 -2.7051 180)
			(unlocked yes)
			(layer "F.Fab")
			(hide yes)
			(effects
				(font
					(size 1.016 1.016)
					(thickness 0.1524)
				)
			)
		)
		(property "Device Type" "C402H22"
			(at 1.1811 -4.2291 180)
			(unlocked yes)
			(layer "F.Fab")
			(hide yes)
			(effects
				(font
					(size 1.016 1.016)
					(thickness 0.1524)
				)
			)
		)
		(duplicate_pad_numbers_are_jumpers no)
		(fp_rect
			(start -0.4318 0.9525)
			(end 0.4318 -0.9525)
			(stroke
				(width 0)
				(type default)
			)
			(fill no)
			(layer "F.CrtYd")
		)
		(fp_rect
			(start -0.4318 0.9525)
			(end 0.4318 -0.9525)
			(stroke
				(width 0)
				(type default)
			)
			(fill no)
			(layer "F.Fab")
		)
		(pad "1" smd custom
			(at 0 -0.4445 180)
			(size 0.1524 0.1524)
			(layers "F.Cu" "F.Mask" "F.Paste")
			(net "PCIE_TX_CAP_P31")
			(options
				(clearance outline)
				(anchor circle)
			)
			(primitives
				(gr_poly
					(pts
						(arc
							(start 0.3048 -0.2032)
							(mid 0.275042 -0.275042)
							(end 0.2032 -0.3048)
						)
						(arc
							(start -0.2032 -0.3048)
							(mid -0.275042 -0.275042)
							(end -0.3048 -0.2032)
						)
						(arc
							(start -0.3048 0.2032)
							(mid -0.275042 0.275042)
							(end -0.2032 0.3048)
						)
						(arc
							(start 0.2032 0.3048)
							(mid 0.275042 0.275042)
							(end 0.3048 0.2032)
						)
					)
					(width 0)
					(fill yes)
				)
			)
		)
		(pad "2" smd custom
			(at 0 0.4445 180)
			(size 0.1524 0.1524)
			(layers "F.Cu" "F.Mask" "F.Paste")
			(net "PCIE_TX_P31")
			(options
				(clearance outline)
				(anchor circle)
			)
			(primitives
				(gr_poly
					(pts
						(arc
							(start 0.3048 -0.2032)
							(mid 0.275042 -0.275042)
							(end 0.2032 -0.3048)
						)
						(arc
							(start -0.2032 -0.3048)
							(mid -0.275042 -0.275042)
							(end -0.3048 -0.2032)
						)
						(arc
							(start -0.3048 0.2032)
							(mid -0.275042 0.275042)
							(end -0.2032 0.3048)
						)
						(arc
							(start 0.2032 0.3048)
							(mid 0.275042 0.275042)
							(end 0.3048 0.2032)
						)
					)
					(width 0)
					(fill yes)
				)
			)
		)
	)
	(footprint ""
		(layer "F.Cu")
		(at 132.816346 -59.750198 180)
		(property "Reference" "R458"
			(at 0 0 180)
			(layer "F.SilkS")
			(hide yes)
			(effects
				(font
					(size 1.27 1.27)
				)
			)
		)
		(property "Value" "100KR2F-L1-GP"
			(at 0.064008 -3.993896 180)
			(unlocked yes)
			(layer "F.Fab")
			(hide yes)
			(effects
				(font
					(size 1.016 1.016)
					(thickness 0.1524)
				)
			)
		)
		(property "Device Type" "R402H16"
			(at 0.064008 -5.517896 180)
			(unlocked yes)
			(layer "F.Fab")
			(hide yes)
			(effects
				(font
					(size 1.016 1.016)
					(thickness 0.1524)
				)
			)
		)
		(duplicate_pad_numbers_are_jumpers no)
		(fp_line
			(start 0.508 -0.9398)
			(end -0.508 -0.9398)
			(stroke
				(width 0.1524)
				(type default)
			)
			(layer "F.SilkS")
		)
		(fp_line
			(start -0.508 -0.9398)
			(end -0.508 0.9398)
			(stroke
				(width 0.1524)
				(type default)
			)
			(layer "F.SilkS")
		)
		(fp_rect
			(start -0.508 0.9398)
			(end 0.508 -0.9398)
			(stroke
				(width 0)
				(type default)
			)
			(fill no)
			(layer "F.CrtYd")
		)
		(fp_rect
			(start -0.508 0.9398)
			(end 0.508 -0.9398)
			(stroke
				(width 0)
				(type default)
			)
			(fill no)
			(layer "F.Fab")
		)
		(pad "1" smd custom
			(at 0 -0.4445 180)
			(size 0.1397 0.1397)
			(layers "F.Cu" "F.Mask" "F.Paste")
			(net "DUT_VDDO")
			(options
				(clearance outline)
				(anchor circle)
			)
			(primitives
				(gr_poly
					(pts
						(arc
							(start -0.1778 -0.2794)
							(mid -0.249642 -0.249642)
							(end -0.2794 -0.1778)
						)
						(arc
							(start -0.2794 0.1778)
							(mid -0.249642 0.249642)
							(end -0.1778 0.2794)
						)
						(arc
							(start 0.1778 0.2794)
							(mid 0.249642 0.249642)
							(end 0.2794 0.1778)
						)
						(arc
							(start 0.2794 -0.1778)
							(mid 0.249642 -0.249642)
							(end 0.1778 -0.2794)
						)
					)
					(width 0)
					(fill yes)
				)
			)
		)
		(pad "2" smd custom
			(at 0 0.4445 180)
			(size 0.1397 0.1397)
			(layers "F.Cu" "F.Mask" "F.Paste")
			(net "SPI_DATA0_1_R")
			(options
				(clearance outline)
				(anchor circle)
			)
			(primitives
				(gr_poly
					(pts
						(arc
							(start -0.1778 -0.2794)
							(mid -0.249642 -0.249642)
							(end -0.2794 -0.1778)
						)
						(arc
							(start -0.2794 0.1778)
							(mid -0.249642 0.249642)
							(end -0.1778 0.2794)
						)
						(arc
							(start 0.1778 0.2794)
							(mid 0.249642 0.249642)
							(end 0.2794 0.1778)
						)
						(arc
							(start 0.2794 -0.1778)
							(mid 0.249642 -0.249642)
							(end 0.1778 -0.2794)
						)
					)
					(width 0)
					(fill yes)
				)
			)
		)
	)
	(footprint ""
		(layer "F.Cu")
		(at 42.0878 -191.3636 90)
		(property "Reference" "R871"
			(at 0 0 90)
			(layer "F.SilkS")
			(hide yes)
			(effects
				(font
					(size 1.27 1.27)
				)
			)
		)
		(property "Value" "2KR2F-3-GP"
			(at 0.064008 -3.993896 90)
			(unlocked yes)
			(layer "F.Fab")
			(hide yes)
			(effects
				(font
					(size 1.016 1.016)
					(thickness 0.1524)
				)
			)
		)
		(property "Device Type" "R402H16"
			(at 0.064008 -5.517896 90)
			(unlocked yes)
			(layer "F.Fab")
			(hide yes)
			(effects
				(font
					(size 1.016 1.016)
					(thickness 0.1524)
				)
			)
		)
		(duplicate_pad_numbers_are_jumpers no)
		(fp_line
			(start 0.508 -0.9398)
			(end -0.508 -0.9398)
			(stroke
				(width 0.1524)
				(type default)
			)
			(layer "F.SilkS")
		)
		(fp_line
			(start -0.508 -0.9398)
			(end -0.508 0.9398)
			(stroke
				(width 0.1524)
				(type default)
			)
			(layer "F.SilkS")
		)
		(fp_rect
			(start -0.508 0.9398)
			(end 0.508 -0.9398)
			(stroke
				(width 0)
				(type default)
			)
			(fill no)
			(layer "F.CrtYd")
		)
		(fp_rect
			(start -0.508 0.9398)
			(end 0.508 -0.9398)
			(stroke
				(width 0)
				(type default)
			)
			(fill no)
			(layer "F.Fab")
		)
		(pad "1" smd custom
			(at 0 -0.4445 90)
			(size 0.1397 0.1397)
			(layers "F.Cu" "F.Mask" "F.Paste")
			(net "P3V3_STBY")
			(options
				(clearance outline)
				(anchor circle)
			)
			(primitives
				(gr_poly
					(pts
						(arc
							(start -0.1778 -0.2794)
							(mid -0.249642 -0.249642)
							(end -0.2794 -0.1778)
						)
						(arc
							(start -0.2794 0.1778)
							(mid -0.249642 0.249642)
							(end -0.1778 0.2794)
						)
						(arc
							(start 0.1778 0.2794)
							(mid 0.249642 0.249642)
							(end 0.2794 0.1778)
						)
						(arc
							(start 0.2794 -0.1778)
							(mid 0.249642 -0.249642)
							(end 0.1778 -0.2794)
						)
					)
					(width 0)
					(fill yes)
				)
			)
		)
		(pad "2" smd custom
			(at 0 0.4445 90)
			(size 0.1397 0.1397)
			(layers "F.Cu" "F.Mask" "F.Paste")
			(net "BUF_I2C9_CLKBUF2_SDA_R")
			(options
				(clearance outline)
				(anchor circle)
			)
			(primitives
				(gr_poly
					(pts
						(arc
							(start -0.1778 -0.2794)
							(mid -0.249642 -0.249642)
							(end -0.2794 -0.1778)
						)
						(arc
							(start -0.2794 0.1778)
							(mid -0.249642 0.249642)
							(end -0.1778 0.2794)
						)
						(arc
							(start 0.1778 0.2794)
							(mid 0.249642 0.249642)
							(end 0.2794 0.1778)
						)
						(arc
							(start 0.2794 -0.1778)
							(mid 0.249642 -0.249642)
							(end 0.1778 -0.2794)
						)
					)
					(width 0)
					(fill yes)
				)
			)
		)
	)
	(footprint ""
		(layer "F.Cu")
		(at 36.842954 -163.559744 90)
		(property "Reference" "C179"
			(at 0 0 90)
			(layer "F.SilkS")
			(hide yes)
			(effects
				(font
					(size 1.27 1.27)
				)
			)
		)
		(property "Value" "SCD01U25V2KX-3GP"
			(at 1.1811 -2.7051 90)
			(unlocked yes)
			(layer "F.Fab")
			(hide yes)
			(effects
				(font
					(size 1.016 1.016)
					(thickness 0.1524)
				)
			)
		)
		(property "Device Type" "C402H22"
			(at 1.1811 -4.2291 90)
			(unlocked yes)
			(layer "F.Fab")
			(hide yes)
			(effects
				(font
					(size 1.016 1.016)
					(thickness 0.1524)
				)
			)
		)
		(duplicate_pad_numbers_are_jumpers no)
		(fp_rect
			(start -0.4318 0.9525)
			(end 0.4318 -0.9525)
			(stroke
				(width 0)
				(type default)
			)
			(fill no)
			(layer "F.CrtYd")
		)
		(fp_rect
			(start -0.4318 0.9525)
			(end 0.4318 -0.9525)
			(stroke
				(width 0)
				(type default)
			)
			(fill no)
			(layer "F.Fab")
		)
		(pad "1" smd custom
			(at 0 -0.4445 90)
			(size 0.1524 0.1524)
			(layers "F.Cu" "F.Mask" "F.Paste")
			(net "DDR_VREF")
			(options
				(clearance outline)
				(anchor circle)
			)
			(primitives
				(gr_poly
					(pts
						(arc
							(start 0.3048 -0.2032)
							(mid 0.275042 -0.275042)
							(end 0.2032 -0.3048)
						)
						(arc
							(start -0.2032 -0.3048)
							(mid -0.275042 -0.275042)
							(end -0.3048 -0.2032)
						)
						(arc
							(start -0.3048 0.2032)
							(mid -0.275042 0.275042)
							(end -0.2032 0.3048)
						)
						(arc
							(start 0.2032 0.3048)
							(mid 0.275042 0.275042)
							(end 0.3048 0.2032)
						)
					)
					(width 0)
					(fill yes)
				)
			)
		)
		(pad "2" smd custom
			(at 0 0.4445 90)
			(size 0.1524 0.1524)
			(layers "F.Cu" "F.Mask" "F.Paste")
			(net "GND")
			(options
				(clearance outline)
				(anchor circle)
			)
			(primitives
				(gr_poly
					(pts
						(arc
							(start 0.3048 -0.2032)
							(mid 0.275042 -0.275042)
							(end 0.2032 -0.3048)
						)
						(arc
							(start -0.2032 -0.3048)
							(mid -0.275042 -0.275042)
							(end -0.3048 -0.2032)
						)
						(arc
							(start -0.3048 0.2032)
							(mid -0.275042 0.275042)
							(end -0.2032 0.3048)
						)
						(arc
							(start 0.2032 0.3048)
							(mid 0.275042 0.275042)
							(end 0.3048 0.2032)
						)
					)
					(width 0)
					(fill yes)
				)
			)
		)
	)
	(footprint ""
		(layer "F.Cu")
		(at 16.256 -143.383 90)
		(property "Reference" "L6"
			(at 0 0 90)
			(layer "F.SilkS")
			(hide yes)
			(effects
				(font
					(size 1.27 1.27)
				)
			)
		)
		(property "Value" "MMZ2012S601ATA1N-GP"
			(at 0 -4.2418 90)
			(unlocked yes)
			(layer "F.Fab")
			(hide yes)
			(effects
				(font
					(size 1.016 1.016)
					(thickness 0.1524)
				)
			)
		)
		(property "Device Type" "L805H42"
			(at 0 -5.7912 90)
			(unlocked yes)
			(layer "F.Fab")
			(hide yes)
			(effects
				(font
					(size 1.016 1.016)
					(thickness 0.1524)
				)
			)
		)
		(duplicate_pad_numbers_are_jumpers no)
		(fp_line
			(start 0.889 -1.7018)
			(end 0.889 1.7018)
			(stroke
				(width 0.1524)
				(type default)
			)
			(layer "F.SilkS")
		)
		(fp_line
			(start -0.889 -1.7018)
			(end 0.889 -1.7018)
			(stroke
				(width 0.1524)
				(type default)
			)
			(layer "F.SilkS")
		)
		(fp_line
			(start 0.889 1.7018)
			(end -0.889 1.7018)
			(stroke
				(width 0.1524)
				(type default)
			)
			(layer "F.SilkS")
		)
		(fp_line
			(start -0.889 1.7018)
			(end -0.889 -1.7018)
			(stroke
				(width 0.1524)
				(type default)
			)
			(layer "F.SilkS")
		)
		(fp_rect
			(start -0.9652 1.778)
			(end 0.9652 -1.778)
			(stroke
				(width 0)
				(type default)
			)
			(fill no)
			(layer "F.CrtYd")
		)
		(fp_rect
			(start -0.9652 1.778)
			(end 0.9652 -1.778)
			(stroke
				(width 0)
				(type default)
			)
			(fill no)
			(layer "F.Fab")
		)
		(pad "1" smd rect
			(at 0 -0.9652 90)
			(size 1.397 1.143)
			(layers "F.Cu" "F.Mask" "F.Paste")
			(net "P1V26_STBY")
		)
		(pad "2" smd rect
			(at 0 0.9652 90)
			(size 1.397 1.143)
			(layers "F.Cu" "F.Mask" "F.Paste")
			(net "V1PLLAV12")
		)
	)
	(footprint ""
		(layer "F.Cu")
		(at 27.686 -142.621 -90)
		(property "Reference" "R449"
			(at 0 0 270)
			(layer "F.SilkS")
			(hide yes)
			(effects
				(font
					(size 1.27 1.27)
				)
			)
		)
		(property "Value" "0R2J-2-GP"
			(at 0.064008 -3.993896 270)
			(unlocked yes)
			(layer "F.Fab")
			(hide yes)
			(effects
				(font
					(size 1.016 1.016)
					(thickness 0.1524)
				)
			)
		)
		(property "Device Type" "R402H16"
			(at 0.064008 -5.517896 270)
			(unlocked yes)
			(layer "F.Fab")
			(hide yes)
			(effects
				(font
					(size 1.016 1.016)
					(thickness 0.1524)
				)
			)
		)
		(duplicate_pad_numbers_are_jumpers no)
		(fp_line
			(start -0.508 -0.9398)
			(end -0.508 0.9398)
			(stroke
				(width 0.1524)
				(type default)
			)
			(layer "F.SilkS")
		)
		(fp_line
			(start 0.508 -0.9398)
			(end -0.508 -0.9398)
			(stroke
				(width 0.1524)
				(type default)
			)
			(layer "F.SilkS")
		)
		(fp_rect
			(start -0.508 0.9398)
			(end 0.508 -0.9398)
			(stroke
				(width 0)
				(type default)
			)
			(fill no)
			(layer "F.CrtYd")
		)
		(fp_rect
			(start -0.508 0.9398)
			(end 0.508 -0.9398)
			(stroke
				(width 0)
				(type default)
			)
			(fill no)
			(layer "F.Fab")
		)
		(pad "1" smd custom
			(at 0 -0.4445 270)
			(size 0.1397 0.1397)
			(layers "F.Cu" "F.Mask" "F.Paste")
			(net "BMC_USB2_HDP")
			(options
				(clearance outline)
				(anchor circle)
			)
			(primitives
				(gr_poly
					(pts
						(arc
							(start -0.1778 -0.2794)
							(mid -0.249642 -0.249642)
							(end -0.2794 -0.1778)
						)
						(arc
							(start -0.2794 0.1778)
							(mid -0.249642 0.249642)
							(end -0.1778 0.2794)
						)
						(arc
							(start 0.1778 0.2794)
							(mid 0.249642 0.249642)
							(end 0.2794 0.1778)
						)
						(arc
							(start 0.2794 -0.1778)
							(mid 0.249642 -0.249642)
							(end 0.1778 -0.2794)
						)
					)
					(width 0)
					(fill yes)
				)
			)
		)
		(pad "2" smd custom
			(at 0 0.4445 270)
			(size 0.1397 0.1397)
			(layers "F.Cu" "F.Mask" "F.Paste")
			(net "USB2_BMC_DP")
			(options
				(clearance outline)
				(anchor circle)
			)
			(primitives
				(gr_poly
					(pts
						(arc
							(start -0.1778 -0.2794)
							(mid -0.249642 -0.249642)
							(end -0.2794 -0.1778)
						)
						(arc
							(start -0.2794 0.1778)
							(mid -0.249642 0.249642)
							(end -0.1778 0.2794)
						)
						(arc
							(start 0.1778 0.2794)
							(mid 0.249642 0.249642)
							(end 0.2794 0.1778)
						)
						(arc
							(start 0.2794 -0.1778)
							(mid 0.249642 -0.249642)
							(end 0.1778 -0.2794)
						)
					)
					(width 0)
					(fill yes)
				)
			)
		)
	)
	(footprint ""
		(layer "F.Cu")
		(at 27.3812 -58.4454 90)
		(property "Reference" "R2949"
			(at 0 0 90)
			(layer "F.SilkS")
			(hide yes)
			(effects
				(font
					(size 1.27 1.27)
				)
			)
		)
		(property "Value" "0R2J-2-GP"
			(at 0.064008 -3.993896 90)
			(unlocked yes)
			(layer "F.Fab")
			(hide yes)
			(effects
				(font
					(size 1.016 1.016)
					(thickness 0.1524)
				)
			)
		)
		(property "Device Type" "R402H16"
			(at 0.064008 -5.517896 90)
			(unlocked yes)
			(layer "F.Fab")
			(hide yes)
			(effects
				(font
					(size 1.016 1.016)
					(thickness 0.1524)
				)
			)
		)
		(duplicate_pad_numbers_are_jumpers no)
		(fp_line
			(start 0.508 -0.9398)
			(end -0.508 -0.9398)
			(stroke
				(width 0.1524)
				(type default)
			)
			(layer "F.SilkS")
		)
		(fp_line
			(start -0.508 -0.9398)
			(end -0.508 0.9398)
			(stroke
				(width 0.1524)
				(type default)
			)
			(layer "F.SilkS")
		)
		(fp_rect
			(start -0.508 0.9398)
			(end 0.508 -0.9398)
			(stroke
				(width 0)
				(type default)
			)
			(fill no)
			(layer "F.CrtYd")
		)
		(fp_rect
			(start -0.508 0.9398)
			(end 0.508 -0.9398)
			(stroke
				(width 0)
				(type default)
			)
			(fill no)
			(layer "F.Fab")
		)
		(pad "1" smd custom
			(at 0 -0.4445 90)
			(size 0.1397 0.1397)
			(layers "F.Cu" "F.Mask" "F.Paste")
			(net "I2C_TPM_SDA")
			(options
				(clearance outline)
				(anchor circle)
			)
			(primitives
				(gr_poly
					(pts
						(arc
							(start -0.1778 -0.2794)
							(mid -0.249642 -0.249642)
							(end -0.2794 -0.1778)
						)
						(arc
							(start -0.2794 0.1778)
							(mid -0.249642 0.249642)
							(end -0.1778 0.2794)
						)
						(arc
							(start 0.1778 0.2794)
							(mid 0.249642 0.249642)
							(end 0.2794 0.1778)
						)
						(arc
							(start 0.2794 -0.1778)
							(mid 0.249642 -0.249642)
							(end 0.1778 -0.2794)
						)
					)
					(width 0)
					(fill yes)
				)
			)
		)
		(pad "2" smd custom
			(at 0 0.4445 90)
			(size 0.1397 0.1397)
			(layers "F.Cu" "F.Mask" "F.Paste")
			(net "BMC_I2C5_D_PEB_DEVICE_SDA")
			(options
				(clearance outline)
				(anchor circle)
			)
			(primitives
				(gr_poly
					(pts
						(arc
							(start -0.1778 -0.2794)
							(mid -0.249642 -0.249642)
							(end -0.2794 -0.1778)
						)
						(arc
							(start -0.2794 0.1778)
							(mid -0.249642 0.249642)
							(end -0.1778 0.2794)
						)
						(arc
							(start 0.1778 0.2794)
							(mid 0.249642 0.249642)
							(end 0.2794 0.1778)
						)
						(arc
							(start 0.2794 -0.1778)
							(mid 0.249642 -0.249642)
							(end 0.1778 -0.2794)
						)
					)
					(width 0)
					(fill yes)
				)
			)
		)
	)
	(footprint ""
		(layer "F.Cu")
		(at 273.939 -15.367 90)
		(property "Reference" "C6"
			(at 0 0 90)
			(layer "F.SilkS")
			(hide yes)
			(effects
				(font
					(size 1.27 1.27)
				)
			)
		)
		(property "Value" "SCD22U10V2KX-1GP"
			(at 1.1811 -2.7051 90)
			(unlocked yes)
			(layer "F.Fab")
			(hide yes)
			(effects
				(font
					(size 1.016 1.016)
					(thickness 0.1524)
				)
			)
		)
		(property "Device Type" "C402H22"
			(at 1.1811 -4.2291 90)
			(unlocked yes)
			(layer "F.Fab")
			(hide yes)
			(effects
				(font
					(size 1.016 1.016)
					(thickness 0.1524)
				)
			)
		)
		(duplicate_pad_numbers_are_jumpers no)
		(fp_rect
			(start -0.4318 0.9525)
			(end 0.4318 -0.9525)
			(stroke
				(width 0)
				(type default)
			)
			(fill no)
			(layer "F.CrtYd")
		)
		(fp_rect
			(start -0.4318 0.9525)
			(end 0.4318 -0.9525)
			(stroke
				(width 0)
				(type default)
			)
			(fill no)
			(layer "F.Fab")
		)
		(pad "1" smd custom
			(at 0 -0.4445 90)
			(size 0.1524 0.1524)
			(layers "F.Cu" "F.Mask" "F.Paste")
			(net "PCIE_TX_CAP_N1")
			(options
				(clearance outline)
				(anchor circle)
			)
			(primitives
				(gr_poly
					(pts
						(arc
							(start 0.3048 -0.2032)
							(mid 0.275042 -0.275042)
							(end 0.2032 -0.3048)
						)
						(arc
							(start -0.2032 -0.3048)
							(mid -0.275042 -0.275042)
							(end -0.3048 -0.2032)
						)
						(arc
							(start -0.3048 0.2032)
							(mid -0.275042 0.275042)
							(end -0.2032 0.3048)
						)
						(arc
							(start 0.2032 0.3048)
							(mid 0.275042 0.275042)
							(end 0.3048 0.2032)
						)
					)
					(width 0)
					(fill yes)
				)
			)
		)
		(pad "2" smd custom
			(at 0 0.4445 90)
			(size 0.1524 0.1524)
			(layers "F.Cu" "F.Mask" "F.Paste")
			(net "PCIE_TX_N1")
			(options
				(clearance outline)
				(anchor circle)
			)
			(primitives
				(gr_poly
					(pts
						(arc
							(start 0.3048 -0.2032)
							(mid 0.275042 -0.275042)
							(end 0.2032 -0.3048)
						)
						(arc
							(start -0.2032 -0.3048)
							(mid -0.275042 -0.275042)
							(end -0.3048 -0.2032)
						)
						(arc
							(start -0.3048 0.2032)
							(mid -0.275042 0.275042)
							(end -0.2032 0.3048)
						)
						(arc
							(start 0.2032 0.3048)
							(mid 0.275042 0.275042)
							(end 0.3048 0.2032)
						)
					)
					(width 0)
					(fill yes)
				)
			)
		)
	)
	(footprint ""
		(layer "F.Cu")
		(at 194.608196 -212.420454 180)
		(property "Reference" "C120"
			(at 0 0 180)
			(layer "F.SilkS")
			(hide yes)
			(effects
				(font
					(size 1.27 1.27)
				)
			)
		)
		(property "Value" "SCD22U10V2KX-1GP"
			(at 1.1811 -2.7051 180)
			(unlocked yes)
			(layer "F.Fab")
			(hide yes)
			(effects
				(font
					(size 1.016 1.016)
					(thickness 0.1524)
				)
			)
		)
		(property "Device Type" "C402H22"
			(at 1.1811 -4.2291 180)
			(unlocked yes)
			(layer "F.Fab")
			(hide yes)
			(effects
				(font
					(size 1.016 1.016)
					(thickness 0.1524)
				)
			)
		)
		(duplicate_pad_numbers_are_jumpers no)
		(fp_rect
			(start -0.4318 0.9525)
			(end 0.4318 -0.9525)
			(stroke
				(width 0)
				(type default)
			)
			(fill no)
			(layer "F.CrtYd")
		)
		(fp_rect
			(start -0.4318 0.9525)
			(end 0.4318 -0.9525)
			(stroke
				(width 0)
				(type default)
			)
			(fill no)
			(layer "F.Fab")
		)
		(pad "1" smd custom
			(at 0 -0.4445 180)
			(size 0.1524 0.1524)
			(layers "F.Cu" "F.Mask" "F.Paste")
			(net "PCIE_TX_CAP_N44")
			(options
				(clearance outline)
				(anchor circle)
			)
			(primitives
				(gr_poly
					(pts
						(arc
							(start 0.3048 -0.2032)
							(mid 0.275042 -0.275042)
							(end 0.2032 -0.3048)
						)
						(arc
							(start -0.2032 -0.3048)
							(mid -0.275042 -0.275042)
							(end -0.3048 -0.2032)
						)
						(arc
							(start -0.3048 0.2032)
							(mid -0.275042 0.275042)
							(end -0.2032 0.3048)
						)
						(arc
							(start 0.2032 0.3048)
							(mid 0.275042 0.275042)
							(end 0.3048 0.2032)
						)
					)
					(width 0)
					(fill yes)
				)
			)
		)
		(pad "2" smd custom
			(at 0 0.4445 180)
			(size 0.1524 0.1524)
			(layers "F.Cu" "F.Mask" "F.Paste")
			(net "PCIE_TX_N44")
			(options
				(clearance outline)
				(anchor circle)
			)
			(primitives
				(gr_poly
					(pts
						(arc
							(start 0.3048 -0.2032)
							(mid 0.275042 -0.275042)
							(end 0.2032 -0.3048)
						)
						(arc
							(start -0.2032 -0.3048)
							(mid -0.275042 -0.275042)
							(end -0.3048 -0.2032)
						)
						(arc
							(start -0.3048 0.2032)
							(mid -0.275042 0.275042)
							(end -0.2032 0.3048)
						)
						(arc
							(start 0.2032 0.3048)
							(mid 0.275042 0.275042)
							(end 0.3048 0.2032)
						)
					)
					(width 0)
					(fill yes)
				)
			)
		)
	)
	(footprint ""
		(layer "F.Cu")
		(at 78.191106 -86.487254 -90)
		(property "Reference" "R481"
			(at 0 0 270)
			(layer "F.SilkS")
			(hide yes)
			(effects
				(font
					(size 1.27 1.27)
				)
			)
		)
		(property "Value" "200R3F-GP"
			(at -0.0254 -2.5146 270)
			(unlocked yes)
			(layer "F.Fab")
			(hide yes)
			(effects
				(font
					(size 1.016 1.016)
					(thickness 0.1524)
				)
			)
		)
		(property "Device Type" "R603H22"
			(at -0.0254 -4.0386 270)
			(unlocked yes)
			(layer "F.Fab")
			(hide yes)
			(effects
				(font
					(size 1.016 1.016)
					(thickness 0.1524)
				)
			)
		)
		(duplicate_pad_numbers_are_jumpers no)
		(fp_line
			(start -0.4826 0)
			(end -0.2032 0)
			(stroke
				(width 0.2032)
				(type default)
			)
			(layer "F.SilkS")
		)
		(fp_line
			(start 0.2032 0)
			(end 0.4826 0)
			(stroke
				(width 0.2032)
				(type default)
			)
			(layer "F.SilkS")
		)
		(fp_rect
			(start -0.5842 1.3335)
			(end 0.5842 -1.3335)
			(stroke
				(width 0)
				(type default)
			)
			(fill no)
			(layer "F.CrtYd")
		)
		(fp_rect
			(start -0.5842 1.3335)
			(end 0.5842 -1.3335)
			(stroke
				(width 0)
				(type default)
			)
			(fill no)
			(layer "F.Fab")
		)
		(pad "1" smd custom
			(at 0 -0.762 270)
			(size 0.2159 0.2159)
			(layers "F.Cu" "F.Mask" "F.Paste")
			(net "P3V3_STBY")
			(options
				(clearance outline)
				(anchor circle)
			)
			(primitives
				(gr_poly
					(pts
						(arc
							(start -0.3302 -0.4318)
							(mid -0.402042 -0.402042)
							(end -0.4318 -0.3302)
						)
						(arc
							(start -0.4318 0.3302)
							(mid -0.402042 0.402042)
							(end -0.3302 0.4318)
						)
						(arc
							(start 0.3302 0.4318)
							(mid 0.402042 0.402042)
							(end 0.4318 0.3302)
						)
						(arc
							(start 0.4318 -0.3302)
							(mid 0.402042 -0.402042)
							(end 0.3302 -0.4318)
						)
					)
					(width 0)
					(fill yes)
				)
			)
		)
		(pad "2" smd custom
			(at 0 0.762 270)
			(size 0.2159 0.2159)
			(layers "F.Cu" "F.Mask" "F.Paste")
			(net "HB_A_OUT")
			(options
				(clearance outline)
				(anchor circle)
			)
			(primitives
				(gr_poly
					(pts
						(arc
							(start -0.3302 -0.4318)
							(mid -0.402042 -0.402042)
							(end -0.4318 -0.3302)
						)
						(arc
							(start -0.4318 0.3302)
							(mid -0.402042 0.402042)
							(end -0.3302 0.4318)
						)
						(arc
							(start 0.3302 0.4318)
							(mid 0.402042 0.402042)
							(end 0.4318 0.3302)
						)
						(arc
							(start 0.4318 -0.3302)
							(mid 0.402042 -0.402042)
							(end 0.3302 -0.4318)
						)
					)
					(width 0)
					(fill yes)
				)
			)
		)
	)
	(footprint ""
		(layer "F.Cu")
		(at 238.252 -23.241)
		(property "Reference" "R796"
			(at 0 0 0)
			(layer "F.SilkS")
			(hide yes)
			(effects
				(font
					(size 1.27 1.27)
				)
			)
		)
		(property "Value" "4K7R2F-GP"
			(at 0.064008 -3.993896 0)
			(unlocked yes)
			(layer "F.Fab")
			(hide yes)
			(effects
				(font
					(size 1.016 1.016)
					(thickness 0.1524)
				)
			)
		)
		(property "Device Type" "R402H16"
			(at 0.064008 -5.517896 0)
			(unlocked yes)
			(layer "F.Fab")
			(hide yes)
			(effects
				(font
					(size 1.016 1.016)
					(thickness 0.1524)
				)
			)
		)
		(duplicate_pad_numbers_are_jumpers no)
		(fp_line
			(start -0.508 -0.9398)
			(end -0.508 0.9398)
			(stroke
				(width 0.1524)
				(type default)
			)
			(layer "F.SilkS")
		)
		(fp_line
			(start 0.508 -0.9398)
			(end -0.508 -0.9398)
			(stroke
				(width 0.1524)
				(type default)
			)
			(layer "F.SilkS")
		)
		(fp_rect
			(start -0.508 0.9398)
			(end 0.508 -0.9398)
			(stroke
				(width 0)
				(type default)
			)
			(fill no)
			(layer "F.CrtYd")
		)
		(fp_rect
			(start -0.508 0.9398)
			(end 0.508 -0.9398)
			(stroke
				(width 0)
				(type default)
			)
			(fill no)
			(layer "F.Fab")
		)
		(pad "1" smd custom
			(at 0 -0.4445)
			(size 0.1397 0.1397)
			(layers "F.Cu" "F.Mask" "F.Paste")
			(net "GND")
			(options
				(clearance outline)
				(anchor circle)
			)
			(primitives
				(gr_poly
					(pts
						(arc
							(start -0.1778 -0.2794)
							(mid -0.249642 -0.249642)
							(end -0.2794 -0.1778)
						)
						(arc
							(start -0.2794 0.1778)
							(mid -0.249642 0.249642)
							(end -0.1778 0.2794)
						)
						(arc
							(start 0.1778 0.2794)
							(mid 0.249642 0.249642)
							(end 0.2794 0.1778)
						)
						(arc
							(start 0.2794 -0.1778)
							(mid 0.249642 -0.249642)
							(end 0.1778 -0.2794)
						)
					)
					(width 0)
					(fill yes)
				)
			)
		)
		(pad "2" smd custom
			(at 0 0.4445)
			(size 0.1397 0.1397)
			(layers "F.Cu" "F.Mask" "F.Paste")
			(net "BOOTSTRAP2")
			(options
				(clearance outline)
				(anchor circle)
			)
			(primitives
				(gr_poly
					(pts
						(arc
							(start -0.1778 -0.2794)
							(mid -0.249642 -0.249642)
							(end -0.2794 -0.1778)
						)
						(arc
							(start -0.2794 0.1778)
							(mid -0.249642 0.249642)
							(end -0.1778 0.2794)
						)
						(arc
							(start 0.1778 0.2794)
							(mid 0.249642 0.249642)
							(end 0.2794 0.1778)
						)
						(arc
							(start 0.2794 -0.1778)
							(mid 0.249642 -0.249642)
							(end 0.1778 -0.2794)
						)
					)
					(width 0)
					(fill yes)
				)
			)
		)
	)
	(footprint ""
		(layer "F.Cu")
		(at 44.323 -142.621)
		(property "Reference" "TP232"
			(at 0 0 0)
			(layer "F.SilkS")
			(hide yes)
			(effects
				(font
					(size 1.27 1.27)
				)
			)
		)
		(property "Value" "TPAD28-2-GP"
			(at -0.0127 -1.6637 0)
			(unlocked yes)
			(layer "F.Fab")
			(hide yes)
			(effects
				(font
					(size 1.016 1.016)
					(thickness 0.1524)
				)
			)
		)
		(property "Device Type" "TPAD28"
			(at -0.0127 -3.1877 0)
			(unlocked yes)
			(layer "F.Fab")
			(hide yes)
			(effects
				(font
					(size 1.016 1.016)
					(thickness 0.1524)
				)
			)
		)
		(duplicate_pad_numbers_are_jumpers no)
		(fp_poly
			(pts
				(arc
					(start 0.3556 0)
					(mid -0.3556 0)
					(end 0.3556 0)
				)
			)
			(stroke
				(width 0)
				(type default)
			)
			(fill no)
			(layer "F.CrtYd")
		)
		(fp_poly
			(pts
				(arc
					(start 0.6096 0)
					(mid -0.6096 0)
					(end 0.6096 0)
				)
			)
			(stroke
				(width 0)
				(type default)
			)
			(fill no)
			(layer "F.Fab")
		)
		(pad "1" smd circle
			(at 0 0)
			(size 0.7112 0.7112)
			(layers "F.Cu" "F.Mask" "F.Paste")
			(net "TP_GPIOP6")
		)
	)
	(footprint ""
		(layer "F.Cu")
		(at 213.808056 -212.420454 180)
		(property "Reference" "C110"
			(at 0 0 180)
			(layer "F.SilkS")
			(hide yes)
			(effects
				(font
					(size 1.27 1.27)
				)
			)
		)
		(property "Value" "SCD22U10V2KX-1GP"
			(at 1.1811 -2.7051 180)
			(unlocked yes)
			(layer "F.Fab")
			(hide yes)
			(effects
				(font
					(size 1.016 1.016)
					(thickness 0.1524)
				)
			)
		)
		(property "Device Type" "C402H22"
			(at 1.1811 -4.2291 180)
			(unlocked yes)
			(layer "F.Fab")
			(hide yes)
			(effects
				(font
					(size 1.016 1.016)
					(thickness 0.1524)
				)
			)
		)
		(duplicate_pad_numbers_are_jumpers no)
		(fp_rect
			(start -0.4318 0.9525)
			(end 0.4318 -0.9525)
			(stroke
				(width 0)
				(type default)
			)
			(fill no)
			(layer "F.CrtYd")
		)
		(fp_rect
			(start -0.4318 0.9525)
			(end 0.4318 -0.9525)
			(stroke
				(width 0)
				(type default)
			)
			(fill no)
			(layer "F.Fab")
		)
		(pad "1" smd custom
			(at 0 -0.4445 180)
			(size 0.1524 0.1524)
			(layers "F.Cu" "F.Mask" "F.Paste")
			(net "PCIE_TX_CAP_N39")
			(options
				(clearance outline)
				(anchor circle)
			)
			(primitives
				(gr_poly
					(pts
						(arc
							(start 0.3048 -0.2032)
							(mid 0.275042 -0.275042)
							(end 0.2032 -0.3048)
						)
						(arc
							(start -0.2032 -0.3048)
							(mid -0.275042 -0.275042)
							(end -0.3048 -0.2032)
						)
						(arc
							(start -0.3048 0.2032)
							(mid -0.275042 0.275042)
							(end -0.2032 0.3048)
						)
						(arc
							(start 0.2032 0.3048)
							(mid 0.275042 0.275042)
							(end 0.3048 0.2032)
						)
					)
					(width 0)
					(fill yes)
				)
			)
		)
		(pad "2" smd custom
			(at 0 0.4445 180)
			(size 0.1524 0.1524)
			(layers "F.Cu" "F.Mask" "F.Paste")
			(net "PCIE_TX_N39")
			(options
				(clearance outline)
				(anchor circle)
			)
			(primitives
				(gr_poly
					(pts
						(arc
							(start 0.3048 -0.2032)
							(mid 0.275042 -0.275042)
							(end 0.2032 -0.3048)
						)
						(arc
							(start -0.2032 -0.3048)
							(mid -0.275042 -0.275042)
							(end -0.3048 -0.2032)
						)
						(arc
							(start -0.3048 0.2032)
							(mid -0.275042 0.275042)
							(end -0.2032 0.3048)
						)
						(arc
							(start 0.2032 0.3048)
							(mid 0.275042 0.275042)
							(end 0.3048 0.2032)
						)
					)
					(width 0)
					(fill yes)
				)
			)
		)
	)
	(footprint ""
		(layer "F.Cu")
		(at 53.721 -127.508 90)
		(property "Reference" "R451"
			(at 0 0 90)
			(layer "F.SilkS")
			(hide yes)
			(effects
				(font
					(size 1.27 1.27)
				)
			)
		)
		(property "Value" "0R2J-2-GP"
			(at 0.064008 -3.993896 90)
			(unlocked yes)
			(layer "F.Fab")
			(hide yes)
			(effects
				(font
					(size 1.016 1.016)
					(thickness 0.1524)
				)
			)
		)
		(property "Device Type" "R402H16"
			(at 0.064008 -5.517896 90)
			(unlocked yes)
			(layer "F.Fab")
			(hide yes)
			(effects
				(font
					(size 1.016 1.016)
					(thickness 0.1524)
				)
			)
		)
		(duplicate_pad_numbers_are_jumpers no)
		(fp_line
			(start 0.508 -0.9398)
			(end -0.508 -0.9398)
			(stroke
				(width 0.1524)
				(type default)
			)
			(layer "F.SilkS")
		)
		(fp_line
			(start -0.508 -0.9398)
			(end -0.508 0.9398)
			(stroke
				(width 0.1524)
				(type default)
			)
			(layer "F.SilkS")
		)
		(fp_rect
			(start -0.508 0.9398)
			(end 0.508 -0.9398)
			(stroke
				(width 0)
				(type default)
			)
			(fill no)
			(layer "F.CrtYd")
		)
		(fp_rect
			(start -0.508 0.9398)
			(end 0.508 -0.9398)
			(stroke
				(width 0)
				(type default)
			)
			(fill no)
			(layer "F.Fab")
		)
		(pad "1" smd custom
			(at 0 -0.4445 90)
			(size 0.1397 0.1397)
			(layers "F.Cu" "F.Mask" "F.Paste")
			(net "BMC_USB1_HDP")
			(options
				(clearance outline)
				(anchor circle)
			)
			(primitives
				(gr_poly
					(pts
						(arc
							(start -0.1778 -0.2794)
							(mid -0.249642 -0.249642)
							(end -0.2794 -0.1778)
						)
						(arc
							(start -0.2794 0.1778)
							(mid -0.249642 0.249642)
							(end -0.1778 0.2794)
						)
						(arc
							(start 0.1778 0.2794)
							(mid 0.249642 0.249642)
							(end 0.2794 0.1778)
						)
						(arc
							(start 0.2794 -0.1778)
							(mid 0.249642 -0.249642)
							(end 0.1778 -0.2794)
						)
					)
					(width 0)
					(fill yes)
				)
			)
		)
		(pad "2" smd custom
			(at 0 0.4445 90)
			(size 0.1397 0.1397)
			(layers "F.Cu" "F.Mask" "F.Paste")
			(net "USB_P2_DP")
			(options
				(clearance outline)
				(anchor circle)
			)
			(primitives
				(gr_poly
					(pts
						(arc
							(start -0.1778 -0.2794)
							(mid -0.249642 -0.249642)
							(end -0.2794 -0.1778)
						)
						(arc
							(start -0.2794 0.1778)
							(mid -0.249642 0.249642)
							(end -0.1778 0.2794)
						)
						(arc
							(start 0.1778 0.2794)
							(mid 0.249642 0.249642)
							(end 0.2794 0.1778)
						)
						(arc
							(start 0.2794 -0.1778)
							(mid 0.249642 -0.249642)
							(end 0.1778 -0.2794)
						)
					)
					(width 0)
					(fill yes)
				)
			)
		)
	)
	(footprint ""
		(layer "F.Cu")
		(at 62.611 -133.985)
		(property "Reference" "C8083"
			(at 0 0 0)
			(layer "F.SilkS")
			(hide yes)
			(effects
				(font
					(size 1.27 1.27)
				)
			)
		)
		(property "Value" "SCD1U25V2KX-2-GP"
			(at 1.1811 -2.7051 0)
			(unlocked yes)
			(layer "F.Fab")
			(hide yes)
			(effects
				(font
					(size 1.016 1.016)
					(thickness 0.1524)
				)
			)
		)
		(property "Device Type" "C402H22"
			(at 1.1811 -4.2291 0)
			(unlocked yes)
			(layer "F.Fab")
			(hide yes)
			(effects
				(font
					(size 1.016 1.016)
					(thickness 0.1524)
				)
			)
		)
		(duplicate_pad_numbers_are_jumpers no)
		(fp_rect
			(start -0.4318 0.9525)
			(end 0.4318 -0.9525)
			(stroke
				(width 0)
				(type default)
			)
			(fill no)
			(layer "F.CrtYd")
		)
		(fp_rect
			(start -0.4318 0.9525)
			(end 0.4318 -0.9525)
			(stroke
				(width 0)
				(type default)
			)
			(fill no)
			(layer "F.Fab")
		)
		(pad "1" smd custom
			(at 0 -0.4445)
			(size 0.1524 0.1524)
			(layers "F.Cu" "F.Mask" "F.Paste")
			(net "ADC_P0V9")
			(options
				(clearance outline)
				(anchor circle)
			)
			(primitives
				(gr_poly
					(pts
						(arc
							(start 0.3048 -0.2032)
							(mid 0.275042 -0.275042)
							(end 0.2032 -0.3048)
						)
						(arc
							(start -0.2032 -0.3048)
							(mid -0.275042 -0.275042)
							(end -0.3048 -0.2032)
						)
						(arc
							(start -0.3048 0.2032)
							(mid -0.275042 0.275042)
							(end -0.2032 0.3048)
						)
						(arc
							(start 0.2032 0.3048)
							(mid 0.275042 0.275042)
							(end 0.3048 0.2032)
						)
					)
					(width 0)
					(fill yes)
				)
			)
		)
		(pad "2" smd custom
			(at 0 0.4445)
			(size 0.1524 0.1524)
			(layers "F.Cu" "F.Mask" "F.Paste")
			(net "GND")
			(options
				(clearance outline)
				(anchor circle)
			)
			(primitives
				(gr_poly
					(pts
						(arc
							(start 0.3048 -0.2032)
							(mid 0.275042 -0.275042)
							(end 0.2032 -0.3048)
						)
						(arc
							(start -0.2032 -0.3048)
							(mid -0.275042 -0.275042)
							(end -0.3048 -0.2032)
						)
						(arc
							(start -0.3048 0.2032)
							(mid -0.275042 0.275042)
							(end -0.2032 0.3048)
						)
						(arc
							(start 0.2032 0.3048)
							(mid 0.275042 0.275042)
							(end 0.3048 0.2032)
						)
					)
					(width 0)
					(fill yes)
				)
			)
		)
	)
	(footprint ""
		(layer "F.Cu")
		(at 230.251 -10.414 90)
		(property "Reference" "R652"
			(at 0 0 90)
			(layer "F.SilkS")
			(hide yes)
			(effects
				(font
					(size 1.27 1.27)
				)
			)
		)
		(property "Value" "100KR2F-L1-GP"
			(at 0.064008 -3.993896 90)
			(unlocked yes)
			(layer "F.Fab")
			(hide yes)
			(effects
				(font
					(size 1.016 1.016)
					(thickness 0.1524)
				)
			)
		)
		(property "Device Type" "R402H16"
			(at 0.064008 -5.517896 90)
			(unlocked yes)
			(layer "F.Fab")
			(hide yes)
			(effects
				(font
					(size 1.016 1.016)
					(thickness 0.1524)
				)
			)
		)
		(duplicate_pad_numbers_are_jumpers no)
		(fp_line
			(start 0.508 -0.9398)
			(end -0.508 -0.9398)
			(stroke
				(width 0.1524)
				(type default)
			)
			(layer "F.SilkS")
		)
		(fp_line
			(start -0.508 -0.9398)
			(end -0.508 0.9398)
			(stroke
				(width 0.1524)
				(type default)
			)
			(layer "F.SilkS")
		)
		(fp_rect
			(start -0.508 0.9398)
			(end 0.508 -0.9398)
			(stroke
				(width 0)
				(type default)
			)
			(fill no)
			(layer "F.CrtYd")
		)
		(fp_rect
			(start -0.508 0.9398)
			(end 0.508 -0.9398)
			(stroke
				(width 0)
				(type default)
			)
			(fill no)
			(layer "F.Fab")
		)
		(pad "1" smd custom
			(at 0 -0.4445 90)
			(size 0.1397 0.1397)
			(layers "F.Cu" "F.Mask" "F.Paste")
			(net "EEPROM_WP_8536")
			(options
				(clearance outline)
				(anchor circle)
			)
			(primitives
				(gr_poly
					(pts
						(arc
							(start -0.1778 -0.2794)
							(mid -0.249642 -0.249642)
							(end -0.2794 -0.1778)
						)
						(arc
							(start -0.2794 0.1778)
							(mid -0.249642 0.249642)
							(end -0.1778 0.2794)
						)
						(arc
							(start 0.1778 0.2794)
							(mid 0.249642 0.249642)
							(end 0.2794 0.1778)
						)
						(arc
							(start 0.2794 -0.1778)
							(mid 0.249642 -0.249642)
							(end 0.1778 -0.2794)
						)
					)
					(width 0)
					(fill yes)
				)
			)
		)
		(pad "2" smd custom
			(at 0 0.4445 90)
			(size 0.1397 0.1397)
			(layers "F.Cu" "F.Mask" "F.Paste")
			(net "GND")
			(options
				(clearance outline)
				(anchor circle)
			)
			(primitives
				(gr_poly
					(pts
						(arc
							(start -0.1778 -0.2794)
							(mid -0.249642 -0.249642)
							(end -0.2794 -0.1778)
						)
						(arc
							(start -0.2794 0.1778)
							(mid -0.249642 0.249642)
							(end -0.1778 0.2794)
						)
						(arc
							(start 0.1778 0.2794)
							(mid 0.249642 0.249642)
							(end 0.2794 0.1778)
						)
						(arc
							(start 0.2794 -0.1778)
							(mid 0.249642 -0.249642)
							(end 0.1778 -0.2794)
						)
					)
					(width 0)
					(fill yes)
				)
			)
		)
	)
	(footprint ""
		(layer "F.Cu")
		(at 345.60002 -34.499804)
		(property "Reference" ""
			(at 0 0 0)
			(layer "F.SilkS")
			(hide yes)
			(effects
				(font
					(size 1.27 1.27)
				)
			)
		)
		(property "Value" "*"
			(at -0.1524 -7.3914 0)
			(unlocked yes)
			(layer "F.Fab")
			(hide yes)
			(effects
				(font
					(size 1.016 1.016)
					(thickness 0.1524)
				)
			)
		)
		(duplicate_pad_numbers_are_jumpers no)
		(fp_poly
			(pts
				(arc
					(start 4.3053 0)
					(mid -4.3053 0)
					(end 4.3053 0)
				)
			)
			(stroke
				(width 0)
				(type default)
			)
			(fill no)
			(layer "B.CrtYd")
		)
		(fp_poly
			(pts
				(arc
					(start 4.3053 0)
					(mid -4.3053 0)
					(end 4.3053 0)
				)
			)
			(stroke
				(width 0)
				(type default)
			)
			(fill no)
			(layer "F.CrtYd")
		)
		(fp_poly
			(pts
				(arc
					(start 4.3053 0)
					(mid -4.3053 0)
					(end 4.3053 0)
				)
			)
			(stroke
				(width 0)
				(type default)
			)
			(fill no)
			(layer "B.Fab")
		)
		(fp_poly
			(pts
				(arc
					(start 4.3053 0)
					(mid -4.3053 0)
					(end 4.3053 0)
				)
			)
			(stroke
				(width 0)
				(type default)
			)
			(fill no)
			(layer "F.Fab")
		)
		(pad "1" thru_hole circle
			(at 0 0)
			(size 8.001 8.001)
			(drill 3.81)
			(layers "*.Cu" "*.Mask")
			(remove_unused_layers no)
			(net "Net_116")
			(clearance -1.5875)
			(thermal_gap 0.3048)
			(padstack
				(mode front_inner_back)
				(layer "Inner"
					(shape circle)
					(size 4.2164 4.2164)
					(clearance 0.3048)
				)
				(layer "B.Cu"
					(shape circle)
					(size 8.001 8.001)
					(clearance -1.5875)
				)
			)
		)
	)
	(footprint ""
		(layer "F.Cu")
		(at 308.102 -57.0992)
		(property "Reference" "C439"
			(at 0 0 0)
			(layer "F.SilkS")
			(hide yes)
			(effects
				(font
					(size 1.27 1.27)
				)
			)
		)
		(property "Value" "SC10U16V5KX-1-GP"
			(at -0.0762 -6.1214 0)
			(unlocked yes)
			(layer "F.Fab")
			(hide yes)
			(effects
				(font
					(size 1.016 1.016)
					(thickness 0.1524)
				)
			)
		)
		(property "Device Type" "C805H54"
			(at -0.0762 -8.1534 0)
			(unlocked yes)
			(layer "F.Fab")
			(hide yes)
			(effects
				(font
					(size 1.016 1.016)
					(thickness 0.1524)
				)
			)
		)
		(duplicate_pad_numbers_are_jumpers no)
		(fp_line
			(start 0.635 0)
			(end -0.635 0)
			(stroke
				(width 0.508)
				(type default)
			)
			(layer "F.SilkS")
		)
		(fp_rect
			(start -0.9652 1.778)
			(end 0.9652 -1.778)
			(stroke
				(width 0)
				(type default)
			)
			(fill no)
			(layer "F.CrtYd")
		)
		(fp_poly
			(pts
				(xy -0.9652 -1.778) (xy 0.9652 -1.778) (xy 0.9652 1.778) (xy -0.9652 1.778)
			)
			(stroke
				(width 0)
				(type default)
			)
			(fill no)
			(layer "F.Fab")
		)
		(pad "1" smd rect
			(at 0 -0.9652)
			(size 1.397 1.143)
			(layers "F.Cu" "F.Mask" "F.Paste")
			(net "DUT_VDD")
		)
		(pad "2" smd rect
			(at 0 0.9652)
			(size 1.397 1.143)
			(layers "F.Cu" "F.Mask" "F.Paste")
			(net "GND")
		)
	)
	(footprint ""
		(layer "F.Cu")
		(at 181.61 -20.701 -90)
		(property "Reference" "C411"
			(at 0 0 270)
			(layer "F.SilkS")
			(hide yes)
			(effects
				(font
					(size 1.27 1.27)
				)
			)
		)
		(property "Value" "SCD22U10V2KX-1GP"
			(at 1.1811 -2.7051 270)
			(unlocked yes)
			(layer "F.Fab")
			(hide yes)
			(effects
				(font
					(size 1.016 1.016)
					(thickness 0.1524)
				)
			)
		)
		(property "Device Type" "C402H22"
			(at 1.1811 -4.2291 270)
			(unlocked yes)
			(layer "F.Fab")
			(hide yes)
			(effects
				(font
					(size 1.016 1.016)
					(thickness 0.1524)
				)
			)
		)
		(duplicate_pad_numbers_are_jumpers no)
		(fp_rect
			(start -0.4318 0.9525)
			(end 0.4318 -0.9525)
			(stroke
				(width 0)
				(type default)
			)
			(fill no)
			(layer "F.CrtYd")
		)
		(fp_rect
			(start -0.4318 0.9525)
			(end 0.4318 -0.9525)
			(stroke
				(width 0)
				(type default)
			)
			(fill no)
			(layer "F.Fab")
		)
		(pad "1" smd custom
			(at 0 -0.4445 270)
			(size 0.1524 0.1524)
			(layers "F.Cu" "F.Mask" "F.Paste")
			(net "PCIE_TX_CAP_P95")
			(options
				(clearance outline)
				(anchor circle)
			)
			(primitives
				(gr_poly
					(pts
						(arc
							(start 0.3048 -0.2032)
							(mid 0.275042 -0.275042)
							(end 0.2032 -0.3048)
						)
						(arc
							(start -0.2032 -0.3048)
							(mid -0.275042 -0.275042)
							(end -0.3048 -0.2032)
						)
						(arc
							(start -0.3048 0.2032)
							(mid -0.275042 0.275042)
							(end -0.2032 0.3048)
						)
						(arc
							(start 0.2032 0.3048)
							(mid 0.275042 0.275042)
							(end 0.3048 0.2032)
						)
					)
					(width 0)
					(fill yes)
				)
			)
		)
		(pad "2" smd custom
			(at 0 0.4445 270)
			(size 0.1524 0.1524)
			(layers "F.Cu" "F.Mask" "F.Paste")
			(net "PCIE_TX_P95")
			(options
				(clearance outline)
				(anchor circle)
			)
			(primitives
				(gr_poly
					(pts
						(arc
							(start 0.3048 -0.2032)
							(mid 0.275042 -0.275042)
							(end 0.2032 -0.3048)
						)
						(arc
							(start -0.2032 -0.3048)
							(mid -0.275042 -0.275042)
							(end -0.3048 -0.2032)
						)
						(arc
							(start -0.3048 0.2032)
							(mid -0.275042 0.275042)
							(end -0.2032 0.3048)
						)
						(arc
							(start 0.2032 0.3048)
							(mid 0.275042 0.275042)
							(end 0.3048 0.2032)
						)
					)
					(width 0)
					(fill yes)
				)
			)
		)
	)
	(footprint ""
		(layer "F.Cu")
		(at 70.1802 -158.8516)
		(property "Reference" "PC95"
			(at 0 0 0)
			(layer "F.SilkS")
			(hide yes)
			(effects
				(font
					(size 1.27 1.27)
				)
			)
		)
		(property "Value" "SC22U6D3V5MX-5-GP"
			(at -0.0762 -6.1214 0)
			(unlocked yes)
			(layer "F.Fab")
			(hide yes)
			(effects
				(font
					(size 1.016 1.016)
					(thickness 0.1524)
				)
			)
		)
		(property "Device Type" "C805H56"
			(at -0.0762 -8.1534 0)
			(unlocked yes)
			(layer "F.Fab")
			(hide yes)
			(effects
				(font
					(size 1.016 1.016)
					(thickness 0.1524)
				)
			)
		)
		(duplicate_pad_numbers_are_jumpers no)
		(fp_line
			(start 0.635 0)
			(end -0.635 0)
			(stroke
				(width 0.508)
				(type default)
			)
			(layer "F.SilkS")
		)
		(fp_rect
			(start -0.9652 1.778)
			(end 0.9652 -1.778)
			(stroke
				(width 0)
				(type default)
			)
			(fill no)
			(layer "F.CrtYd")
		)
		(fp_poly
			(pts
				(xy -0.9652 -1.778) (xy 0.9652 -1.778) (xy 0.9652 1.778) (xy -0.9652 1.778)
			)
			(stroke
				(width 0)
				(type default)
			)
			(fill no)
			(layer "F.Fab")
		)
		(pad "1" smd rect
			(at 0 -0.9652)
			(size 1.397 1.143)
			(layers "F.Cu" "F.Mask" "F.Paste")
			(net "VR_P1V538_STBY_IN")
		)
		(pad "2" smd rect
			(at 0 0.9652)
			(size 1.397 1.143)
			(layers "F.Cu" "F.Mask" "F.Paste")
			(net "GND")
		)
	)
	(footprint ""
		(layer "F.Cu")
		(at 74.144124 -189.585092)
		(property "Reference" "U198"
			(at 0 0 0)
			(layer "F.SilkS")
			(hide yes)
			(effects
				(font
					(size 1.27 1.27)
				)
			)
		)
		(property "Value" "MAX7311AUG-GP"
			(at 0 -12.1412 0)
			(unlocked yes)
			(layer "F.Fab")
			(hide yes)
			(effects
				(font
					(size 1.016 1.016)
					(thickness 0.1524)
				)
			)
		)
		(property "Device Type" "TSOIC24H44"
			(at 0 -13.6652 0)
			(unlocked yes)
			(layer "F.Fab")
			(hide yes)
			(effects
				(font
					(size 1.016 1.016)
					(thickness 0.1524)
				)
			)
		)
		(duplicate_pad_numbers_are_jumpers no)
		(fp_line
			(start -4.1148 -1.778)
			(end -4.1148 1.778)
			(stroke
				(width 0.1524)
				(type default)
			)
			(layer "F.SilkS")
		)
		(fp_line
			(start -4.1148 -1.778)
			(end 3.683 -1.778)
			(stroke
				(width 0.1524)
				(type default)
			)
			(layer "F.SilkS")
		)
		(fp_line
			(start -4.0386 1.778)
			(end -4.0386 3.556)
			(stroke
				(width 0.3556)
				(type default)
			)
			(layer "F.SilkS")
		)
		(fp_line
			(start -3.8354 0)
			(end -4.1148 -0.2794)
			(stroke
				(width 0.1524)
				(type default)
			)
			(layer "F.SilkS")
		)
		(fp_line
			(start -3.8354 0)
			(end -4.1148 0.2794)
			(stroke
				(width 0.1524)
				(type default)
			)
			(layer "F.SilkS")
		)
		(fp_line
			(start 3.683 -1.778)
			(end 3.683 1.778)
			(stroke
				(width 0.1524)
				(type default)
			)
			(layer "F.SilkS")
		)
		(fp_line
			(start 3.683 1.778)
			(end -4.1148 1.778)
			(stroke
				(width 0.1524)
				(type default)
			)
			(layer "F.SilkS")
		)
		(fp_poly
			(pts
				(xy -3.7592 -1.778) (xy 3.683 -1.778) (xy 3.683 1.778) (xy -3.7592 1.778)
			)
			(stroke
				(width 0)
				(type default)
			)
			(fill yes)
			(layer "F.SilkS")
		)
		(fp_poly
			(pts
				(xy -4.22656 3.81) (xy 4.22656 3.81) (xy 4.22656 -3.81) (xy -4.22656 -3.81)
			)
			(stroke
				(width 0)
				(type default)
			)
			(fill no)
			(layer "F.CrtYd")
		)
		(fp_poly
			(pts
				(xy -4.22656 -3.81) (xy 4.22656 -3.81) (xy 4.22656 3.81) (xy -4.22656 3.81)
			)
			(stroke
				(width 0)
				(type default)
			)
			(fill no)
			(layer "F.Fab")
		)
		(pad "1" smd rect
			(at -3.57632 2.8194)
			(size 0.3556 1.524)
			(layers "F.Cu" "F.Mask" "F.Paste")
			(net "IOEXP_INT#_1")
		)
		(pad "2" smd rect
			(at -2.92608 2.8194)
			(size 0.3556 1.524)
			(layers "F.Cu" "F.Mask" "F.Paste")
			(net "IOEXP1_AD1")
		)
		(pad "3" smd rect
			(at -2.27584 2.8194)
			(size 0.3556 1.524)
			(layers "F.Cu" "F.Mask" "F.Paste")
			(net "IOEXP1_AD2")
		)
		(pad "4" smd rect
			(at -1.6256 2.8194)
			(size 0.3556 1.524)
			(layers "F.Cu" "F.Mask" "F.Paste")
			(net "SSD_PRSNT#0")
		)
		(pad "5" smd rect
			(at -0.97536 2.8194)
			(size 0.3556 1.524)
			(layers "F.Cu" "F.Mask" "F.Paste")
			(net "SSD_ATNLED#0")
		)
		(pad "6" smd rect
			(at -0.32512 2.8194)
			(size 0.3556 1.524)
			(layers "F.Cu" "F.Mask" "F.Paste")
			(net "SSD_PWREN0")
		)
		(pad "7" smd rect
			(at 0.32512 2.8194)
			(size 0.3556 1.524)
			(layers "F.Cu" "F.Mask" "F.Paste")
			(net "SSD_PERST#0")
		)
		(pad "8" smd rect
			(at 0.97536 2.8194)
			(size 0.3556 1.524)
			(layers "F.Cu" "F.Mask" "F.Paste")
			(net "SSD_PRSNT#5")
		)
		(pad "9" smd rect
			(at 1.6256 2.8194)
			(size 0.3556 1.524)
			(layers "F.Cu" "F.Mask" "F.Paste")
			(net "SSD_ATNLED#5")
		)
		(pad "10" smd rect
			(at 2.27584 2.8194)
			(size 0.3556 1.524)
			(layers "F.Cu" "F.Mask" "F.Paste")
			(net "SSD_PWREN5")
		)
		(pad "11" smd rect
			(at 2.92608 2.8194)
			(size 0.3556 1.524)
			(layers "F.Cu" "F.Mask" "F.Paste")
			(net "SSD_PERST#5")
		)
		(pad "12" smd rect
			(at 3.57632 2.8194)
			(size 0.3556 1.524)
			(layers "F.Cu" "F.Mask" "F.Paste")
			(net "GND")
		)
		(pad "13" smd rect
			(at 3.57632 -2.8194)
			(size 0.3556 1.524)
			(layers "F.Cu" "F.Mask" "F.Paste")
			(net "SSD_PRSNT#10")
		)
		(pad "14" smd rect
			(at 2.92608 -2.8194)
			(size 0.3556 1.524)
			(layers "F.Cu" "F.Mask" "F.Paste")
			(net "SSD_ATNLED#10")
		)
		(pad "15" smd rect
			(at 2.27584 -2.8194)
			(size 0.3556 1.524)
			(layers "F.Cu" "F.Mask" "F.Paste")
			(net "SSD_PWREN10")
		)
		(pad "16" smd rect
			(at 1.6256 -2.8194)
			(size 0.3556 1.524)
			(layers "F.Cu" "F.Mask" "F.Paste")
			(net "SSD_PERST#10")
		)
		(pad "17" smd rect
			(at 0.97536 -2.8194)
			(size 0.3556 1.524)
			(layers "F.Cu" "F.Mask" "F.Paste")
			(net "SSD_PRSNT#11")
		)
		(pad "18" smd rect
			(at 0.32512 -2.8194)
			(size 0.3556 1.524)
			(layers "F.Cu" "F.Mask" "F.Paste")
			(net "SSD_ATNLED#11")
		)
		(pad "19" smd rect
			(at -0.32512 -2.8194)
			(size 0.3556 1.524)
			(layers "F.Cu" "F.Mask" "F.Paste")
			(net "SSD_PWREN11")
		)
		(pad "20" smd rect
			(at -0.97536 -2.8194)
			(size 0.3556 1.524)
			(layers "F.Cu" "F.Mask" "F.Paste")
			(net "SSD_PERST#11")
		)
		(pad "21" smd rect
			(at -1.6256 -2.8194)
			(size 0.3556 1.524)
			(layers "F.Cu" "F.Mask" "F.Paste")
			(net "IOEXP1_AD0")
		)
		(pad "22" smd rect
			(at -2.27584 -2.8194)
			(size 0.3556 1.524)
			(layers "F.Cu" "F.Mask" "F.Paste")
			(net "I2C_GPIO_SCL_1")
		)
		(pad "23" smd rect
			(at -2.92608 -2.8194)
			(size 0.3556 1.524)
			(layers "F.Cu" "F.Mask" "F.Paste")
			(net "I2C_GPIO_SDA_1")
		)
		(pad "24" smd rect
			(at -3.57632 -2.8194)
			(size 0.3556 1.524)
			(layers "F.Cu" "F.Mask" "F.Paste")
			(net "P3V3_STBY")
		)
	)
	(footprint ""
		(layer "F.Cu")
		(at 15.0114 -119.4054 90)
		(property "Reference" "R239"
			(at 0 0 90)
			(layer "F.SilkS")
			(hide yes)
			(effects
				(font
					(size 1.27 1.27)
				)
			)
		)
		(property "Value" "0R2J-2-GP"
			(at 0.064008 -3.993896 90)
			(unlocked yes)
			(layer "F.Fab")
			(hide yes)
			(effects
				(font
					(size 1.016 1.016)
					(thickness 0.1524)
				)
			)
		)
		(property "Device Type" "R402H16"
			(at 0.064008 -5.517896 90)
			(unlocked yes)
			(layer "F.Fab")
			(hide yes)
			(effects
				(font
					(size 1.016 1.016)
					(thickness 0.1524)
				)
			)
		)
		(duplicate_pad_numbers_are_jumpers no)
		(fp_line
			(start 0.508 -0.9398)
			(end -0.508 -0.9398)
			(stroke
				(width 0.1524)
				(type default)
			)
			(layer "F.SilkS")
		)
		(fp_line
			(start -0.508 -0.9398)
			(end -0.508 0.9398)
			(stroke
				(width 0.1524)
				(type default)
			)
			(layer "F.SilkS")
		)
		(fp_rect
			(start -0.508 0.9398)
			(end 0.508 -0.9398)
			(stroke
				(width 0)
				(type default)
			)
			(fill no)
			(layer "F.CrtYd")
		)
		(fp_rect
			(start -0.508 0.9398)
			(end 0.508 -0.9398)
			(stroke
				(width 0)
				(type default)
			)
			(fill no)
			(layer "F.Fab")
		)
		(pad "1" smd custom
			(at 0 -0.4445 90)
			(size 0.1397 0.1397)
			(layers "F.Cu" "F.Mask" "F.Paste")
			(net "BMC_I2C1_MINI1_SDA_S")
			(options
				(clearance outline)
				(anchor circle)
			)
			(primitives
				(gr_poly
					(pts
						(arc
							(start -0.1778 -0.2794)
							(mid -0.249642 -0.249642)
							(end -0.2794 -0.1778)
						)
						(arc
							(start -0.2794 0.1778)
							(mid -0.249642 0.249642)
							(end -0.1778 0.2794)
						)
						(arc
							(start 0.1778 0.2794)
							(mid 0.249642 0.249642)
							(end 0.2794 0.1778)
						)
						(arc
							(start 0.2794 -0.1778)
							(mid 0.249642 -0.249642)
							(end 0.1778 -0.2794)
						)
					)
					(width 0)
					(fill yes)
				)
			)
		)
		(pad "2" smd custom
			(at 0 0.4445 90)
			(size 0.1397 0.1397)
			(layers "F.Cu" "F.Mask" "F.Paste")
			(net "BMC0_SMB1_DAT")
			(options
				(clearance outline)
				(anchor circle)
			)
			(primitives
				(gr_poly
					(pts
						(arc
							(start -0.1778 -0.2794)
							(mid -0.249642 -0.249642)
							(end -0.2794 -0.1778)
						)
						(arc
							(start -0.2794 0.1778)
							(mid -0.249642 0.249642)
							(end -0.1778 0.2794)
						)
						(arc
							(start 0.1778 0.2794)
							(mid 0.249642 0.249642)
							(end 0.2794 0.1778)
						)
						(arc
							(start 0.2794 -0.1778)
							(mid 0.249642 -0.249642)
							(end 0.1778 -0.2794)
						)
					)
					(width 0)
					(fill yes)
				)
			)
		)
	)
	(footprint ""
		(layer "F.Cu")
		(at 28.918154 -146.414744)
		(property "Reference" "C183"
			(at 0 0 0)
			(layer "F.SilkS")
			(hide yes)
			(effects
				(font
					(size 1.27 1.27)
				)
			)
		)
		(property "Value" "SCD1U16V2KX-3GP"
			(at 1.1811 -2.7051 0)
			(unlocked yes)
			(layer "F.Fab")
			(hide yes)
			(effects
				(font
					(size 1.016 1.016)
					(thickness 0.1524)
				)
			)
		)
		(property "Device Type" "C402H22"
			(at 1.1811 -4.2291 0)
			(unlocked yes)
			(layer "F.Fab")
			(hide yes)
			(effects
				(font
					(size 1.016 1.016)
					(thickness 0.1524)
				)
			)
		)
		(duplicate_pad_numbers_are_jumpers no)
		(fp_rect
			(start -0.4318 0.9525)
			(end 0.4318 -0.9525)
			(stroke
				(width 0)
				(type default)
			)
			(fill no)
			(layer "F.CrtYd")
		)
		(fp_rect
			(start -0.4318 0.9525)
			(end 0.4318 -0.9525)
			(stroke
				(width 0)
				(type default)
			)
			(fill no)
			(layer "F.Fab")
		)
		(pad "1" smd custom
			(at 0 -0.4445)
			(size 0.1524 0.1524)
			(layers "F.Cu" "F.Mask" "F.Paste")
			(net "P1V53_STBY")
			(options
				(clearance outline)
				(anchor circle)
			)
			(primitives
				(gr_poly
					(pts
						(arc
							(start 0.3048 -0.2032)
							(mid 0.275042 -0.275042)
							(end 0.2032 -0.3048)
						)
						(arc
							(start -0.2032 -0.3048)
							(mid -0.275042 -0.275042)
							(end -0.3048 -0.2032)
						)
						(arc
							(start -0.3048 0.2032)
							(mid -0.275042 0.275042)
							(end -0.2032 0.3048)
						)
						(arc
							(start 0.2032 0.3048)
							(mid 0.275042 0.275042)
							(end 0.3048 0.2032)
						)
					)
					(width 0)
					(fill yes)
				)
			)
		)
		(pad "2" smd custom
			(at 0 0.4445)
			(size 0.1524 0.1524)
			(layers "F.Cu" "F.Mask" "F.Paste")
			(net "GND")
			(options
				(clearance outline)
				(anchor circle)
			)
			(primitives
				(gr_poly
					(pts
						(arc
							(start 0.3048 -0.2032)
							(mid 0.275042 -0.275042)
							(end 0.2032 -0.3048)
						)
						(arc
							(start -0.2032 -0.3048)
							(mid -0.275042 -0.275042)
							(end -0.3048 -0.2032)
						)
						(arc
							(start -0.3048 0.2032)
							(mid -0.275042 0.275042)
							(end -0.2032 0.3048)
						)
						(arc
							(start 0.2032 0.3048)
							(mid 0.275042 0.275042)
							(end 0.3048 0.2032)
						)
					)
					(width 0)
					(fill yes)
				)
			)
		)
	)
	(footprint ""
		(layer "F.Cu")
		(at 273.517106 -3.57378 -90)
		(property "Reference" "R217"
			(at 0 0 270)
			(layer "F.SilkS")
			(hide yes)
			(effects
				(font
					(size 1.27 1.27)
				)
			)
		)
		(property "Value" "4K7R2F-GP"
			(at 0.064008 -3.993896 270)
			(unlocked yes)
			(layer "F.Fab")
			(hide yes)
			(effects
				(font
					(size 1.016 1.016)
					(thickness 0.1524)
				)
			)
		)
		(property "Device Type" "R402H16"
			(at 0.064008 -5.517896 270)
			(unlocked yes)
			(layer "F.Fab")
			(hide yes)
			(effects
				(font
					(size 1.016 1.016)
					(thickness 0.1524)
				)
			)
		)
		(duplicate_pad_numbers_are_jumpers no)
		(fp_line
			(start -0.508 -0.9398)
			(end -0.508 0.9398)
			(stroke
				(width 0.1524)
				(type default)
			)
			(layer "F.SilkS")
		)
		(fp_line
			(start 0.508 -0.9398)
			(end -0.508 -0.9398)
			(stroke
				(width 0.1524)
				(type default)
			)
			(layer "F.SilkS")
		)
		(fp_rect
			(start -0.508 0.9398)
			(end 0.508 -0.9398)
			(stroke
				(width 0)
				(type default)
			)
			(fill no)
			(layer "F.CrtYd")
		)
		(fp_rect
			(start -0.508 0.9398)
			(end 0.508 -0.9398)
			(stroke
				(width 0)
				(type default)
			)
			(fill no)
			(layer "F.Fab")
		)
		(pad "1" smd custom
			(at 0 -0.4445 270)
			(size 0.1397 0.1397)
			(layers "F.Cu" "F.Mask" "F.Paste")
			(net "CLK_P_6_R")
			(options
				(clearance outline)
				(anchor circle)
			)
			(primitives
				(gr_poly
					(pts
						(arc
							(start -0.1778 -0.2794)
							(mid -0.249642 -0.249642)
							(end -0.2794 -0.1778)
						)
						(arc
							(start -0.2794 0.1778)
							(mid -0.249642 0.249642)
							(end -0.1778 0.2794)
						)
						(arc
							(start 0.1778 0.2794)
							(mid 0.249642 0.249642)
							(end 0.2794 0.1778)
						)
						(arc
							(start 0.2794 -0.1778)
							(mid 0.249642 -0.249642)
							(end 0.1778 -0.2794)
						)
					)
					(width 0)
					(fill yes)
				)
			)
		)
		(pad "2" smd custom
			(at 0 0.4445 270)
			(size 0.1397 0.1397)
			(layers "F.Cu" "F.Mask" "F.Paste")
			(net "GND")
			(options
				(clearance outline)
				(anchor circle)
			)
			(primitives
				(gr_poly
					(pts
						(arc
							(start -0.1778 -0.2794)
							(mid -0.249642 -0.249642)
							(end -0.2794 -0.1778)
						)
						(arc
							(start -0.2794 0.1778)
							(mid -0.249642 0.249642)
							(end -0.1778 0.2794)
						)
						(arc
							(start 0.1778 0.2794)
							(mid 0.249642 0.249642)
							(end 0.2794 0.1778)
						)
						(arc
							(start 0.2794 -0.1778)
							(mid 0.249642 -0.249642)
							(end 0.1778 -0.2794)
						)
					)
					(width 0)
					(fill yes)
				)
			)
		)
	)
	(footprint ""
		(layer "F.Cu")
		(at 29.911294 -94.184724 180)
		(property "Reference" "R2944"
			(at 0 0 180)
			(layer "F.SilkS")
			(hide yes)
			(effects
				(font
					(size 1.27 1.27)
				)
			)
		)
		(property "Value" "4K75R2F-1-GP"
			(at 0.064008 -3.993896 180)
			(unlocked yes)
			(layer "F.Fab")
			(hide yes)
			(effects
				(font
					(size 1.016 1.016)
					(thickness 0.1524)
				)
			)
		)
		(property "Device Type" "R402H16"
			(at 0.064008 -5.517896 180)
			(unlocked yes)
			(layer "F.Fab")
			(hide yes)
			(effects
				(font
					(size 1.016 1.016)
					(thickness 0.1524)
				)
			)
		)
		(duplicate_pad_numbers_are_jumpers no)
		(fp_line
			(start 0.508 -0.9398)
			(end -0.508 -0.9398)
			(stroke
				(width 0.1524)
				(type default)
			)
			(layer "F.SilkS")
		)
		(fp_line
			(start -0.508 -0.9398)
			(end -0.508 0.9398)
			(stroke
				(width 0.1524)
				(type default)
			)
			(layer "F.SilkS")
		)
		(fp_rect
			(start -0.508 0.9398)
			(end 0.508 -0.9398)
			(stroke
				(width 0)
				(type default)
			)
			(fill no)
			(layer "F.CrtYd")
		)
		(fp_rect
			(start -0.508 0.9398)
			(end 0.508 -0.9398)
			(stroke
				(width 0)
				(type default)
			)
			(fill no)
			(layer "F.Fab")
		)
		(pad "1" smd custom
			(at 0 -0.4445 180)
			(size 0.1397 0.1397)
			(layers "F.Cu" "F.Mask" "F.Paste")
			(net "P3V3_STBY")
			(options
				(clearance outline)
				(anchor circle)
			)
			(primitives
				(gr_poly
					(pts
						(arc
							(start -0.1778 -0.2794)
							(mid -0.249642 -0.249642)
							(end -0.2794 -0.1778)
						)
						(arc
							(start -0.2794 0.1778)
							(mid -0.249642 0.249642)
							(end -0.1778 0.2794)
						)
						(arc
							(start 0.1778 0.2794)
							(mid 0.249642 0.249642)
							(end 0.2794 0.1778)
						)
						(arc
							(start 0.2794 -0.1778)
							(mid 0.249642 -0.249642)
							(end 0.1778 -0.2794)
						)
					)
					(width 0)
					(fill yes)
				)
			)
		)
		(pad "2" smd custom
			(at 0 0.4445 180)
			(size 0.1397 0.1397)
			(layers "F.Cu" "F.Mask" "F.Paste")
			(net "RST_BMC_EXTRST_N")
			(options
				(clearance outline)
				(anchor circle)
			)
			(primitives
				(gr_poly
					(pts
						(arc
							(start -0.1778 -0.2794)
							(mid -0.249642 -0.249642)
							(end -0.2794 -0.1778)
						)
						(arc
							(start -0.2794 0.1778)
							(mid -0.249642 0.249642)
							(end -0.1778 0.2794)
						)
						(arc
							(start 0.1778 0.2794)
							(mid 0.249642 0.249642)
							(end 0.2794 0.1778)
						)
						(arc
							(start 0.2794 -0.1778)
							(mid 0.249642 -0.249642)
							(end 0.1778 -0.2794)
						)
					)
					(width 0)
					(fill yes)
				)
			)
		)
	)
	(footprint ""
		(layer "F.Cu")
		(at 30.48 -196.85 -90)
		(property "Reference" "R2115"
			(at 0 0 270)
			(layer "F.SilkS")
			(hide yes)
			(effects
				(font
					(size 1.27 1.27)
				)
			)
		)
		(property "Value" "0R2J-2-GP"
			(at 0.064008 -3.993896 270)
			(unlocked yes)
			(layer "F.Fab")
			(hide yes)
			(effects
				(font
					(size 1.016 1.016)
					(thickness 0.1524)
				)
			)
		)
		(property "Device Type" "R402H16"
			(at 0.064008 -5.517896 270)
			(unlocked yes)
			(layer "F.Fab")
			(hide yes)
			(effects
				(font
					(size 1.016 1.016)
					(thickness 0.1524)
				)
			)
		)
		(duplicate_pad_numbers_are_jumpers no)
		(fp_line
			(start -0.508 -0.9398)
			(end -0.508 0.9398)
			(stroke
				(width 0.1524)
				(type default)
			)
			(layer "F.SilkS")
		)
		(fp_line
			(start 0.508 -0.9398)
			(end -0.508 -0.9398)
			(stroke
				(width 0.1524)
				(type default)
			)
			(layer "F.SilkS")
		)
		(fp_rect
			(start -0.508 0.9398)
			(end 0.508 -0.9398)
			(stroke
				(width 0)
				(type default)
			)
			(fill no)
			(layer "F.CrtYd")
		)
		(fp_rect
			(start -0.508 0.9398)
			(end 0.508 -0.9398)
			(stroke
				(width 0)
				(type default)
			)
			(fill no)
			(layer "F.Fab")
		)
		(pad "1" smd custom
			(at 0 -0.4445 270)
			(size 0.1397 0.1397)
			(layers "F.Cu" "F.Mask" "F.Paste")
			(net "MB0_P12V_R")
			(options
				(clearance outline)
				(anchor circle)
			)
			(primitives
				(gr_poly
					(pts
						(arc
							(start -0.1778 -0.2794)
							(mid -0.249642 -0.249642)
							(end -0.2794 -0.1778)
						)
						(arc
							(start -0.2794 0.1778)
							(mid -0.249642 0.249642)
							(end -0.1778 0.2794)
						)
						(arc
							(start 0.1778 0.2794)
							(mid 0.249642 0.249642)
							(end 0.2794 0.1778)
						)
						(arc
							(start 0.2794 -0.1778)
							(mid 0.249642 -0.249642)
							(end 0.1778 -0.2794)
						)
					)
					(width 0)
					(fill yes)
				)
			)
		)
		(pad "2" smd custom
			(at 0 0.4445 270)
			(size 0.1397 0.1397)
			(layers "F.Cu" "F.Mask" "F.Paste")
			(net "P12V")
			(options
				(clearance outline)
				(anchor circle)
			)
			(primitives
				(gr_poly
					(pts
						(arc
							(start -0.1778 -0.2794)
							(mid -0.249642 -0.249642)
							(end -0.2794 -0.1778)
						)
						(arc
							(start -0.2794 0.1778)
							(mid -0.249642 0.249642)
							(end -0.1778 0.2794)
						)
						(arc
							(start 0.1778 0.2794)
							(mid 0.249642 0.249642)
							(end 0.2794 0.1778)
						)
						(arc
							(start 0.2794 -0.1778)
							(mid 0.249642 -0.249642)
							(end 0.1778 -0.2794)
						)
					)
					(width 0)
					(fill yes)
				)
			)
		)
	)
	(footprint ""
		(layer "F.Cu")
		(at 310.007 -63.2206)
		(property "Reference" "PG50"
			(at 0 0 0)
			(layer "F.SilkS")
			(hide yes)
			(effects
				(font
					(size 1.27 1.27)
				)
			)
		)
		(property "Value" "GAP-CLOSE-PWR-3-GP"
			(at 0.0254 -6.5786 0)
			(unlocked yes)
			(layer "F.Fab")
			(hide yes)
			(effects
				(font
					(size 1.016 1.016)
					(thickness 0.1524)
				)
			)
		)
		(property "Device Type" "GAP-CLOSE-PWR-3"
			(at 0.0254 -8.255 0)
			(unlocked yes)
			(layer "F.Fab")
			(hide yes)
			(effects
				(font
					(size 1.016 1.016)
					(thickness 0.1524)
				)
			)
		)
		(duplicate_pad_numbers_are_jumpers no)
		(fp_rect
			(start -0.7112 0.4572)
			(end 0.7112 -0.4572)
			(stroke
				(width 0)
				(type default)
			)
			(fill no)
			(layer "F.CrtYd")
		)
		(fp_poly
			(pts
				(xy -0.7112 -0.4572) (xy 0.7112 -0.4572) (xy 0.7112 0.4572) (xy -0.7112 0.4572)
			)
			(stroke
				(width 0)
				(type default)
			)
			(fill no)
			(layer "F.Fab")
		)
		(pad "1" smd rect
			(at -0.3048 0)
			(size 0.6604 0.762)
			(layers "F.Cu" "F.Mask" "F.Paste")
			(net "DUT_VDD")
		)
		(pad "2" smd rect
			(at 0.3048 0)
			(size 0.6604 0.762)
			(layers "F.Cu" "F.Mask" "F.Paste")
			(net "P0V9_E")
		)
	)
	(footprint ""
		(layer "F.Cu")
		(at 12.1158 -175.3362 90)
		(property "Reference" "Q96"
			(at 0 0 90)
			(layer "F.SilkS")
			(hide yes)
			(effects
				(font
					(size 1.27 1.27)
				)
			)
		)
		(property "Value" "2N7002K-1-GP"
			(at 0.127 -8.9662 90)
			(unlocked yes)
			(layer "F.Fab")
			(hide yes)
			(effects
				(font
					(size 1.016 1.016)
					(thickness 0.1524)
				)
			)
		)
		(property "Device Type" "SOT23DGS2D4H44"
			(at 0.127 -10.4902 90)
			(unlocked yes)
			(layer "F.Fab")
			(hide yes)
			(effects
				(font
					(size 1.016 1.016)
					(thickness 0.1524)
				)
			)
		)
		(duplicate_pad_numbers_are_jumpers no)
		(fp_line
			(start 1.651 -1.778)
			(end -1.651 -1.778)
			(stroke
				(width 0.1524)
				(type default)
			)
			(layer "F.SilkS")
		)
		(fp_line
			(start -1.651 -1.778)
			(end -1.651 1.778)
			(stroke
				(width 0.1524)
				(type default)
			)
			(layer "F.SilkS")
		)
		(fp_line
			(start 1.651 1.778)
			(end 1.651 -1.778)
			(stroke
				(width 0.1524)
				(type default)
			)
			(layer "F.SilkS")
		)
		(fp_line
			(start -1.651 1.778)
			(end 1.651 1.778)
			(stroke
				(width 0.1524)
				(type default)
			)
			(layer "F.SilkS")
		)
		(fp_poly
			(pts
				(xy -1.778 1.8796) (xy -1.778 -1.8796) (xy 1.778 -1.8796) (xy 1.778 1.8796)
			)
			(stroke
				(width 0)
				(type default)
			)
			(fill no)
			(layer "F.CrtYd")
		)
		(fp_poly
			(pts
				(xy -1.778 1.8796) (xy -1.778 -1.8796) (xy 1.778 -1.8796) (xy 1.778 1.8796)
			)
			(stroke
				(width 0)
				(type default)
			)
			(fill no)
			(layer "F.Fab")
		)
		(pad "D" smd custom
			(at 0 -0.9525 90)
			(size 0.1905 0.1905)
			(layers "F.Cu" "F.Mask" "F.Paste")
			(net "Q95_G")
			(options
				(clearance outline)
				(anchor circle)
			)
			(primitives
				(gr_poly
					(pts
						(arc
							(start -0.1778 0.5715)
							(mid -0.321484 0.511984)
							(end -0.381 0.3683)
						)
						(arc
							(start -0.381 -0.3683)
							(mid -0.321484 -0.511984)
							(end -0.1778 -0.5715)
						)
						(arc
							(start 0.1778 -0.5715)
							(mid 0.321484 -0.511984)
							(end 0.381 -0.3683)
						)
						(arc
							(start 0.381 0.3683)
							(mid 0.321484 0.511984)
							(end 0.1778 0.5715)
						)
					)
					(width 0)
					(fill yes)
				)
			)
		)
		(pad "G" smd custom
			(at -0.98425 0.9525 90)
			(size 0.1905 0.1905)
			(layers "F.Cu" "F.Mask" "F.Paste")
			(net "TRAY_MBP_CTRL_EN_N")
			(options
				(clearance outline)
				(anchor circle)
			)
			(primitives
				(gr_poly
					(pts
						(arc
							(start -0.1778 0.5715)
							(mid -0.321484 0.511984)
							(end -0.381 0.3683)
						)
						(arc
							(start -0.381 -0.3683)
							(mid -0.321484 -0.511984)
							(end -0.1778 -0.5715)
						)
						(arc
							(start 0.1778 -0.5715)
							(mid 0.321484 -0.511984)
							(end 0.381 -0.3683)
						)
						(arc
							(start 0.381 0.3683)
							(mid 0.321484 0.511984)
							(end 0.1778 0.5715)
						)
					)
					(width 0)
					(fill yes)
				)
			)
		)
		(pad "S" smd custom
			(at 0.98425 0.9525 90)
			(size 0.1905 0.1905)
			(layers "F.Cu" "F.Mask" "F.Paste")
			(net "GND")
			(options
				(clearance outline)
				(anchor circle)
			)
			(primitives
				(gr_poly
					(pts
						(arc
							(start -0.1778 0.5715)
							(mid -0.321484 0.511984)
							(end -0.381 0.3683)
						)
						(arc
							(start -0.381 -0.3683)
							(mid -0.321484 -0.511984)
							(end -0.1778 -0.5715)
						)
						(arc
							(start 0.1778 -0.5715)
							(mid 0.321484 -0.511984)
							(end 0.381 -0.3683)
						)
						(arc
							(start 0.381 0.3683)
							(mid 0.321484 0.511984)
							(end 0.1778 0.5715)
						)
					)
					(width 0)
					(fill yes)
				)
			)
		)
	)
	(footprint ""
		(layer "F.Cu")
		(at 47.244 -196.596 180)
		(property "Reference" "R887"
			(at 0 0 180)
			(layer "F.SilkS")
			(hide yes)
			(effects
				(font
					(size 1.27 1.27)
				)
			)
		)
		(property "Value" "10KR2F-2-GP"
			(at 0.064008 -3.993896 180)
			(unlocked yes)
			(layer "F.Fab")
			(hide yes)
			(effects
				(font
					(size 1.016 1.016)
					(thickness 0.1524)
				)
			)
		)
		(property "Device Type" "R402H16"
			(at 0.064008 -5.517896 180)
			(unlocked yes)
			(layer "F.Fab")
			(hide yes)
			(effects
				(font
					(size 1.016 1.016)
					(thickness 0.1524)
				)
			)
		)
		(duplicate_pad_numbers_are_jumpers no)
		(fp_line
			(start 0.508 -0.9398)
			(end -0.508 -0.9398)
			(stroke
				(width 0.1524)
				(type default)
			)
			(layer "F.SilkS")
		)
		(fp_line
			(start -0.508 -0.9398)
			(end -0.508 0.9398)
			(stroke
				(width 0.1524)
				(type default)
			)
			(layer "F.SilkS")
		)
		(fp_rect
			(start -0.508 0.9398)
			(end 0.508 -0.9398)
			(stroke
				(width 0)
				(type default)
			)
			(fill no)
			(layer "F.CrtYd")
		)
		(fp_rect
			(start -0.508 0.9398)
			(end 0.508 -0.9398)
			(stroke
				(width 0)
				(type default)
			)
			(fill no)
			(layer "F.Fab")
		)
		(pad "1" smd custom
			(at 0 -0.4445 180)
			(size 0.1397 0.1397)
			(layers "F.Cu" "F.Mask" "F.Paste")
			(net "I2C7_BUF_READY")
			(options
				(clearance outline)
				(anchor circle)
			)
			(primitives
				(gr_poly
					(pts
						(arc
							(start -0.1778 -0.2794)
							(mid -0.249642 -0.249642)
							(end -0.2794 -0.1778)
						)
						(arc
							(start -0.2794 0.1778)
							(mid -0.249642 0.249642)
							(end -0.1778 0.2794)
						)
						(arc
							(start 0.1778 0.2794)
							(mid 0.249642 0.249642)
							(end 0.2794 0.1778)
						)
						(arc
							(start 0.2794 -0.1778)
							(mid 0.249642 -0.249642)
							(end 0.1778 -0.2794)
						)
					)
					(width 0)
					(fill yes)
				)
			)
		)
		(pad "2" smd custom
			(at 0 0.4445 180)
			(size 0.1397 0.1397)
			(layers "F.Cu" "F.Mask" "F.Paste")
			(net "P3V3_STBY")
			(options
				(clearance outline)
				(anchor circle)
			)
			(primitives
				(gr_poly
					(pts
						(arc
							(start -0.1778 -0.2794)
							(mid -0.249642 -0.249642)
							(end -0.2794 -0.1778)
						)
						(arc
							(start -0.2794 0.1778)
							(mid -0.249642 0.249642)
							(end -0.1778 0.2794)
						)
						(arc
							(start 0.1778 0.2794)
							(mid 0.249642 0.249642)
							(end 0.2794 0.1778)
						)
						(arc
							(start 0.2794 -0.1778)
							(mid 0.249642 -0.249642)
							(end 0.1778 -0.2794)
						)
					)
					(width 0)
					(fill yes)
				)
			)
		)
	)
	(footprint ""
		(layer "F.Cu")
		(at 62.2046 -109.8804)
		(property "Reference" "R313"
			(at 0 0 0)
			(layer "F.SilkS")
			(hide yes)
			(effects
				(font
					(size 1.27 1.27)
				)
			)
		)
		(property "Value" "4K7R2F-GP"
			(at 0.064008 -3.993896 0)
			(unlocked yes)
			(layer "F.Fab")
			(hide yes)
			(effects
				(font
					(size 1.016 1.016)
					(thickness 0.1524)
				)
			)
		)
		(property "Device Type" "R402H16"
			(at 0.064008 -5.517896 0)
			(unlocked yes)
			(layer "F.Fab")
			(hide yes)
			(effects
				(font
					(size 1.016 1.016)
					(thickness 0.1524)
				)
			)
		)
		(duplicate_pad_numbers_are_jumpers no)
		(fp_line
			(start -0.508 -0.9398)
			(end -0.508 0.9398)
			(stroke
				(width 0.1524)
				(type default)
			)
			(layer "F.SilkS")
		)
		(fp_line
			(start 0.508 -0.9398)
			(end -0.508 -0.9398)
			(stroke
				(width 0.1524)
				(type default)
			)
			(layer "F.SilkS")
		)
		(fp_rect
			(start -0.508 0.9398)
			(end 0.508 -0.9398)
			(stroke
				(width 0)
				(type default)
			)
			(fill no)
			(layer "F.CrtYd")
		)
		(fp_rect
			(start -0.508 0.9398)
			(end 0.508 -0.9398)
			(stroke
				(width 0)
				(type default)
			)
			(fill no)
			(layer "F.Fab")
		)
		(pad "1" smd custom
			(at 0 -0.4445)
			(size 0.1397 0.1397)
			(layers "F.Cu" "F.Mask" "F.Paste")
			(net "P3V3_STBY")
			(options
				(clearance outline)
				(anchor circle)
			)
			(primitives
				(gr_poly
					(pts
						(arc
							(start -0.1778 -0.2794)
							(mid -0.249642 -0.249642)
							(end -0.2794 -0.1778)
						)
						(arc
							(start -0.2794 0.1778)
							(mid -0.249642 0.249642)
							(end -0.1778 0.2794)
						)
						(arc
							(start 0.1778 0.2794)
							(mid 0.249642 0.249642)
							(end 0.2794 0.1778)
						)
						(arc
							(start 0.2794 -0.1778)
							(mid 0.249642 -0.249642)
							(end 0.1778 -0.2794)
						)
					)
					(width 0)
					(fill yes)
				)
			)
		)
		(pad "2" smd custom
			(at 0 0.4445)
			(size 0.1397 0.1397)
			(layers "F.Cu" "F.Mask" "F.Paste")
			(net "I2C5_LS_G1")
			(options
				(clearance outline)
				(anchor circle)
			)
			(primitives
				(gr_poly
					(pts
						(arc
							(start -0.1778 -0.2794)
							(mid -0.249642 -0.249642)
							(end -0.2794 -0.1778)
						)
						(arc
							(start -0.2794 0.1778)
							(mid -0.249642 0.249642)
							(end -0.1778 0.2794)
						)
						(arc
							(start 0.1778 0.2794)
							(mid 0.249642 0.249642)
							(end 0.2794 0.1778)
						)
						(arc
							(start 0.2794 -0.1778)
							(mid 0.249642 -0.249642)
							(end 0.1778 -0.2794)
						)
					)
					(width 0)
					(fill yes)
				)
			)
		)
	)
	(footprint ""
		(layer "F.Cu")
		(at 225.1964 -187.9092 90)
		(property "Reference" "C4124"
			(at 0 0 90)
			(layer "F.SilkS")
			(hide yes)
			(effects
				(font
					(size 1.27 1.27)
				)
			)
		)
		(property "Value" "SCD1U25V3KX-GP"
			(at 0 -2.8194 90)
			(unlocked yes)
			(layer "F.Fab")
			(hide yes)
			(effects
				(font
					(size 1.016 1.016)
					(thickness 0.1524)
				)
			)
		)
		(property "Device Type" "C603H36"
			(at 0 -4.3434 90)
			(unlocked yes)
			(layer "F.Fab")
			(hide yes)
			(effects
				(font
					(size 1.016 1.016)
					(thickness 0.1524)
				)
			)
		)
		(duplicate_pad_numbers_are_jumpers no)
		(fp_line
			(start 0.508 0)
			(end -0.508 0)
			(stroke
				(width 0.2032)
				(type default)
			)
			(layer "F.SilkS")
		)
		(fp_rect
			(start -0.5842 1.3335)
			(end 0.5842 -1.3335)
			(stroke
				(width 0)
				(type default)
			)
			(fill no)
			(layer "F.CrtYd")
		)
		(fp_rect
			(start -0.5842 1.3335)
			(end 0.5842 -1.3335)
			(stroke
				(width 0)
				(type default)
			)
			(fill no)
			(layer "F.Fab")
		)
		(pad "1" smd custom
			(at 0 -0.762 90)
			(size 0.2159 0.2159)
			(layers "F.Cu" "F.Mask" "F.Paste")
			(net "GND")
			(options
				(clearance outline)
				(anchor circle)
			)
			(primitives
				(gr_poly
					(pts
						(arc
							(start -0.3302 -0.4318)
							(mid -0.402042 -0.402042)
							(end -0.4318 -0.3302)
						)
						(arc
							(start -0.4318 0.3302)
							(mid -0.402042 0.402042)
							(end -0.3302 0.4318)
						)
						(arc
							(start 0.3302 0.4318)
							(mid 0.402042 0.402042)
							(end 0.4318 0.3302)
						)
						(arc
							(start 0.4318 -0.3302)
							(mid 0.402042 -0.402042)
							(end 0.3302 -0.4318)
						)
					)
					(width 0)
					(fill yes)
				)
			)
		)
		(pad "2" smd custom
			(at 0 0.762 90)
			(size 0.2159 0.2159)
			(layers "F.Cu" "F.Mask" "F.Paste")
			(net "SSD_PWREN8_R")
			(options
				(clearance outline)
				(anchor circle)
			)
			(primitives
				(gr_poly
					(pts
						(arc
							(start -0.3302 -0.4318)
							(mid -0.402042 -0.402042)
							(end -0.4318 -0.3302)
						)
						(arc
							(start -0.4318 0.3302)
							(mid -0.402042 0.402042)
							(end -0.3302 0.4318)
						)
						(arc
							(start 0.3302 0.4318)
							(mid 0.402042 0.402042)
							(end 0.4318 0.3302)
						)
						(arc
							(start 0.4318 -0.3302)
							(mid 0.402042 -0.402042)
							(end 0.3302 -0.4318)
						)
					)
					(width 0)
					(fill yes)
				)
			)
		)
	)
	(footprint ""
		(layer "F.Cu")
		(at 25.9842 -83.4644 90)
		(property "Reference" "R382"
			(at 0 0 90)
			(layer "F.SilkS")
			(hide yes)
			(effects
				(font
					(size 1.27 1.27)
				)
			)
		)
		(property "Value" "0R2J-2-GP"
			(at 0.064008 -3.993896 90)
			(unlocked yes)
			(layer "F.Fab")
			(hide yes)
			(effects
				(font
					(size 1.016 1.016)
					(thickness 0.1524)
				)
			)
		)
		(property "Device Type" "R402H16"
			(at 0.064008 -5.517896 90)
			(unlocked yes)
			(layer "F.Fab")
			(hide yes)
			(effects
				(font
					(size 1.016 1.016)
					(thickness 0.1524)
				)
			)
		)
		(duplicate_pad_numbers_are_jumpers no)
		(fp_line
			(start 0.508 -0.9398)
			(end -0.508 -0.9398)
			(stroke
				(width 0.1524)
				(type default)
			)
			(layer "F.SilkS")
		)
		(fp_line
			(start -0.508 -0.9398)
			(end -0.508 0.9398)
			(stroke
				(width 0.1524)
				(type default)
			)
			(layer "F.SilkS")
		)
		(fp_rect
			(start -0.508 0.9398)
			(end 0.508 -0.9398)
			(stroke
				(width 0)
				(type default)
			)
			(fill no)
			(layer "F.CrtYd")
		)
		(fp_rect
			(start -0.508 0.9398)
			(end 0.508 -0.9398)
			(stroke
				(width 0)
				(type default)
			)
			(fill no)
			(layer "F.Fab")
		)
		(pad "1" smd custom
			(at 0 -0.4445 90)
			(size 0.1397 0.1397)
			(layers "F.Cu" "F.Mask" "F.Paste")
			(net "NVM_CS_N")
			(options
				(clearance outline)
				(anchor circle)
			)
			(primitives
				(gr_poly
					(pts
						(arc
							(start -0.1778 -0.2794)
							(mid -0.249642 -0.249642)
							(end -0.2794 -0.1778)
						)
						(arc
							(start -0.2794 0.1778)
							(mid -0.249642 0.249642)
							(end -0.1778 0.2794)
						)
						(arc
							(start 0.1778 0.2794)
							(mid 0.249642 0.249642)
							(end 0.2794 0.1778)
						)
						(arc
							(start 0.2794 -0.1778)
							(mid 0.249642 -0.249642)
							(end 0.1778 -0.2794)
						)
					)
					(width 0)
					(fill yes)
				)
			)
		)
		(pad "2" smd custom
			(at 0 0.4445 90)
			(size 0.1397 0.1397)
			(layers "F.Cu" "F.Mask" "F.Paste")
			(net "I210_CS_N_R")
			(options
				(clearance outline)
				(anchor circle)
			)
			(primitives
				(gr_poly
					(pts
						(arc
							(start -0.1778 -0.2794)
							(mid -0.249642 -0.249642)
							(end -0.2794 -0.1778)
						)
						(arc
							(start -0.2794 0.1778)
							(mid -0.249642 0.249642)
							(end -0.1778 0.2794)
						)
						(arc
							(start 0.1778 0.2794)
							(mid 0.249642 0.249642)
							(end 0.2794 0.1778)
						)
						(arc
							(start 0.2794 -0.1778)
							(mid 0.249642 -0.249642)
							(end 0.1778 -0.2794)
						)
					)
					(width 0)
					(fill yes)
				)
			)
		)
	)
	(footprint ""
		(layer "F.Cu")
		(at 328.803 -86.487)
		(property "Reference" "R4172"
			(at 0 0 0)
			(layer "F.SilkS")
			(hide yes)
			(effects
				(font
					(size 1.27 1.27)
				)
			)
		)
		(property "Value" "4K7R2F-GP"
			(at 0.064008 -3.993896 0)
			(unlocked yes)
			(layer "F.Fab")
			(hide yes)
			(effects
				(font
					(size 1.016 1.016)
					(thickness 0.1524)
				)
			)
		)
		(property "Device Type" "R402H16"
			(at 0.064008 -5.517896 0)
			(unlocked yes)
			(layer "F.Fab")
			(hide yes)
			(effects
				(font
					(size 1.016 1.016)
					(thickness 0.1524)
				)
			)
		)
		(duplicate_pad_numbers_are_jumpers no)
		(fp_line
			(start -0.508 -0.9398)
			(end -0.508 0.9398)
			(stroke
				(width 0.1524)
				(type default)
			)
			(layer "F.SilkS")
		)
		(fp_line
			(start 0.508 -0.9398)
			(end -0.508 -0.9398)
			(stroke
				(width 0.1524)
				(type default)
			)
			(layer "F.SilkS")
		)
		(fp_rect
			(start -0.508 0.9398)
			(end 0.508 -0.9398)
			(stroke
				(width 0)
				(type default)
			)
			(fill no)
			(layer "F.CrtYd")
		)
		(fp_rect
			(start -0.508 0.9398)
			(end 0.508 -0.9398)
			(stroke
				(width 0)
				(type default)
			)
			(fill no)
			(layer "F.Fab")
		)
		(pad "1" smd custom
			(at 0 -0.4445)
			(size 0.1397 0.1397)
			(layers "F.Cu" "F.Mask" "F.Paste")
			(net "UPLINK6")
			(options
				(clearance outline)
				(anchor circle)
			)
			(primitives
				(gr_poly
					(pts
						(arc
							(start -0.1778 -0.2794)
							(mid -0.249642 -0.249642)
							(end -0.2794 -0.1778)
						)
						(arc
							(start -0.2794 0.1778)
							(mid -0.249642 0.249642)
							(end -0.1778 0.2794)
						)
						(arc
							(start 0.1778 0.2794)
							(mid 0.249642 0.249642)
							(end 0.2794 0.1778)
						)
						(arc
							(start 0.2794 -0.1778)
							(mid 0.249642 -0.249642)
							(end 0.1778 -0.2794)
						)
					)
					(width 0)
					(fill yes)
				)
			)
		)
		(pad "2" smd custom
			(at 0 0.4445)
			(size 0.1397 0.1397)
			(layers "F.Cu" "F.Mask" "F.Paste")
			(net "P3V3_STBY")
			(options
				(clearance outline)
				(anchor circle)
			)
			(primitives
				(gr_poly
					(pts
						(arc
							(start -0.1778 -0.2794)
							(mid -0.249642 -0.249642)
							(end -0.2794 -0.1778)
						)
						(arc
							(start -0.2794 0.1778)
							(mid -0.249642 0.249642)
							(end -0.1778 0.2794)
						)
						(arc
							(start 0.1778 0.2794)
							(mid 0.249642 0.249642)
							(end 0.2794 0.1778)
						)
						(arc
							(start 0.2794 -0.1778)
							(mid 0.249642 -0.249642)
							(end 0.1778 -0.2794)
						)
					)
					(width 0)
					(fill yes)
				)
			)
		)
	)
	(footprint ""
		(layer "F.Cu")
		(at 87.9602 -80.899 -90)
		(property "Reference" "SR950"
			(at 0 0 270)
			(layer "F.SilkS")
			(hide yes)
			(effects
				(font
					(size 1.27 1.27)
				)
			)
		)
		(property "Value" "0R2J-2-GP"
			(at 0.064008 -3.993896 270)
			(unlocked yes)
			(layer "F.Fab")
			(hide yes)
			(effects
				(font
					(size 1.016 1.016)
					(thickness 0.1524)
				)
			)
		)
		(property "Device Type" "R402H16"
			(at 0.064008 -5.517896 270)
			(unlocked yes)
			(layer "F.Fab")
			(hide yes)
			(effects
				(font
					(size 1.016 1.016)
					(thickness 0.1524)
				)
			)
		)
		(duplicate_pad_numbers_are_jumpers no)
		(fp_line
			(start -0.508 -0.9398)
			(end -0.508 0.9398)
			(stroke
				(width 0.1524)
				(type default)
			)
			(layer "F.SilkS")
		)
		(fp_line
			(start 0.508 -0.9398)
			(end -0.508 -0.9398)
			(stroke
				(width 0.1524)
				(type default)
			)
			(layer "F.SilkS")
		)
		(fp_rect
			(start -0.508 0.9398)
			(end 0.508 -0.9398)
			(stroke
				(width 0)
				(type default)
			)
			(fill no)
			(layer "F.CrtYd")
		)
		(fp_rect
			(start -0.508 0.9398)
			(end 0.508 -0.9398)
			(stroke
				(width 0)
				(type default)
			)
			(fill no)
			(layer "F.Fab")
		)
		(pad "1" smd custom
			(at 0 -0.4445 270)
			(size 0.1397 0.1397)
			(layers "F.Cu" "F.Mask" "F.Paste")
			(net "SAS_SMART_R_TX")
			(options
				(clearance outline)
				(anchor circle)
			)
			(primitives
				(gr_poly
					(pts
						(arc
							(start -0.1778 -0.2794)
							(mid -0.249642 -0.249642)
							(end -0.2794 -0.1778)
						)
						(arc
							(start -0.2794 0.1778)
							(mid -0.249642 0.249642)
							(end -0.1778 0.2794)
						)
						(arc
							(start 0.1778 0.2794)
							(mid 0.249642 0.249642)
							(end 0.2794 0.1778)
						)
						(arc
							(start 0.2794 -0.1778)
							(mid 0.249642 -0.249642)
							(end 0.1778 -0.2794)
						)
					)
					(width 0)
					(fill yes)
				)
			)
		)
		(pad "2" smd custom
			(at 0 0.4445 270)
			(size 0.1397 0.1397)
			(layers "F.Cu" "F.Mask" "F.Paste")
			(net "UART_USOUT")
			(options
				(clearance outline)
				(anchor circle)
			)
			(primitives
				(gr_poly
					(pts
						(arc
							(start -0.1778 -0.2794)
							(mid -0.249642 -0.249642)
							(end -0.2794 -0.1778)
						)
						(arc
							(start -0.2794 0.1778)
							(mid -0.249642 0.249642)
							(end -0.1778 0.2794)
						)
						(arc
							(start 0.1778 0.2794)
							(mid 0.249642 0.249642)
							(end 0.2794 0.1778)
						)
						(arc
							(start 0.2794 -0.1778)
							(mid 0.249642 -0.249642)
							(end 0.1778 -0.2794)
						)
					)
					(width 0)
					(fill yes)
				)
			)
		)
	)
	(footprint ""
		(layer "F.Cu")
		(at 350.05264 -46.431454)
		(property "Reference" "C3212"
			(at 0 0 0)
			(layer "F.SilkS")
			(hide yes)
			(effects
				(font
					(size 1.27 1.27)
				)
			)
		)
		(property "Value" "SCD1U25V2KX-2-GP"
			(at 1.1811 -2.7051 0)
			(unlocked yes)
			(layer "F.Fab")
			(hide yes)
			(effects
				(font
					(size 1.016 1.016)
					(thickness 0.1524)
				)
			)
		)
		(property "Device Type" "C402H22"
			(at 1.1811 -4.2291 0)
			(unlocked yes)
			(layer "F.Fab")
			(hide yes)
			(effects
				(font
					(size 1.016 1.016)
					(thickness 0.1524)
				)
			)
		)
		(duplicate_pad_numbers_are_jumpers no)
		(fp_rect
			(start -0.4318 0.9525)
			(end 0.4318 -0.9525)
			(stroke
				(width 0)
				(type default)
			)
			(fill no)
			(layer "F.CrtYd")
		)
		(fp_rect
			(start -0.4318 0.9525)
			(end 0.4318 -0.9525)
			(stroke
				(width 0)
				(type default)
			)
			(fill no)
			(layer "F.Fab")
		)
		(pad "1" smd custom
			(at 0 -0.4445)
			(size 0.1524 0.1524)
			(layers "F.Cu" "F.Mask" "F.Paste")
			(net "P3V3_STBY")
			(options
				(clearance outline)
				(anchor circle)
			)
			(primitives
				(gr_poly
					(pts
						(arc
							(start 0.3048 -0.2032)
							(mid 0.275042 -0.275042)
							(end 0.2032 -0.3048)
						)
						(arc
							(start -0.2032 -0.3048)
							(mid -0.275042 -0.275042)
							(end -0.3048 -0.2032)
						)
						(arc
							(start -0.3048 0.2032)
							(mid -0.275042 0.275042)
							(end -0.2032 0.3048)
						)
						(arc
							(start 0.2032 0.3048)
							(mid 0.275042 0.275042)
							(end 0.3048 0.2032)
						)
					)
					(width 0)
					(fill yes)
				)
			)
		)
		(pad "2" smd custom
			(at 0 0.4445)
			(size 0.1524 0.1524)
			(layers "F.Cu" "F.Mask" "F.Paste")
			(net "GND")
			(options
				(clearance outline)
				(anchor circle)
			)
			(primitives
				(gr_poly
					(pts
						(arc
							(start 0.3048 -0.2032)
							(mid 0.275042 -0.275042)
							(end 0.2032 -0.3048)
						)
						(arc
							(start -0.2032 -0.3048)
							(mid -0.275042 -0.275042)
							(end -0.3048 -0.2032)
						)
						(arc
							(start -0.3048 0.2032)
							(mid -0.275042 0.275042)
							(end -0.2032 0.3048)
						)
						(arc
							(start 0.2032 0.3048)
							(mid 0.275042 0.275042)
							(end 0.3048 0.2032)
						)
					)
					(width 0)
					(fill yes)
				)
			)
		)
	)
	(footprint ""
		(layer "F.Cu")
		(at 278.207978 -212.420454 180)
		(property "Reference" "C98"
			(at 0 0 180)
			(layer "F.SilkS")
			(hide yes)
			(effects
				(font
					(size 1.27 1.27)
				)
			)
		)
		(property "Value" "SCD22U10V2KX-1GP"
			(at 1.1811 -2.7051 180)
			(unlocked yes)
			(layer "F.Fab")
			(hide yes)
			(effects
				(font
					(size 1.016 1.016)
					(thickness 0.1524)
				)
			)
		)
		(property "Device Type" "C402H22"
			(at 1.1811 -4.2291 180)
			(unlocked yes)
			(layer "F.Fab")
			(hide yes)
			(effects
				(font
					(size 1.016 1.016)
					(thickness 0.1524)
				)
			)
		)
		(duplicate_pad_numbers_are_jumpers no)
		(fp_rect
			(start -0.4318 0.9525)
			(end 0.4318 -0.9525)
			(stroke
				(width 0)
				(type default)
			)
			(fill no)
			(layer "F.CrtYd")
		)
		(fp_rect
			(start -0.4318 0.9525)
			(end 0.4318 -0.9525)
			(stroke
				(width 0)
				(type default)
			)
			(fill no)
			(layer "F.Fab")
		)
		(pad "1" smd custom
			(at 0 -0.4445 180)
			(size 0.1524 0.1524)
			(layers "F.Cu" "F.Mask" "F.Paste")
			(net "PCIE_TX_CAP_N33")
			(options
				(clearance outline)
				(anchor circle)
			)
			(primitives
				(gr_poly
					(pts
						(arc
							(start 0.3048 -0.2032)
							(mid 0.275042 -0.275042)
							(end 0.2032 -0.3048)
						)
						(arc
							(start -0.2032 -0.3048)
							(mid -0.275042 -0.275042)
							(end -0.3048 -0.2032)
						)
						(arc
							(start -0.3048 0.2032)
							(mid -0.275042 0.275042)
							(end -0.2032 0.3048)
						)
						(arc
							(start 0.2032 0.3048)
							(mid 0.275042 0.275042)
							(end 0.3048 0.2032)
						)
					)
					(width 0)
					(fill yes)
				)
			)
		)
		(pad "2" smd custom
			(at 0 0.4445 180)
			(size 0.1524 0.1524)
			(layers "F.Cu" "F.Mask" "F.Paste")
			(net "PCIE_TX_N33")
			(options
				(clearance outline)
				(anchor circle)
			)
			(primitives
				(gr_poly
					(pts
						(arc
							(start 0.3048 -0.2032)
							(mid 0.275042 -0.275042)
							(end 0.2032 -0.3048)
						)
						(arc
							(start -0.2032 -0.3048)
							(mid -0.275042 -0.275042)
							(end -0.3048 -0.2032)
						)
						(arc
							(start -0.3048 0.2032)
							(mid -0.275042 0.275042)
							(end -0.2032 0.3048)
						)
						(arc
							(start 0.2032 0.3048)
							(mid 0.275042 0.275042)
							(end 0.3048 0.2032)
						)
					)
					(width 0)
					(fill yes)
				)
			)
		)
	)
	(footprint ""
		(layer "F.Cu")
		(at 123.19 -18.63852 90)
		(property "Reference" "SR708"
			(at 0 0 90)
			(layer "F.SilkS")
			(hide yes)
			(effects
				(font
					(size 1.27 1.27)
				)
			)
		)
		(property "Value" "150R2F-1-GP"
			(at 0.064008 -3.993896 90)
			(unlocked yes)
			(layer "F.Fab")
			(hide yes)
			(effects
				(font
					(size 1.016 1.016)
					(thickness 0.1524)
				)
			)
		)
		(property "Device Type" "R402H16"
			(at 0.064008 -5.517896 90)
			(unlocked yes)
			(layer "F.Fab")
			(hide yes)
			(effects
				(font
					(size 1.016 1.016)
					(thickness 0.1524)
				)
			)
		)
		(duplicate_pad_numbers_are_jumpers no)
		(fp_line
			(start 0.508 -0.9398)
			(end -0.508 -0.9398)
			(stroke
				(width 0.1524)
				(type default)
			)
			(layer "F.SilkS")
		)
		(fp_line
			(start -0.508 -0.9398)
			(end -0.508 0.9398)
			(stroke
				(width 0.1524)
				(type default)
			)
			(layer "F.SilkS")
		)
		(fp_rect
			(start -0.508 0.9398)
			(end 0.508 -0.9398)
			(stroke
				(width 0)
				(type default)
			)
			(fill no)
			(layer "F.CrtYd")
		)
		(fp_rect
			(start -0.508 0.9398)
			(end 0.508 -0.9398)
			(stroke
				(width 0)
				(type default)
			)
			(fill no)
			(layer "F.Fab")
		)
		(pad "1" smd custom
			(at 0 -0.4445 90)
			(size 0.1397 0.1397)
			(layers "F.Cu" "F.Mask" "F.Paste")
			(net "P3V3_STBY")
			(options
				(clearance outline)
				(anchor circle)
			)
			(primitives
				(gr_poly
					(pts
						(arc
							(start -0.1778 -0.2794)
							(mid -0.249642 -0.249642)
							(end -0.2794 -0.1778)
						)
						(arc
							(start -0.2794 0.1778)
							(mid -0.249642 0.249642)
							(end -0.1778 0.2794)
						)
						(arc
							(start 0.1778 0.2794)
							(mid 0.249642 0.249642)
							(end 0.2794 0.1778)
						)
						(arc
							(start 0.2794 -0.1778)
							(mid 0.249642 -0.249642)
							(end 0.1778 -0.2794)
						)
					)
					(width 0)
					(fill yes)
				)
			)
		)
		(pad "2" smd custom
			(at 0 0.4445 90)
			(size 0.1397 0.1397)
			(layers "F.Cu" "F.Mask" "F.Paste")
			(net "LED_R_1")
			(options
				(clearance outline)
				(anchor circle)
			)
			(primitives
				(gr_poly
					(pts
						(arc
							(start -0.1778 -0.2794)
							(mid -0.249642 -0.249642)
							(end -0.2794 -0.1778)
						)
						(arc
							(start -0.2794 0.1778)
							(mid -0.249642 0.249642)
							(end -0.1778 0.2794)
						)
						(arc
							(start 0.1778 0.2794)
							(mid 0.249642 0.249642)
							(end 0.2794 0.1778)
						)
						(arc
							(start 0.2794 -0.1778)
							(mid 0.249642 -0.249642)
							(end 0.1778 -0.2794)
						)
					)
					(width 0)
					(fill yes)
				)
			)
		)
	)
	(footprint ""
		(layer "F.Cu")
		(at 205.359 -20.9296 90)
		(property "Reference" "R583"
			(at 0 0 90)
			(layer "F.SilkS")
			(hide yes)
			(effects
				(font
					(size 1.27 1.27)
				)
			)
		)
		(property "Value" "4K7R2F-GP"
			(at 0.064008 -3.993896 90)
			(unlocked yes)
			(layer "F.Fab")
			(hide yes)
			(effects
				(font
					(size 1.016 1.016)
					(thickness 0.1524)
				)
			)
		)
		(property "Device Type" "R402H16"
			(at 0.064008 -5.517896 90)
			(unlocked yes)
			(layer "F.Fab")
			(hide yes)
			(effects
				(font
					(size 1.016 1.016)
					(thickness 0.1524)
				)
			)
		)
		(duplicate_pad_numbers_are_jumpers no)
		(fp_line
			(start 0.508 -0.9398)
			(end -0.508 -0.9398)
			(stroke
				(width 0.1524)
				(type default)
			)
			(layer "F.SilkS")
		)
		(fp_line
			(start -0.508 -0.9398)
			(end -0.508 0.9398)
			(stroke
				(width 0.1524)
				(type default)
			)
			(layer "F.SilkS")
		)
		(fp_rect
			(start -0.508 0.9398)
			(end 0.508 -0.9398)
			(stroke
				(width 0)
				(type default)
			)
			(fill no)
			(layer "F.CrtYd")
		)
		(fp_rect
			(start -0.508 0.9398)
			(end 0.508 -0.9398)
			(stroke
				(width 0)
				(type default)
			)
			(fill no)
			(layer "F.Fab")
		)
		(pad "1" smd custom
			(at 0 -0.4445 90)
			(size 0.1397 0.1397)
			(layers "F.Cu" "F.Mask" "F.Paste")
			(net "MINISAS_CN16_D_I2C_INT#")
			(options
				(clearance outline)
				(anchor circle)
			)
			(primitives
				(gr_poly
					(pts
						(arc
							(start -0.1778 -0.2794)
							(mid -0.249642 -0.249642)
							(end -0.2794 -0.1778)
						)
						(arc
							(start -0.2794 0.1778)
							(mid -0.249642 0.249642)
							(end -0.1778 0.2794)
						)
						(arc
							(start 0.1778 0.2794)
							(mid 0.249642 0.249642)
							(end 0.2794 0.1778)
						)
						(arc
							(start 0.2794 -0.1778)
							(mid 0.249642 -0.249642)
							(end 0.1778 -0.2794)
						)
					)
					(width 0)
					(fill yes)
				)
			)
		)
		(pad "2" smd custom
			(at 0 0.4445 90)
			(size 0.1397 0.1397)
			(layers "F.Cu" "F.Mask" "F.Paste")
			(net "P3V3_STBY")
			(options
				(clearance outline)
				(anchor circle)
			)
			(primitives
				(gr_poly
					(pts
						(arc
							(start -0.1778 -0.2794)
							(mid -0.249642 -0.249642)
							(end -0.2794 -0.1778)
						)
						(arc
							(start -0.2794 0.1778)
							(mid -0.249642 0.249642)
							(end -0.1778 0.2794)
						)
						(arc
							(start 0.1778 0.2794)
							(mid 0.249642 0.249642)
							(end 0.2794 0.1778)
						)
						(arc
							(start 0.2794 -0.1778)
							(mid 0.249642 -0.249642)
							(end 0.1778 -0.2794)
						)
					)
					(width 0)
					(fill yes)
				)
			)
		)
	)
	(footprint ""
		(layer "F.Cu")
		(at 28.321 -116.713)
		(property "Reference" "R258"
			(at 0 0 0)
			(layer "F.SilkS")
			(hide yes)
			(effects
				(font
					(size 1.27 1.27)
				)
			)
		)
		(property "Value" "100KR2F-L1-GP"
			(at 0.064008 -3.993896 0)
			(unlocked yes)
			(layer "F.Fab")
			(hide yes)
			(effects
				(font
					(size 1.016 1.016)
					(thickness 0.1524)
				)
			)
		)
		(property "Device Type" "R402H16"
			(at 0.064008 -5.517896 0)
			(unlocked yes)
			(layer "F.Fab")
			(hide yes)
			(effects
				(font
					(size 1.016 1.016)
					(thickness 0.1524)
				)
			)
		)
		(duplicate_pad_numbers_are_jumpers no)
		(fp_line
			(start -0.508 -0.9398)
			(end -0.508 0.9398)
			(stroke
				(width 0.1524)
				(type default)
			)
			(layer "F.SilkS")
		)
		(fp_line
			(start 0.508 -0.9398)
			(end -0.508 -0.9398)
			(stroke
				(width 0.1524)
				(type default)
			)
			(layer "F.SilkS")
		)
		(fp_rect
			(start -0.508 0.9398)
			(end 0.508 -0.9398)
			(stroke
				(width 0)
				(type default)
			)
			(fill no)
			(layer "F.CrtYd")
		)
		(fp_rect
			(start -0.508 0.9398)
			(end 0.508 -0.9398)
			(stroke
				(width 0)
				(type default)
			)
			(fill no)
			(layer "F.Fab")
		)
		(pad "1" smd custom
			(at 0 -0.4445)
			(size 0.1397 0.1397)
			(layers "F.Cu" "F.Mask" "F.Paste")
			(net "TP_LPC_CPU_FRAME_N")
			(options
				(clearance outline)
				(anchor circle)
			)
			(primitives
				(gr_poly
					(pts
						(arc
							(start -0.1778 -0.2794)
							(mid -0.249642 -0.249642)
							(end -0.2794 -0.1778)
						)
						(arc
							(start -0.2794 0.1778)
							(mid -0.249642 0.249642)
							(end -0.1778 0.2794)
						)
						(arc
							(start 0.1778 0.2794)
							(mid 0.249642 0.249642)
							(end 0.2794 0.1778)
						)
						(arc
							(start 0.2794 -0.1778)
							(mid 0.249642 -0.249642)
							(end 0.1778 -0.2794)
						)
					)
					(width 0)
					(fill yes)
				)
			)
		)
		(pad "2" smd custom
			(at 0 0.4445)
			(size 0.1397 0.1397)
			(layers "F.Cu" "F.Mask" "F.Paste")
			(net "GND")
			(options
				(clearance outline)
				(anchor circle)
			)
			(primitives
				(gr_poly
					(pts
						(arc
							(start -0.1778 -0.2794)
							(mid -0.249642 -0.249642)
							(end -0.2794 -0.1778)
						)
						(arc
							(start -0.2794 0.1778)
							(mid -0.249642 0.249642)
							(end -0.1778 0.2794)
						)
						(arc
							(start 0.1778 0.2794)
							(mid 0.249642 0.249642)
							(end 0.2794 0.1778)
						)
						(arc
							(start 0.2794 -0.1778)
							(mid 0.249642 -0.249642)
							(end 0.1778 -0.2794)
						)
					)
					(width 0)
					(fill yes)
				)
			)
		)
	)
	(footprint ""
		(layer "F.Cu")
		(at 220.918024 -203.047092 180)
		(property "Reference" "R7979"
			(at 0 0 180)
			(layer "F.SilkS")
			(hide yes)
			(effects
				(font
					(size 1.27 1.27)
				)
			)
		)
		(property "Value" "0R2J-2-GP"
			(at 0.064008 -3.993896 180)
			(unlocked yes)
			(layer "F.Fab")
			(hide yes)
			(effects
				(font
					(size 1.016 1.016)
					(thickness 0.1524)
				)
			)
		)
		(property "Device Type" "R402H16"
			(at 0.064008 -5.517896 180)
			(unlocked yes)
			(layer "F.Fab")
			(hide yes)
			(effects
				(font
					(size 1.016 1.016)
					(thickness 0.1524)
				)
			)
		)
		(duplicate_pad_numbers_are_jumpers no)
		(fp_line
			(start 0.508 -0.9398)
			(end -0.508 -0.9398)
			(stroke
				(width 0.1524)
				(type default)
			)
			(layer "F.SilkS")
		)
		(fp_line
			(start -0.508 -0.9398)
			(end -0.508 0.9398)
			(stroke
				(width 0.1524)
				(type default)
			)
			(layer "F.SilkS")
		)
		(fp_rect
			(start -0.508 0.9398)
			(end 0.508 -0.9398)
			(stroke
				(width 0)
				(type default)
			)
			(fill no)
			(layer "F.CrtYd")
		)
		(fp_rect
			(start -0.508 0.9398)
			(end 0.508 -0.9398)
			(stroke
				(width 0)
				(type default)
			)
			(fill no)
			(layer "F.Fab")
		)
		(pad "1" smd custom
			(at 0 -0.4445 180)
			(size 0.1397 0.1397)
			(layers "F.Cu" "F.Mask" "F.Paste")
			(net "SSD_PERST#13")
			(options
				(clearance outline)
				(anchor circle)
			)
			(primitives
				(gr_poly
					(pts
						(arc
							(start -0.1778 -0.2794)
							(mid -0.249642 -0.249642)
							(end -0.2794 -0.1778)
						)
						(arc
							(start -0.2794 0.1778)
							(mid -0.249642 0.249642)
							(end -0.1778 0.2794)
						)
						(arc
							(start 0.1778 0.2794)
							(mid 0.249642 0.249642)
							(end 0.2794 0.1778)
						)
						(arc
							(start 0.2794 -0.1778)
							(mid 0.249642 -0.249642)
							(end 0.1778 -0.2794)
						)
					)
					(width 0)
					(fill yes)
				)
			)
		)
		(pad "2" smd custom
			(at 0 0.4445 180)
			(size 0.1397 0.1397)
			(layers "F.Cu" "F.Mask" "F.Paste")
			(net "SSD_PERST#13_R")
			(options
				(clearance outline)
				(anchor circle)
			)
			(primitives
				(gr_poly
					(pts
						(arc
							(start -0.1778 -0.2794)
							(mid -0.249642 -0.249642)
							(end -0.2794 -0.1778)
						)
						(arc
							(start -0.2794 0.1778)
							(mid -0.249642 0.249642)
							(end -0.1778 0.2794)
						)
						(arc
							(start 0.1778 0.2794)
							(mid 0.249642 0.249642)
							(end 0.2794 0.1778)
						)
						(arc
							(start 0.2794 -0.1778)
							(mid 0.249642 -0.249642)
							(end 0.1778 -0.2794)
						)
					)
					(width 0)
					(fill yes)
				)
			)
		)
	)
	(footprint ""
		(layer "F.Cu")
		(at 63.9318 -112.5982 -90)
		(property "Reference" "R439"
			(at 0 0 270)
			(layer "F.SilkS")
			(hide yes)
			(effects
				(font
					(size 1.27 1.27)
				)
			)
		)
		(property "Value" "4K7R2F-GP"
			(at 0.064008 -3.993896 270)
			(unlocked yes)
			(layer "F.Fab")
			(hide yes)
			(effects
				(font
					(size 1.016 1.016)
					(thickness 0.1524)
				)
			)
		)
		(property "Device Type" "R402H16"
			(at 0.064008 -5.517896 270)
			(unlocked yes)
			(layer "F.Fab")
			(hide yes)
			(effects
				(font
					(size 1.016 1.016)
					(thickness 0.1524)
				)
			)
		)
		(duplicate_pad_numbers_are_jumpers no)
		(fp_line
			(start -0.508 -0.9398)
			(end -0.508 0.9398)
			(stroke
				(width 0.1524)
				(type default)
			)
			(layer "F.SilkS")
		)
		(fp_line
			(start 0.508 -0.9398)
			(end -0.508 -0.9398)
			(stroke
				(width 0.1524)
				(type default)
			)
			(layer "F.SilkS")
		)
		(fp_rect
			(start -0.508 0.9398)
			(end 0.508 -0.9398)
			(stroke
				(width 0)
				(type default)
			)
			(fill no)
			(layer "F.CrtYd")
		)
		(fp_rect
			(start -0.508 0.9398)
			(end 0.508 -0.9398)
			(stroke
				(width 0)
				(type default)
			)
			(fill no)
			(layer "F.Fab")
		)
		(pad "1" smd custom
			(at 0 -0.4445 270)
			(size 0.1397 0.1397)
			(layers "F.Cu" "F.Mask" "F.Paste")
			(net "BMC_I2C11_MINI5_SDA_S")
			(options
				(clearance outline)
				(anchor circle)
			)
			(primitives
				(gr_poly
					(pts
						(arc
							(start -0.1778 -0.2794)
							(mid -0.249642 -0.249642)
							(end -0.2794 -0.1778)
						)
						(arc
							(start -0.2794 0.1778)
							(mid -0.249642 0.249642)
							(end -0.1778 0.2794)
						)
						(arc
							(start 0.1778 0.2794)
							(mid 0.249642 0.249642)
							(end 0.2794 0.1778)
						)
						(arc
							(start 0.2794 -0.1778)
							(mid 0.249642 -0.249642)
							(end 0.1778 -0.2794)
						)
					)
					(width 0)
					(fill yes)
				)
			)
		)
		(pad "2" smd custom
			(at 0 0.4445 270)
			(size 0.1397 0.1397)
			(layers "F.Cu" "F.Mask" "F.Paste")
			(net "P3V3_STBY")
			(options
				(clearance outline)
				(anchor circle)
			)
			(primitives
				(gr_poly
					(pts
						(arc
							(start -0.1778 -0.2794)
							(mid -0.249642 -0.249642)
							(end -0.2794 -0.1778)
						)
						(arc
							(start -0.2794 0.1778)
							(mid -0.249642 0.249642)
							(end -0.1778 0.2794)
						)
						(arc
							(start 0.1778 0.2794)
							(mid 0.249642 0.249642)
							(end 0.2794 0.1778)
						)
						(arc
							(start 0.2794 -0.1778)
							(mid 0.249642 -0.249642)
							(end 0.1778 -0.2794)
						)
					)
					(width 0)
					(fill yes)
				)
			)
		)
	)
	(footprint ""
		(layer "F.Cu")
		(at 201.1172 -7.0104 180)
		(property "Reference" "R25"
			(at 0 0 180)
			(layer "F.SilkS")
			(hide yes)
			(effects
				(font
					(size 1.27 1.27)
				)
			)
		)
		(property "Value" "4K7R2F-GP"
			(at 0.064008 -3.993896 180)
			(unlocked yes)
			(layer "F.Fab")
			(hide yes)
			(effects
				(font
					(size 1.016 1.016)
					(thickness 0.1524)
				)
			)
		)
		(property "Device Type" "R402H16"
			(at 0.064008 -5.517896 180)
			(unlocked yes)
			(layer "F.Fab")
			(hide yes)
			(effects
				(font
					(size 1.016 1.016)
					(thickness 0.1524)
				)
			)
		)
		(duplicate_pad_numbers_are_jumpers no)
		(fp_line
			(start 0.508 -0.9398)
			(end -0.508 -0.9398)
			(stroke
				(width 0.1524)
				(type default)
			)
			(layer "F.SilkS")
		)
		(fp_line
			(start -0.508 -0.9398)
			(end -0.508 0.9398)
			(stroke
				(width 0.1524)
				(type default)
			)
			(layer "F.SilkS")
		)
		(fp_rect
			(start -0.508 0.9398)
			(end 0.508 -0.9398)
			(stroke
				(width 0)
				(type default)
			)
			(fill no)
			(layer "F.CrtYd")
		)
		(fp_rect
			(start -0.508 0.9398)
			(end 0.508 -0.9398)
			(stroke
				(width 0)
				(type default)
			)
			(fill no)
			(layer "F.Fab")
		)
		(pad "1" smd custom
			(at 0 -0.4445 180)
			(size 0.1397 0.1397)
			(layers "F.Cu" "F.Mask" "F.Paste")
			(net "BOOT_RECOVERY_0")
			(options
				(clearance outline)
				(anchor circle)
			)
			(primitives
				(gr_poly
					(pts
						(arc
							(start -0.1778 -0.2794)
							(mid -0.249642 -0.249642)
							(end -0.2794 -0.1778)
						)
						(arc
							(start -0.2794 0.1778)
							(mid -0.249642 0.249642)
							(end -0.1778 0.2794)
						)
						(arc
							(start 0.1778 0.2794)
							(mid 0.249642 0.249642)
							(end 0.2794 0.1778)
						)
						(arc
							(start 0.2794 -0.1778)
							(mid 0.249642 -0.249642)
							(end 0.1778 -0.2794)
						)
					)
					(width 0)
					(fill yes)
				)
			)
		)
		(pad "2" smd custom
			(at 0 0.4445 180)
			(size 0.1397 0.1397)
			(layers "F.Cu" "F.Mask" "F.Paste")
			(net "GND")
			(options
				(clearance outline)
				(anchor circle)
			)
			(primitives
				(gr_poly
					(pts
						(arc
							(start -0.1778 -0.2794)
							(mid -0.249642 -0.249642)
							(end -0.2794 -0.1778)
						)
						(arc
							(start -0.2794 0.1778)
							(mid -0.249642 0.249642)
							(end -0.1778 0.2794)
						)
						(arc
							(start 0.1778 0.2794)
							(mid 0.249642 0.249642)
							(end 0.2794 0.1778)
						)
						(arc
							(start 0.2794 -0.1778)
							(mid 0.249642 -0.249642)
							(end 0.1778 -0.2794)
						)
					)
					(width 0)
					(fill yes)
				)
			)
		)
	)
	(footprint ""
		(layer "F.Cu")
		(at 206.392018 -212.420454 180)
		(property "Reference" "C113"
			(at 0 0 180)
			(layer "F.SilkS")
			(hide yes)
			(effects
				(font
					(size 1.27 1.27)
				)
			)
		)
		(property "Value" "SCD22U10V2KX-1GP"
			(at 1.1811 -2.7051 180)
			(unlocked yes)
			(layer "F.Fab")
			(hide yes)
			(effects
				(font
					(size 1.016 1.016)
					(thickness 0.1524)
				)
			)
		)
		(property "Device Type" "C402H22"
			(at 1.1811 -4.2291 180)
			(unlocked yes)
			(layer "F.Fab")
			(hide yes)
			(effects
				(font
					(size 1.016 1.016)
					(thickness 0.1524)
				)
			)
		)
		(duplicate_pad_numbers_are_jumpers no)
		(fp_rect
			(start -0.4318 0.9525)
			(end 0.4318 -0.9525)
			(stroke
				(width 0)
				(type default)
			)
			(fill no)
			(layer "F.CrtYd")
		)
		(fp_rect
			(start -0.4318 0.9525)
			(end 0.4318 -0.9525)
			(stroke
				(width 0)
				(type default)
			)
			(fill no)
			(layer "F.Fab")
		)
		(pad "1" smd custom
			(at 0 -0.4445 180)
			(size 0.1524 0.1524)
			(layers "F.Cu" "F.Mask" "F.Paste")
			(net "PCIE_TX_CAP_P40")
			(options
				(clearance outline)
				(anchor circle)
			)
			(primitives
				(gr_poly
					(pts
						(arc
							(start 0.3048 -0.2032)
							(mid 0.275042 -0.275042)
							(end 0.2032 -0.3048)
						)
						(arc
							(start -0.2032 -0.3048)
							(mid -0.275042 -0.275042)
							(end -0.3048 -0.2032)
						)
						(arc
							(start -0.3048 0.2032)
							(mid -0.275042 0.275042)
							(end -0.2032 0.3048)
						)
						(arc
							(start 0.2032 0.3048)
							(mid 0.275042 0.275042)
							(end 0.3048 0.2032)
						)
					)
					(width 0)
					(fill yes)
				)
			)
		)
		(pad "2" smd custom
			(at 0 0.4445 180)
			(size 0.1524 0.1524)
			(layers "F.Cu" "F.Mask" "F.Paste")
			(net "PCIE_TX_P40")
			(options
				(clearance outline)
				(anchor circle)
			)
			(primitives
				(gr_poly
					(pts
						(arc
							(start 0.3048 -0.2032)
							(mid 0.275042 -0.275042)
							(end 0.2032 -0.3048)
						)
						(arc
							(start -0.2032 -0.3048)
							(mid -0.275042 -0.275042)
							(end -0.3048 -0.2032)
						)
						(arc
							(start -0.3048 0.2032)
							(mid -0.275042 0.275042)
							(end -0.2032 0.3048)
						)
						(arc
							(start 0.2032 0.3048)
							(mid 0.275042 0.275042)
							(end 0.3048 0.2032)
						)
					)
					(width 0)
					(fill yes)
				)
			)
		)
	)
	(footprint ""
		(layer "F.Cu")
		(at 159.350202 -58.447432 180)
		(property "Reference" "PR176"
			(at 0 0 180)
			(layer "F.SilkS")
			(hide yes)
			(effects
				(font
					(size 1.27 1.27)
				)
			)
		)
		(property "Value" "100KR2F-L1-GP"
			(at 0.064008 -3.993896 180)
			(unlocked yes)
			(layer "F.Fab")
			(hide yes)
			(effects
				(font
					(size 1.016 1.016)
					(thickness 0.1524)
				)
			)
		)
		(property "Device Type" "R402H16"
			(at 0.064008 -5.517896 180)
			(unlocked yes)
			(layer "F.Fab")
			(hide yes)
			(effects
				(font
					(size 1.016 1.016)
					(thickness 0.1524)
				)
			)
		)
		(duplicate_pad_numbers_are_jumpers no)
		(fp_line
			(start 0.508 -0.9398)
			(end -0.508 -0.9398)
			(stroke
				(width 0.1524)
				(type default)
			)
			(layer "F.SilkS")
		)
		(fp_line
			(start -0.508 -0.9398)
			(end -0.508 0.9398)
			(stroke
				(width 0.1524)
				(type default)
			)
			(layer "F.SilkS")
		)
		(fp_rect
			(start -0.508 0.9398)
			(end 0.508 -0.9398)
			(stroke
				(width 0)
				(type default)
			)
			(fill no)
			(layer "F.CrtYd")
		)
		(fp_rect
			(start -0.508 0.9398)
			(end 0.508 -0.9398)
			(stroke
				(width 0)
				(type default)
			)
			(fill no)
			(layer "F.Fab")
		)
		(pad "1" smd custom
			(at 0 -0.4445 180)
			(size 0.1397 0.1397)
			(layers "F.Cu" "F.Mask" "F.Paste")
			(net "P12V")
			(options
				(clearance outline)
				(anchor circle)
			)
			(primitives
				(gr_poly
					(pts
						(arc
							(start -0.1778 -0.2794)
							(mid -0.249642 -0.249642)
							(end -0.2794 -0.1778)
						)
						(arc
							(start -0.2794 0.1778)
							(mid -0.249642 0.249642)
							(end -0.1778 0.2794)
						)
						(arc
							(start 0.1778 0.2794)
							(mid 0.249642 0.249642)
							(end 0.2794 0.1778)
						)
						(arc
							(start 0.2794 -0.1778)
							(mid 0.249642 -0.249642)
							(end 0.1778 -0.2794)
						)
					)
					(width 0)
					(fill yes)
				)
			)
		)
		(pad "2" smd custom
			(at 0 0.4445 180)
			(size 0.1397 0.1397)
			(layers "F.Cu" "F.Mask" "F.Paste")
			(net "P0V9_EN")
			(options
				(clearance outline)
				(anchor circle)
			)
			(primitives
				(gr_poly
					(pts
						(arc
							(start -0.1778 -0.2794)
							(mid -0.249642 -0.249642)
							(end -0.2794 -0.1778)
						)
						(arc
							(start -0.2794 0.1778)
							(mid -0.249642 0.249642)
							(end -0.1778 0.2794)
						)
						(arc
							(start 0.1778 0.2794)
							(mid 0.249642 0.249642)
							(end 0.2794 0.1778)
						)
						(arc
							(start 0.2794 -0.1778)
							(mid 0.249642 -0.249642)
							(end 0.1778 -0.2794)
						)
					)
					(width 0)
					(fill yes)
				)
			)
		)
	)
	(footprint ""
		(layer "F.Cu")
		(at 53.721 -137.795 90)
		(property "Reference" "R153"
			(at 0 0 90)
			(layer "F.SilkS")
			(hide yes)
			(effects
				(font
					(size 1.27 1.27)
				)
			)
		)
		(property "Value" "4K7R2F-GP"
			(at 0.064008 -3.993896 90)
			(unlocked yes)
			(layer "F.Fab")
			(hide yes)
			(effects
				(font
					(size 1.016 1.016)
					(thickness 0.1524)
				)
			)
		)
		(property "Device Type" "R402H16"
			(at 0.064008 -5.517896 90)
			(unlocked yes)
			(layer "F.Fab")
			(hide yes)
			(effects
				(font
					(size 1.016 1.016)
					(thickness 0.1524)
				)
			)
		)
		(duplicate_pad_numbers_are_jumpers no)
		(fp_line
			(start 0.508 -0.9398)
			(end -0.508 -0.9398)
			(stroke
				(width 0.1524)
				(type default)
			)
			(layer "F.SilkS")
		)
		(fp_line
			(start -0.508 -0.9398)
			(end -0.508 0.9398)
			(stroke
				(width 0.1524)
				(type default)
			)
			(layer "F.SilkS")
		)
		(fp_rect
			(start -0.508 0.9398)
			(end 0.508 -0.9398)
			(stroke
				(width 0)
				(type default)
			)
			(fill no)
			(layer "F.CrtYd")
		)
		(fp_rect
			(start -0.508 0.9398)
			(end 0.508 -0.9398)
			(stroke
				(width 0)
				(type default)
			)
			(fill no)
			(layer "F.Fab")
		)
		(pad "1" smd custom
			(at 0 -0.4445 90)
			(size 0.1397 0.1397)
			(layers "F.Cu" "F.Mask" "F.Paste")
			(net "CBL_PRSNT_N_4")
			(options
				(clearance outline)
				(anchor circle)
			)
			(primitives
				(gr_poly
					(pts
						(arc
							(start -0.1778 -0.2794)
							(mid -0.249642 -0.249642)
							(end -0.2794 -0.1778)
						)
						(arc
							(start -0.2794 0.1778)
							(mid -0.249642 0.249642)
							(end -0.1778 0.2794)
						)
						(arc
							(start 0.1778 0.2794)
							(mid 0.249642 0.249642)
							(end 0.2794 0.1778)
						)
						(arc
							(start 0.2794 -0.1778)
							(mid 0.249642 -0.249642)
							(end 0.1778 -0.2794)
						)
					)
					(width 0)
					(fill yes)
				)
			)
		)
		(pad "2" smd custom
			(at 0 0.4445 90)
			(size 0.1397 0.1397)
			(layers "F.Cu" "F.Mask" "F.Paste")
			(net "P3V3_STBY")
			(options
				(clearance outline)
				(anchor circle)
			)
			(primitives
				(gr_poly
					(pts
						(arc
							(start -0.1778 -0.2794)
							(mid -0.249642 -0.249642)
							(end -0.2794 -0.1778)
						)
						(arc
							(start -0.2794 0.1778)
							(mid -0.249642 0.249642)
							(end -0.1778 0.2794)
						)
						(arc
							(start 0.1778 0.2794)
							(mid 0.249642 0.249642)
							(end 0.2794 0.1778)
						)
						(arc
							(start 0.2794 -0.1778)
							(mid 0.249642 -0.249642)
							(end 0.1778 -0.2794)
						)
					)
					(width 0)
					(fill yes)
				)
			)
		)
	)
	(footprint ""
		(layer "F.Cu")
		(at 20.6502 -191.4398 90)
		(property "Reference" "R2109"
			(at 0 0 90)
			(layer "F.SilkS")
			(hide yes)
			(effects
				(font
					(size 1.27 1.27)
				)
			)
		)
		(property "Value" "6K04R2F-GP"
			(at 0.064008 -3.993896 90)
			(unlocked yes)
			(layer "F.Fab")
			(hide yes)
			(effects
				(font
					(size 1.016 1.016)
					(thickness 0.1524)
				)
			)
		)
		(property "Device Type" "R402H16"
			(at 0.064008 -5.517896 90)
			(unlocked yes)
			(layer "F.Fab")
			(hide yes)
			(effects
				(font
					(size 1.016 1.016)
					(thickness 0.1524)
				)
			)
		)
		(duplicate_pad_numbers_are_jumpers no)
		(fp_line
			(start 0.508 -0.9398)
			(end -0.508 -0.9398)
			(stroke
				(width 0.1524)
				(type default)
			)
			(layer "F.SilkS")
		)
		(fp_line
			(start -0.508 -0.9398)
			(end -0.508 0.9398)
			(stroke
				(width 0.1524)
				(type default)
			)
			(layer "F.SilkS")
		)
		(fp_rect
			(start -0.508 0.9398)
			(end 0.508 -0.9398)
			(stroke
				(width 0)
				(type default)
			)
			(fill no)
			(layer "F.CrtYd")
		)
		(fp_rect
			(start -0.508 0.9398)
			(end 0.508 -0.9398)
			(stroke
				(width 0)
				(type default)
			)
			(fill no)
			(layer "F.Fab")
		)
		(pad "1" smd custom
			(at 0 -0.4445 90)
			(size 0.1397 0.1397)
			(layers "F.Cu" "F.Mask" "F.Paste")
			(net "MB0_CM_UV_R")
			(options
				(clearance outline)
				(anchor circle)
			)
			(primitives
				(gr_poly
					(pts
						(arc
							(start -0.1778 -0.2794)
							(mid -0.249642 -0.249642)
							(end -0.2794 -0.1778)
						)
						(arc
							(start -0.2794 0.1778)
							(mid -0.249642 0.249642)
							(end -0.1778 0.2794)
						)
						(arc
							(start 0.1778 0.2794)
							(mid 0.249642 0.249642)
							(end 0.2794 0.1778)
						)
						(arc
							(start 0.2794 -0.1778)
							(mid 0.249642 -0.249642)
							(end 0.1778 -0.2794)
						)
					)
					(width 0)
					(fill yes)
				)
			)
		)
		(pad "2" smd custom
			(at 0 0.4445 90)
			(size 0.1397 0.1397)
			(layers "F.Cu" "F.Mask" "F.Paste")
			(net "AGND_CURRENT_MON")
			(options
				(clearance outline)
				(anchor circle)
			)
			(primitives
				(gr_poly
					(pts
						(arc
							(start -0.1778 -0.2794)
							(mid -0.249642 -0.249642)
							(end -0.2794 -0.1778)
						)
						(arc
							(start -0.2794 0.1778)
							(mid -0.249642 0.249642)
							(end -0.1778 0.2794)
						)
						(arc
							(start 0.1778 0.2794)
							(mid 0.249642 0.249642)
							(end 0.2794 0.1778)
						)
						(arc
							(start 0.2794 -0.1778)
							(mid 0.249642 -0.249642)
							(end 0.1778 -0.2794)
						)
					)
					(width 0)
					(fill yes)
				)
			)
		)
	)
	(footprint ""
		(layer "F.Cu")
		(at 14.5034 -180.0606 -90)
		(property "Reference" "R1227"
			(at 0 0 270)
			(layer "F.SilkS")
			(hide yes)
			(effects
				(font
					(size 1.27 1.27)
				)
			)
		)
		(property "Value" "100KR2F-L1-GP"
			(at 0.064008 -3.993896 270)
			(unlocked yes)
			(layer "F.Fab")
			(hide yes)
			(effects
				(font
					(size 1.016 1.016)
					(thickness 0.1524)
				)
			)
		)
		(property "Device Type" "R402H16"
			(at 0.064008 -5.517896 270)
			(unlocked yes)
			(layer "F.Fab")
			(hide yes)
			(effects
				(font
					(size 1.016 1.016)
					(thickness 0.1524)
				)
			)
		)
		(duplicate_pad_numbers_are_jumpers no)
		(fp_line
			(start -0.508 -0.9398)
			(end -0.508 0.9398)
			(stroke
				(width 0.1524)
				(type default)
			)
			(layer "F.SilkS")
		)
		(fp_line
			(start 0.508 -0.9398)
			(end -0.508 -0.9398)
			(stroke
				(width 0.1524)
				(type default)
			)
			(layer "F.SilkS")
		)
		(fp_rect
			(start -0.508 0.9398)
			(end 0.508 -0.9398)
			(stroke
				(width 0)
				(type default)
			)
			(fill no)
			(layer "F.CrtYd")
		)
		(fp_rect
			(start -0.508 0.9398)
			(end 0.508 -0.9398)
			(stroke
				(width 0)
				(type default)
			)
			(fill no)
			(layer "F.Fab")
		)
		(pad "1" smd custom
			(at 0 -0.4445 270)
			(size 0.1397 0.1397)
			(layers "F.Cu" "F.Mask" "F.Paste")
			(net "P12V")
			(options
				(clearance outline)
				(anchor circle)
			)
			(primitives
				(gr_poly
					(pts
						(arc
							(start -0.1778 -0.2794)
							(mid -0.249642 -0.249642)
							(end -0.2794 -0.1778)
						)
						(arc
							(start -0.2794 0.1778)
							(mid -0.249642 0.249642)
							(end -0.1778 0.2794)
						)
						(arc
							(start 0.1778 0.2794)
							(mid 0.249642 0.249642)
							(end 0.2794 0.1778)
						)
						(arc
							(start 0.2794 -0.1778)
							(mid 0.249642 -0.249642)
							(end 0.1778 -0.2794)
						)
					)
					(width 0)
					(fill yes)
				)
			)
		)
		(pad "2" smd custom
			(at 0 0.4445 270)
			(size 0.1397 0.1397)
			(layers "F.Cu" "F.Mask" "F.Paste")
			(net "MB0_P12V_PWGIN_R")
			(options
				(clearance outline)
				(anchor circle)
			)
			(primitives
				(gr_poly
					(pts
						(arc
							(start -0.1778 -0.2794)
							(mid -0.249642 -0.249642)
							(end -0.2794 -0.1778)
						)
						(arc
							(start -0.2794 0.1778)
							(mid -0.249642 0.249642)
							(end -0.1778 0.2794)
						)
						(arc
							(start 0.1778 0.2794)
							(mid 0.249642 0.249642)
							(end 0.2794 0.1778)
						)
						(arc
							(start 0.2794 -0.1778)
							(mid 0.249642 -0.249642)
							(end 0.1778 -0.2794)
						)
					)
					(width 0)
					(fill yes)
				)
			)
		)
	)
	(footprint ""
		(layer "F.Cu")
		(at 51.181 -181.483 90)
		(property "Reference" "U33"
			(at 0 0 90)
			(layer "F.SilkS")
			(hide yes)
			(effects
				(font
					(size 1.27 1.27)
				)
			)
		)
		(property "Value" "PCA9511ADP-T-GP"
			(at 0 -13.1572 90)
			(unlocked yes)
			(layer "F.Fab")
			(hide yes)
			(effects
				(font
					(size 1.016 1.016)
					(thickness 0.1524)
				)
			)
		)
		(property "Device Type" "SSOIC8-2H44"
			(at 0 -15.1892 90)
			(unlocked yes)
			(layer "F.Fab")
			(hide yes)
			(effects
				(font
					(size 1.016 1.016)
					(thickness 0.1524)
				)
			)
		)
		(duplicate_pad_numbers_are_jumpers no)
		(fp_line
			(start 1.0922 -1.016)
			(end 1.0922 1.016)
			(stroke
				(width 0.1524)
				(type default)
			)
			(layer "F.SilkS")
		)
		(fp_line
			(start -1.9304 -1.016)
			(end 1.0922 -1.016)
			(stroke
				(width 0.1524)
				(type default)
			)
			(layer "F.SilkS")
		)
		(fp_line
			(start -1.524 0)
			(end -1.9304 -0.4064)
			(stroke
				(width 0.1524)
				(type default)
			)
			(layer "F.SilkS")
		)
		(fp_line
			(start -1.524 0)
			(end -1.9304 0.4064)
			(stroke
				(width 0.1524)
				(type default)
			)
			(layer "F.SilkS")
		)
		(fp_line
			(start 1.0922 1.016)
			(end -1.9304 1.016)
			(stroke
				(width 0.1524)
				(type default)
			)
			(layer "F.SilkS")
		)
		(fp_line
			(start -1.9304 1.016)
			(end -1.9304 -1.016)
			(stroke
				(width 0.1524)
				(type default)
			)
			(layer "F.SilkS")
		)
		(fp_line
			(start -1.7018 1.0414)
			(end -1.7018 2.9718)
			(stroke
				(width 0.635)
				(type default)
			)
			(layer "F.SilkS")
		)
		(fp_poly
			(pts
				(xy -1.1938 -1.016) (xy 1.0922 -1.016) (xy 1.0922 1.016) (xy -1.1938 1.016)
			)
			(stroke
				(width 0)
				(type default)
			)
			(fill yes)
			(layer "F.SilkS")
		)
		(fp_rect
			(start -2.0066 3.3401)
			(end 2.0066 -3.3401)
			(stroke
				(width 0)
				(type default)
			)
			(fill no)
			(layer "F.CrtYd")
		)
		(fp_poly
			(pts
				(xy -2.0066 -3.3401) (xy 2.0066 -3.3401) (xy 2.0066 3.3401) (xy -2.0066 3.3401)
			)
			(stroke
				(width 0)
				(type default)
			)
			(fill no)
			(layer "F.Fab")
		)
		(pad "1" smd rect
			(at -0.97536 2.0701 90)
			(size 0.4064 1.524)
			(layers "F.Cu" "F.Mask" "F.Paste")
			(net "I2C8_BUFF_EN")
		)
		(pad "2" smd rect
			(at -0.32512 2.0701 90)
			(size 0.4064 1.524)
			(layers "F.Cu" "F.Mask" "F.Paste")
			(net "BMC_I2C8_CLKBUF1_SCL_R")
		)
		(pad "3" smd rect
			(at 0.32512 2.0701 90)
			(size 0.4064 1.524)
			(layers "F.Cu" "F.Mask" "F.Paste")
			(net "BUF_I2C8_CLKBUF1_SCL_R")
		)
		(pad "4" smd rect
			(at 0.97536 2.0701 90)
			(size 0.4064 1.524)
			(layers "F.Cu" "F.Mask" "F.Paste")
			(net "GND")
		)
		(pad "5" smd rect
			(at 0.97536 -2.0701 90)
			(size 0.4064 1.524)
			(layers "F.Cu" "F.Mask" "F.Paste")
			(net "I2C8_BUF_READY")
		)
		(pad "6" smd rect
			(at 0.32512 -2.0701 90)
			(size 0.4064 1.524)
			(layers "F.Cu" "F.Mask" "F.Paste")
			(net "BUF_I2C8_CLKBUF1_SDA_R")
		)
		(pad "7" smd rect
			(at -0.32512 -2.0701 90)
			(size 0.4064 1.524)
			(layers "F.Cu" "F.Mask" "F.Paste")
			(net "BMC_I2C8_CLKBUF1_SDA_R")
		)
		(pad "8" smd rect
			(at -0.97536 -2.0701 90)
			(size 0.4064 1.524)
			(layers "F.Cu" "F.Mask" "F.Paste")
			(net "P3V3_STBY")
		)
	)
	(footprint ""
		(layer "F.Cu")
		(at 12.6365 -50.8254 -90)
		(property "Reference" "D12"
			(at 0 0 270)
			(layer "F.SilkS")
			(hide yes)
			(effects
				(font
					(size 1.27 1.27)
				)
			)
		)
		(property "Value" "PGB1010603MR-GP"
			(at -0.0254 -2.8956 270)
			(unlocked yes)
			(layer "F.Fab")
			(hide yes)
			(effects
				(font
					(size 1.016 1.016)
					(thickness 0.1524)
				)
			)
		)
		(property "Device Type" "L1608-UH15"
			(at -0.0254 -4.4196 270)
			(unlocked yes)
			(layer "F.Fab")
			(hide yes)
			(effects
				(font
					(size 1.016 1.016)
					(thickness 0.1524)
				)
			)
		)
		(duplicate_pad_numbers_are_jumpers no)
		(fp_line
			(start 0.254 0)
			(end -0.254 0)
			(stroke
				(width 0.2032)
				(type default)
			)
			(layer "F.SilkS")
		)
		(fp_rect
			(start -0.5842 1.3335)
			(end 0.5842 -1.3335)
			(stroke
				(width 0)
				(type default)
			)
			(fill no)
			(layer "F.CrtYd")
		)
		(fp_rect
			(start -0.5842 1.3335)
			(end 0.5842 -1.3335)
			(stroke
				(width 0)
				(type default)
			)
			(fill no)
			(layer "F.Fab")
		)
		(pad "1" smd custom
			(at 0 -0.762 270)
			(size 0.2159 0.2159)
			(layers "F.Cu" "F.Mask" "F.Paste")
			(net "NIC0_MDI0_N1_R")
			(options
				(clearance outline)
				(anchor circle)
			)
			(primitives
				(gr_poly
					(pts
						(arc
							(start -0.3302 -0.4318)
							(mid -0.402042 -0.402042)
							(end -0.4318 -0.3302)
						)
						(arc
							(start -0.4318 0.3302)
							(mid -0.402042 0.402042)
							(end -0.3302 0.4318)
						)
						(arc
							(start 0.3302 0.4318)
							(mid 0.402042 0.402042)
							(end 0.4318 0.3302)
						)
						(arc
							(start 0.4318 -0.3302)
							(mid 0.402042 -0.402042)
							(end 0.3302 -0.4318)
						)
					)
					(width 0)
					(fill yes)
				)
			)
		)
		(pad "2" smd custom
			(at 0 0.762 270)
			(size 0.2159 0.2159)
			(layers "F.Cu" "F.Mask" "F.Paste")
			(net "GND")
			(options
				(clearance outline)
				(anchor circle)
			)
			(primitives
				(gr_poly
					(pts
						(arc
							(start -0.3302 -0.4318)
							(mid -0.402042 -0.402042)
							(end -0.4318 -0.3302)
						)
						(arc
							(start -0.4318 0.3302)
							(mid -0.402042 0.402042)
							(end -0.3302 0.4318)
						)
						(arc
							(start 0.3302 0.4318)
							(mid 0.402042 0.402042)
							(end 0.4318 0.3302)
						)
						(arc
							(start 0.4318 -0.3302)
							(mid 0.402042 -0.402042)
							(end 0.3302 -0.4318)
						)
					)
					(width 0)
					(fill yes)
				)
			)
		)
	)
	(footprint ""
		(layer "F.Cu")
		(at 157.318202 -58.447432 180)
		(property "Reference" "PC204"
			(at 0 0 180)
			(layer "F.SilkS")
			(hide yes)
			(effects
				(font
					(size 1.27 1.27)
				)
			)
		)
		(property "Value" "SC1U10V2KX-1GP"
			(at 1.1811 -2.7051 180)
			(unlocked yes)
			(layer "F.Fab")
			(hide yes)
			(effects
				(font
					(size 1.016 1.016)
					(thickness 0.1524)
				)
			)
		)
		(property "Device Type" "C402H22"
			(at 1.1811 -4.2291 180)
			(unlocked yes)
			(layer "F.Fab")
			(hide yes)
			(effects
				(font
					(size 1.016 1.016)
					(thickness 0.1524)
				)
			)
		)
		(duplicate_pad_numbers_are_jumpers no)
		(fp_rect
			(start -0.4318 0.9525)
			(end 0.4318 -0.9525)
			(stroke
				(width 0)
				(type default)
			)
			(fill no)
			(layer "F.CrtYd")
		)
		(fp_rect
			(start -0.4318 0.9525)
			(end 0.4318 -0.9525)
			(stroke
				(width 0)
				(type default)
			)
			(fill no)
			(layer "F.Fab")
		)
		(pad "1" smd custom
			(at 0 -0.4445 180)
			(size 0.1524 0.1524)
			(layers "F.Cu" "F.Mask" "F.Paste")
			(net "GND")
			(options
				(clearance outline)
				(anchor circle)
			)
			(primitives
				(gr_poly
					(pts
						(arc
							(start 0.3048 -0.2032)
							(mid 0.275042 -0.275042)
							(end 0.2032 -0.3048)
						)
						(arc
							(start -0.2032 -0.3048)
							(mid -0.275042 -0.275042)
							(end -0.3048 -0.2032)
						)
						(arc
							(start -0.3048 0.2032)
							(mid -0.275042 0.275042)
							(end -0.2032 0.3048)
						)
						(arc
							(start 0.2032 0.3048)
							(mid 0.275042 0.275042)
							(end 0.3048 0.2032)
						)
					)
					(width 0)
					(fill yes)
				)
			)
		)
		(pad "2" smd custom
			(at 0 0.4445 180)
			(size 0.1524 0.1524)
			(layers "F.Cu" "F.Mask" "F.Paste")
			(net "P0V9_EN")
			(options
				(clearance outline)
				(anchor circle)
			)
			(primitives
				(gr_poly
					(pts
						(arc
							(start 0.3048 -0.2032)
							(mid 0.275042 -0.275042)
							(end 0.2032 -0.3048)
						)
						(arc
							(start -0.2032 -0.3048)
							(mid -0.275042 -0.275042)
							(end -0.3048 -0.2032)
						)
						(arc
							(start -0.3048 0.2032)
							(mid -0.275042 0.275042)
							(end -0.2032 0.3048)
						)
						(arc
							(start 0.2032 0.3048)
							(mid 0.275042 0.275042)
							(end 0.3048 0.2032)
						)
					)
					(width 0)
					(fill yes)
				)
			)
		)
	)
	(footprint ""
		(layer "F.Cu")
		(at 313.563 -54.483)
		(property "Reference" "PTC5"
			(at 0 0 0)
			(layer "F.SilkS")
			(hide yes)
			(effects
				(font
					(size 1.27 1.27)
				)
			)
		)
		(property "Value" "SE470UF2VDM-GP"
			(at 0 -9.6012 0)
			(unlocked yes)
			(layer "F.Fab")
			(hide yes)
			(effects
				(font
					(size 1.016 1.016)
					(thickness 0.1524)
				)
			)
		)
		(property "Device Type" "CT7343H83"
			(at 0 -11.1252 0)
			(unlocked yes)
			(layer "F.Fab")
			(hide yes)
			(effects
				(font
					(size 1.016 1.016)
					(thickness 0.1524)
				)
			)
		)
		(duplicate_pad_numbers_are_jumpers no)
		(fp_line
			(start -2.286 -4.8768)
			(end -2.286 -2.032)
			(stroke
				(width 0.1524)
				(type default)
			)
			(layer "F.SilkS")
		)
		(fp_line
			(start -2.286 4.8768)
			(end -2.286 2.032)
			(stroke
				(width 0.1524)
				(type default)
			)
			(layer "F.SilkS")
		)
		(fp_line
			(start 2.1082 -4.699)
			(end -2.1082 -4.699)
			(stroke
				(width 0.508)
				(type default)
			)
			(layer "F.SilkS")
		)
		(fp_line
			(start 2.286 -4.8768)
			(end -2.286 -4.8768)
			(stroke
				(width 0.1524)
				(type default)
			)
			(layer "F.SilkS")
		)
		(fp_line
			(start 2.286 -2.032)
			(end 2.286 -4.8768)
			(stroke
				(width 0.1524)
				(type default)
			)
			(layer "F.SilkS")
		)
		(fp_line
			(start 2.286 2.032)
			(end 2.286 4.8768)
			(stroke
				(width 0.1524)
				(type default)
			)
			(layer "F.SilkS")
		)
		(fp_line
			(start 2.286 4.8768)
			(end -2.286 4.8768)
			(stroke
				(width 0.1524)
				(type default)
			)
			(layer "F.SilkS")
		)
		(fp_rect
			(start -2.1463 3.6449)
			(end 2.1463 -3.6449)
			(stroke
				(width 0)
				(type default)
			)
			(fill no)
			(layer "F.CrtYd")
		)
		(fp_poly
			(pts
				(xy -2.54 4.953) (xy -2.54 4.2926) (xy -3.81 4.2926) (xy -3.81 -4.2926) (xy -2.54 -4.2926) (xy -2.54 -4.953)
				(xy 2.54 -4.953) (xy 2.54 -4.2926) (xy 3.81 -4.2926) (xy 3.81 -1.6256) (xy 2.1463 -1.6256) (xy 2.1463 -3.6449)
				(xy -2.1463 -3.6449) (xy -2.1463 3.6449) (xy 2.1463 3.6449) (xy 2.1463 -1.6129) (xy 3.81 -1.6129)
				(xy 3.81 4.2926) (xy 2.54 4.2926) (xy 2.54 4.953)
			)
			(stroke
				(width 0)
				(type default)
			)
			(fill no)
			(layer "F.CrtYd")
		)
		(fp_rect
			(start -3.81 4.2926)
			(end -2.54 -4.2926)
			(stroke
				(width 0)
				(type default)
			)
			(fill no)
			(layer "F.Fab")
		)
		(fp_rect
			(start -2.54 4.953)
			(end 2.54 -4.953)
			(stroke
				(width 0)
				(type default)
			)
			(fill no)
			(layer "F.Fab")
		)
		(fp_rect
			(start 2.54 4.2926)
			(end 3.81 -4.2926)
			(stroke
				(width 0)
				(type default)
			)
			(fill no)
			(layer "F.Fab")
		)
		(pad "1" smd rect
			(at 0 -3.1496)
			(size 2.413 2.286)
			(layers "F.Cu" "F.Mask" "F.Paste")
			(net "P0V9_E")
		)
		(pad "2" smd rect
			(at 0 3.1496)
			(size 2.413 2.286)
			(layers "F.Cu" "F.Mask" "F.Paste")
			(net "GND")
		)
		(zone
			(layer "F.Cu")
			(hatch none 0.5)
			(connect_pads
				(clearance 0)
			)
			(min_thickness 0.25)
			(keepout
				(tracks allowed)
				(vias not_allowed)
				(pads allowed)
				(copperpour not_allowed)
				(footprints allowed)
			)
			(placement
				(enabled no)
				(sheetname "")
			)
			(fill
				(thermal_gap 0.5)
				(thermal_bridge_width 0.5)
				(island_removal_mode 0)
			)
			(polygon
				(pts
					(xy 312.0517 -49.8856) (xy 315.0743 -49.8856) (xy 315.0743 -52.7812) (xy 315.0743 -53.1114) (xy 312.0517 -53.1114)
					(xy 312.0517 -52.7812)
				)
			)
		)
		(zone
			(layer "F.Cu")
			(hatch none 0.5)
			(connect_pads
				(clearance 0)
			)
			(min_thickness 0.25)
			(keepout
				(tracks allowed)
				(vias not_allowed)
				(pads allowed)
				(copperpour not_allowed)
				(footprints allowed)
			)
			(placement
				(enabled no)
				(sheetname "")
			)
			(fill
				(thermal_gap 0.5)
				(thermal_bridge_width 0.5)
				(island_removal_mode 0)
			)
			(polygon
				(pts
					(xy 315.0743 -56.1721) (xy 315.0743 -59.0804) (xy 312.0517 -59.0804) (xy 312.0517 -56.1848) (xy 312.0517 -55.8546)
					(xy 315.0743 -55.8546)
				)
			)
		)
	)
	(footprint ""
		(layer "F.Cu")
		(at 310.007 -61.6966)
		(property "Reference" "PG45"
			(at 0 0 0)
			(layer "F.SilkS")
			(hide yes)
			(effects
				(font
					(size 1.27 1.27)
				)
			)
		)
		(property "Value" "GAP-CLOSE-PWR-3-GP"
			(at 0.0254 -6.5786 0)
			(unlocked yes)
			(layer "F.Fab")
			(hide yes)
			(effects
				(font
					(size 1.016 1.016)
					(thickness 0.1524)
				)
			)
		)
		(property "Device Type" "GAP-CLOSE-PWR-3"
			(at 0.0254 -8.255 0)
			(unlocked yes)
			(layer "F.Fab")
			(hide yes)
			(effects
				(font
					(size 1.016 1.016)
					(thickness 0.1524)
				)
			)
		)
		(duplicate_pad_numbers_are_jumpers no)
		(fp_rect
			(start -0.7112 0.4572)
			(end 0.7112 -0.4572)
			(stroke
				(width 0)
				(type default)
			)
			(fill no)
			(layer "F.CrtYd")
		)
		(fp_poly
			(pts
				(xy -0.7112 -0.4572) (xy 0.7112 -0.4572) (xy 0.7112 0.4572) (xy -0.7112 0.4572)
			)
			(stroke
				(width 0)
				(type default)
			)
			(fill no)
			(layer "F.Fab")
		)
		(pad "1" smd rect
			(at -0.3048 0)
			(size 0.6604 0.762)
			(layers "F.Cu" "F.Mask" "F.Paste")
			(net "DUT_VDD")
		)
		(pad "2" smd rect
			(at 0.3048 0)
			(size 0.6604 0.762)
			(layers "F.Cu" "F.Mask" "F.Paste")
			(net "P0V9_E")
		)
	)
	(footprint ""
		(layer "F.Cu")
		(at 8.001 -55.5498 180)
		(property "Reference" "C421"
			(at 0 0 180)
			(layer "F.SilkS")
			(hide yes)
			(effects
				(font
					(size 1.27 1.27)
				)
			)
		)
		(property "Value" "SCD1U16V2KX-3GP"
			(at 1.1811 -2.7051 180)
			(unlocked yes)
			(layer "F.Fab")
			(hide yes)
			(effects
				(font
					(size 1.016 1.016)
					(thickness 0.1524)
				)
			)
		)
		(property "Device Type" "C402H22"
			(at 1.1811 -4.2291 180)
			(unlocked yes)
			(layer "F.Fab")
			(hide yes)
			(effects
				(font
					(size 1.016 1.016)
					(thickness 0.1524)
				)
			)
		)
		(duplicate_pad_numbers_are_jumpers no)
		(fp_rect
			(start -0.4318 0.9525)
			(end 0.4318 -0.9525)
			(stroke
				(width 0)
				(type default)
			)
			(fill no)
			(layer "F.CrtYd")
		)
		(fp_rect
			(start -0.4318 0.9525)
			(end 0.4318 -0.9525)
			(stroke
				(width 0)
				(type default)
			)
			(fill no)
			(layer "F.Fab")
		)
		(pad "1" smd custom
			(at 0 -0.4445 180)
			(size 0.1524 0.1524)
			(layers "F.Cu" "F.Mask" "F.Paste")
			(net "LED_MDI0_LINK_N")
			(options
				(clearance outline)
				(anchor circle)
			)
			(primitives
				(gr_poly
					(pts
						(arc
							(start 0.3048 -0.2032)
							(mid 0.275042 -0.275042)
							(end 0.2032 -0.3048)
						)
						(arc
							(start -0.2032 -0.3048)
							(mid -0.275042 -0.275042)
							(end -0.3048 -0.2032)
						)
						(arc
							(start -0.3048 0.2032)
							(mid -0.275042 0.275042)
							(end -0.2032 0.3048)
						)
						(arc
							(start 0.2032 0.3048)
							(mid 0.275042 0.275042)
							(end 0.3048 0.2032)
						)
					)
					(width 0)
					(fill yes)
				)
			)
		)
		(pad "2" smd custom
			(at 0 0.4445 180)
			(size 0.1524 0.1524)
			(layers "F.Cu" "F.Mask" "F.Paste")
			(net "GND")
			(options
				(clearance outline)
				(anchor circle)
			)
			(primitives
				(gr_poly
					(pts
						(arc
							(start 0.3048 -0.2032)
							(mid 0.275042 -0.275042)
							(end 0.2032 -0.3048)
						)
						(arc
							(start -0.2032 -0.3048)
							(mid -0.275042 -0.275042)
							(end -0.3048 -0.2032)
						)
						(arc
							(start -0.3048 0.2032)
							(mid -0.275042 0.275042)
							(end -0.2032 0.3048)
						)
						(arc
							(start 0.2032 0.3048)
							(mid 0.275042 0.275042)
							(end 0.3048 0.2032)
						)
					)
					(width 0)
					(fill yes)
				)
			)
		)
	)
	(footprint ""
		(layer "F.Cu")
		(at 119.4308 -17.0688 180)
		(property "Reference" "R752"
			(at 0 0 180)
			(layer "F.SilkS")
			(hide yes)
			(effects
				(font
					(size 1.27 1.27)
				)
			)
		)
		(property "Value" "4K7R2F-GP"
			(at 0.064008 -3.993896 180)
			(unlocked yes)
			(layer "F.Fab")
			(hide yes)
			(effects
				(font
					(size 1.016 1.016)
					(thickness 0.1524)
				)
			)
		)
		(property "Device Type" "R402H16"
			(at 0.064008 -5.517896 180)
			(unlocked yes)
			(layer "F.Fab")
			(hide yes)
			(effects
				(font
					(size 1.016 1.016)
					(thickness 0.1524)
				)
			)
		)
		(duplicate_pad_numbers_are_jumpers no)
		(fp_line
			(start 0.508 -0.9398)
			(end -0.508 -0.9398)
			(stroke
				(width 0.1524)
				(type default)
			)
			(layer "F.SilkS")
		)
		(fp_line
			(start -0.508 -0.9398)
			(end -0.508 0.9398)
			(stroke
				(width 0.1524)
				(type default)
			)
			(layer "F.SilkS")
		)
		(fp_rect
			(start -0.508 0.9398)
			(end 0.508 -0.9398)
			(stroke
				(width 0)
				(type default)
			)
			(fill no)
			(layer "F.CrtYd")
		)
		(fp_rect
			(start -0.508 0.9398)
			(end 0.508 -0.9398)
			(stroke
				(width 0)
				(type default)
			)
			(fill no)
			(layer "F.Fab")
		)
		(pad "1" smd custom
			(at 0 -0.4445 180)
			(size 0.1397 0.1397)
			(layers "F.Cu" "F.Mask" "F.Paste")
			(net "GND")
			(options
				(clearance outline)
				(anchor circle)
			)
			(primitives
				(gr_poly
					(pts
						(arc
							(start -0.1778 -0.2794)
							(mid -0.249642 -0.249642)
							(end -0.2794 -0.1778)
						)
						(arc
							(start -0.2794 0.1778)
							(mid -0.249642 0.249642)
							(end -0.1778 0.2794)
						)
						(arc
							(start 0.1778 0.2794)
							(mid 0.249642 0.249642)
							(end 0.2794 0.1778)
						)
						(arc
							(start 0.2794 -0.1778)
							(mid 0.249642 -0.249642)
							(end 0.1778 -0.2794)
						)
					)
					(width 0)
					(fill yes)
				)
			)
		)
		(pad "2" smd custom
			(at 0 0.4445 180)
			(size 0.1397 0.1397)
			(layers "F.Cu" "F.Mask" "F.Paste")
			(net "U54_A1")
			(options
				(clearance outline)
				(anchor circle)
			)
			(primitives
				(gr_poly
					(pts
						(arc
							(start -0.1778 -0.2794)
							(mid -0.249642 -0.249642)
							(end -0.2794 -0.1778)
						)
						(arc
							(start -0.2794 0.1778)
							(mid -0.249642 0.249642)
							(end -0.1778 0.2794)
						)
						(arc
							(start 0.1778 0.2794)
							(mid 0.249642 0.249642)
							(end 0.2794 0.1778)
						)
						(arc
							(start 0.2794 -0.1778)
							(mid 0.249642 -0.249642)
							(end 0.1778 -0.2794)
						)
					)
					(width 0)
					(fill yes)
				)
			)
		)
	)
	(footprint ""
		(layer "F.Cu")
		(at 34.08172 -79.048356 90)
		(property "Reference" "PR1"
			(at 0 0 90)
			(layer "F.SilkS")
			(hide yes)
			(effects
				(font
					(size 1.27 1.27)
				)
			)
		)
		(property "Value" "13K3R2F-L1-GP"
			(at 0.064008 -3.993896 90)
			(unlocked yes)
			(layer "F.Fab")
			(hide yes)
			(effects
				(font
					(size 1.016 1.016)
					(thickness 0.1524)
				)
			)
		)
		(property "Device Type" "R402H16"
			(at 0.064008 -5.517896 90)
			(unlocked yes)
			(layer "F.Fab")
			(hide yes)
			(effects
				(font
					(size 1.016 1.016)
					(thickness 0.1524)
				)
			)
		)
		(duplicate_pad_numbers_are_jumpers no)
		(fp_line
			(start 0.508 -0.9398)
			(end -0.508 -0.9398)
			(stroke
				(width 0.1524)
				(type default)
			)
			(layer "F.SilkS")
		)
		(fp_line
			(start -0.508 -0.9398)
			(end -0.508 0.9398)
			(stroke
				(width 0.1524)
				(type default)
			)
			(layer "F.SilkS")
		)
		(fp_rect
			(start -0.508 0.9398)
			(end 0.508 -0.9398)
			(stroke
				(width 0)
				(type default)
			)
			(fill no)
			(layer "F.CrtYd")
		)
		(fp_rect
			(start -0.508 0.9398)
			(end 0.508 -0.9398)
			(stroke
				(width 0)
				(type default)
			)
			(fill no)
			(layer "F.Fab")
		)
		(pad "1" smd custom
			(at 0 -0.4445 90)
			(size 0.1397 0.1397)
			(layers "F.Cu" "F.Mask" "F.Paste")
			(net "P5V_STBY_FB")
			(options
				(clearance outline)
				(anchor circle)
			)
			(primitives
				(gr_poly
					(pts
						(arc
							(start -0.1778 -0.2794)
							(mid -0.249642 -0.249642)
							(end -0.2794 -0.1778)
						)
						(arc
							(start -0.2794 0.1778)
							(mid -0.249642 0.249642)
							(end -0.1778 0.2794)
						)
						(arc
							(start 0.1778 0.2794)
							(mid 0.249642 0.249642)
							(end 0.2794 0.1778)
						)
						(arc
							(start 0.2794 -0.1778)
							(mid 0.249642 -0.249642)
							(end 0.1778 -0.2794)
						)
					)
					(width 0)
					(fill yes)
				)
			)
		)
		(pad "2" smd custom
			(at 0 0.4445 90)
			(size 0.1397 0.1397)
			(layers "F.Cu" "F.Mask" "F.Paste")
			(net "GND")
			(options
				(clearance outline)
				(anchor circle)
			)
			(primitives
				(gr_poly
					(pts
						(arc
							(start -0.1778 -0.2794)
							(mid -0.249642 -0.249642)
							(end -0.2794 -0.1778)
						)
						(arc
							(start -0.2794 0.1778)
							(mid -0.249642 0.249642)
							(end -0.1778 0.2794)
						)
						(arc
							(start 0.1778 0.2794)
							(mid 0.249642 0.249642)
							(end 0.2794 0.1778)
						)
						(arc
							(start 0.2794 -0.1778)
							(mid 0.249642 -0.249642)
							(end 0.1778 -0.2794)
						)
					)
					(width 0)
					(fill yes)
				)
			)
		)
	)
	(footprint ""
		(layer "F.Cu")
		(at 68.8594 -123.3932 -90)
		(property "Reference" "R309"
			(at 0 0 270)
			(layer "F.SilkS")
			(hide yes)
			(effects
				(font
					(size 1.27 1.27)
				)
			)
		)
		(property "Value" "4K7R2F-GP"
			(at 0.064008 -3.993896 270)
			(unlocked yes)
			(layer "F.Fab")
			(hide yes)
			(effects
				(font
					(size 1.016 1.016)
					(thickness 0.1524)
				)
			)
		)
		(property "Device Type" "R402H16"
			(at 0.064008 -5.517896 270)
			(unlocked yes)
			(layer "F.Fab")
			(hide yes)
			(effects
				(font
					(size 1.016 1.016)
					(thickness 0.1524)
				)
			)
		)
		(duplicate_pad_numbers_are_jumpers no)
		(fp_line
			(start -0.508 -0.9398)
			(end -0.508 0.9398)
			(stroke
				(width 0.1524)
				(type default)
			)
			(layer "F.SilkS")
		)
		(fp_line
			(start 0.508 -0.9398)
			(end -0.508 -0.9398)
			(stroke
				(width 0.1524)
				(type default)
			)
			(layer "F.SilkS")
		)
		(fp_rect
			(start -0.508 0.9398)
			(end 0.508 -0.9398)
			(stroke
				(width 0)
				(type default)
			)
			(fill no)
			(layer "F.CrtYd")
		)
		(fp_rect
			(start -0.508 0.9398)
			(end 0.508 -0.9398)
			(stroke
				(width 0)
				(type default)
			)
			(fill no)
			(layer "F.Fab")
		)
		(pad "1" smd custom
			(at 0 -0.4445 270)
			(size 0.1397 0.1397)
			(layers "F.Cu" "F.Mask" "F.Paste")
			(net "P3V3_STBY")
			(options
				(clearance outline)
				(anchor circle)
			)
			(primitives
				(gr_poly
					(pts
						(arc
							(start -0.1778 -0.2794)
							(mid -0.249642 -0.249642)
							(end -0.2794 -0.1778)
						)
						(arc
							(start -0.2794 0.1778)
							(mid -0.249642 0.249642)
							(end -0.1778 0.2794)
						)
						(arc
							(start 0.1778 0.2794)
							(mid 0.249642 0.249642)
							(end 0.2794 0.1778)
						)
						(arc
							(start 0.2794 -0.1778)
							(mid 0.249642 -0.249642)
							(end 0.1778 -0.2794)
						)
					)
					(width 0)
					(fill yes)
				)
			)
		)
		(pad "2" smd custom
			(at 0 0.4445 270)
			(size 0.1397 0.1397)
			(layers "F.Cu" "F.Mask" "F.Paste")
			(net "I2C4_LS_G1")
			(options
				(clearance outline)
				(anchor circle)
			)
			(primitives
				(gr_poly
					(pts
						(arc
							(start -0.1778 -0.2794)
							(mid -0.249642 -0.249642)
							(end -0.2794 -0.1778)
						)
						(arc
							(start -0.2794 0.1778)
							(mid -0.249642 0.249642)
							(end -0.1778 0.2794)
						)
						(arc
							(start 0.1778 0.2794)
							(mid 0.249642 0.249642)
							(end 0.2794 0.1778)
						)
						(arc
							(start 0.2794 -0.1778)
							(mid 0.249642 -0.249642)
							(end 0.1778 -0.2794)
						)
					)
					(width 0)
					(fill yes)
				)
			)
		)
	)
	(footprint ""
		(layer "F.Cu")
		(at 125.832362 -39.469568 180)
		(property "Reference" "Q26"
			(at 0 0 180)
			(layer "F.SilkS")
			(hide yes)
			(effects
				(font
					(size 1.27 1.27)
				)
			)
		)
		(property "Value" "2N7002K-1-GP"
			(at 0.127 -8.9662 180)
			(unlocked yes)
			(layer "F.Fab")
			(hide yes)
			(effects
				(font
					(size 1.016 1.016)
					(thickness 0.1524)
				)
			)
		)
		(property "Device Type" "SOT23DGS2D4H44"
			(at 0.127 -10.4902 180)
			(unlocked yes)
			(layer "F.Fab")
			(hide yes)
			(effects
				(font
					(size 1.016 1.016)
					(thickness 0.1524)
				)
			)
		)
		(duplicate_pad_numbers_are_jumpers no)
		(fp_line
			(start 1.651 1.778)
			(end 1.651 -1.778)
			(stroke
				(width 0.1524)
				(type default)
			)
			(layer "F.SilkS")
		)
		(fp_line
			(start 1.651 -1.778)
			(end -1.651 -1.778)
			(stroke
				(width 0.1524)
				(type default)
			)
			(layer "F.SilkS")
		)
		(fp_line
			(start -1.651 1.778)
			(end 1.651 1.778)
			(stroke
				(width 0.1524)
				(type default)
			)
			(layer "F.SilkS")
		)
		(fp_line
			(start -1.651 -1.778)
			(end -1.651 1.778)
			(stroke
				(width 0.1524)
				(type default)
			)
			(layer "F.SilkS")
		)
		(fp_poly
			(pts
				(xy -1.778 1.8796) (xy -1.778 -1.8796) (xy 1.778 -1.8796) (xy 1.778 1.8796)
			)
			(stroke
				(width 0)
				(type default)
			)
			(fill no)
			(layer "F.CrtYd")
		)
		(fp_poly
			(pts
				(xy -1.778 1.8796) (xy -1.778 -1.8796) (xy 1.778 -1.8796) (xy 1.778 1.8796)
			)
			(stroke
				(width 0)
				(type default)
			)
			(fill no)
			(layer "F.Fab")
		)
		(pad "D" smd custom
			(at 0 -0.9525 180)
			(size 0.1905 0.1905)
			(layers "F.Cu" "F.Mask" "F.Paste")
			(net "LED_Q_3")
			(options
				(clearance outline)
				(anchor circle)
			)
			(primitives
				(gr_poly
					(pts
						(arc
							(start -0.1778 0.5715)
							(mid -0.321484 0.511984)
							(end -0.381 0.3683)
						)
						(arc
							(start -0.381 -0.3683)
							(mid -0.321484 -0.511984)
							(end -0.1778 -0.5715)
						)
						(arc
							(start 0.1778 -0.5715)
							(mid 0.321484 -0.511984)
							(end 0.381 -0.3683)
						)
						(arc
							(start 0.381 0.3683)
							(mid 0.321484 0.511984)
							(end 0.1778 0.5715)
						)
					)
					(width 0)
					(fill yes)
				)
			)
		)
		(pad "G" smd custom
			(at -0.98425 0.9525 180)
			(size 0.1905 0.1905)
			(layers "F.Cu" "F.Mask" "F.Paste")
			(net "UPLINK3_R")
			(options
				(clearance outline)
				(anchor circle)
			)
			(primitives
				(gr_poly
					(pts
						(arc
							(start -0.1778 0.5715)
							(mid -0.321484 0.511984)
							(end -0.381 0.3683)
						)
						(arc
							(start -0.381 -0.3683)
							(mid -0.321484 -0.511984)
							(end -0.1778 -0.5715)
						)
						(arc
							(start 0.1778 -0.5715)
							(mid 0.321484 -0.511984)
							(end 0.381 -0.3683)
						)
						(arc
							(start 0.381 0.3683)
							(mid 0.321484 0.511984)
							(end 0.1778 0.5715)
						)
					)
					(width 0)
					(fill yes)
				)
			)
		)
		(pad "S" smd custom
			(at 0.98425 0.9525 180)
			(size 0.1905 0.1905)
			(layers "F.Cu" "F.Mask" "F.Paste")
			(net "GND")
			(options
				(clearance outline)
				(anchor circle)
			)
			(primitives
				(gr_poly
					(pts
						(arc
							(start -0.1778 0.5715)
							(mid -0.321484 0.511984)
							(end -0.381 0.3683)
						)
						(arc
							(start -0.381 -0.3683)
							(mid -0.321484 -0.511984)
							(end -0.1778 -0.5715)
						)
						(arc
							(start 0.1778 -0.5715)
							(mid 0.321484 -0.511984)
							(end 0.381 -0.3683)
						)
						(arc
							(start 0.381 0.3683)
							(mid 0.321484 0.511984)
							(end 0.1778 0.5715)
						)
					)
					(width 0)
					(fill yes)
				)
			)
		)
	)
	(footprint ""
		(layer "F.Cu")
		(at 211.455 -0.508 -90)
		(property "Reference" "R5774"
			(at 0 0 270)
			(layer "F.SilkS")
			(hide yes)
			(effects
				(font
					(size 1.27 1.27)
				)
			)
		)
		(property "Value" "330R1210J-GP"
			(at 0.0889 -6.9977 270)
			(unlocked yes)
			(layer "F.Fab")
			(hide yes)
			(effects
				(font
					(size 1.016 1.016)
					(thickness 0.1524)
				)
			)
		)
		(property "Device Type" "R1210H24"
			(at 0.0635 -8.636 270)
			(unlocked yes)
			(layer "F.Fab")
			(hide yes)
			(effects
				(font
					(size 1.016 1.016)
					(thickness 0.1524)
				)
			)
		)
		(duplicate_pad_numbers_are_jumpers no)
		(fp_line
			(start -1.651 2.413)
			(end -1.651 -2.413)
			(stroke
				(width 0.1524)
				(type default)
			)
			(layer "F.SilkS")
		)
		(fp_line
			(start 1.651 2.413)
			(end -1.651 2.413)
			(stroke
				(width 0.1524)
				(type default)
			)
			(layer "F.SilkS")
		)
		(fp_line
			(start -1.651 -2.413)
			(end 1.651 -2.413)
			(stroke
				(width 0.1524)
				(type default)
			)
			(layer "F.SilkS")
		)
		(fp_line
			(start 1.651 -2.413)
			(end 1.651 2.413)
			(stroke
				(width 0.1524)
				(type default)
			)
			(layer "F.SilkS")
		)
		(fp_poly
			(pts
				(xy -1.651 -2.413) (xy 1.651 -2.413) (xy 1.651 2.413) (xy -1.651 2.413)
			)
			(stroke
				(width 0)
				(type default)
			)
			(fill no)
			(layer "F.CrtYd")
		)
		(fp_poly
			(pts
				(xy -1.651 -2.413) (xy 1.651 -2.413) (xy 1.651 2.413) (xy -1.651 2.413)
			)
			(stroke
				(width 0)
				(type default)
			)
			(fill no)
			(layer "F.Fab")
		)
		(pad "1" smd rect
			(at 0 -1.4732 270)
			(size 2.794 1.397)
			(layers "F.Cu" "F.Mask" "F.Paste")
			(net "P5V_STBY")
		)
		(pad "2" smd rect
			(at 0 1.4732 270)
			(size 2.794 1.397)
			(layers "F.Cu" "F.Mask" "F.Paste")
			(net "LED_PWR_N_R")
		)
	)
	(footprint ""
		(layer "F.Cu")
		(at 185.15584 -4.27482)
		(property "Reference" "R2935"
			(at 0 0 0)
			(layer "F.SilkS")
			(hide yes)
			(effects
				(font
					(size 1.27 1.27)
				)
			)
		)
		(property "Value" "0R2J-2-GP"
			(at 0.064008 -3.993896 0)
			(unlocked yes)
			(layer "F.Fab")
			(hide yes)
			(effects
				(font
					(size 1.016 1.016)
					(thickness 0.1524)
				)
			)
		)
		(property "Device Type" "R402H16"
			(at 0.064008 -5.517896 0)
			(unlocked yes)
			(layer "F.Fab")
			(hide yes)
			(effects
				(font
					(size 1.016 1.016)
					(thickness 0.1524)
				)
			)
		)
		(duplicate_pad_numbers_are_jumpers no)
		(fp_line
			(start -0.508 -0.9398)
			(end -0.508 0.9398)
			(stroke
				(width 0.1524)
				(type default)
			)
			(layer "F.SilkS")
		)
		(fp_line
			(start 0.508 -0.9398)
			(end -0.508 -0.9398)
			(stroke
				(width 0.1524)
				(type default)
			)
			(layer "F.SilkS")
		)
		(fp_rect
			(start -0.508 0.9398)
			(end 0.508 -0.9398)
			(stroke
				(width 0)
				(type default)
			)
			(fill no)
			(layer "F.CrtYd")
		)
		(fp_rect
			(start -0.508 0.9398)
			(end 0.508 -0.9398)
			(stroke
				(width 0)
				(type default)
			)
			(fill no)
			(layer "F.Fab")
		)
		(pad "1" smd custom
			(at 0 -0.4445)
			(size 0.1397 0.1397)
			(layers "F.Cu" "F.Mask" "F.Paste")
			(net "HOST1_RST_N")
			(options
				(clearance outline)
				(anchor circle)
			)
			(primitives
				(gr_poly
					(pts
						(arc
							(start -0.1778 -0.2794)
							(mid -0.249642 -0.249642)
							(end -0.2794 -0.1778)
						)
						(arc
							(start -0.2794 0.1778)
							(mid -0.249642 0.249642)
							(end -0.1778 0.2794)
						)
						(arc
							(start 0.1778 0.2794)
							(mid 0.249642 0.249642)
							(end 0.2794 0.1778)
						)
						(arc
							(start 0.2794 -0.1778)
							(mid 0.249642 -0.249642)
							(end 0.1778 -0.2794)
						)
					)
					(width 0)
					(fill yes)
				)
			)
		)
		(pad "2" smd custom
			(at 0 0.4445)
			(size 0.1397 0.1397)
			(layers "F.Cu" "F.Mask" "F.Paste")
			(net "HOST1_RST_N_C")
			(options
				(clearance outline)
				(anchor circle)
			)
			(primitives
				(gr_poly
					(pts
						(arc
							(start -0.1778 -0.2794)
							(mid -0.249642 -0.249642)
							(end -0.2794 -0.1778)
						)
						(arc
							(start -0.2794 0.1778)
							(mid -0.249642 0.249642)
							(end -0.1778 0.2794)
						)
						(arc
							(start 0.1778 0.2794)
							(mid 0.249642 0.249642)
							(end 0.2794 0.1778)
						)
						(arc
							(start 0.2794 -0.1778)
							(mid 0.249642 -0.249642)
							(end 0.1778 -0.2794)
						)
					)
					(width 0)
					(fill yes)
				)
			)
		)
	)
	(footprint ""
		(layer "F.Cu")
		(at 40.7162 -118.3386)
		(property "Reference" "TP293"
			(at 0 0 0)
			(layer "F.SilkS")
			(hide yes)
			(effects
				(font
					(size 1.27 1.27)
				)
			)
		)
		(property "Value" "TPAD28-2-GP"
			(at -0.0127 -1.6637 0)
			(unlocked yes)
			(layer "F.Fab")
			(hide yes)
			(effects
				(font
					(size 1.016 1.016)
					(thickness 0.1524)
				)
			)
		)
		(property "Device Type" "TPAD28"
			(at -0.0127 -3.1877 0)
			(unlocked yes)
			(layer "F.Fab")
			(hide yes)
			(effects
				(font
					(size 1.016 1.016)
					(thickness 0.1524)
				)
			)
		)
		(duplicate_pad_numbers_are_jumpers no)
		(fp_poly
			(pts
				(arc
					(start 0.3556 0)
					(mid -0.3556 0)
					(end 0.3556 0)
				)
			)
			(stroke
				(width 0)
				(type default)
			)
			(fill no)
			(layer "F.CrtYd")
		)
		(fp_poly
			(pts
				(arc
					(start 0.6096 0)
					(mid -0.6096 0)
					(end 0.6096 0)
				)
			)
			(stroke
				(width 0)
				(type default)
			)
			(fill no)
			(layer "F.Fab")
		)
		(pad "1" smd circle
			(at 0 0)
			(size 0.7112 0.7112)
			(layers "F.Cu" "F.Mask" "F.Paste")
			(net "TP_GPIOV4")
		)
	)
	(footprint ""
		(layer "F.Cu")
		(at 150.622 -33.528)
		(property "Reference" "C389"
			(at 0 0 0)
			(layer "F.SilkS")
			(hide yes)
			(effects
				(font
					(size 1.27 1.27)
				)
			)
		)
		(property "Value" "SCD22U10V2KX-1GP"
			(at 1.1811 -2.7051 0)
			(unlocked yes)
			(layer "F.Fab")
			(hide yes)
			(effects
				(font
					(size 1.016 1.016)
					(thickness 0.1524)
				)
			)
		)
		(property "Device Type" "C402H22"
			(at 1.1811 -4.2291 0)
			(unlocked yes)
			(layer "F.Fab")
			(hide yes)
			(effects
				(font
					(size 1.016 1.016)
					(thickness 0.1524)
				)
			)
		)
		(duplicate_pad_numbers_are_jumpers no)
		(fp_rect
			(start -0.4318 0.9525)
			(end 0.4318 -0.9525)
			(stroke
				(width 0)
				(type default)
			)
			(fill no)
			(layer "F.CrtYd")
		)
		(fp_rect
			(start -0.4318 0.9525)
			(end 0.4318 -0.9525)
			(stroke
				(width 0)
				(type default)
			)
			(fill no)
			(layer "F.Fab")
		)
		(pad "1" smd custom
			(at 0 -0.4445)
			(size 0.1524 0.1524)
			(layers "F.Cu" "F.Mask" "F.Paste")
			(net "PCIE_TX_CAP_P84")
			(options
				(clearance outline)
				(anchor circle)
			)
			(primitives
				(gr_poly
					(pts
						(arc
							(start 0.3048 -0.2032)
							(mid 0.275042 -0.275042)
							(end 0.2032 -0.3048)
						)
						(arc
							(start -0.2032 -0.3048)
							(mid -0.275042 -0.275042)
							(end -0.3048 -0.2032)
						)
						(arc
							(start -0.3048 0.2032)
							(mid -0.275042 0.275042)
							(end -0.2032 0.3048)
						)
						(arc
							(start 0.2032 0.3048)
							(mid 0.275042 0.275042)
							(end 0.3048 0.2032)
						)
					)
					(width 0)
					(fill yes)
				)
			)
		)
		(pad "2" smd custom
			(at 0 0.4445)
			(size 0.1524 0.1524)
			(layers "F.Cu" "F.Mask" "F.Paste")
			(net "PCIE_TX_P84")
			(options
				(clearance outline)
				(anchor circle)
			)
			(primitives
				(gr_poly
					(pts
						(arc
							(start 0.3048 -0.2032)
							(mid 0.275042 -0.275042)
							(end 0.2032 -0.3048)
						)
						(arc
							(start -0.2032 -0.3048)
							(mid -0.275042 -0.275042)
							(end -0.3048 -0.2032)
						)
						(arc
							(start -0.3048 0.2032)
							(mid -0.275042 0.275042)
							(end -0.2032 0.3048)
						)
						(arc
							(start 0.2032 0.3048)
							(mid 0.275042 0.275042)
							(end 0.3048 0.2032)
						)
					)
					(width 0)
					(fill yes)
				)
			)
		)
	)
	(footprint ""
		(layer "F.Cu")
		(at 65.7606 -75.0062)
		(property "Reference" "R733"
			(at 0 0 0)
			(layer "F.SilkS")
			(hide yes)
			(effects
				(font
					(size 1.27 1.27)
				)
			)
		)
		(property "Value" "0R2J-2-GP"
			(at 0.064008 -3.993896 0)
			(unlocked yes)
			(layer "F.Fab")
			(hide yes)
			(effects
				(font
					(size 1.016 1.016)
					(thickness 0.1524)
				)
			)
		)
		(property "Device Type" "R402H16"
			(at 0.064008 -5.517896 0)
			(unlocked yes)
			(layer "F.Fab")
			(hide yes)
			(effects
				(font
					(size 1.016 1.016)
					(thickness 0.1524)
				)
			)
		)
		(duplicate_pad_numbers_are_jumpers no)
		(fp_line
			(start -0.508 -0.9398)
			(end -0.508 0.9398)
			(stroke
				(width 0.1524)
				(type default)
			)
			(layer "F.SilkS")
		)
		(fp_line
			(start 0.508 -0.9398)
			(end -0.508 -0.9398)
			(stroke
				(width 0.1524)
				(type default)
			)
			(layer "F.SilkS")
		)
		(fp_rect
			(start -0.508 0.9398)
			(end 0.508 -0.9398)
			(stroke
				(width 0)
				(type default)
			)
			(fill no)
			(layer "F.CrtYd")
		)
		(fp_rect
			(start -0.508 0.9398)
			(end 0.508 -0.9398)
			(stroke
				(width 0)
				(type default)
			)
			(fill no)
			(layer "F.Fab")
		)
		(pad "1" smd custom
			(at 0 -0.4445)
			(size 0.1397 0.1397)
			(layers "F.Cu" "F.Mask" "F.Paste")
			(net "FM_BMC_RESET_N")
			(options
				(clearance outline)
				(anchor circle)
			)
			(primitives
				(gr_poly
					(pts
						(arc
							(start -0.1778 -0.2794)
							(mid -0.249642 -0.249642)
							(end -0.2794 -0.1778)
						)
						(arc
							(start -0.2794 0.1778)
							(mid -0.249642 0.249642)
							(end -0.1778 0.2794)
						)
						(arc
							(start 0.1778 0.2794)
							(mid 0.249642 0.249642)
							(end 0.2794 0.1778)
						)
						(arc
							(start 0.2794 -0.1778)
							(mid 0.249642 -0.249642)
							(end 0.1778 -0.2794)
						)
					)
					(width 0)
					(fill yes)
				)
			)
		)
		(pad "2" smd custom
			(at 0 0.4445)
			(size 0.1397 0.1397)
			(layers "F.Cu" "F.Mask" "F.Paste")
			(net "U19_PERST_N")
			(options
				(clearance outline)
				(anchor circle)
			)
			(primitives
				(gr_poly
					(pts
						(arc
							(start -0.1778 -0.2794)
							(mid -0.249642 -0.249642)
							(end -0.2794 -0.1778)
						)
						(arc
							(start -0.2794 0.1778)
							(mid -0.249642 0.249642)
							(end -0.1778 0.2794)
						)
						(arc
							(start 0.1778 0.2794)
							(mid 0.249642 0.249642)
							(end 0.2794 0.1778)
						)
						(arc
							(start 0.2794 -0.1778)
							(mid 0.249642 -0.249642)
							(end 0.1778 -0.2794)
						)
					)
					(width 0)
					(fill yes)
				)
			)
		)
	)
	(footprint ""
		(layer "F.Cu")
		(at 72.90816 -37.9349 90)
		(property "Reference" "PR36"
			(at 0 0 90)
			(layer "F.SilkS")
			(hide yes)
			(effects
				(font
					(size 1.27 1.27)
				)
			)
		)
		(property "Value" "0R2J-2-GP"
			(at 0.064008 -3.993896 90)
			(unlocked yes)
			(layer "F.Fab")
			(hide yes)
			(effects
				(font
					(size 1.016 1.016)
					(thickness 0.1524)
				)
			)
		)
		(property "Device Type" "R402H16"
			(at 0.064008 -5.517896 90)
			(unlocked yes)
			(layer "F.Fab")
			(hide yes)
			(effects
				(font
					(size 1.016 1.016)
					(thickness 0.1524)
				)
			)
		)
		(duplicate_pad_numbers_are_jumpers no)
		(fp_line
			(start 0.508 -0.9398)
			(end -0.508 -0.9398)
			(stroke
				(width 0.1524)
				(type default)
			)
			(layer "F.SilkS")
		)
		(fp_line
			(start -0.508 -0.9398)
			(end -0.508 0.9398)
			(stroke
				(width 0.1524)
				(type default)
			)
			(layer "F.SilkS")
		)
		(fp_rect
			(start -0.508 0.9398)
			(end 0.508 -0.9398)
			(stroke
				(width 0)
				(type default)
			)
			(fill no)
			(layer "F.CrtYd")
		)
		(fp_rect
			(start -0.508 0.9398)
			(end 0.508 -0.9398)
			(stroke
				(width 0)
				(type default)
			)
			(fill no)
			(layer "F.Fab")
		)
		(pad "1" smd custom
			(at 0 -0.4445 90)
			(size 0.1397 0.1397)
			(layers "F.Cu" "F.Mask" "F.Paste")
			(net "P3V3_STBY_ROVP")
			(options
				(clearance outline)
				(anchor circle)
			)
			(primitives
				(gr_poly
					(pts
						(arc
							(start -0.1778 -0.2794)
							(mid -0.249642 -0.249642)
							(end -0.2794 -0.1778)
						)
						(arc
							(start -0.2794 0.1778)
							(mid -0.249642 0.249642)
							(end -0.1778 0.2794)
						)
						(arc
							(start 0.1778 0.2794)
							(mid 0.249642 0.249642)
							(end 0.2794 0.1778)
						)
						(arc
							(start 0.2794 -0.1778)
							(mid 0.249642 -0.249642)
							(end 0.1778 -0.2794)
						)
					)
					(width 0)
					(fill yes)
				)
			)
		)
		(pad "2" smd custom
			(at 0 0.4445 90)
			(size 0.1397 0.1397)
			(layers "F.Cu" "F.Mask" "F.Paste")
			(net "AGND_P3V3_STBY")
			(options
				(clearance outline)
				(anchor circle)
			)
			(primitives
				(gr_poly
					(pts
						(arc
							(start -0.1778 -0.2794)
							(mid -0.249642 -0.249642)
							(end -0.2794 -0.1778)
						)
						(arc
							(start -0.2794 0.1778)
							(mid -0.249642 0.249642)
							(end -0.1778 0.2794)
						)
						(arc
							(start 0.1778 0.2794)
							(mid 0.249642 0.249642)
							(end 0.2794 0.1778)
						)
						(arc
							(start 0.2794 -0.1778)
							(mid 0.249642 -0.249642)
							(end 0.1778 -0.2794)
						)
					)
					(width 0)
					(fill yes)
				)
			)
		)
	)
	(footprint ""
		(layer "F.Cu")
		(at 167.609774 -51.102768 180)
		(property "Reference" "Q34"
			(at 0 0 180)
			(layer "F.SilkS")
			(hide yes)
			(effects
				(font
					(size 1.27 1.27)
				)
			)
		)
		(property "Value" "2N7002K-1-GP"
			(at 0.127 -8.9662 180)
			(unlocked yes)
			(layer "F.Fab")
			(hide yes)
			(effects
				(font
					(size 1.016 1.016)
					(thickness 0.1524)
				)
			)
		)
		(property "Device Type" "SOT23DGS2D4H44"
			(at 0.127 -10.4902 180)
			(unlocked yes)
			(layer "F.Fab")
			(hide yes)
			(effects
				(font
					(size 1.016 1.016)
					(thickness 0.1524)
				)
			)
		)
		(duplicate_pad_numbers_are_jumpers no)
		(fp_line
			(start 1.651 1.778)
			(end 1.651 -1.778)
			(stroke
				(width 0.1524)
				(type default)
			)
			(layer "F.SilkS")
		)
		(fp_line
			(start 1.651 -1.778)
			(end -1.651 -1.778)
			(stroke
				(width 0.1524)
				(type default)
			)
			(layer "F.SilkS")
		)
		(fp_line
			(start -1.651 1.778)
			(end 1.651 1.778)
			(stroke
				(width 0.1524)
				(type default)
			)
			(layer "F.SilkS")
		)
		(fp_line
			(start -1.651 -1.778)
			(end -1.651 1.778)
			(stroke
				(width 0.1524)
				(type default)
			)
			(layer "F.SilkS")
		)
		(fp_poly
			(pts
				(xy -1.778 1.8796) (xy -1.778 -1.8796) (xy 1.778 -1.8796) (xy 1.778 1.8796)
			)
			(stroke
				(width 0)
				(type default)
			)
			(fill no)
			(layer "F.CrtYd")
		)
		(fp_poly
			(pts
				(xy -1.778 1.8796) (xy -1.778 -1.8796) (xy 1.778 -1.8796) (xy 1.778 1.8796)
			)
			(stroke
				(width 0)
				(type default)
			)
			(fill no)
			(layer "F.Fab")
		)
		(pad "D" smd custom
			(at 0 -0.9525 180)
			(size 0.1905 0.1905)
			(layers "F.Cu" "F.Mask" "F.Paste")
			(net "LED_Q_9")
			(options
				(clearance outline)
				(anchor circle)
			)
			(primitives
				(gr_poly
					(pts
						(arc
							(start -0.1778 0.5715)
							(mid -0.321484 0.511984)
							(end -0.381 0.3683)
						)
						(arc
							(start -0.381 -0.3683)
							(mid -0.321484 -0.511984)
							(end -0.1778 -0.5715)
						)
						(arc
							(start 0.1778 -0.5715)
							(mid 0.321484 -0.511984)
							(end 0.381 -0.3683)
						)
						(arc
							(start 0.381 0.3683)
							(mid 0.321484 0.511984)
							(end 0.1778 0.5715)
						)
					)
					(width 0)
					(fill yes)
				)
			)
		)
		(pad "G" smd custom
			(at -0.98425 0.9525 180)
			(size 0.1905 0.1905)
			(layers "F.Cu" "F.Mask" "F.Paste")
			(net "VS1_LED_R")
			(options
				(clearance outline)
				(anchor circle)
			)
			(primitives
				(gr_poly
					(pts
						(arc
							(start -0.1778 0.5715)
							(mid -0.321484 0.511984)
							(end -0.381 0.3683)
						)
						(arc
							(start -0.381 -0.3683)
							(mid -0.321484 -0.511984)
							(end -0.1778 -0.5715)
						)
						(arc
							(start 0.1778 -0.5715)
							(mid 0.321484 -0.511984)
							(end 0.381 -0.3683)
						)
						(arc
							(start 0.381 0.3683)
							(mid 0.321484 0.511984)
							(end 0.1778 0.5715)
						)
					)
					(width 0)
					(fill yes)
				)
			)
		)
		(pad "S" smd custom
			(at 0.98425 0.9525 180)
			(size 0.1905 0.1905)
			(layers "F.Cu" "F.Mask" "F.Paste")
			(net "GND")
			(options
				(clearance outline)
				(anchor circle)
			)
			(primitives
				(gr_poly
					(pts
						(arc
							(start -0.1778 0.5715)
							(mid -0.321484 0.511984)
							(end -0.381 0.3683)
						)
						(arc
							(start -0.381 -0.3683)
							(mid -0.321484 -0.511984)
							(end -0.1778 -0.5715)
						)
						(arc
							(start 0.1778 -0.5715)
							(mid 0.321484 -0.511984)
							(end 0.381 -0.3683)
						)
						(arc
							(start 0.381 0.3683)
							(mid 0.321484 0.511984)
							(end 0.1778 0.5715)
						)
					)
					(width 0)
					(fill yes)
				)
			)
		)
	)
	(footprint ""
		(layer "F.Cu")
		(at 340.233 -55.245 -90)
		(property "Reference" "PC221"
			(at 0 0 270)
			(layer "F.SilkS")
			(hide yes)
			(effects
				(font
					(size 1.27 1.27)
				)
			)
		)
		(property "Value" "SC22U25V6KX-GP-U"
			(at -2.860802 -5.279644 270)
			(unlocked yes)
			(layer "F.Fab")
			(hide yes)
			(effects
				(font
					(size 1.016 1.016)
					(thickness 0.1524)
				)
			)
		)
		(property "Device Type" "C1206-TO0D3H75"
			(at -2.860802 -6.803644 270)
			(unlocked yes)
			(layer "F.Fab")
			(hide yes)
			(effects
				(font
					(size 1.016 1.016)
					(thickness 0.1524)
				)
			)
		)
		(duplicate_pad_numbers_are_jumpers no)
		(fp_line
			(start -1.3081 2.3749)
			(end -1.3081 -2.3749)
			(stroke
				(width 0.1524)
				(type default)
			)
			(layer "F.SilkS")
		)
		(fp_line
			(start 1.3081 2.3749)
			(end -1.3081 2.3749)
			(stroke
				(width 0.1524)
				(type default)
			)
			(layer "F.SilkS")
		)
		(fp_line
			(start -1.3081 -2.3749)
			(end 1.3081 -2.3749)
			(stroke
				(width 0.1524)
				(type default)
			)
			(layer "F.SilkS")
		)
		(fp_line
			(start 1.3081 -2.3749)
			(end 1.3081 2.3749)
			(stroke
				(width 0.1524)
				(type default)
			)
			(layer "F.SilkS")
		)
		(fp_rect
			(start -0.8001 1.6002)
			(end 0.8001 -1.6002)
			(stroke
				(width 0)
				(type default)
			)
			(fill no)
			(layer "F.CrtYd")
		)
		(fp_poly
			(pts
				(xy -1.5621 2.4511) (xy -1.5621 1.6002) (xy 0.8001 1.6002) (xy 0.8001 -1.6002) (xy -0.8001 -1.6002)
				(xy -0.8001 1.5875) (xy -1.5621 1.5875) (xy -1.5621 -2.4511) (xy 1.5621 -2.4511) (xy 1.5621 2.4511)
			)
			(stroke
				(width 0)
				(type default)
			)
			(fill no)
			(layer "F.CrtYd")
		)
		(fp_rect
			(start -1.5621 2.4511)
			(end 1.5621 -2.4511)
			(stroke
				(width 0)
				(type default)
			)
			(fill no)
			(layer "F.Fab")
		)
		(pad "1" smd rect
			(at 0 -1.392936 270)
			(size 2.1082 1.4478)
			(layers "F.Cu" "F.Mask" "F.Paste")
			(net "P0V9_E_VIN")
		)
		(pad "2" smd rect
			(at 0 1.392936 270)
			(size 2.1082 1.4478)
			(layers "F.Cu" "F.Mask" "F.Paste")
			(net "GND")
		)
	)
	(footprint ""
		(layer "F.Cu")
		(at 227.9904 -190.5762)
		(property "Reference" "R9037"
			(at 0 0 0)
			(layer "F.SilkS")
			(hide yes)
			(effects
				(font
					(size 1.27 1.27)
				)
			)
		)
		(property "Value" "4K7R2F-GP"
			(at 0.064008 -3.993896 0)
			(unlocked yes)
			(layer "F.Fab")
			(hide yes)
			(effects
				(font
					(size 1.016 1.016)
					(thickness 0.1524)
				)
			)
		)
		(property "Device Type" "R402H16"
			(at 0.064008 -5.517896 0)
			(unlocked yes)
			(layer "F.Fab")
			(hide yes)
			(effects
				(font
					(size 1.016 1.016)
					(thickness 0.1524)
				)
			)
		)
		(duplicate_pad_numbers_are_jumpers no)
		(fp_line
			(start -0.508 -0.9398)
			(end -0.508 0.9398)
			(stroke
				(width 0.1524)
				(type default)
			)
			(layer "F.SilkS")
		)
		(fp_line
			(start 0.508 -0.9398)
			(end -0.508 -0.9398)
			(stroke
				(width 0.1524)
				(type default)
			)
			(layer "F.SilkS")
		)
		(fp_rect
			(start -0.508 0.9398)
			(end 0.508 -0.9398)
			(stroke
				(width 0)
				(type default)
			)
			(fill no)
			(layer "F.CrtYd")
		)
		(fp_rect
			(start -0.508 0.9398)
			(end 0.508 -0.9398)
			(stroke
				(width 0)
				(type default)
			)
			(fill no)
			(layer "F.Fab")
		)
		(pad "1" smd custom
			(at 0 -0.4445)
			(size 0.1397 0.1397)
			(layers "F.Cu" "F.Mask" "F.Paste")
			(net "SSD_PERST#8")
			(options
				(clearance outline)
				(anchor circle)
			)
			(primitives
				(gr_poly
					(pts
						(arc
							(start -0.1778 -0.2794)
							(mid -0.249642 -0.249642)
							(end -0.2794 -0.1778)
						)
						(arc
							(start -0.2794 0.1778)
							(mid -0.249642 0.249642)
							(end -0.1778 0.2794)
						)
						(arc
							(start 0.1778 0.2794)
							(mid 0.249642 0.249642)
							(end 0.2794 0.1778)
						)
						(arc
							(start 0.2794 -0.1778)
							(mid 0.249642 -0.249642)
							(end 0.1778 -0.2794)
						)
					)
					(width 0)
					(fill yes)
				)
			)
		)
		(pad "2" smd custom
			(at 0 0.4445)
			(size 0.1397 0.1397)
			(layers "F.Cu" "F.Mask" "F.Paste")
			(net "GND")
			(options
				(clearance outline)
				(anchor circle)
			)
			(primitives
				(gr_poly
					(pts
						(arc
							(start -0.1778 -0.2794)
							(mid -0.249642 -0.249642)
							(end -0.2794 -0.1778)
						)
						(arc
							(start -0.2794 0.1778)
							(mid -0.249642 0.249642)
							(end -0.1778 0.2794)
						)
						(arc
							(start 0.1778 0.2794)
							(mid 0.249642 0.249642)
							(end 0.2794 0.1778)
						)
						(arc
							(start 0.2794 -0.1778)
							(mid 0.249642 -0.249642)
							(end 0.1778 -0.2794)
						)
					)
					(width 0)
					(fill yes)
				)
			)
		)
	)
	(footprint ""
		(layer "F.Cu")
		(at 49.911 -178.816 -90)
		(property "Reference" "C709"
			(at 0 0 270)
			(layer "F.SilkS")
			(hide yes)
			(effects
				(font
					(size 1.27 1.27)
				)
			)
		)
		(property "Value" "SC220P50V3JN-GP"
			(at 0 -2.8194 270)
			(unlocked yes)
			(layer "F.Fab")
			(hide yes)
			(effects
				(font
					(size 1.016 1.016)
					(thickness 0.1524)
				)
			)
		)
		(property "Device Type" "C603H36"
			(at 0 -4.3434 270)
			(unlocked yes)
			(layer "F.Fab")
			(hide yes)
			(effects
				(font
					(size 1.016 1.016)
					(thickness 0.1524)
				)
			)
		)
		(duplicate_pad_numbers_are_jumpers no)
		(fp_line
			(start 0.508 0)
			(end -0.508 0)
			(stroke
				(width 0.2032)
				(type default)
			)
			(layer "F.SilkS")
		)
		(fp_rect
			(start -0.5842 1.3335)
			(end 0.5842 -1.3335)
			(stroke
				(width 0)
				(type default)
			)
			(fill no)
			(layer "F.CrtYd")
		)
		(fp_rect
			(start -0.5842 1.3335)
			(end 0.5842 -1.3335)
			(stroke
				(width 0)
				(type default)
			)
			(fill no)
			(layer "F.Fab")
		)
		(pad "1" smd custom
			(at 0 -0.762 270)
			(size 0.2159 0.2159)
			(layers "F.Cu" "F.Mask" "F.Paste")
			(net "BMC_I2C8_CLKBUF1_SDA_R")
			(options
				(clearance outline)
				(anchor circle)
			)
			(primitives
				(gr_poly
					(pts
						(arc
							(start -0.3302 -0.4318)
							(mid -0.402042 -0.402042)
							(end -0.4318 -0.3302)
						)
						(arc
							(start -0.4318 0.3302)
							(mid -0.402042 0.402042)
							(end -0.3302 0.4318)
						)
						(arc
							(start 0.3302 0.4318)
							(mid 0.402042 0.402042)
							(end 0.4318 0.3302)
						)
						(arc
							(start 0.4318 -0.3302)
							(mid 0.402042 -0.402042)
							(end 0.3302 -0.4318)
						)
					)
					(width 0)
					(fill yes)
				)
			)
		)
		(pad "2" smd custom
			(at 0 0.762 270)
			(size 0.2159 0.2159)
			(layers "F.Cu" "F.Mask" "F.Paste")
			(net "GND")
			(options
				(clearance outline)
				(anchor circle)
			)
			(primitives
				(gr_poly
					(pts
						(arc
							(start -0.3302 -0.4318)
							(mid -0.402042 -0.402042)
							(end -0.4318 -0.3302)
						)
						(arc
							(start -0.4318 0.3302)
							(mid -0.402042 0.402042)
							(end -0.3302 0.4318)
						)
						(arc
							(start 0.3302 0.4318)
							(mid 0.402042 0.402042)
							(end 0.4318 0.3302)
						)
						(arc
							(start 0.4318 -0.3302)
							(mid 0.402042 -0.402042)
							(end 0.3302 -0.4318)
						)
					)
					(width 0)
					(fill yes)
				)
			)
		)
	)
	(footprint ""
		(layer "F.Cu")
		(at 44.831 -145.161)
		(property "Reference" "TP230"
			(at 0 0 0)
			(layer "F.SilkS")
			(hide yes)
			(effects
				(font
					(size 1.27 1.27)
				)
			)
		)
		(property "Value" "TPAD28-2-GP"
			(at -0.0127 -1.6637 0)
			(unlocked yes)
			(layer "F.Fab")
			(hide yes)
			(effects
				(font
					(size 1.016 1.016)
					(thickness 0.1524)
				)
			)
		)
		(property "Device Type" "TPAD28"
			(at -0.0127 -3.1877 0)
			(unlocked yes)
			(layer "F.Fab")
			(hide yes)
			(effects
				(font
					(size 1.016 1.016)
					(thickness 0.1524)
				)
			)
		)
		(duplicate_pad_numbers_are_jumpers no)
		(fp_poly
			(pts
				(arc
					(start 0.3556 0)
					(mid -0.3556 0)
					(end 0.3556 0)
				)
			)
			(stroke
				(width 0)
				(type default)
			)
			(fill no)
			(layer "F.CrtYd")
		)
		(fp_poly
			(pts
				(arc
					(start 0.6096 0)
					(mid -0.6096 0)
					(end 0.6096 0)
				)
			)
			(stroke
				(width 0)
				(type default)
			)
			(fill no)
			(layer "F.Fab")
		)
		(pad "1" smd circle
			(at 0 0)
			(size 0.7112 0.7112)
			(layers "F.Cu" "F.Mask" "F.Paste")
			(net "TP_GPIOP1")
		)
	)
	(footprint ""
		(layer "F.Cu")
		(at 334.01 -71.247 180)
		(property "Reference" "PR157"
			(at 0 0 180)
			(layer "F.SilkS")
			(hide yes)
			(effects
				(font
					(size 1.27 1.27)
				)
			)
		)
		(property "Value" "51KR2F-L-GP"
			(at 0.064008 -3.993896 180)
			(unlocked yes)
			(layer "F.Fab")
			(hide yes)
			(effects
				(font
					(size 1.016 1.016)
					(thickness 0.1524)
				)
			)
		)
		(property "Device Type" "R402H16"
			(at 0.064008 -5.517896 180)
			(unlocked yes)
			(layer "F.Fab")
			(hide yes)
			(effects
				(font
					(size 1.016 1.016)
					(thickness 0.1524)
				)
			)
		)
		(duplicate_pad_numbers_are_jumpers no)
		(fp_line
			(start 0.508 -0.9398)
			(end -0.508 -0.9398)
			(stroke
				(width 0.1524)
				(type default)
			)
			(layer "F.SilkS")
		)
		(fp_line
			(start -0.508 -0.9398)
			(end -0.508 0.9398)
			(stroke
				(width 0.1524)
				(type default)
			)
			(layer "F.SilkS")
		)
		(fp_rect
			(start -0.508 0.9398)
			(end 0.508 -0.9398)
			(stroke
				(width 0)
				(type default)
			)
			(fill no)
			(layer "F.CrtYd")
		)
		(fp_rect
			(start -0.508 0.9398)
			(end 0.508 -0.9398)
			(stroke
				(width 0)
				(type default)
			)
			(fill no)
			(layer "F.Fab")
		)
		(pad "1" smd custom
			(at 0 -0.4445 180)
			(size 0.1397 0.1397)
			(layers "F.Cu" "F.Mask" "F.Paste")
			(net "P0V9_E_EN")
			(options
				(clearance outline)
				(anchor circle)
			)
			(primitives
				(gr_poly
					(pts
						(arc
							(start -0.1778 -0.2794)
							(mid -0.249642 -0.249642)
							(end -0.2794 -0.1778)
						)
						(arc
							(start -0.2794 0.1778)
							(mid -0.249642 0.249642)
							(end -0.1778 0.2794)
						)
						(arc
							(start 0.1778 0.2794)
							(mid 0.249642 0.249642)
							(end 0.2794 0.1778)
						)
						(arc
							(start 0.2794 -0.1778)
							(mid 0.249642 -0.249642)
							(end 0.1778 -0.2794)
						)
					)
					(width 0)
					(fill yes)
				)
			)
		)
		(pad "2" smd custom
			(at 0 0.4445 180)
			(size 0.1397 0.1397)
			(layers "F.Cu" "F.Mask" "F.Paste")
			(net "GND")
			(options
				(clearance outline)
				(anchor circle)
			)
			(primitives
				(gr_poly
					(pts
						(arc
							(start -0.1778 -0.2794)
							(mid -0.249642 -0.249642)
							(end -0.2794 -0.1778)
						)
						(arc
							(start -0.2794 0.1778)
							(mid -0.249642 0.249642)
							(end -0.1778 0.2794)
						)
						(arc
							(start 0.1778 0.2794)
							(mid 0.249642 0.249642)
							(end 0.2794 0.1778)
						)
						(arc
							(start 0.2794 -0.1778)
							(mid 0.249642 -0.249642)
							(end 0.1778 -0.2794)
						)
					)
					(width 0)
					(fill yes)
				)
			)
		)
	)
	(footprint ""
		(layer "F.Cu")
		(at 72.1868 -120.0912 180)
		(property "Reference" "R567"
			(at 0 0 180)
			(layer "F.SilkS")
			(hide yes)
			(effects
				(font
					(size 1.27 1.27)
				)
			)
		)
		(property "Value" "4K7R2F-GP"
			(at 0.064008 -3.993896 180)
			(unlocked yes)
			(layer "F.Fab")
			(hide yes)
			(effects
				(font
					(size 1.016 1.016)
					(thickness 0.1524)
				)
			)
		)
		(property "Device Type" "R402H16"
			(at 0.064008 -5.517896 180)
			(unlocked yes)
			(layer "F.Fab")
			(hide yes)
			(effects
				(font
					(size 1.016 1.016)
					(thickness 0.1524)
				)
			)
		)
		(duplicate_pad_numbers_are_jumpers no)
		(fp_line
			(start 0.508 -0.9398)
			(end -0.508 -0.9398)
			(stroke
				(width 0.1524)
				(type default)
			)
			(layer "F.SilkS")
		)
		(fp_line
			(start -0.508 -0.9398)
			(end -0.508 0.9398)
			(stroke
				(width 0.1524)
				(type default)
			)
			(layer "F.SilkS")
		)
		(fp_rect
			(start -0.508 0.9398)
			(end 0.508 -0.9398)
			(stroke
				(width 0)
				(type default)
			)
			(fill no)
			(layer "F.CrtYd")
		)
		(fp_rect
			(start -0.508 0.9398)
			(end 0.508 -0.9398)
			(stroke
				(width 0)
				(type default)
			)
			(fill no)
			(layer "F.Fab")
		)
		(pad "1" smd custom
			(at 0 -0.4445 180)
			(size 0.1397 0.1397)
			(layers "F.Cu" "F.Mask" "F.Paste")
			(net "P3V3_STBY")
			(options
				(clearance outline)
				(anchor circle)
			)
			(primitives
				(gr_poly
					(pts
						(arc
							(start -0.1778 -0.2794)
							(mid -0.249642 -0.249642)
							(end -0.2794 -0.1778)
						)
						(arc
							(start -0.2794 0.1778)
							(mid -0.249642 0.249642)
							(end -0.1778 0.2794)
						)
						(arc
							(start 0.1778 0.2794)
							(mid 0.249642 0.249642)
							(end 0.2794 0.1778)
						)
						(arc
							(start 0.2794 -0.1778)
							(mid 0.249642 -0.249642)
							(end 0.1778 -0.2794)
						)
					)
					(width 0)
					(fill yes)
				)
			)
		)
		(pad "2" smd custom
			(at 0 0.4445 180)
			(size 0.1397 0.1397)
			(layers "F.Cu" "F.Mask" "F.Paste")
			(net "BMC_RXD5_R")
			(options
				(clearance outline)
				(anchor circle)
			)
			(primitives
				(gr_poly
					(pts
						(arc
							(start -0.1778 -0.2794)
							(mid -0.249642 -0.249642)
							(end -0.2794 -0.1778)
						)
						(arc
							(start -0.2794 0.1778)
							(mid -0.249642 0.249642)
							(end -0.1778 0.2794)
						)
						(arc
							(start 0.1778 0.2794)
							(mid 0.249642 0.249642)
							(end 0.2794 0.1778)
						)
						(arc
							(start 0.2794 -0.1778)
							(mid 0.249642 -0.249642)
							(end 0.1778 -0.2794)
						)
					)
					(width 0)
					(fill yes)
				)
			)
		)
	)
	(footprint ""
		(layer "F.Cu")
		(at 14.605 -127.508 -90)
		(property "Reference" "R296"
			(at 0 0 270)
			(layer "F.SilkS")
			(hide yes)
			(effects
				(font
					(size 1.27 1.27)
				)
			)
		)
		(property "Value" "4K7R2F-GP"
			(at 0.064008 -3.993896 270)
			(unlocked yes)
			(layer "F.Fab")
			(hide yes)
			(effects
				(font
					(size 1.016 1.016)
					(thickness 0.1524)
				)
			)
		)
		(property "Device Type" "R402H16"
			(at 0.064008 -5.517896 270)
			(unlocked yes)
			(layer "F.Fab")
			(hide yes)
			(effects
				(font
					(size 1.016 1.016)
					(thickness 0.1524)
				)
			)
		)
		(duplicate_pad_numbers_are_jumpers no)
		(fp_line
			(start -0.508 -0.9398)
			(end -0.508 0.9398)
			(stroke
				(width 0.1524)
				(type default)
			)
			(layer "F.SilkS")
		)
		(fp_line
			(start 0.508 -0.9398)
			(end -0.508 -0.9398)
			(stroke
				(width 0.1524)
				(type default)
			)
			(layer "F.SilkS")
		)
		(fp_rect
			(start -0.508 0.9398)
			(end 0.508 -0.9398)
			(stroke
				(width 0)
				(type default)
			)
			(fill no)
			(layer "F.CrtYd")
		)
		(fp_rect
			(start -0.508 0.9398)
			(end 0.508 -0.9398)
			(stroke
				(width 0)
				(type default)
			)
			(fill no)
			(layer "F.Fab")
		)
		(pad "1" smd custom
			(at 0 -0.4445 270)
			(size 0.1397 0.1397)
			(layers "F.Cu" "F.Mask" "F.Paste")
			(net "P3V3_STBY")
			(options
				(clearance outline)
				(anchor circle)
			)
			(primitives
				(gr_poly
					(pts
						(arc
							(start -0.1778 -0.2794)
							(mid -0.249642 -0.249642)
							(end -0.2794 -0.1778)
						)
						(arc
							(start -0.2794 0.1778)
							(mid -0.249642 0.249642)
							(end -0.1778 0.2794)
						)
						(arc
							(start 0.1778 0.2794)
							(mid 0.249642 0.249642)
							(end 0.2794 0.1778)
						)
						(arc
							(start 0.2794 -0.1778)
							(mid 0.249642 -0.249642)
							(end 0.1778 -0.2794)
						)
					)
					(width 0)
					(fill yes)
				)
			)
		)
		(pad "2" smd custom
			(at 0 0.4445 270)
			(size 0.1397 0.1397)
			(layers "F.Cu" "F.Mask" "F.Paste")
			(net "I2C2_LS_G1")
			(options
				(clearance outline)
				(anchor circle)
			)
			(primitives
				(gr_poly
					(pts
						(arc
							(start -0.1778 -0.2794)
							(mid -0.249642 -0.249642)
							(end -0.2794 -0.1778)
						)
						(arc
							(start -0.2794 0.1778)
							(mid -0.249642 0.249642)
							(end -0.1778 0.2794)
						)
						(arc
							(start 0.1778 0.2794)
							(mid 0.249642 0.249642)
							(end 0.2794 0.1778)
						)
						(arc
							(start 0.2794 -0.1778)
							(mid 0.249642 -0.249642)
							(end 0.1778 -0.2794)
						)
					)
					(width 0)
					(fill yes)
				)
			)
		)
	)
	(footprint ""
		(layer "F.Cu")
		(at 5.5626 -49.3014 180)
		(property "Reference" "C329"
			(at 0 0 180)
			(layer "F.SilkS")
			(hide yes)
			(effects
				(font
					(size 1.27 1.27)
				)
			)
		)
		(property "Value" "SCD1U16V2KX-3GP"
			(at 1.1811 -2.7051 180)
			(unlocked yes)
			(layer "F.Fab")
			(hide yes)
			(effects
				(font
					(size 1.016 1.016)
					(thickness 0.1524)
				)
			)
		)
		(property "Device Type" "C402H22"
			(at 1.1811 -4.2291 180)
			(unlocked yes)
			(layer "F.Fab")
			(hide yes)
			(effects
				(font
					(size 1.016 1.016)
					(thickness 0.1524)
				)
			)
		)
		(duplicate_pad_numbers_are_jumpers no)
		(fp_rect
			(start -0.4318 0.9525)
			(end 0.4318 -0.9525)
			(stroke
				(width 0)
				(type default)
			)
			(fill no)
			(layer "F.CrtYd")
		)
		(fp_rect
			(start -0.4318 0.9525)
			(end 0.4318 -0.9525)
			(stroke
				(width 0)
				(type default)
			)
			(fill no)
			(layer "F.Fab")
		)
		(pad "1" smd custom
			(at 0 -0.4445 180)
			(size 0.1524 0.1524)
			(layers "F.Cu" "F.Mask" "F.Paste")
			(net "NIC0_CT_POWER")
			(options
				(clearance outline)
				(anchor circle)
			)
			(primitives
				(gr_poly
					(pts
						(arc
							(start 0.3048 -0.2032)
							(mid 0.275042 -0.275042)
							(end 0.2032 -0.3048)
						)
						(arc
							(start -0.2032 -0.3048)
							(mid -0.275042 -0.275042)
							(end -0.3048 -0.2032)
						)
						(arc
							(start -0.3048 0.2032)
							(mid -0.275042 0.275042)
							(end -0.2032 0.3048)
						)
						(arc
							(start 0.2032 0.3048)
							(mid 0.275042 0.275042)
							(end 0.3048 0.2032)
						)
					)
					(width 0)
					(fill yes)
				)
			)
		)
		(pad "2" smd custom
			(at 0 0.4445 180)
			(size 0.1524 0.1524)
			(layers "F.Cu" "F.Mask" "F.Paste")
			(net "GND")
			(options
				(clearance outline)
				(anchor circle)
			)
			(primitives
				(gr_poly
					(pts
						(arc
							(start 0.3048 -0.2032)
							(mid 0.275042 -0.275042)
							(end 0.2032 -0.3048)
						)
						(arc
							(start -0.2032 -0.3048)
							(mid -0.275042 -0.275042)
							(end -0.3048 -0.2032)
						)
						(arc
							(start -0.3048 0.2032)
							(mid -0.275042 0.275042)
							(end -0.2032 0.3048)
						)
						(arc
							(start 0.2032 0.3048)
							(mid 0.275042 0.275042)
							(end 0.3048 0.2032)
						)
					)
					(width 0)
					(fill yes)
				)
			)
		)
	)
	(footprint ""
		(layer "F.Cu")
		(at 138.6586 -46.736)
		(property "Reference" "CN5"
			(at 0 0 0)
			(layer "F.SilkS")
			(hide yes)
			(effects
				(font
					(size 1.27 1.27)
				)
			)
		)
		(property "Value" "MLX-CONN14A-16-GP"
			(at -6.941312 -6.705854 0)
			(unlocked yes)
			(layer "F.Fab")
			(hide yes)
			(effects
				(font
					(size 1.016 1.016)
					(thickness 0.1524)
				)
			)
		)
		(property "Device Type" "87332-1420-1"
			(at -6.941312 -8.229854 0)
			(unlocked yes)
			(layer "F.Fab")
			(hide yes)
			(effects
				(font
					(size 1.016 1.016)
					(thickness 0.1524)
				)
			)
		)
		(duplicate_pad_numbers_are_jumpers no)
		(fp_line
			(start -8.5852 -3.7465)
			(end -8.5852 3.7465)
			(stroke
				(width 0.1524)
				(type default)
			)
			(layer "F.SilkS")
		)
		(fp_line
			(start -8.5852 3.7465)
			(end 8.5852 3.7465)
			(stroke
				(width 0.1524)
				(type default)
			)
			(layer "F.SilkS")
		)
		(fp_line
			(start -6.5024 3.8608)
			(end -5.4356 3.8608)
			(stroke
				(width 0.3302)
				(type default)
			)
			(layer "F.SilkS")
		)
		(fp_line
			(start 8.5852 -3.7465)
			(end -8.5852 -3.7465)
			(stroke
				(width 0.1524)
				(type default)
			)
			(layer "F.SilkS")
		)
		(fp_line
			(start 8.5852 3.7465)
			(end 8.5852 -3.7465)
			(stroke
				(width 0.1524)
				(type default)
			)
			(layer "F.SilkS")
		)
		(fp_poly
			(pts
				(xy -5.969 3.8227) (xy -6.477 4.3307) (xy -5.461 4.3307)
			)
			(stroke
				(width 0)
				(type default)
			)
			(fill yes)
			(layer "F.SilkS")
		)
		(fp_poly
			(pts
				(xy -4.18719 -0.550164) (xy -4.18719 0.550164) (xy 4.18719 0.550164) (xy 4.18719 -0.550164)
			)
			(stroke
				(width 0)
				(type default)
			)
			(fill yes)
			(layer "F.SilkS")
		)
		(fp_rect
			(start -8.3312 3.1496)
			(end 8.3312 -3.1496)
			(stroke
				(width 0)
				(type default)
			)
			(fill no)
			(layer "F.CrtYd")
		)
		(fp_poly
			(pts
				(xy -8.8392 4.0005) (xy -8.8392 -4.0005) (xy 8.8392 -4.0005) (xy 8.8392 4.0005) (xy 0.00254 4.0005)
				(xy 0.00254 3.1496) (xy 8.3312 3.1496) (xy 8.3312 -3.1496) (xy -8.3312 -3.1496) (xy -8.3312 3.1496)
				(xy -0.00254 3.1496) (xy -0.00254 4.0005)
			)
			(stroke
				(width 0)
				(type default)
			)
			(fill no)
			(layer "F.CrtYd")
		)
		(fp_rect
			(start -8.8392 4.0005)
			(end 8.8392 -4.0005)
			(stroke
				(width 0)
				(type default)
			)
			(fill no)
			(layer "F.Fab")
		)
		(pad "" np_thru_hole circle
			(at -4.99999 0)
			(size 0.254 0.254)
			(drill 1.016)
			(layers "*.Cu" "*.Mask")
			(clearance 0.7366)
			(thermal_gap 0.7366)
		)
		(pad "" np_thru_hole circle
			(at 4.99999 0)
			(size 0.254 0.254)
			(drill 1.016)
			(layers "*.Cu" "*.Mask")
			(clearance 0.7366)
			(thermal_gap 0.7366)
		)
		(pad "1" smd rect
			(at -5.999988 2.124964)
			(size 0.9906 2.7432)
			(layers "F.Cu" "F.Mask" "F.Paste")
			(net "EJTAG_TRSTB")
		)
		(pad "2" smd rect
			(at -5.999988 -2.124964)
			(size 0.9906 2.7432)
			(layers "F.Cu" "F.Mask" "F.Paste")
			(net "GND")
		)
		(pad "3" smd rect
			(at -3.999992 2.124964)
			(size 0.9906 2.7432)
			(layers "F.Cu" "F.Mask" "F.Paste")
			(net "EJTAG_TDI")
		)
		(pad "4" smd rect
			(at -3.999992 -2.124964)
			(size 0.9906 2.7432)
			(layers "F.Cu" "F.Mask" "F.Paste")
			(net "GND")
		)
		(pad "5" smd rect
			(at -1.999996 2.124964)
			(size 0.9906 2.7432)
			(layers "F.Cu" "F.Mask" "F.Paste")
			(net "EJTAG_TDO")
		)
		(pad "6" smd rect
			(at -1.999996 -2.124964)
			(size 0.9906 2.7432)
			(layers "F.Cu" "F.Mask" "F.Paste")
			(net "GND")
		)
		(pad "7" smd rect
			(at 0 2.124964)
			(size 0.9906 2.7432)
			(layers "F.Cu" "F.Mask" "F.Paste")
			(net "EJTAG_TMS")
		)
		(pad "8" smd rect
			(at 0 -2.124964)
			(size 0.9906 2.7432)
			(layers "F.Cu" "F.Mask" "F.Paste")
			(net "GND")
		)
		(pad "9" smd rect
			(at 1.999996 2.124964)
			(size 0.9906 2.7432)
			(layers "F.Cu" "F.Mask" "F.Paste")
			(net "EJTAG_TCK")
		)
		(pad "10" smd rect
			(at 1.999996 -2.124964)
			(size 0.9906 2.7432)
			(layers "F.Cu" "F.Mask" "F.Paste")
			(net "GND")
		)
		(pad "11" smd rect
			(at 3.999992 2.124964)
			(size 0.9906 2.7432)
			(layers "F.Cu" "F.Mask" "F.Paste")
			(net "EJTAG_RSTB")
		)
		(pad "12" smd rect
			(at 3.999992 -2.124964)
			(size 0.9906 2.7432)
			(layers "F.Cu" "F.Mask" "F.Paste")
			(net "Net_4")
		)
		(pad "13" smd rect
			(at 5.999988 2.124964)
			(size 0.9906 2.7432)
			(layers "F.Cu" "F.Mask" "F.Paste")
			(net "EJTAG_DINT")
		)
		(pad "14" smd rect
			(at 5.999988 -2.124964)
			(size 0.9906 2.7432)
			(layers "F.Cu" "F.Mask" "F.Paste")
			(net "EJTAG_PWR")
		)
		(zone
			(layer "F.Cu")
			(hatch none 0.5)
			(connect_pads
				(clearance 0)
			)
			(min_thickness 0.25)
			(keepout
				(tracks allowed)
				(vias not_allowed)
				(pads allowed)
				(copperpour not_allowed)
				(footprints allowed)
			)
			(placement
				(enabled no)
				(sheetname "")
			)
			(fill
				(thermal_gap 0.5)
				(thermal_bridge_width 0.5)
				(island_removal_mode 0)
			)
			(polygon
				(pts
					(xy 132.163312 -47.489364) (xy 132.163312 -46.981364) (xy 145.153888 -46.981364) (xy 145.153888 -47.489364)
				)
			)
		)
		(zone
			(layer "F.Cu")
			(hatch none 0.5)
			(connect_pads
				(clearance 0)
			)
			(min_thickness 0.25)
			(keepout
				(tracks allowed)
				(vias not_allowed)
				(pads allowed)
				(copperpour not_allowed)
				(footprints allowed)
			)
			(placement
				(enabled no)
				(sheetname "")
			)
			(fill
				(thermal_gap 0.5)
				(thermal_bridge_width 0.5)
				(island_removal_mode 0)
			)
			(polygon
				(pts
					(xy 132.163312 -47.489364) (xy 132.163312 -45.982636) (xy 145.153888 -45.982636) (xy 145.153888 -47.489364)
				)
			)
		)
		(zone
			(layer "F.Cu")
			(hatch none 0.5)
			(connect_pads
				(clearance 0)
			)
			(min_thickness 0.25)
			(keepout
				(tracks not_allowed)
				(vias allowed)
				(pads allowed)
				(copperpour not_allowed)
				(footprints allowed)
			)
			(placement
				(enabled no)
				(sheetname "")
			)
			(fill
				(thermal_gap 0.5)
				(thermal_bridge_width 0.5)
				(island_removal_mode 0)
			)
			(polygon
				(pts
					(xy 132.163312 -47.489364) (xy 132.163312 -45.982636) (xy 145.153888 -45.982636) (xy 145.153888 -47.489364)
				)
			)
		)
		(zone
			(layer "F.Cu")
			(hatch none 0.5)
			(connect_pads
				(clearance 0)
			)
			(min_thickness 0.25)
			(keepout
				(tracks allowed)
				(vias not_allowed)
				(pads allowed)
				(copperpour not_allowed)
				(footprints allowed)
			)
			(placement
				(enabled no)
				(sheetname "")
			)
			(fill
				(thermal_gap 0.5)
				(thermal_bridge_width 0.5)
				(island_removal_mode 0)
			)
			(polygon
				(pts
					(xy 132.163312 -46.490636) (xy 132.163312 -45.982636) (xy 145.153888 -45.982636) (xy 145.153888 -46.490636)
				)
			)
		)
		(zone
			(layers "F.Cu" "B.Cu" "In1.Cu" "In2.Cu" "In3.Cu" "In4.Cu" "In5.Cu" "In6.Cu")
			(hatch none 0.5)
			(connect_pads
				(clearance 0)
			)
			(min_thickness 0.25)
			(keepout
				(tracks not_allowed)
				(vias allowed)
				(pads allowed)
				(copperpour not_allowed)
				(footprints allowed)
			)
			(placement
				(enabled no)
				(sheetname "")
			)
			(fill
				(thermal_gap 0.5)
				(thermal_bridge_width 0.5)
				(island_removal_mode 0)
			)
			(polygon
				(pts
					(arc
						(start 134.47141 -46.736)
						(mid 132.84581 -46.736)
						(end 134.47141 -46.736)
					)
				)
			)
		)
		(zone
			(layers "F.Cu" "B.Cu" "In1.Cu" "In2.Cu" "In3.Cu" "In4.Cu" "In5.Cu" "In6.Cu")
			(hatch none 0.5)
			(connect_pads
				(clearance 0)
			)
			(min_thickness 0.25)
			(keepout
				(tracks not_allowed)
				(vias allowed)
				(pads allowed)
				(copperpour not_allowed)
				(footprints allowed)
			)
			(placement
				(enabled no)
				(sheetname "")
			)
			(fill
				(thermal_gap 0.5)
				(thermal_bridge_width 0.5)
				(island_removal_mode 0)
			)
			(polygon
				(pts
					(arc
						(start 144.47139 -46.736)
						(mid 142.84579 -46.736)
						(end 144.47139 -46.736)
					)
				)
			)
		)
	)
	(footprint ""
		(layer "F.Cu")
		(at 189.611 -7.9248 -90)
		(property "Reference" "U38"
			(at 0 0 270)
			(layer "F.SilkS")
			(hide yes)
			(effects
				(font
					(size 1.27 1.27)
				)
			)
		)
		(property "Value" "SN74LVC1G08DCKR-GP"
			(at -2.3368 -8.6868 270)
			(unlocked yes)
			(layer "F.Fab")
			(hide yes)
			(effects
				(font
					(size 1.016 1.016)
					(thickness 0.1524)
				)
			)
		)
		(property "Device Type" "SC70-5H44"
			(at -2.3114 -10.414 270)
			(unlocked yes)
			(layer "F.Fab")
			(hide yes)
			(effects
				(font
					(size 1.016 1.016)
					(thickness 0.1524)
				)
			)
		)
		(duplicate_pad_numbers_are_jumpers no)
		(fp_line
			(start -1.27 1.7018)
			(end -1.27 -1.7018)
			(stroke
				(width 0.1524)
				(type default)
			)
			(layer "F.SilkS")
		)
		(fp_line
			(start 1.27 1.7018)
			(end -1.27 1.7018)
			(stroke
				(width 0.1524)
				(type default)
			)
			(layer "F.SilkS")
		)
		(fp_line
			(start -1.27 -1.7018)
			(end 1.27 -1.7018)
			(stroke
				(width 0.1524)
				(type default)
			)
			(layer "F.SilkS")
		)
		(fp_line
			(start 1.27 -1.7018)
			(end 1.27 1.7018)
			(stroke
				(width 0.1524)
				(type default)
			)
			(layer "F.SilkS")
		)
		(fp_line
			(start 0.6604 -1.8034)
			(end 1.3843 -1.8034)
			(stroke
				(width 0.3302)
				(type default)
			)
			(layer "F.SilkS")
		)
		(fp_line
			(start 1.3843 -1.8034)
			(end 1.3843 -1.1176)
			(stroke
				(width 0.3302)
				(type default)
			)
			(layer "F.SilkS")
		)
		(fp_rect
			(start -1.524 1.9558)
			(end 1.524 -1.9558)
			(stroke
				(width 0)
				(type default)
			)
			(fill no)
			(layer "F.CrtYd")
		)
		(fp_poly
			(pts
				(xy -1.524 -1.9558) (xy 1.524 -1.9558) (xy 1.524 1.9558) (xy -1.524 1.9558)
			)
			(stroke
				(width 0)
				(type default)
			)
			(fill no)
			(layer "F.Fab")
		)
		(pad "1" smd rect
			(at 0.65024 -0.8255 270)
			(size 0.4064 1.2192)
			(layers "F.Cu" "F.Mask" "F.Paste")
			(net "HB_OUT_R")
		)
		(pad "2" smd rect
			(at 0 -0.8255 270)
			(size 0.4064 1.2192)
			(layers "F.Cu" "F.Mask" "F.Paste")
			(net "BMC_ENCLOSURE_LED_R")
		)
		(pad "3" smd rect
			(at -0.65024 -0.8255 270)
			(size 0.4064 1.2192)
			(layers "F.Cu" "F.Mask" "F.Paste")
			(net "GND")
		)
		(pad "4" smd rect
			(at -0.65024 0.8255 270)
			(size 0.4064 1.2192)
			(layers "F.Cu" "F.Mask" "F.Paste")
			(net "ENCLO_LED_BLUE_OUT")
		)
		(pad "5" smd rect
			(at 0.65024 0.8255 270)
			(size 0.4064 1.2192)
			(layers "F.Cu" "F.Mask" "F.Paste")
			(net "P3V3_STBY")
		)
	)
	(footprint ""
		(layer "F.Cu")
		(at 15.4432 -194.2592 180)
		(property "Reference" "R2174"
			(at 0 0 180)
			(layer "F.SilkS")
			(hide yes)
			(effects
				(font
					(size 1.27 1.27)
				)
			)
		)
		(property "Value" "100KR2J-4-GP"
			(at 0.064008 -3.993896 180)
			(unlocked yes)
			(layer "F.Fab")
			(hide yes)
			(effects
				(font
					(size 1.016 1.016)
					(thickness 0.1524)
				)
			)
		)
		(property "Device Type" "R402H15"
			(at 0.064008 -5.517896 180)
			(unlocked yes)
			(layer "F.Fab")
			(hide yes)
			(effects
				(font
					(size 1.016 1.016)
					(thickness 0.1524)
				)
			)
		)
		(duplicate_pad_numbers_are_jumpers no)
		(fp_line
			(start 0.508 -0.9398)
			(end -0.508 -0.9398)
			(stroke
				(width 0.1524)
				(type default)
			)
			(layer "F.SilkS")
		)
		(fp_line
			(start -0.508 -0.9398)
			(end -0.508 0.9398)
			(stroke
				(width 0.1524)
				(type default)
			)
			(layer "F.SilkS")
		)
		(fp_rect
			(start -0.508 0.9398)
			(end 0.508 -0.9398)
			(stroke
				(width 0)
				(type default)
			)
			(fill no)
			(layer "F.CrtYd")
		)
		(fp_rect
			(start -0.508 0.9398)
			(end 0.508 -0.9398)
			(stroke
				(width 0)
				(type default)
			)
			(fill no)
			(layer "F.Fab")
		)
		(pad "1" smd custom
			(at 0 -0.4445 180)
			(size 0.1397 0.1397)
			(layers "F.Cu" "F.Mask" "F.Paste")
			(net "MB0_VCAP_R")
			(options
				(clearance outline)
				(anchor circle)
			)
			(primitives
				(gr_poly
					(pts
						(arc
							(start -0.1778 -0.2794)
							(mid -0.249642 -0.249642)
							(end -0.2794 -0.1778)
						)
						(arc
							(start -0.2794 0.1778)
							(mid -0.249642 0.249642)
							(end -0.1778 0.2794)
						)
						(arc
							(start 0.1778 0.2794)
							(mid 0.249642 0.249642)
							(end 0.2794 0.1778)
						)
						(arc
							(start 0.2794 -0.1778)
							(mid 0.249642 -0.249642)
							(end 0.1778 -0.2794)
						)
					)
					(width 0)
					(fill yes)
				)
			)
		)
		(pad "2" smd custom
			(at 0 0.4445 180)
			(size 0.1397 0.1397)
			(layers "F.Cu" "F.Mask" "F.Paste")
			(net "MB0_ISTART_R")
			(options
				(clearance outline)
				(anchor circle)
			)
			(primitives
				(gr_poly
					(pts
						(arc
							(start -0.1778 -0.2794)
							(mid -0.249642 -0.249642)
							(end -0.2794 -0.1778)
						)
						(arc
							(start -0.2794 0.1778)
							(mid -0.249642 0.249642)
							(end -0.1778 0.2794)
						)
						(arc
							(start 0.1778 0.2794)
							(mid 0.249642 0.249642)
							(end 0.2794 0.1778)
						)
						(arc
							(start 0.2794 -0.1778)
							(mid 0.249642 -0.249642)
							(end 0.1778 -0.2794)
						)
					)
					(width 0)
					(fill yes)
				)
			)
		)
	)
	(footprint ""
		(layer "F.Cu")
		(at 23.876 -128.524 90)
		(property "Reference" "R365"
			(at 0 0 90)
			(layer "F.SilkS")
			(hide yes)
			(effects
				(font
					(size 1.27 1.27)
				)
			)
		)
		(property "Value" "3K3R2F-2-GP"
			(at 0.064008 -3.993896 90)
			(unlocked yes)
			(layer "F.Fab")
			(hide yes)
			(effects
				(font
					(size 1.016 1.016)
					(thickness 0.1524)
				)
			)
		)
		(property "Device Type" "R402H16"
			(at 0.064008 -5.517896 90)
			(unlocked yes)
			(layer "F.Fab")
			(hide yes)
			(effects
				(font
					(size 1.016 1.016)
					(thickness 0.1524)
				)
			)
		)
		(duplicate_pad_numbers_are_jumpers no)
		(fp_line
			(start 0.508 -0.9398)
			(end -0.508 -0.9398)
			(stroke
				(width 0.1524)
				(type default)
			)
			(layer "F.SilkS")
		)
		(fp_line
			(start -0.508 -0.9398)
			(end -0.508 0.9398)
			(stroke
				(width 0.1524)
				(type default)
			)
			(layer "F.SilkS")
		)
		(fp_rect
			(start -0.508 0.9398)
			(end 0.508 -0.9398)
			(stroke
				(width 0)
				(type default)
			)
			(fill no)
			(layer "F.CrtYd")
		)
		(fp_rect
			(start -0.508 0.9398)
			(end 0.508 -0.9398)
			(stroke
				(width 0)
				(type default)
			)
			(fill no)
			(layer "F.Fab")
		)
		(pad "1" smd custom
			(at 0 -0.4445 90)
			(size 0.1397 0.1397)
			(layers "F.Cu" "F.Mask" "F.Paste")
			(net "P3V3_STBY")
			(options
				(clearance outline)
				(anchor circle)
			)
			(primitives
				(gr_poly
					(pts
						(arc
							(start -0.1778 -0.2794)
							(mid -0.249642 -0.249642)
							(end -0.2794 -0.1778)
						)
						(arc
							(start -0.2794 0.1778)
							(mid -0.249642 0.249642)
							(end -0.1778 0.2794)
						)
						(arc
							(start 0.1778 0.2794)
							(mid 0.249642 0.249642)
							(end 0.2794 0.1778)
						)
						(arc
							(start 0.2794 -0.1778)
							(mid 0.249642 -0.249642)
							(end 0.1778 -0.2794)
						)
					)
					(width 0)
					(fill yes)
				)
			)
		)
		(pad "2" smd custom
			(at 0 0.4445 90)
			(size 0.1397 0.1397)
			(layers "F.Cu" "F.Mask" "F.Paste")
			(net "ROMA22")
			(options
				(clearance outline)
				(anchor circle)
			)
			(primitives
				(gr_poly
					(pts
						(arc
							(start -0.1778 -0.2794)
							(mid -0.249642 -0.249642)
							(end -0.2794 -0.1778)
						)
						(arc
							(start -0.2794 0.1778)
							(mid -0.249642 0.249642)
							(end -0.1778 0.2794)
						)
						(arc
							(start 0.1778 0.2794)
							(mid 0.249642 0.249642)
							(end 0.2794 0.1778)
						)
						(arc
							(start 0.2794 -0.1778)
							(mid 0.249642 -0.249642)
							(end 0.1778 -0.2794)
						)
					)
					(width 0)
					(fill yes)
				)
			)
		)
	)
	(footprint ""
		(layer "F.Cu")
		(at 73.7108 -180.1622 180)
		(property "Reference" "C4104"
			(at 0 0 180)
			(layer "F.SilkS")
			(hide yes)
			(effects
				(font
					(size 1.27 1.27)
				)
			)
		)
		(property "Value" "SCD1U25V3KX-GP"
			(at 0 -2.8194 180)
			(unlocked yes)
			(layer "F.Fab")
			(hide yes)
			(effects
				(font
					(size 1.016 1.016)
					(thickness 0.1524)
				)
			)
		)
		(property "Device Type" "C603H36"
			(at 0 -4.3434 180)
			(unlocked yes)
			(layer "F.Fab")
			(hide yes)
			(effects
				(font
					(size 1.016 1.016)
					(thickness 0.1524)
				)
			)
		)
		(duplicate_pad_numbers_are_jumpers no)
		(fp_line
			(start 0.508 0)
			(end -0.508 0)
			(stroke
				(width 0.2032)
				(type default)
			)
			(layer "F.SilkS")
		)
		(fp_rect
			(start -0.5842 1.3335)
			(end 0.5842 -1.3335)
			(stroke
				(width 0)
				(type default)
			)
			(fill no)
			(layer "F.CrtYd")
		)
		(fp_rect
			(start -0.5842 1.3335)
			(end 0.5842 -1.3335)
			(stroke
				(width 0)
				(type default)
			)
			(fill no)
			(layer "F.Fab")
		)
		(pad "1" smd custom
			(at 0 -0.762 180)
			(size 0.2159 0.2159)
			(layers "F.Cu" "F.Mask" "F.Paste")
			(net "GND")
			(options
				(clearance outline)
				(anchor circle)
			)
			(primitives
				(gr_poly
					(pts
						(arc
							(start -0.3302 -0.4318)
							(mid -0.402042 -0.402042)
							(end -0.4318 -0.3302)
						)
						(arc
							(start -0.4318 0.3302)
							(mid -0.402042 0.402042)
							(end -0.3302 0.4318)
						)
						(arc
							(start 0.3302 0.4318)
							(mid 0.402042 0.402042)
							(end 0.4318 0.3302)
						)
						(arc
							(start 0.4318 -0.3302)
							(mid 0.402042 -0.402042)
							(end 0.3302 -0.4318)
						)
					)
					(width 0)
					(fill yes)
				)
			)
		)
		(pad "2" smd custom
			(at 0 0.762 180)
			(size 0.2159 0.2159)
			(layers "F.Cu" "F.Mask" "F.Paste")
			(net "SSD_PWREN0_R")
			(options
				(clearance outline)
				(anchor circle)
			)
			(primitives
				(gr_poly
					(pts
						(arc
							(start -0.3302 -0.4318)
							(mid -0.402042 -0.402042)
							(end -0.4318 -0.3302)
						)
						(arc
							(start -0.4318 0.3302)
							(mid -0.402042 0.402042)
							(end -0.3302 0.4318)
						)
						(arc
							(start 0.3302 0.4318)
							(mid 0.402042 0.402042)
							(end 0.4318 0.3302)
						)
						(arc
							(start 0.4318 -0.3302)
							(mid 0.402042 -0.402042)
							(end 0.3302 -0.4318)
						)
					)
					(width 0)
					(fill yes)
				)
			)
		)
	)
	(footprint ""
		(layer "F.Cu")
		(at 13.5128 -118.9736)
		(property "Reference" "R600"
			(at 0 0 0)
			(layer "F.SilkS")
			(hide yes)
			(effects
				(font
					(size 1.27 1.27)
				)
			)
		)
		(property "Value" "4K7R2F-GP"
			(at 0.064008 -3.993896 0)
			(unlocked yes)
			(layer "F.Fab")
			(hide yes)
			(effects
				(font
					(size 1.016 1.016)
					(thickness 0.1524)
				)
			)
		)
		(property "Device Type" "R402H16"
			(at 0.064008 -5.517896 0)
			(unlocked yes)
			(layer "F.Fab")
			(hide yes)
			(effects
				(font
					(size 1.016 1.016)
					(thickness 0.1524)
				)
			)
		)
		(duplicate_pad_numbers_are_jumpers no)
		(fp_line
			(start -0.508 -0.9398)
			(end -0.508 0.9398)
			(stroke
				(width 0.1524)
				(type default)
			)
			(layer "F.SilkS")
		)
		(fp_line
			(start 0.508 -0.9398)
			(end -0.508 -0.9398)
			(stroke
				(width 0.1524)
				(type default)
			)
			(layer "F.SilkS")
		)
		(fp_rect
			(start -0.508 0.9398)
			(end 0.508 -0.9398)
			(stroke
				(width 0)
				(type default)
			)
			(fill no)
			(layer "F.CrtYd")
		)
		(fp_rect
			(start -0.508 0.9398)
			(end 0.508 -0.9398)
			(stroke
				(width 0)
				(type default)
			)
			(fill no)
			(layer "F.Fab")
		)
		(pad "1" smd custom
			(at 0 -0.4445)
			(size 0.1397 0.1397)
			(layers "F.Cu" "F.Mask" "F.Paste")
			(net "BMC_I2C1_MINI1_SDA_S")
			(options
				(clearance outline)
				(anchor circle)
			)
			(primitives
				(gr_poly
					(pts
						(arc
							(start -0.1778 -0.2794)
							(mid -0.249642 -0.249642)
							(end -0.2794 -0.1778)
						)
						(arc
							(start -0.2794 0.1778)
							(mid -0.249642 0.249642)
							(end -0.1778 0.2794)
						)
						(arc
							(start 0.1778 0.2794)
							(mid 0.249642 0.249642)
							(end 0.2794 0.1778)
						)
						(arc
							(start 0.2794 -0.1778)
							(mid 0.249642 -0.249642)
							(end 0.1778 -0.2794)
						)
					)
					(width 0)
					(fill yes)
				)
			)
		)
		(pad "2" smd custom
			(at 0 0.4445)
			(size 0.1397 0.1397)
			(layers "F.Cu" "F.Mask" "F.Paste")
			(net "P3V3_STBY")
			(options
				(clearance outline)
				(anchor circle)
			)
			(primitives
				(gr_poly
					(pts
						(arc
							(start -0.1778 -0.2794)
							(mid -0.249642 -0.249642)
							(end -0.2794 -0.1778)
						)
						(arc
							(start -0.2794 0.1778)
							(mid -0.249642 0.249642)
							(end -0.1778 0.2794)
						)
						(arc
							(start 0.1778 0.2794)
							(mid 0.249642 0.249642)
							(end 0.2794 0.1778)
						)
						(arc
							(start 0.2794 -0.1778)
							(mid 0.249642 -0.249642)
							(end 0.1778 -0.2794)
						)
					)
					(width 0)
					(fill yes)
				)
			)
		)
	)
	(footprint ""
		(layer "F.Cu")
		(at 15.875 -182.2196 90)
		(property "Reference" "P2121"
			(at 0 0 90)
			(layer "F.SilkS")
			(hide yes)
			(effects
				(font
					(size 1.27 1.27)
				)
			)
		)
		(property "Value" "0R0603-PAD-2-GP-U"
			(at 2.1209 -0.1397 90)
			(unlocked yes)
			(layer "F.Fab")
			(hide yes)
			(effects
				(font
					(size 1.016 1.016)
					(thickness 0.1524)
				)
			)
		)
		(property "Device Type" "0R0603-PAD-1-U"
			(at 2.1209 -1.6637 90)
			(unlocked yes)
			(layer "F.Fab")
			(hide yes)
			(effects
				(font
					(size 1.016 1.016)
					(thickness 0.1524)
				)
			)
		)
		(duplicate_pad_numbers_are_jumpers no)
		(fp_rect
			(start -0.5842 1.3335)
			(end 0.5842 -1.3335)
			(stroke
				(width 0)
				(type default)
			)
			(fill no)
			(layer "F.CrtYd")
		)
		(fp_rect
			(start -0.5842 1.3335)
			(end 0.5842 -1.3335)
			(stroke
				(width 0)
				(type default)
			)
			(fill no)
			(layer "F.Fab")
		)
		(pad "1" smd custom
			(at 0 -0.762 90)
			(size 0.2159 0.2159)
			(layers "F.Cu" "F.Mask" "F.Paste")
			(net "AGND_CURRENT_MON")
			(options
				(clearance outline)
				(anchor circle)
			)
			(primitives
				(gr_poly
					(pts
						(arc
							(start -0.3302 -0.5842)
							(mid -0.402042 -0.554442)
							(end -0.4318 -0.4826)
						)
						(arc
							(start -0.4318 0.4826)
							(mid -0.402042 0.554442)
							(end -0.3302 0.5842)
						)
						(arc
							(start 0.3302 0.5842)
							(mid 0.402042 0.554442)
							(end 0.4318 0.4826)
						)
						(arc
							(start 0.4318 -0.4826)
							(mid 0.402042 -0.554442)
							(end 0.3302 -0.5842)
						)
					)
					(width 0)
					(fill yes)
				)
			)
		)
		(pad "2" smd custom
			(at 0 0.762 90)
			(size 0.2159 0.2159)
			(layers "F.Cu" "F.Mask" "F.Paste")
			(net "GND")
			(options
				(clearance outline)
				(anchor circle)
			)
			(primitives
				(gr_poly
					(pts
						(arc
							(start -0.4318 0.4826)
							(mid -0.402042 0.554442)
							(end -0.3302 0.5842)
						)
						(arc
							(start 0.3302 0.5842)
							(mid 0.402042 0.554442)
							(end 0.4318 0.4826)
						)
						(arc
							(start 0.4318 -0.4826)
							(mid 0.402042 -0.554442)
							(end 0.3302 -0.5842)
						)
						(arc
							(start -0.3302 -0.5842)
							(mid -0.402042 -0.554442)
							(end -0.4318 -0.4826)
						)
					)
					(width 0)
					(fill yes)
				)
			)
		)
	)
	(footprint ""
		(layer "F.Cu")
		(at 51.591972 -212.420454 180)
		(property "Reference" "C363"
			(at 0 0 180)
			(layer "F.SilkS")
			(hide yes)
			(effects
				(font
					(size 1.27 1.27)
				)
			)
		)
		(property "Value" "SCD22U10V2KX-1GP"
			(at 1.1811 -2.7051 180)
			(unlocked yes)
			(layer "F.Fab")
			(hide yes)
			(effects
				(font
					(size 1.016 1.016)
					(thickness 0.1524)
				)
			)
		)
		(property "Device Type" "C402H22"
			(at 1.1811 -4.2291 180)
			(unlocked yes)
			(layer "F.Fab")
			(hide yes)
			(effects
				(font
					(size 1.016 1.016)
					(thickness 0.1524)
				)
			)
		)
		(duplicate_pad_numbers_are_jumpers no)
		(fp_rect
			(start -0.4318 0.9525)
			(end 0.4318 -0.9525)
			(stroke
				(width 0)
				(type default)
			)
			(fill no)
			(layer "F.CrtYd")
		)
		(fp_rect
			(start -0.4318 0.9525)
			(end 0.4318 -0.9525)
			(stroke
				(width 0)
				(type default)
			)
			(fill no)
			(layer "F.Fab")
		)
		(pad "1" smd custom
			(at 0 -0.4445 180)
			(size 0.1524 0.1524)
			(layers "F.Cu" "F.Mask" "F.Paste")
			(net "PCIE_TX_CAP_P74")
			(options
				(clearance outline)
				(anchor circle)
			)
			(primitives
				(gr_poly
					(pts
						(arc
							(start 0.3048 -0.2032)
							(mid 0.275042 -0.275042)
							(end 0.2032 -0.3048)
						)
						(arc
							(start -0.2032 -0.3048)
							(mid -0.275042 -0.275042)
							(end -0.3048 -0.2032)
						)
						(arc
							(start -0.3048 0.2032)
							(mid -0.275042 0.275042)
							(end -0.2032 0.3048)
						)
						(arc
							(start 0.2032 0.3048)
							(mid 0.275042 0.275042)
							(end 0.3048 0.2032)
						)
					)
					(width 0)
					(fill yes)
				)
			)
		)
		(pad "2" smd custom
			(at 0 0.4445 180)
			(size 0.1524 0.1524)
			(layers "F.Cu" "F.Mask" "F.Paste")
			(net "PCIE_TX_P74")
			(options
				(clearance outline)
				(anchor circle)
			)
			(primitives
				(gr_poly
					(pts
						(arc
							(start 0.3048 -0.2032)
							(mid 0.275042 -0.275042)
							(end 0.2032 -0.3048)
						)
						(arc
							(start -0.2032 -0.3048)
							(mid -0.275042 -0.275042)
							(end -0.3048 -0.2032)
						)
						(arc
							(start -0.3048 0.2032)
							(mid -0.275042 0.275042)
							(end -0.2032 0.3048)
						)
						(arc
							(start 0.2032 0.3048)
							(mid 0.275042 0.275042)
							(end 0.3048 0.2032)
						)
					)
					(width 0)
					(fill yes)
				)
			)
		)
	)
	(footprint ""
		(layer "F.Cu")
		(at 11.176 -71.3486 -90)
		(property "Reference" "R386"
			(at 0 0 270)
			(layer "F.SilkS")
			(hide yes)
			(effects
				(font
					(size 1.27 1.27)
				)
			)
		)
		(property "Value" "0R2J-2-GP"
			(at 0.064008 -3.993896 270)
			(unlocked yes)
			(layer "F.Fab")
			(hide yes)
			(effects
				(font
					(size 1.016 1.016)
					(thickness 0.1524)
				)
			)
		)
		(property "Device Type" "R402H16"
			(at 0.064008 -5.517896 270)
			(unlocked yes)
			(layer "F.Fab")
			(hide yes)
			(effects
				(font
					(size 1.016 1.016)
					(thickness 0.1524)
				)
			)
		)
		(duplicate_pad_numbers_are_jumpers no)
		(fp_line
			(start -0.508 -0.9398)
			(end -0.508 0.9398)
			(stroke
				(width 0.1524)
				(type default)
			)
			(layer "F.SilkS")
		)
		(fp_line
			(start 0.508 -0.9398)
			(end -0.508 -0.9398)
			(stroke
				(width 0.1524)
				(type default)
			)
			(layer "F.SilkS")
		)
		(fp_rect
			(start -0.508 0.9398)
			(end 0.508 -0.9398)
			(stroke
				(width 0)
				(type default)
			)
			(fill no)
			(layer "F.CrtYd")
		)
		(fp_rect
			(start -0.508 0.9398)
			(end 0.508 -0.9398)
			(stroke
				(width 0)
				(type default)
			)
			(fill no)
			(layer "F.Fab")
		)
		(pad "1" smd custom
			(at 0 -0.4445 270)
			(size 0.1397 0.1397)
			(layers "F.Cu" "F.Mask" "F.Paste")
			(net "XTAL_OUT_I210")
			(options
				(clearance outline)
				(anchor circle)
			)
			(primitives
				(gr_poly
					(pts
						(arc
							(start -0.1778 -0.2794)
							(mid -0.249642 -0.249642)
							(end -0.2794 -0.1778)
						)
						(arc
							(start -0.2794 0.1778)
							(mid -0.249642 0.249642)
							(end -0.1778 0.2794)
						)
						(arc
							(start 0.1778 0.2794)
							(mid 0.249642 0.249642)
							(end 0.2794 0.1778)
						)
						(arc
							(start 0.2794 -0.1778)
							(mid 0.249642 -0.249642)
							(end 0.1778 -0.2794)
						)
					)
					(width 0)
					(fill yes)
				)
			)
		)
		(pad "2" smd custom
			(at 0 0.4445 270)
			(size 0.1397 0.1397)
			(layers "F.Cu" "F.Mask" "F.Paste")
			(net "XTAL_OUT_I210_R")
			(options
				(clearance outline)
				(anchor circle)
			)
			(primitives
				(gr_poly
					(pts
						(arc
							(start -0.1778 -0.2794)
							(mid -0.249642 -0.249642)
							(end -0.2794 -0.1778)
						)
						(arc
							(start -0.2794 0.1778)
							(mid -0.249642 0.249642)
							(end -0.1778 0.2794)
						)
						(arc
							(start 0.1778 0.2794)
							(mid 0.249642 0.249642)
							(end 0.2794 0.1778)
						)
						(arc
							(start 0.2794 -0.1778)
							(mid 0.249642 -0.249642)
							(end 0.1778 -0.2794)
						)
					)
					(width 0)
					(fill yes)
				)
			)
		)
	)
	(footprint ""
		(layer "F.Cu")
		(at 183.992266 -212.420454 180)
		(property "Reference" "C127"
			(at 0 0 180)
			(layer "F.SilkS")
			(hide yes)
			(effects
				(font
					(size 1.27 1.27)
				)
			)
		)
		(property "Value" "SCD22U10V2KX-1GP"
			(at 1.1811 -2.7051 180)
			(unlocked yes)
			(layer "F.Fab")
			(hide yes)
			(effects
				(font
					(size 1.016 1.016)
					(thickness 0.1524)
				)
			)
		)
		(property "Device Type" "C402H22"
			(at 1.1811 -4.2291 180)
			(unlocked yes)
			(layer "F.Fab")
			(hide yes)
			(effects
				(font
					(size 1.016 1.016)
					(thickness 0.1524)
				)
			)
		)
		(duplicate_pad_numbers_are_jumpers no)
		(fp_rect
			(start -0.4318 0.9525)
			(end 0.4318 -0.9525)
			(stroke
				(width 0)
				(type default)
			)
			(fill no)
			(layer "F.CrtYd")
		)
		(fp_rect
			(start -0.4318 0.9525)
			(end 0.4318 -0.9525)
			(stroke
				(width 0)
				(type default)
			)
			(fill no)
			(layer "F.Fab")
		)
		(pad "1" smd custom
			(at 0 -0.4445 180)
			(size 0.1524 0.1524)
			(layers "F.Cu" "F.Mask" "F.Paste")
			(net "PCIE_TX_CAP_P47")
			(options
				(clearance outline)
				(anchor circle)
			)
			(primitives
				(gr_poly
					(pts
						(arc
							(start 0.3048 -0.2032)
							(mid 0.275042 -0.275042)
							(end 0.2032 -0.3048)
						)
						(arc
							(start -0.2032 -0.3048)
							(mid -0.275042 -0.275042)
							(end -0.3048 -0.2032)
						)
						(arc
							(start -0.3048 0.2032)
							(mid -0.275042 0.275042)
							(end -0.2032 0.3048)
						)
						(arc
							(start 0.2032 0.3048)
							(mid 0.275042 0.275042)
							(end 0.3048 0.2032)
						)
					)
					(width 0)
					(fill yes)
				)
			)
		)
		(pad "2" smd custom
			(at 0 0.4445 180)
			(size 0.1524 0.1524)
			(layers "F.Cu" "F.Mask" "F.Paste")
			(net "PCIE_TX_P47")
			(options
				(clearance outline)
				(anchor circle)
			)
			(primitives
				(gr_poly
					(pts
						(arc
							(start 0.3048 -0.2032)
							(mid 0.275042 -0.275042)
							(end 0.2032 -0.3048)
						)
						(arc
							(start -0.2032 -0.3048)
							(mid -0.275042 -0.275042)
							(end -0.3048 -0.2032)
						)
						(arc
							(start -0.3048 0.2032)
							(mid -0.275042 0.275042)
							(end -0.2032 0.3048)
						)
						(arc
							(start 0.2032 0.3048)
							(mid 0.275042 0.275042)
							(end 0.3048 0.2032)
						)
					)
					(width 0)
					(fill yes)
				)
			)
		)
	)
	(footprint ""
		(layer "F.Cu")
		(at 31.7754 -74.3712 180)
		(property "Reference" "PU58"
			(at 0 0 180)
			(layer "F.SilkS")
			(hide yes)
			(effects
				(font
					(size 1.27 1.27)
				)
			)
		)
		(property "Value" "SY8120ABC-GP"
			(at -0.0254 -11.9634 180)
			(unlocked yes)
			(layer "F.Fab")
			(hide yes)
			(effects
				(font
					(size 1.016 1.016)
					(thickness 0.1524)
				)
			)
		)
		(property "Device Type" "SOT-6H56"
			(at -0.0254 -13.5636 180)
			(unlocked yes)
			(layer "F.Fab")
			(hide yes)
			(effects
				(font
					(size 1.016 1.016)
					(thickness 0.1524)
				)
			)
		)
		(duplicate_pad_numbers_are_jumpers no)
		(fp_line
			(start 1.7145 0.5842)
			(end 1.7145 -0.5842)
			(stroke
				(width 0.1524)
				(type default)
			)
			(layer "F.SilkS")
		)
		(fp_line
			(start 1.7145 -0.5842)
			(end -1.9685 -0.5842)
			(stroke
				(width 0.1524)
				(type default)
			)
			(layer "F.SilkS")
		)
		(fp_line
			(start -1.5621 0)
			(end -1.9685 0.4064)
			(stroke
				(width 0.1524)
				(type default)
			)
			(layer "F.SilkS")
		)
		(fp_line
			(start -1.9685 0.5842)
			(end 1.7145 0.5842)
			(stroke
				(width 0.1524)
				(type default)
			)
			(layer "F.SilkS")
		)
		(fp_line
			(start -1.9685 0.5842)
			(end -1.9685 2.3622)
			(stroke
				(width 0.508)
				(type default)
			)
			(layer "F.SilkS")
		)
		(fp_line
			(start -1.9685 -0.4064)
			(end -1.5621 0)
			(stroke
				(width 0.1524)
				(type default)
			)
			(layer "F.SilkS")
		)
		(fp_line
			(start -1.9685 -0.5842)
			(end -1.9685 0.5842)
			(stroke
				(width 0.1524)
				(type default)
			)
			(layer "F.SilkS")
		)
		(fp_poly
			(pts
				(xy -1.27 -0.635) (xy 1.27 -0.635) (xy 1.27 0.635) (xy -1.27 0.635)
			)
			(stroke
				(width 0)
				(type default)
			)
			(fill yes)
			(layer "F.SilkS")
		)
		(fp_rect
			(start -1.9685 2.3622)
			(end 1.9685 -2.3622)
			(stroke
				(width 0)
				(type default)
			)
			(fill no)
			(layer "F.CrtYd")
		)
		(fp_poly
			(pts
				(xy -1.9685 -2.3622) (xy 1.9685 -2.3622) (xy 1.9685 2.3622) (xy -1.9685 2.3622)
			)
			(stroke
				(width 0)
				(type default)
			)
			(fill no)
			(layer "F.Fab")
		)
		(pad "1" smd rect
			(at -0.9525 1.3462 180)
			(size 0.5842 1.016)
			(layers "F.Cu" "F.Mask" "F.Paste")
			(net "P5V_STBY_BS")
		)
		(pad "2" smd rect
			(at 0 1.3462 180)
			(size 0.5842 1.016)
			(layers "F.Cu" "F.Mask" "F.Paste")
			(net "GND")
		)
		(pad "3" smd rect
			(at 0.9525 1.3462 180)
			(size 0.5842 1.016)
			(layers "F.Cu" "F.Mask" "F.Paste")
			(net "P5V_STBY_FB")
		)
		(pad "4" smd rect
			(at 0.9525 -1.3462 180)
			(size 0.5842 1.016)
			(layers "F.Cu" "F.Mask" "F.Paste")
			(net "P5V_STBY_EN")
		)
		(pad "5" smd rect
			(at 0 -1.3462 180)
			(size 0.5842 1.016)
			(layers "F.Cu" "F.Mask" "F.Paste")
			(net "P12V")
		)
		(pad "6" smd rect
			(at -0.9525 -1.3462 180)
			(size 0.5842 1.016)
			(layers "F.Cu" "F.Mask" "F.Paste")
			(net "P5V_STBY_LX")
		)
	)
	(footprint ""
		(layer "F.Cu")
		(at 39.0398 -186.5376)
		(property "Reference" "C701"
			(at 0 0 0)
			(layer "F.SilkS")
			(hide yes)
			(effects
				(font
					(size 1.27 1.27)
				)
			)
		)
		(property "Value" "SCD01U50V2KX-1GP"
			(at 1.1811 -2.7051 0)
			(unlocked yes)
			(layer "F.Fab")
			(hide yes)
			(effects
				(font
					(size 1.016 1.016)
					(thickness 0.1524)
				)
			)
		)
		(property "Device Type" "C402H22"
			(at 1.1811 -4.2291 0)
			(unlocked yes)
			(layer "F.Fab")
			(hide yes)
			(effects
				(font
					(size 1.016 1.016)
					(thickness 0.1524)
				)
			)
		)
		(duplicate_pad_numbers_are_jumpers no)
		(fp_rect
			(start -0.4318 0.9525)
			(end 0.4318 -0.9525)
			(stroke
				(width 0)
				(type default)
			)
			(fill no)
			(layer "F.CrtYd")
		)
		(fp_rect
			(start -0.4318 0.9525)
			(end 0.4318 -0.9525)
			(stroke
				(width 0)
				(type default)
			)
			(fill no)
			(layer "F.Fab")
		)
		(pad "1" smd custom
			(at 0 -0.4445)
			(size 0.1524 0.1524)
			(layers "F.Cu" "F.Mask" "F.Paste")
			(net "P3V3_STBY")
			(options
				(clearance outline)
				(anchor circle)
			)
			(primitives
				(gr_poly
					(pts
						(arc
							(start 0.3048 -0.2032)
							(mid 0.275042 -0.275042)
							(end 0.2032 -0.3048)
						)
						(arc
							(start -0.2032 -0.3048)
							(mid -0.275042 -0.275042)
							(end -0.3048 -0.2032)
						)
						(arc
							(start -0.3048 0.2032)
							(mid -0.275042 0.275042)
							(end -0.2032 0.3048)
						)
						(arc
							(start 0.2032 0.3048)
							(mid 0.275042 0.275042)
							(end 0.3048 0.2032)
						)
					)
					(width 0)
					(fill yes)
				)
			)
		)
		(pad "2" smd custom
			(at 0 0.4445)
			(size 0.1524 0.1524)
			(layers "F.Cu" "F.Mask" "F.Paste")
			(net "GND")
			(options
				(clearance outline)
				(anchor circle)
			)
			(primitives
				(gr_poly
					(pts
						(arc
							(start 0.3048 -0.2032)
							(mid 0.275042 -0.275042)
							(end 0.2032 -0.3048)
						)
						(arc
							(start -0.2032 -0.3048)
							(mid -0.275042 -0.275042)
							(end -0.3048 -0.2032)
						)
						(arc
							(start -0.3048 0.2032)
							(mid -0.275042 0.275042)
							(end -0.2032 0.3048)
						)
						(arc
							(start 0.2032 0.3048)
							(mid 0.275042 0.275042)
							(end 0.3048 0.2032)
						)
					)
					(width 0)
					(fill yes)
				)
			)
		)
	)
	(footprint ""
		(layer "F.Cu")
		(at 167.706802 -59.082432)
		(property "Reference" "PC94"
			(at 0 0 0)
			(layer "F.SilkS")
			(hide yes)
			(effects
				(font
					(size 1.27 1.27)
				)
			)
		)
		(property "Value" "SC4D7U16V5KX-1-GP"
			(at -0.0762 -6.1214 0)
			(unlocked yes)
			(layer "F.Fab")
			(hide yes)
			(effects
				(font
					(size 1.016 1.016)
					(thickness 0.1524)
				)
			)
		)
		(property "Device Type" "C805H56"
			(at -0.0762 -8.1534 0)
			(unlocked yes)
			(layer "F.Fab")
			(hide yes)
			(effects
				(font
					(size 1.016 1.016)
					(thickness 0.1524)
				)
			)
		)
		(duplicate_pad_numbers_are_jumpers no)
		(fp_line
			(start 0.635 0)
			(end -0.635 0)
			(stroke
				(width 0.508)
				(type default)
			)
			(layer "F.SilkS")
		)
		(fp_rect
			(start -0.9652 1.778)
			(end 0.9652 -1.778)
			(stroke
				(width 0)
				(type default)
			)
			(fill no)
			(layer "F.CrtYd")
		)
		(fp_poly
			(pts
				(xy -0.9652 -1.778) (xy 0.9652 -1.778) (xy 0.9652 1.778) (xy -0.9652 1.778)
			)
			(stroke
				(width 0)
				(type default)
			)
			(fill no)
			(layer "F.Fab")
		)
		(pad "1" smd rect
			(at 0 -0.9652)
			(size 1.397 1.143)
			(layers "F.Cu" "F.Mask" "F.Paste")
			(net "P0V9")
		)
		(pad "2" smd rect
			(at 0 0.9652)
			(size 1.397 1.143)
			(layers "F.Cu" "F.Mask" "F.Paste")
			(net "GND")
		)
	)
	(footprint ""
		(layer "F.Cu")
		(at 151.527002 -75.948032 90)
		(property "Reference" "PC213"
			(at 0 0 90)
			(layer "F.SilkS")
			(hide yes)
			(effects
				(font
					(size 1.27 1.27)
				)
			)
		)
		(property "Value" "SC22U25V6KX-GP-U"
			(at -2.860802 -5.279644 90)
			(unlocked yes)
			(layer "F.Fab")
			(hide yes)
			(effects
				(font
					(size 1.016 1.016)
					(thickness 0.1524)
				)
			)
		)
		(property "Device Type" "C1206-TO0D3H75"
			(at -2.860802 -6.803644 90)
			(unlocked yes)
			(layer "F.Fab")
			(hide yes)
			(effects
				(font
					(size 1.016 1.016)
					(thickness 0.1524)
				)
			)
		)
		(duplicate_pad_numbers_are_jumpers no)
		(fp_line
			(start 1.3081 -2.3749)
			(end 1.3081 2.3749)
			(stroke
				(width 0.1524)
				(type default)
			)
			(layer "F.SilkS")
		)
		(fp_line
			(start -1.3081 -2.3749)
			(end 1.3081 -2.3749)
			(stroke
				(width 0.1524)
				(type default)
			)
			(layer "F.SilkS")
		)
		(fp_line
			(start 1.3081 2.3749)
			(end -1.3081 2.3749)
			(stroke
				(width 0.1524)
				(type default)
			)
			(layer "F.SilkS")
		)
		(fp_line
			(start -1.3081 2.3749)
			(end -1.3081 -2.3749)
			(stroke
				(width 0.1524)
				(type default)
			)
			(layer "F.SilkS")
		)
		(fp_rect
			(start -0.8001 1.6002)
			(end 0.8001 -1.6002)
			(stroke
				(width 0)
				(type default)
			)
			(fill no)
			(layer "F.CrtYd")
		)
		(fp_poly
			(pts
				(xy -1.5621 2.4511) (xy -1.5621 1.6002) (xy 0.8001 1.6002) (xy 0.8001 -1.6002) (xy -0.8001 -1.6002)
				(xy -0.8001 1.5875) (xy -1.5621 1.5875) (xy -1.5621 -2.4511) (xy 1.5621 -2.4511) (xy 1.5621 2.4511)
			)
			(stroke
				(width 0)
				(type default)
			)
			(fill no)
			(layer "F.CrtYd")
		)
		(fp_rect
			(start -1.5621 2.4511)
			(end 1.5621 -2.4511)
			(stroke
				(width 0)
				(type default)
			)
			(fill no)
			(layer "F.Fab")
		)
		(pad "1" smd rect
			(at 0 -1.392936 90)
			(size 2.1082 1.4478)
			(layers "F.Cu" "F.Mask" "F.Paste")
			(net "P0V9_VIN")
		)
		(pad "2" smd rect
			(at 0 1.392936 90)
			(size 2.1082 1.4478)
			(layers "F.Cu" "F.Mask" "F.Paste")
			(net "GND")
		)
	)
	(footprint ""
		(layer "F.Cu")
		(at 225.17608 -3.810508 180)
		(property "Reference" "R175"
			(at 0 0 180)
			(layer "F.SilkS")
			(hide yes)
			(effects
				(font
					(size 1.27 1.27)
				)
			)
		)
		(property "Value" "4K7R2F-GP"
			(at 0.064008 -3.993896 180)
			(unlocked yes)
			(layer "F.Fab")
			(hide yes)
			(effects
				(font
					(size 1.016 1.016)
					(thickness 0.1524)
				)
			)
		)
		(property "Device Type" "R402H16"
			(at 0.064008 -5.517896 180)
			(unlocked yes)
			(layer "F.Fab")
			(hide yes)
			(effects
				(font
					(size 1.016 1.016)
					(thickness 0.1524)
				)
			)
		)
		(duplicate_pad_numbers_are_jumpers no)
		(fp_line
			(start 0.508 -0.9398)
			(end -0.508 -0.9398)
			(stroke
				(width 0.1524)
				(type default)
			)
			(layer "F.SilkS")
		)
		(fp_line
			(start -0.508 -0.9398)
			(end -0.508 0.9398)
			(stroke
				(width 0.1524)
				(type default)
			)
			(layer "F.SilkS")
		)
		(fp_rect
			(start -0.508 0.9398)
			(end 0.508 -0.9398)
			(stroke
				(width 0)
				(type default)
			)
			(fill no)
			(layer "F.CrtYd")
		)
		(fp_rect
			(start -0.508 0.9398)
			(end 0.508 -0.9398)
			(stroke
				(width 0)
				(type default)
			)
			(fill no)
			(layer "F.Fab")
		)
		(pad "1" smd custom
			(at 0 -0.4445 180)
			(size 0.1397 0.1397)
			(layers "F.Cu" "F.Mask" "F.Paste")
			(net "P3V3_STBY")
			(options
				(clearance outline)
				(anchor circle)
			)
			(primitives
				(gr_poly
					(pts
						(arc
							(start -0.1778 -0.2794)
							(mid -0.249642 -0.249642)
							(end -0.2794 -0.1778)
						)
						(arc
							(start -0.2794 0.1778)
							(mid -0.249642 0.249642)
							(end -0.1778 0.2794)
						)
						(arc
							(start 0.1778 0.2794)
							(mid 0.249642 0.249642)
							(end 0.2794 0.1778)
						)
						(arc
							(start 0.2794 -0.1778)
							(mid 0.249642 -0.249642)
							(end 0.1778 -0.2794)
						)
					)
					(width 0)
					(fill yes)
				)
			)
		)
		(pad "2" smd custom
			(at 0 0.4445 180)
			(size 0.1397 0.1397)
			(layers "F.Cu" "F.Mask" "F.Paste")
			(net "UART_SWITCH_R")
			(options
				(clearance outline)
				(anchor circle)
			)
			(primitives
				(gr_poly
					(pts
						(arc
							(start -0.1778 -0.2794)
							(mid -0.249642 -0.249642)
							(end -0.2794 -0.1778)
						)
						(arc
							(start -0.2794 0.1778)
							(mid -0.249642 0.249642)
							(end -0.1778 0.2794)
						)
						(arc
							(start 0.1778 0.2794)
							(mid 0.249642 0.249642)
							(end 0.2794 0.1778)
						)
						(arc
							(start 0.2794 -0.1778)
							(mid 0.249642 -0.249642)
							(end 0.1778 -0.2794)
						)
					)
					(width 0)
					(fill yes)
				)
			)
		)
	)
	(footprint ""
		(layer "F.Cu")
		(at 171.389802 -60.860432)
		(property "Reference" "PTC8"
			(at 0 0 0)
			(layer "F.SilkS")
			(hide yes)
			(effects
				(font
					(size 1.27 1.27)
				)
			)
		)
		(property "Value" "SE470UF2VDM-GP"
			(at 0 -9.6012 0)
			(unlocked yes)
			(layer "F.Fab")
			(hide yes)
			(effects
				(font
					(size 1.016 1.016)
					(thickness 0.1524)
				)
			)
		)
		(property "Device Type" "CT7343H83"
			(at 0 -11.1252 0)
			(unlocked yes)
			(layer "F.Fab")
			(hide yes)
			(effects
				(font
					(size 1.016 1.016)
					(thickness 0.1524)
				)
			)
		)
		(duplicate_pad_numbers_are_jumpers no)
		(fp_line
			(start -2.286 -4.8768)
			(end -2.286 -2.032)
			(stroke
				(width 0.1524)
				(type default)
			)
			(layer "F.SilkS")
		)
		(fp_line
			(start -2.286 4.8768)
			(end -2.286 2.032)
			(stroke
				(width 0.1524)
				(type default)
			)
			(layer "F.SilkS")
		)
		(fp_line
			(start 2.1082 -4.699)
			(end -2.1082 -4.699)
			(stroke
				(width 0.508)
				(type default)
			)
			(layer "F.SilkS")
		)
		(fp_line
			(start 2.286 -4.8768)
			(end -2.286 -4.8768)
			(stroke
				(width 0.1524)
				(type default)
			)
			(layer "F.SilkS")
		)
		(fp_line
			(start 2.286 -2.032)
			(end 2.286 -4.8768)
			(stroke
				(width 0.1524)
				(type default)
			)
			(layer "F.SilkS")
		)
		(fp_line
			(start 2.286 2.032)
			(end 2.286 4.8768)
			(stroke
				(width 0.1524)
				(type default)
			)
			(layer "F.SilkS")
		)
		(fp_line
			(start 2.286 4.8768)
			(end -2.286 4.8768)
			(stroke
				(width 0.1524)
				(type default)
			)
			(layer "F.SilkS")
		)
		(fp_rect
			(start -2.1463 3.6449)
			(end 2.1463 -3.6449)
			(stroke
				(width 0)
				(type default)
			)
			(fill no)
			(layer "F.CrtYd")
		)
		(fp_poly
			(pts
				(xy -2.54 4.953) (xy -2.54 4.2926) (xy -3.81 4.2926) (xy -3.81 -4.2926) (xy -2.54 -4.2926) (xy -2.54 -4.953)
				(xy 2.54 -4.953) (xy 2.54 -4.2926) (xy 3.81 -4.2926) (xy 3.81 -1.6256) (xy 2.1463 -1.6256) (xy 2.1463 -3.6449)
				(xy -2.1463 -3.6449) (xy -2.1463 3.6449) (xy 2.1463 3.6449) (xy 2.1463 -1.6129) (xy 3.81 -1.6129)
				(xy 3.81 4.2926) (xy 2.54 4.2926) (xy 2.54 4.953)
			)
			(stroke
				(width 0)
				(type default)
			)
			(fill no)
			(layer "F.CrtYd")
		)
		(fp_rect
			(start -3.81 4.2926)
			(end -2.54 -4.2926)
			(stroke
				(width 0)
				(type default)
			)
			(fill no)
			(layer "F.Fab")
		)
		(fp_rect
			(start -2.54 4.953)
			(end 2.54 -4.953)
			(stroke
				(width 0)
				(type default)
			)
			(fill no)
			(layer "F.Fab")
		)
		(fp_rect
			(start 2.54 4.2926)
			(end 3.81 -4.2926)
			(stroke
				(width 0)
				(type default)
			)
			(fill no)
			(layer "F.Fab")
		)
		(pad "1" smd rect
			(at 0 -3.1496)
			(size 2.413 2.286)
			(layers "F.Cu" "F.Mask" "F.Paste")
			(net "P0V9")
		)
		(pad "2" smd rect
			(at 0 3.1496)
			(size 2.413 2.286)
			(layers "F.Cu" "F.Mask" "F.Paste")
			(net "GND")
		)
		(zone
			(layer "F.Cu")
			(hatch none 0.5)
			(connect_pads
				(clearance 0)
			)
			(min_thickness 0.25)
			(keepout
				(tracks allowed)
				(vias not_allowed)
				(pads allowed)
				(copperpour not_allowed)
				(footprints allowed)
			)
			(placement
				(enabled no)
				(sheetname "")
			)
			(fill
				(thermal_gap 0.5)
				(thermal_bridge_width 0.5)
				(island_removal_mode 0)
			)
			(polygon
				(pts
					(xy 169.878502 -56.263032) (xy 172.901102 -56.263032) (xy 172.901102 -59.158632) (xy 172.901102 -59.488832)
					(xy 169.878502 -59.488832) (xy 169.878502 -59.158632)
				)
			)
		)
		(zone
			(layer "F.Cu")
			(hatch none 0.5)
			(connect_pads
				(clearance 0)
			)
			(min_thickness 0.25)
			(keepout
				(tracks allowed)
				(vias not_allowed)
				(pads allowed)
				(copperpour not_allowed)
				(footprints allowed)
			)
			(placement
				(enabled no)
				(sheetname "")
			)
			(fill
				(thermal_gap 0.5)
				(thermal_bridge_width 0.5)
				(island_removal_mode 0)
			)
			(polygon
				(pts
					(xy 172.901102 -62.549532) (xy 172.901102 -65.457832) (xy 169.878502 -65.457832) (xy 169.878502 -62.562232)
					(xy 169.878502 -62.232032) (xy 172.901102 -62.232032)
				)
			)
		)
	)
	(footprint ""
		(layer "F.Cu")
		(at 49.657 -150.495)
		(property "Reference" "R165"
			(at 0 0 0)
			(layer "F.SilkS")
			(hide yes)
			(effects
				(font
					(size 1.27 1.27)
				)
			)
		)
		(property "Value" "4K7R2F-GP"
			(at 0.064008 -3.993896 0)
			(unlocked yes)
			(layer "F.Fab")
			(hide yes)
			(effects
				(font
					(size 1.016 1.016)
					(thickness 0.1524)
				)
			)
		)
		(property "Device Type" "R402H16"
			(at 0.064008 -5.517896 0)
			(unlocked yes)
			(layer "F.Fab")
			(hide yes)
			(effects
				(font
					(size 1.016 1.016)
					(thickness 0.1524)
				)
			)
		)
		(duplicate_pad_numbers_are_jumpers no)
		(fp_line
			(start -0.508 -0.9398)
			(end -0.508 0.9398)
			(stroke
				(width 0.1524)
				(type default)
			)
			(layer "F.SilkS")
		)
		(fp_line
			(start 0.508 -0.9398)
			(end -0.508 -0.9398)
			(stroke
				(width 0.1524)
				(type default)
			)
			(layer "F.SilkS")
		)
		(fp_rect
			(start -0.508 0.9398)
			(end 0.508 -0.9398)
			(stroke
				(width 0)
				(type default)
			)
			(fill no)
			(layer "F.CrtYd")
		)
		(fp_rect
			(start -0.508 0.9398)
			(end 0.508 -0.9398)
			(stroke
				(width 0)
				(type default)
			)
			(fill no)
			(layer "F.Fab")
		)
		(pad "1" smd custom
			(at 0 -0.4445)
			(size 0.1397 0.1397)
			(layers "F.Cu" "F.Mask" "F.Paste")
			(net "TEMP_2_A1")
			(options
				(clearance outline)
				(anchor circle)
			)
			(primitives
				(gr_poly
					(pts
						(arc
							(start -0.1778 -0.2794)
							(mid -0.249642 -0.249642)
							(end -0.2794 -0.1778)
						)
						(arc
							(start -0.2794 0.1778)
							(mid -0.249642 0.249642)
							(end -0.1778 0.2794)
						)
						(arc
							(start 0.1778 0.2794)
							(mid 0.249642 0.249642)
							(end 0.2794 0.1778)
						)
						(arc
							(start 0.2794 -0.1778)
							(mid 0.249642 -0.249642)
							(end 0.1778 -0.2794)
						)
					)
					(width 0)
					(fill yes)
				)
			)
		)
		(pad "2" smd custom
			(at 0 0.4445)
			(size 0.1397 0.1397)
			(layers "F.Cu" "F.Mask" "F.Paste")
			(net "GND")
			(options
				(clearance outline)
				(anchor circle)
			)
			(primitives
				(gr_poly
					(pts
						(arc
							(start -0.1778 -0.2794)
							(mid -0.249642 -0.249642)
							(end -0.2794 -0.1778)
						)
						(arc
							(start -0.2794 0.1778)
							(mid -0.249642 0.249642)
							(end -0.1778 0.2794)
						)
						(arc
							(start 0.1778 0.2794)
							(mid 0.249642 0.249642)
							(end 0.2794 0.1778)
						)
						(arc
							(start 0.2794 -0.1778)
							(mid 0.249642 -0.249642)
							(end 0.1778 -0.2794)
						)
					)
					(width 0)
					(fill yes)
				)
			)
		)
	)
	(footprint ""
		(layer "F.Cu")
		(at 75.180952 -146.85391 90)
		(property "Reference" "R197"
			(at 0 0 90)
			(layer "F.SilkS")
			(hide yes)
			(effects
				(font
					(size 1.27 1.27)
				)
			)
		)
		(property "Value" "8K2R2J-3-GP"
			(at 0.064008 -3.993896 90)
			(unlocked yes)
			(layer "F.Fab")
			(hide yes)
			(effects
				(font
					(size 1.016 1.016)
					(thickness 0.1524)
				)
			)
		)
		(property "Device Type" "R402H16"
			(at 0.064008 -5.517896 90)
			(unlocked yes)
			(layer "F.Fab")
			(hide yes)
			(effects
				(font
					(size 1.016 1.016)
					(thickness 0.1524)
				)
			)
		)
		(duplicate_pad_numbers_are_jumpers no)
		(fp_line
			(start 0.508 -0.9398)
			(end -0.508 -0.9398)
			(stroke
				(width 0.1524)
				(type default)
			)
			(layer "F.SilkS")
		)
		(fp_line
			(start -0.508 -0.9398)
			(end -0.508 0.9398)
			(stroke
				(width 0.1524)
				(type default)
			)
			(layer "F.SilkS")
		)
		(fp_rect
			(start -0.508 0.9398)
			(end 0.508 -0.9398)
			(stroke
				(width 0)
				(type default)
			)
			(fill no)
			(layer "F.CrtYd")
		)
		(fp_rect
			(start -0.508 0.9398)
			(end 0.508 -0.9398)
			(stroke
				(width 0)
				(type default)
			)
			(fill no)
			(layer "F.Fab")
		)
		(pad "1" smd custom
			(at 0 -0.4445 90)
			(size 0.1397 0.1397)
			(layers "F.Cu" "F.Mask" "F.Paste")
			(net "EEPROM_A0_R")
			(options
				(clearance outline)
				(anchor circle)
			)
			(primitives
				(gr_poly
					(pts
						(arc
							(start -0.1778 -0.2794)
							(mid -0.249642 -0.249642)
							(end -0.2794 -0.1778)
						)
						(arc
							(start -0.2794 0.1778)
							(mid -0.249642 0.249642)
							(end -0.1778 0.2794)
						)
						(arc
							(start 0.1778 0.2794)
							(mid 0.249642 0.249642)
							(end 0.2794 0.1778)
						)
						(arc
							(start 0.2794 -0.1778)
							(mid 0.249642 -0.249642)
							(end 0.1778 -0.2794)
						)
					)
					(width 0)
					(fill yes)
				)
			)
		)
		(pad "2" smd custom
			(at 0 0.4445 90)
			(size 0.1397 0.1397)
			(layers "F.Cu" "F.Mask" "F.Paste")
			(net "GND")
			(options
				(clearance outline)
				(anchor circle)
			)
			(primitives
				(gr_poly
					(pts
						(arc
							(start -0.1778 -0.2794)
							(mid -0.249642 -0.249642)
							(end -0.2794 -0.1778)
						)
						(arc
							(start -0.2794 0.1778)
							(mid -0.249642 0.249642)
							(end -0.1778 0.2794)
						)
						(arc
							(start 0.1778 0.2794)
							(mid 0.249642 0.249642)
							(end 0.2794 0.1778)
						)
						(arc
							(start 0.2794 -0.1778)
							(mid 0.249642 -0.249642)
							(end 0.1778 -0.2794)
						)
					)
					(width 0)
					(fill yes)
				)
			)
		)
	)
	(footprint ""
		(layer "F.Cu")
		(at 298.792138 -212.420454 180)
		(property "Reference" "C76"
			(at 0 0 180)
			(layer "F.SilkS")
			(hide yes)
			(effects
				(font
					(size 1.27 1.27)
				)
			)
		)
		(property "Value" "SCD22U10V2KX-1GP"
			(at 1.1811 -2.7051 180)
			(unlocked yes)
			(layer "F.Fab")
			(hide yes)
			(effects
				(font
					(size 1.016 1.016)
					(thickness 0.1524)
				)
			)
		)
		(property "Device Type" "C402H22"
			(at 1.1811 -4.2291 180)
			(unlocked yes)
			(layer "F.Fab")
			(hide yes)
			(effects
				(font
					(size 1.016 1.016)
					(thickness 0.1524)
				)
			)
		)
		(duplicate_pad_numbers_are_jumpers no)
		(fp_rect
			(start -0.4318 0.9525)
			(end 0.4318 -0.9525)
			(stroke
				(width 0)
				(type default)
			)
			(fill no)
			(layer "F.CrtYd")
		)
		(fp_rect
			(start -0.4318 0.9525)
			(end 0.4318 -0.9525)
			(stroke
				(width 0)
				(type default)
			)
			(fill no)
			(layer "F.Fab")
		)
		(pad "1" smd custom
			(at 0 -0.4445 180)
			(size 0.1524 0.1524)
			(layers "F.Cu" "F.Mask" "F.Paste")
			(net "PCIE_TX_CAP_P27")
			(options
				(clearance outline)
				(anchor circle)
			)
			(primitives
				(gr_poly
					(pts
						(arc
							(start 0.3048 -0.2032)
							(mid 0.275042 -0.275042)
							(end 0.2032 -0.3048)
						)
						(arc
							(start -0.2032 -0.3048)
							(mid -0.275042 -0.275042)
							(end -0.3048 -0.2032)
						)
						(arc
							(start -0.3048 0.2032)
							(mid -0.275042 0.275042)
							(end -0.2032 0.3048)
						)
						(arc
							(start 0.2032 0.3048)
							(mid 0.275042 0.275042)
							(end 0.3048 0.2032)
						)
					)
					(width 0)
					(fill yes)
				)
			)
		)
		(pad "2" smd custom
			(at 0 0.4445 180)
			(size 0.1524 0.1524)
			(layers "F.Cu" "F.Mask" "F.Paste")
			(net "PCIE_TX_P27")
			(options
				(clearance outline)
				(anchor circle)
			)
			(primitives
				(gr_poly
					(pts
						(arc
							(start 0.3048 -0.2032)
							(mid 0.275042 -0.275042)
							(end 0.2032 -0.3048)
						)
						(arc
							(start -0.2032 -0.3048)
							(mid -0.275042 -0.275042)
							(end -0.3048 -0.2032)
						)
						(arc
							(start -0.3048 0.2032)
							(mid -0.275042 0.275042)
							(end -0.2032 0.3048)
						)
						(arc
							(start 0.2032 0.3048)
							(mid 0.275042 0.275042)
							(end 0.3048 0.2032)
						)
					)
					(width 0)
					(fill yes)
				)
			)
		)
	)
	(footprint ""
		(layer "F.Cu")
		(at 20.864576 -129.243074 90)
		(property "Reference" "R352"
			(at 0 0 90)
			(layer "F.SilkS")
			(hide yes)
			(effects
				(font
					(size 1.27 1.27)
				)
			)
		)
		(property "Value" "3K3R2F-2-GP"
			(at 0.064008 -3.993896 90)
			(unlocked yes)
			(layer "F.Fab")
			(hide yes)
			(effects
				(font
					(size 1.016 1.016)
					(thickness 0.1524)
				)
			)
		)
		(property "Device Type" "R402H16"
			(at 0.064008 -5.517896 90)
			(unlocked yes)
			(layer "F.Fab")
			(hide yes)
			(effects
				(font
					(size 1.016 1.016)
					(thickness 0.1524)
				)
			)
		)
		(duplicate_pad_numbers_are_jumpers no)
		(fp_line
			(start 0.508 -0.9398)
			(end -0.508 -0.9398)
			(stroke
				(width 0.1524)
				(type default)
			)
			(layer "F.SilkS")
		)
		(fp_line
			(start -0.508 -0.9398)
			(end -0.508 0.9398)
			(stroke
				(width 0.1524)
				(type default)
			)
			(layer "F.SilkS")
		)
		(fp_rect
			(start -0.508 0.9398)
			(end 0.508 -0.9398)
			(stroke
				(width 0)
				(type default)
			)
			(fill no)
			(layer "F.CrtYd")
		)
		(fp_rect
			(start -0.508 0.9398)
			(end 0.508 -0.9398)
			(stroke
				(width 0)
				(type default)
			)
			(fill no)
			(layer "F.Fab")
		)
		(pad "1" smd custom
			(at 0 -0.4445 90)
			(size 0.1397 0.1397)
			(layers "F.Cu" "F.Mask" "F.Paste")
			(net "P3V3_STBY")
			(options
				(clearance outline)
				(anchor circle)
			)
			(primitives
				(gr_poly
					(pts
						(arc
							(start -0.1778 -0.2794)
							(mid -0.249642 -0.249642)
							(end -0.2794 -0.1778)
						)
						(arc
							(start -0.2794 0.1778)
							(mid -0.249642 0.249642)
							(end -0.1778 0.2794)
						)
						(arc
							(start 0.1778 0.2794)
							(mid 0.249642 0.249642)
							(end 0.2794 0.1778)
						)
						(arc
							(start 0.2794 -0.1778)
							(mid 0.249642 -0.249642)
							(end 0.1778 -0.2794)
						)
					)
					(width 0)
					(fill yes)
				)
			)
		)
		(pad "2" smd custom
			(at 0 0.4445 90)
			(size 0.1397 0.1397)
			(layers "F.Cu" "F.Mask" "F.Paste")
			(net "ROMA11")
			(options
				(clearance outline)
				(anchor circle)
			)
			(primitives
				(gr_poly
					(pts
						(arc
							(start -0.1778 -0.2794)
							(mid -0.249642 -0.249642)
							(end -0.2794 -0.1778)
						)
						(arc
							(start -0.2794 0.1778)
							(mid -0.249642 0.249642)
							(end -0.1778 0.2794)
						)
						(arc
							(start 0.1778 0.2794)
							(mid 0.249642 0.249642)
							(end 0.2794 0.1778)
						)
						(arc
							(start 0.2794 -0.1778)
							(mid 0.249642 -0.249642)
							(end 0.1778 -0.2794)
						)
					)
					(width 0)
					(fill yes)
				)
			)
		)
	)
	(footprint ""
		(layer "F.Cu")
		(at 273.992086 -212.420454 180)
		(property "Reference" "C101"
			(at 0 0 180)
			(layer "F.SilkS")
			(hide yes)
			(effects
				(font
					(size 1.27 1.27)
				)
			)
		)
		(property "Value" "SCD22U10V2KX-1GP"
			(at 1.1811 -2.7051 180)
			(unlocked yes)
			(layer "F.Fab")
			(hide yes)
			(effects
				(font
					(size 1.016 1.016)
					(thickness 0.1524)
				)
			)
		)
		(property "Device Type" "C402H22"
			(at 1.1811 -4.2291 180)
			(unlocked yes)
			(layer "F.Fab")
			(hide yes)
			(effects
				(font
					(size 1.016 1.016)
					(thickness 0.1524)
				)
			)
		)
		(duplicate_pad_numbers_are_jumpers no)
		(fp_rect
			(start -0.4318 0.9525)
			(end 0.4318 -0.9525)
			(stroke
				(width 0)
				(type default)
			)
			(fill no)
			(layer "F.CrtYd")
		)
		(fp_rect
			(start -0.4318 0.9525)
			(end 0.4318 -0.9525)
			(stroke
				(width 0)
				(type default)
			)
			(fill no)
			(layer "F.Fab")
		)
		(pad "1" smd custom
			(at 0 -0.4445 180)
			(size 0.1524 0.1524)
			(layers "F.Cu" "F.Mask" "F.Paste")
			(net "PCIE_TX_CAP_P34")
			(options
				(clearance outline)
				(anchor circle)
			)
			(primitives
				(gr_poly
					(pts
						(arc
							(start 0.3048 -0.2032)
							(mid 0.275042 -0.275042)
							(end 0.2032 -0.3048)
						)
						(arc
							(start -0.2032 -0.3048)
							(mid -0.275042 -0.275042)
							(end -0.3048 -0.2032)
						)
						(arc
							(start -0.3048 0.2032)
							(mid -0.275042 0.275042)
							(end -0.2032 0.3048)
						)
						(arc
							(start 0.2032 0.3048)
							(mid 0.275042 0.275042)
							(end 0.3048 0.2032)
						)
					)
					(width 0)
					(fill yes)
				)
			)
		)
		(pad "2" smd custom
			(at 0 0.4445 180)
			(size 0.1524 0.1524)
			(layers "F.Cu" "F.Mask" "F.Paste")
			(net "PCIE_TX_P34")
			(options
				(clearance outline)
				(anchor circle)
			)
			(primitives
				(gr_poly
					(pts
						(arc
							(start 0.3048 -0.2032)
							(mid 0.275042 -0.275042)
							(end 0.2032 -0.3048)
						)
						(arc
							(start -0.2032 -0.3048)
							(mid -0.275042 -0.275042)
							(end -0.3048 -0.2032)
						)
						(arc
							(start -0.3048 0.2032)
							(mid -0.275042 0.275042)
							(end -0.2032 0.3048)
						)
						(arc
							(start 0.2032 0.3048)
							(mid 0.275042 0.275042)
							(end 0.3048 0.2032)
						)
					)
					(width 0)
					(fill yes)
				)
			)
		)
	)
	(footprint ""
		(layer "F.Cu")
		(at 154.1018 -87.4268 -90)
		(property "Reference" "R99"
			(at 0 0 270)
			(layer "F.SilkS")
			(hide yes)
			(effects
				(font
					(size 1.27 1.27)
				)
			)
		)
		(property "Value" "10KR2F-2-GP"
			(at 0.064008 -3.993896 270)
			(unlocked yes)
			(layer "F.Fab")
			(hide yes)
			(effects
				(font
					(size 1.016 1.016)
					(thickness 0.1524)
				)
			)
		)
		(property "Device Type" "R402H16"
			(at 0.064008 -5.517896 270)
			(unlocked yes)
			(layer "F.Fab")
			(hide yes)
			(effects
				(font
					(size 1.016 1.016)
					(thickness 0.1524)
				)
			)
		)
		(duplicate_pad_numbers_are_jumpers no)
		(fp_line
			(start -0.508 -0.9398)
			(end -0.508 0.9398)
			(stroke
				(width 0.1524)
				(type default)
			)
			(layer "F.SilkS")
		)
		(fp_line
			(start 0.508 -0.9398)
			(end -0.508 -0.9398)
			(stroke
				(width 0.1524)
				(type default)
			)
			(layer "F.SilkS")
		)
		(fp_rect
			(start -0.508 0.9398)
			(end 0.508 -0.9398)
			(stroke
				(width 0)
				(type default)
			)
			(fill no)
			(layer "F.CrtYd")
		)
		(fp_rect
			(start -0.508 0.9398)
			(end 0.508 -0.9398)
			(stroke
				(width 0)
				(type default)
			)
			(fill no)
			(layer "F.Fab")
		)
		(pad "1" smd custom
			(at 0 -0.4445 270)
			(size 0.1397 0.1397)
			(layers "F.Cu" "F.Mask" "F.Paste")
			(net "GND")
			(options
				(clearance outline)
				(anchor circle)
			)
			(primitives
				(gr_poly
					(pts
						(arc
							(start -0.1778 -0.2794)
							(mid -0.249642 -0.249642)
							(end -0.2794 -0.1778)
						)
						(arc
							(start -0.2794 0.1778)
							(mid -0.249642 0.249642)
							(end -0.1778 0.2794)
						)
						(arc
							(start 0.1778 0.2794)
							(mid 0.249642 0.249642)
							(end 0.2794 0.1778)
						)
						(arc
							(start 0.2794 -0.1778)
							(mid 0.249642 -0.249642)
							(end 0.1778 -0.2794)
						)
					)
					(width 0)
					(fill yes)
				)
			)
		)
		(pad "2" smd custom
			(at 0 0.4445 270)
			(size 0.1397 0.1397)
			(layers "F.Cu" "F.Mask" "F.Paste")
			(net "CLKGNE_SADR_R")
			(options
				(clearance outline)
				(anchor circle)
			)
			(primitives
				(gr_poly
					(pts
						(arc
							(start -0.1778 -0.2794)
							(mid -0.249642 -0.249642)
							(end -0.2794 -0.1778)
						)
						(arc
							(start -0.2794 0.1778)
							(mid -0.249642 0.249642)
							(end -0.1778 0.2794)
						)
						(arc
							(start 0.1778 0.2794)
							(mid 0.249642 0.249642)
							(end 0.2794 0.1778)
						)
						(arc
							(start 0.2794 -0.1778)
							(mid 0.249642 -0.249642)
							(end 0.1778 -0.2794)
						)
					)
					(width 0)
					(fill yes)
				)
			)
		)
	)
	(footprint ""
		(layer "F.Cu")
		(at 37.211 -200.533)
		(property "Reference" "C695"
			(at 0 0 0)
			(layer "F.SilkS")
			(hide yes)
			(effects
				(font
					(size 1.27 1.27)
				)
			)
		)
		(property "Value" "SCD01U50V2KX-1GP"
			(at 1.1811 -2.7051 0)
			(unlocked yes)
			(layer "F.Fab")
			(hide yes)
			(effects
				(font
					(size 1.016 1.016)
					(thickness 0.1524)
				)
			)
		)
		(property "Device Type" "C402H22"
			(at 1.1811 -4.2291 0)
			(unlocked yes)
			(layer "F.Fab")
			(hide yes)
			(effects
				(font
					(size 1.016 1.016)
					(thickness 0.1524)
				)
			)
		)
		(duplicate_pad_numbers_are_jumpers no)
		(fp_rect
			(start -0.4318 0.9525)
			(end 0.4318 -0.9525)
			(stroke
				(width 0)
				(type default)
			)
			(fill no)
			(layer "F.CrtYd")
		)
		(fp_rect
			(start -0.4318 0.9525)
			(end 0.4318 -0.9525)
			(stroke
				(width 0)
				(type default)
			)
			(fill no)
			(layer "F.Fab")
		)
		(pad "1" smd custom
			(at 0 -0.4445)
			(size 0.1524 0.1524)
			(layers "F.Cu" "F.Mask" "F.Paste")
			(net "P3V3_STBY")
			(options
				(clearance outline)
				(anchor circle)
			)
			(primitives
				(gr_poly
					(pts
						(arc
							(start 0.3048 -0.2032)
							(mid 0.275042 -0.275042)
							(end 0.2032 -0.3048)
						)
						(arc
							(start -0.2032 -0.3048)
							(mid -0.275042 -0.275042)
							(end -0.3048 -0.2032)
						)
						(arc
							(start -0.3048 0.2032)
							(mid -0.275042 0.275042)
							(end -0.2032 0.3048)
						)
						(arc
							(start 0.2032 0.3048)
							(mid 0.275042 0.275042)
							(end 0.3048 0.2032)
						)
					)
					(width 0)
					(fill yes)
				)
			)
		)
		(pad "2" smd custom
			(at 0 0.4445)
			(size 0.1524 0.1524)
			(layers "F.Cu" "F.Mask" "F.Paste")
			(net "GND")
			(options
				(clearance outline)
				(anchor circle)
			)
			(primitives
				(gr_poly
					(pts
						(arc
							(start 0.3048 -0.2032)
							(mid 0.275042 -0.275042)
							(end 0.2032 -0.3048)
						)
						(arc
							(start -0.2032 -0.3048)
							(mid -0.275042 -0.275042)
							(end -0.3048 -0.2032)
						)
						(arc
							(start -0.3048 0.2032)
							(mid -0.275042 0.275042)
							(end -0.2032 0.3048)
						)
						(arc
							(start 0.2032 0.3048)
							(mid 0.275042 0.275042)
							(end 0.3048 0.2032)
						)
					)
					(width 0)
					(fill yes)
				)
			)
		)
	)
	(footprint ""
		(layer "F.Cu")
		(at 56.261 -119.126 90)
		(property "Reference" "R580"
			(at 0 0 90)
			(layer "F.SilkS")
			(hide yes)
			(effects
				(font
					(size 1.27 1.27)
				)
			)
		)
		(property "Value" "4K7R2F-GP"
			(at 0.064008 -3.993896 90)
			(unlocked yes)
			(layer "F.Fab")
			(hide yes)
			(effects
				(font
					(size 1.016 1.016)
					(thickness 0.1524)
				)
			)
		)
		(property "Device Type" "R402H16"
			(at 0.064008 -5.517896 90)
			(unlocked yes)
			(layer "F.Fab")
			(hide yes)
			(effects
				(font
					(size 1.016 1.016)
					(thickness 0.1524)
				)
			)
		)
		(duplicate_pad_numbers_are_jumpers no)
		(fp_line
			(start 0.508 -0.9398)
			(end -0.508 -0.9398)
			(stroke
				(width 0.1524)
				(type default)
			)
			(layer "F.SilkS")
		)
		(fp_line
			(start -0.508 -0.9398)
			(end -0.508 0.9398)
			(stroke
				(width 0.1524)
				(type default)
			)
			(layer "F.SilkS")
		)
		(fp_rect
			(start -0.508 0.9398)
			(end 0.508 -0.9398)
			(stroke
				(width 0)
				(type default)
			)
			(fill no)
			(layer "F.CrtYd")
		)
		(fp_rect
			(start -0.508 0.9398)
			(end 0.508 -0.9398)
			(stroke
				(width 0)
				(type default)
			)
			(fill no)
			(layer "F.Fab")
		)
		(pad "1" smd custom
			(at 0 -0.4445 90)
			(size 0.1397 0.1397)
			(layers "F.Cu" "F.Mask" "F.Paste")
			(net "BMC_I2C7_B_DBP_SCL")
			(options
				(clearance outline)
				(anchor circle)
			)
			(primitives
				(gr_poly
					(pts
						(arc
							(start -0.1778 -0.2794)
							(mid -0.249642 -0.249642)
							(end -0.2794 -0.1778)
						)
						(arc
							(start -0.2794 0.1778)
							(mid -0.249642 0.249642)
							(end -0.1778 0.2794)
						)
						(arc
							(start 0.1778 0.2794)
							(mid 0.249642 0.249642)
							(end 0.2794 0.1778)
						)
						(arc
							(start 0.2794 -0.1778)
							(mid 0.249642 -0.249642)
							(end 0.1778 -0.2794)
						)
					)
					(width 0)
					(fill yes)
				)
			)
		)
		(pad "2" smd custom
			(at 0 0.4445 90)
			(size 0.1397 0.1397)
			(layers "F.Cu" "F.Mask" "F.Paste")
			(net "P3V3_STBY")
			(options
				(clearance outline)
				(anchor circle)
			)
			(primitives
				(gr_poly
					(pts
						(arc
							(start -0.1778 -0.2794)
							(mid -0.249642 -0.249642)
							(end -0.2794 -0.1778)
						)
						(arc
							(start -0.2794 0.1778)
							(mid -0.249642 0.249642)
							(end -0.1778 0.2794)
						)
						(arc
							(start 0.1778 0.2794)
							(mid 0.249642 0.249642)
							(end 0.2794 0.1778)
						)
						(arc
							(start 0.2794 -0.1778)
							(mid 0.249642 -0.249642)
							(end 0.1778 -0.2794)
						)
					)
					(width 0)
					(fill yes)
				)
			)
		)
	)
	(footprint ""
		(layer "F.Cu")
		(at 133.1214 -86.487 -90)
		(property "Reference" "R655"
			(at 0 0 270)
			(layer "F.SilkS")
			(hide yes)
			(effects
				(font
					(size 1.27 1.27)
				)
			)
		)
		(property "Value" "4K7R2F-GP"
			(at 0.064008 -3.993896 270)
			(unlocked yes)
			(layer "F.Fab")
			(hide yes)
			(effects
				(font
					(size 1.016 1.016)
					(thickness 0.1524)
				)
			)
		)
		(property "Device Type" "R402H16"
			(at 0.064008 -5.517896 270)
			(unlocked yes)
			(layer "F.Fab")
			(hide yes)
			(effects
				(font
					(size 1.016 1.016)
					(thickness 0.1524)
				)
			)
		)
		(duplicate_pad_numbers_are_jumpers no)
		(fp_line
			(start -0.508 -0.9398)
			(end -0.508 0.9398)
			(stroke
				(width 0.1524)
				(type default)
			)
			(layer "F.SilkS")
		)
		(fp_line
			(start 0.508 -0.9398)
			(end -0.508 -0.9398)
			(stroke
				(width 0.1524)
				(type default)
			)
			(layer "F.SilkS")
		)
		(fp_rect
			(start -0.508 0.9398)
			(end 0.508 -0.9398)
			(stroke
				(width 0)
				(type default)
			)
			(fill no)
			(layer "F.CrtYd")
		)
		(fp_rect
			(start -0.508 0.9398)
			(end 0.508 -0.9398)
			(stroke
				(width 0)
				(type default)
			)
			(fill no)
			(layer "F.Fab")
		)
		(pad "1" smd custom
			(at 0 -0.4445 270)
			(size 0.1397 0.1397)
			(layers "F.Cu" "F.Mask" "F.Paste")
			(net "P3V3_RTC")
			(options
				(clearance outline)
				(anchor circle)
			)
			(primitives
				(gr_poly
					(pts
						(arc
							(start -0.1778 -0.2794)
							(mid -0.249642 -0.249642)
							(end -0.2794 -0.1778)
						)
						(arc
							(start -0.2794 0.1778)
							(mid -0.249642 0.249642)
							(end -0.1778 0.2794)
						)
						(arc
							(start 0.1778 0.2794)
							(mid 0.249642 0.249642)
							(end 0.2794 0.1778)
						)
						(arc
							(start 0.2794 -0.1778)
							(mid 0.249642 -0.249642)
							(end 0.1778 -0.2794)
						)
					)
					(width 0)
					(fill yes)
				)
			)
		)
		(pad "2" smd custom
			(at 0 0.4445 270)
			(size 0.1397 0.1397)
			(layers "F.Cu" "F.Mask" "F.Paste")
			(net "RTC_INT_N")
			(options
				(clearance outline)
				(anchor circle)
			)
			(primitives
				(gr_poly
					(pts
						(arc
							(start -0.1778 -0.2794)
							(mid -0.249642 -0.249642)
							(end -0.2794 -0.1778)
						)
						(arc
							(start -0.2794 0.1778)
							(mid -0.249642 0.249642)
							(end -0.1778 0.2794)
						)
						(arc
							(start 0.1778 0.2794)
							(mid 0.249642 0.249642)
							(end 0.2794 0.1778)
						)
						(arc
							(start 0.2794 -0.1778)
							(mid 0.249642 -0.249642)
							(end 0.1778 -0.2794)
						)
					)
					(width 0)
					(fill yes)
				)
			)
		)
	)
	(footprint ""
		(layer "F.Cu")
		(at 230.251 -7.366 90)
		(property "Reference" "R952"
			(at 0 0 90)
			(layer "F.SilkS")
			(hide yes)
			(effects
				(font
					(size 1.27 1.27)
				)
			)
		)
		(property "Value" "0R2J-2-GP"
			(at 0.064008 -3.993896 90)
			(unlocked yes)
			(layer "F.Fab")
			(hide yes)
			(effects
				(font
					(size 1.016 1.016)
					(thickness 0.1524)
				)
			)
		)
		(property "Device Type" "R402H16"
			(at 0.064008 -5.517896 90)
			(unlocked yes)
			(layer "F.Fab")
			(hide yes)
			(effects
				(font
					(size 1.016 1.016)
					(thickness 0.1524)
				)
			)
		)
		(duplicate_pad_numbers_are_jumpers no)
		(fp_line
			(start 0.508 -0.9398)
			(end -0.508 -0.9398)
			(stroke
				(width 0.1524)
				(type default)
			)
			(layer "F.SilkS")
		)
		(fp_line
			(start -0.508 -0.9398)
			(end -0.508 0.9398)
			(stroke
				(width 0.1524)
				(type default)
			)
			(layer "F.SilkS")
		)
		(fp_rect
			(start -0.508 0.9398)
			(end 0.508 -0.9398)
			(stroke
				(width 0)
				(type default)
			)
			(fill no)
			(layer "F.CrtYd")
		)
		(fp_rect
			(start -0.508 0.9398)
			(end 0.508 -0.9398)
			(stroke
				(width 0)
				(type default)
			)
			(fill no)
			(layer "F.Fab")
		)
		(pad "1" smd custom
			(at 0 -0.4445 90)
			(size 0.1397 0.1397)
			(layers "F.Cu" "F.Mask" "F.Paste")
			(net "TWI_SDA2_R")
			(options
				(clearance outline)
				(anchor circle)
			)
			(primitives
				(gr_poly
					(pts
						(arc
							(start -0.1778 -0.2794)
							(mid -0.249642 -0.249642)
							(end -0.2794 -0.1778)
						)
						(arc
							(start -0.2794 0.1778)
							(mid -0.249642 0.249642)
							(end -0.1778 0.2794)
						)
						(arc
							(start 0.1778 0.2794)
							(mid 0.249642 0.249642)
							(end 0.2794 0.1778)
						)
						(arc
							(start 0.2794 -0.1778)
							(mid 0.249642 -0.249642)
							(end 0.1778 -0.2794)
						)
					)
					(width 0)
					(fill yes)
				)
			)
		)
		(pad "2" smd custom
			(at 0 0.4445 90)
			(size 0.1397 0.1397)
			(layers "F.Cu" "F.Mask" "F.Paste")
			(net "TWI_SDA2")
			(options
				(clearance outline)
				(anchor circle)
			)
			(primitives
				(gr_poly
					(pts
						(arc
							(start -0.1778 -0.2794)
							(mid -0.249642 -0.249642)
							(end -0.2794 -0.1778)
						)
						(arc
							(start -0.2794 0.1778)
							(mid -0.249642 0.249642)
							(end -0.1778 0.2794)
						)
						(arc
							(start 0.1778 0.2794)
							(mid 0.249642 0.249642)
							(end 0.2794 0.1778)
						)
						(arc
							(start 0.2794 -0.1778)
							(mid 0.249642 -0.249642)
							(end 0.1778 -0.2794)
						)
					)
					(width 0)
					(fill yes)
				)
			)
		)
	)
	(footprint ""
		(layer "F.Cu")
		(at 32.55772 -79.429356)
		(property "Reference" "PR65"
			(at 0 0 0)
			(layer "F.SilkS")
			(hide yes)
			(effects
				(font
					(size 1.27 1.27)
				)
			)
		)
		(property "Value" "100KR2F-L1-GP"
			(at 0.064008 -3.993896 0)
			(unlocked yes)
			(layer "F.Fab")
			(hide yes)
			(effects
				(font
					(size 1.016 1.016)
					(thickness 0.1524)
				)
			)
		)
		(property "Device Type" "R402H16"
			(at 0.064008 -5.517896 0)
			(unlocked yes)
			(layer "F.Fab")
			(hide yes)
			(effects
				(font
					(size 1.016 1.016)
					(thickness 0.1524)
				)
			)
		)
		(duplicate_pad_numbers_are_jumpers no)
		(fp_line
			(start -0.508 -0.9398)
			(end -0.508 0.9398)
			(stroke
				(width 0.1524)
				(type default)
			)
			(layer "F.SilkS")
		)
		(fp_line
			(start 0.508 -0.9398)
			(end -0.508 -0.9398)
			(stroke
				(width 0.1524)
				(type default)
			)
			(layer "F.SilkS")
		)
		(fp_rect
			(start -0.508 0.9398)
			(end 0.508 -0.9398)
			(stroke
				(width 0)
				(type default)
			)
			(fill no)
			(layer "F.CrtYd")
		)
		(fp_rect
			(start -0.508 0.9398)
			(end 0.508 -0.9398)
			(stroke
				(width 0)
				(type default)
			)
			(fill no)
			(layer "F.Fab")
		)
		(pad "1" smd custom
			(at 0 -0.4445)
			(size 0.1397 0.1397)
			(layers "F.Cu" "F.Mask" "F.Paste")
			(net "P5V_STBY_LR")
			(options
				(clearance outline)
				(anchor circle)
			)
			(primitives
				(gr_poly
					(pts
						(arc
							(start -0.1778 -0.2794)
							(mid -0.249642 -0.249642)
							(end -0.2794 -0.1778)
						)
						(arc
							(start -0.2794 0.1778)
							(mid -0.249642 0.249642)
							(end -0.1778 0.2794)
						)
						(arc
							(start 0.1778 0.2794)
							(mid 0.249642 0.249642)
							(end 0.2794 0.1778)
						)
						(arc
							(start 0.2794 -0.1778)
							(mid 0.249642 -0.249642)
							(end 0.1778 -0.2794)
						)
					)
					(width 0)
					(fill yes)
				)
			)
		)
		(pad "2" smd custom
			(at 0 0.4445)
			(size 0.1397 0.1397)
			(layers "F.Cu" "F.Mask" "F.Paste")
			(net "P5V_STBY_FB")
			(options
				(clearance outline)
				(anchor circle)
			)
			(primitives
				(gr_poly
					(pts
						(arc
							(start -0.1778 -0.2794)
							(mid -0.249642 -0.249642)
							(end -0.2794 -0.1778)
						)
						(arc
							(start -0.2794 0.1778)
							(mid -0.249642 0.249642)
							(end -0.1778 0.2794)
						)
						(arc
							(start 0.1778 0.2794)
							(mid 0.249642 0.249642)
							(end 0.2794 0.1778)
						)
						(arc
							(start 0.2794 -0.1778)
							(mid 0.249642 -0.249642)
							(end 0.1778 -0.2794)
						)
					)
					(width 0)
					(fill yes)
				)
			)
		)
	)
	(footprint ""
		(layer "F.Cu")
		(at 69.991986 -212.420454 180)
		(property "Reference" "C353"
			(at 0 0 180)
			(layer "F.SilkS")
			(hide yes)
			(effects
				(font
					(size 1.27 1.27)
				)
			)
		)
		(property "Value" "SCD22U10V2KX-1GP"
			(at 1.1811 -2.7051 180)
			(unlocked yes)
			(layer "F.Fab")
			(hide yes)
			(effects
				(font
					(size 1.016 1.016)
					(thickness 0.1524)
				)
			)
		)
		(property "Device Type" "C402H22"
			(at 1.1811 -4.2291 180)
			(unlocked yes)
			(layer "F.Fab")
			(hide yes)
			(effects
				(font
					(size 1.016 1.016)
					(thickness 0.1524)
				)
			)
		)
		(duplicate_pad_numbers_are_jumpers no)
		(fp_rect
			(start -0.4318 0.9525)
			(end 0.4318 -0.9525)
			(stroke
				(width 0)
				(type default)
			)
			(fill no)
			(layer "F.CrtYd")
		)
		(fp_rect
			(start -0.4318 0.9525)
			(end 0.4318 -0.9525)
			(stroke
				(width 0)
				(type default)
			)
			(fill no)
			(layer "F.Fab")
		)
		(pad "1" smd custom
			(at 0 -0.4445 180)
			(size 0.1524 0.1524)
			(layers "F.Cu" "F.Mask" "F.Paste")
			(net "PCIE_TX_CAP_P69")
			(options
				(clearance outline)
				(anchor circle)
			)
			(primitives
				(gr_poly
					(pts
						(arc
							(start 0.3048 -0.2032)
							(mid 0.275042 -0.275042)
							(end 0.2032 -0.3048)
						)
						(arc
							(start -0.2032 -0.3048)
							(mid -0.275042 -0.275042)
							(end -0.3048 -0.2032)
						)
						(arc
							(start -0.3048 0.2032)
							(mid -0.275042 0.275042)
							(end -0.2032 0.3048)
						)
						(arc
							(start 0.2032 0.3048)
							(mid 0.275042 0.275042)
							(end 0.3048 0.2032)
						)
					)
					(width 0)
					(fill yes)
				)
			)
		)
		(pad "2" smd custom
			(at 0 0.4445 180)
			(size 0.1524 0.1524)
			(layers "F.Cu" "F.Mask" "F.Paste")
			(net "PCIE_TX_P69")
			(options
				(clearance outline)
				(anchor circle)
			)
			(primitives
				(gr_poly
					(pts
						(arc
							(start 0.3048 -0.2032)
							(mid 0.275042 -0.275042)
							(end 0.2032 -0.3048)
						)
						(arc
							(start -0.2032 -0.3048)
							(mid -0.275042 -0.275042)
							(end -0.3048 -0.2032)
						)
						(arc
							(start -0.3048 0.2032)
							(mid -0.275042 0.275042)
							(end -0.2032 0.3048)
						)
						(arc
							(start 0.2032 0.3048)
							(mid 0.275042 0.275042)
							(end 0.3048 0.2032)
						)
					)
					(width 0)
					(fill yes)
				)
			)
		)
	)
	(footprint ""
		(layer "F.Cu")
		(at 335.026 -74.676 90)
		(property "Reference" "PR161"
			(at 0 0 90)
			(layer "F.SilkS")
			(hide yes)
			(effects
				(font
					(size 1.27 1.27)
				)
			)
		)
		(property "Value" "4K42R2F-GP"
			(at 0.064008 -3.993896 90)
			(unlocked yes)
			(layer "F.Fab")
			(hide yes)
			(effects
				(font
					(size 1.016 1.016)
					(thickness 0.1524)
				)
			)
		)
		(property "Device Type" "R402H16"
			(at 0.064008 -5.517896 90)
			(unlocked yes)
			(layer "F.Fab")
			(hide yes)
			(effects
				(font
					(size 1.016 1.016)
					(thickness 0.1524)
				)
			)
		)
		(duplicate_pad_numbers_are_jumpers no)
		(fp_line
			(start 0.508 -0.9398)
			(end -0.508 -0.9398)
			(stroke
				(width 0.1524)
				(type default)
			)
			(layer "F.SilkS")
		)
		(fp_line
			(start -0.508 -0.9398)
			(end -0.508 0.9398)
			(stroke
				(width 0.1524)
				(type default)
			)
			(layer "F.SilkS")
		)
		(fp_rect
			(start -0.508 0.9398)
			(end 0.508 -0.9398)
			(stroke
				(width 0)
				(type default)
			)
			(fill no)
			(layer "F.CrtYd")
		)
		(fp_rect
			(start -0.508 0.9398)
			(end 0.508 -0.9398)
			(stroke
				(width 0)
				(type default)
			)
			(fill no)
			(layer "F.Fab")
		)
		(pad "1" smd custom
			(at 0 -0.4445 90)
			(size 0.1397 0.1397)
			(layers "F.Cu" "F.Mask" "F.Paste")
			(net "P0V9_E_VFB_R")
			(options
				(clearance outline)
				(anchor circle)
			)
			(primitives
				(gr_poly
					(pts
						(arc
							(start -0.1778 -0.2794)
							(mid -0.249642 -0.249642)
							(end -0.2794 -0.1778)
						)
						(arc
							(start -0.2794 0.1778)
							(mid -0.249642 0.249642)
							(end -0.1778 0.2794)
						)
						(arc
							(start 0.1778 0.2794)
							(mid 0.249642 0.249642)
							(end 0.2794 0.1778)
						)
						(arc
							(start 0.2794 -0.1778)
							(mid 0.249642 -0.249642)
							(end 0.1778 -0.2794)
						)
					)
					(width 0)
					(fill yes)
				)
			)
		)
		(pad "2" smd custom
			(at 0 0.4445 90)
			(size 0.1397 0.1397)
			(layers "F.Cu" "F.Mask" "F.Paste")
			(net "P0V9_E_VFB")
			(options
				(clearance outline)
				(anchor circle)
			)
			(primitives
				(gr_poly
					(pts
						(arc
							(start -0.1778 -0.2794)
							(mid -0.249642 -0.249642)
							(end -0.2794 -0.1778)
						)
						(arc
							(start -0.2794 0.1778)
							(mid -0.249642 0.249642)
							(end -0.1778 0.2794)
						)
						(arc
							(start 0.1778 0.2794)
							(mid 0.249642 0.249642)
							(end 0.2794 0.1778)
						)
						(arc
							(start 0.2794 -0.1778)
							(mid 0.249642 -0.249642)
							(end 0.1778 -0.2794)
						)
					)
					(width 0)
					(fill yes)
				)
			)
		)
	)
	(footprint ""
		(layer "F.Cu")
		(at 207.408018 -212.420454 180)
		(property "Reference" "C112"
			(at 0 0 180)
			(layer "F.SilkS")
			(hide yes)
			(effects
				(font
					(size 1.27 1.27)
				)
			)
		)
		(property "Value" "SCD22U10V2KX-1GP"
			(at 1.1811 -2.7051 180)
			(unlocked yes)
			(layer "F.Fab")
			(hide yes)
			(effects
				(font
					(size 1.016 1.016)
					(thickness 0.1524)
				)
			)
		)
		(property "Device Type" "C402H22"
			(at 1.1811 -4.2291 180)
			(unlocked yes)
			(layer "F.Fab")
			(hide yes)
			(effects
				(font
					(size 1.016 1.016)
					(thickness 0.1524)
				)
			)
		)
		(duplicate_pad_numbers_are_jumpers no)
		(fp_rect
			(start -0.4318 0.9525)
			(end 0.4318 -0.9525)
			(stroke
				(width 0)
				(type default)
			)
			(fill no)
			(layer "F.CrtYd")
		)
		(fp_rect
			(start -0.4318 0.9525)
			(end 0.4318 -0.9525)
			(stroke
				(width 0)
				(type default)
			)
			(fill no)
			(layer "F.Fab")
		)
		(pad "1" smd custom
			(at 0 -0.4445 180)
			(size 0.1524 0.1524)
			(layers "F.Cu" "F.Mask" "F.Paste")
			(net "PCIE_TX_CAP_N40")
			(options
				(clearance outline)
				(anchor circle)
			)
			(primitives
				(gr_poly
					(pts
						(arc
							(start 0.3048 -0.2032)
							(mid 0.275042 -0.275042)
							(end 0.2032 -0.3048)
						)
						(arc
							(start -0.2032 -0.3048)
							(mid -0.275042 -0.275042)
							(end -0.3048 -0.2032)
						)
						(arc
							(start -0.3048 0.2032)
							(mid -0.275042 0.275042)
							(end -0.2032 0.3048)
						)
						(arc
							(start 0.2032 0.3048)
							(mid 0.275042 0.275042)
							(end 0.3048 0.2032)
						)
					)
					(width 0)
					(fill yes)
				)
			)
		)
		(pad "2" smd custom
			(at 0 0.4445 180)
			(size 0.1524 0.1524)
			(layers "F.Cu" "F.Mask" "F.Paste")
			(net "PCIE_TX_N40")
			(options
				(clearance outline)
				(anchor circle)
			)
			(primitives
				(gr_poly
					(pts
						(arc
							(start 0.3048 -0.2032)
							(mid 0.275042 -0.275042)
							(end 0.2032 -0.3048)
						)
						(arc
							(start -0.2032 -0.3048)
							(mid -0.275042 -0.275042)
							(end -0.3048 -0.2032)
						)
						(arc
							(start -0.3048 0.2032)
							(mid -0.275042 0.275042)
							(end -0.2032 0.3048)
						)
						(arc
							(start 0.2032 0.3048)
							(mid 0.275042 0.275042)
							(end 0.3048 0.2032)
						)
					)
					(width 0)
					(fill yes)
				)
			)
		)
	)
	(footprint ""
		(layer "F.Cu")
		(at 194.8688 -33.909 -90)
		(property "Reference" "R763"
			(at 0 0 270)
			(layer "F.SilkS")
			(hide yes)
			(effects
				(font
					(size 1.27 1.27)
				)
			)
		)
		(property "Value" "4K7R2F-GP"
			(at 0.064008 -3.993896 270)
			(unlocked yes)
			(layer "F.Fab")
			(hide yes)
			(effects
				(font
					(size 1.016 1.016)
					(thickness 0.1524)
				)
			)
		)
		(property "Device Type" "R402H16"
			(at 0.064008 -5.517896 270)
			(unlocked yes)
			(layer "F.Fab")
			(hide yes)
			(effects
				(font
					(size 1.016 1.016)
					(thickness 0.1524)
				)
			)
		)
		(duplicate_pad_numbers_are_jumpers no)
		(fp_line
			(start -0.508 -0.9398)
			(end -0.508 0.9398)
			(stroke
				(width 0.1524)
				(type default)
			)
			(layer "F.SilkS")
		)
		(fp_line
			(start 0.508 -0.9398)
			(end -0.508 -0.9398)
			(stroke
				(width 0.1524)
				(type default)
			)
			(layer "F.SilkS")
		)
		(fp_rect
			(start -0.508 0.9398)
			(end 0.508 -0.9398)
			(stroke
				(width 0)
				(type default)
			)
			(fill no)
			(layer "F.CrtYd")
		)
		(fp_rect
			(start -0.508 0.9398)
			(end 0.508 -0.9398)
			(stroke
				(width 0)
				(type default)
			)
			(fill no)
			(layer "F.Fab")
		)
		(pad "1" smd custom
			(at 0 -0.4445 270)
			(size 0.1397 0.1397)
			(layers "F.Cu" "F.Mask" "F.Paste")
			(net "U55_A1")
			(options
				(clearance outline)
				(anchor circle)
			)
			(primitives
				(gr_poly
					(pts
						(arc
							(start -0.1778 -0.2794)
							(mid -0.249642 -0.249642)
							(end -0.2794 -0.1778)
						)
						(arc
							(start -0.2794 0.1778)
							(mid -0.249642 0.249642)
							(end -0.1778 0.2794)
						)
						(arc
							(start 0.1778 0.2794)
							(mid 0.249642 0.249642)
							(end 0.2794 0.1778)
						)
						(arc
							(start 0.2794 -0.1778)
							(mid 0.249642 -0.249642)
							(end 0.1778 -0.2794)
						)
					)
					(width 0)
					(fill yes)
				)
			)
		)
		(pad "2" smd custom
			(at 0 0.4445 270)
			(size 0.1397 0.1397)
			(layers "F.Cu" "F.Mask" "F.Paste")
			(net "P3V3_STBY")
			(options
				(clearance outline)
				(anchor circle)
			)
			(primitives
				(gr_poly
					(pts
						(arc
							(start -0.1778 -0.2794)
							(mid -0.249642 -0.249642)
							(end -0.2794 -0.1778)
						)
						(arc
							(start -0.2794 0.1778)
							(mid -0.249642 0.249642)
							(end -0.1778 0.2794)
						)
						(arc
							(start 0.1778 0.2794)
							(mid 0.249642 0.249642)
							(end 0.2794 0.1778)
						)
						(arc
							(start 0.2794 -0.1778)
							(mid 0.249642 -0.249642)
							(end 0.1778 -0.2794)
						)
					)
					(width 0)
					(fill yes)
				)
			)
		)
	)
	(footprint ""
		(layer "F.Cu")
		(at 33.6296 -184.0992)
		(property "Reference" "C262"
			(at 0 0 0)
			(layer "F.SilkS")
			(hide yes)
			(effects
				(font
					(size 1.27 1.27)
				)
			)
		)
		(property "Value" "SC220P50V3JN-GP"
			(at 0 -2.8194 0)
			(unlocked yes)
			(layer "F.Fab")
			(hide yes)
			(effects
				(font
					(size 1.016 1.016)
					(thickness 0.1524)
				)
			)
		)
		(property "Device Type" "C603H36"
			(at 0 -4.3434 0)
			(unlocked yes)
			(layer "F.Fab")
			(hide yes)
			(effects
				(font
					(size 1.016 1.016)
					(thickness 0.1524)
				)
			)
		)
		(duplicate_pad_numbers_are_jumpers no)
		(fp_line
			(start 0.508 0)
			(end -0.508 0)
			(stroke
				(width 0.2032)
				(type default)
			)
			(layer "F.SilkS")
		)
		(fp_rect
			(start -0.5842 1.3335)
			(end 0.5842 -1.3335)
			(stroke
				(width 0)
				(type default)
			)
			(fill no)
			(layer "F.CrtYd")
		)
		(fp_rect
			(start -0.5842 1.3335)
			(end 0.5842 -1.3335)
			(stroke
				(width 0)
				(type default)
			)
			(fill no)
			(layer "F.Fab")
		)
		(pad "1" smd custom
			(at 0 -0.762)
			(size 0.2159 0.2159)
			(layers "F.Cu" "F.Mask" "F.Paste")
			(net "BUF_I2C5_SDA_R")
			(options
				(clearance outline)
				(anchor circle)
			)
			(primitives
				(gr_poly
					(pts
						(arc
							(start -0.3302 -0.4318)
							(mid -0.402042 -0.402042)
							(end -0.4318 -0.3302)
						)
						(arc
							(start -0.4318 0.3302)
							(mid -0.402042 0.402042)
							(end -0.3302 0.4318)
						)
						(arc
							(start 0.3302 0.4318)
							(mid 0.402042 0.402042)
							(end 0.4318 0.3302)
						)
						(arc
							(start 0.4318 -0.3302)
							(mid 0.402042 -0.402042)
							(end 0.3302 -0.4318)
						)
					)
					(width 0)
					(fill yes)
				)
			)
		)
		(pad "2" smd custom
			(at 0 0.762)
			(size 0.2159 0.2159)
			(layers "F.Cu" "F.Mask" "F.Paste")
			(net "GND")
			(options
				(clearance outline)
				(anchor circle)
			)
			(primitives
				(gr_poly
					(pts
						(arc
							(start -0.3302 -0.4318)
							(mid -0.402042 -0.402042)
							(end -0.4318 -0.3302)
						)
						(arc
							(start -0.4318 0.3302)
							(mid -0.402042 0.402042)
							(end -0.3302 0.4318)
						)
						(arc
							(start 0.3302 0.4318)
							(mid 0.402042 0.402042)
							(end 0.4318 0.3302)
						)
						(arc
							(start 0.4318 -0.3302)
							(mid 0.402042 -0.402042)
							(end 0.3302 -0.4318)
						)
					)
					(width 0)
					(fill yes)
				)
			)
		)
	)
	(footprint ""
		(layer "F.Cu")
		(at 291.008054 -212.420454 180)
		(property "Reference" "C91"
			(at 0 0 180)
			(layer "F.SilkS")
			(hide yes)
			(effects
				(font
					(size 1.27 1.27)
				)
			)
		)
		(property "Value" "SCD22U10V2KX-1GP"
			(at 1.1811 -2.7051 180)
			(unlocked yes)
			(layer "F.Fab")
			(hide yes)
			(effects
				(font
					(size 1.016 1.016)
					(thickness 0.1524)
				)
			)
		)
		(property "Device Type" "C402H22"
			(at 1.1811 -4.2291 180)
			(unlocked yes)
			(layer "F.Fab")
			(hide yes)
			(effects
				(font
					(size 1.016 1.016)
					(thickness 0.1524)
				)
			)
		)
		(duplicate_pad_numbers_are_jumpers no)
		(fp_rect
			(start -0.4318 0.9525)
			(end 0.4318 -0.9525)
			(stroke
				(width 0)
				(type default)
			)
			(fill no)
			(layer "F.CrtYd")
		)
		(fp_rect
			(start -0.4318 0.9525)
			(end 0.4318 -0.9525)
			(stroke
				(width 0)
				(type default)
			)
			(fill no)
			(layer "F.Fab")
		)
		(pad "1" smd custom
			(at 0 -0.4445 180)
			(size 0.1524 0.1524)
			(layers "F.Cu" "F.Mask" "F.Paste")
			(net "PCIE_TX_CAP_N29")
			(options
				(clearance outline)
				(anchor circle)
			)
			(primitives
				(gr_poly
					(pts
						(arc
							(start 0.3048 -0.2032)
							(mid 0.275042 -0.275042)
							(end 0.2032 -0.3048)
						)
						(arc
							(start -0.2032 -0.3048)
							(mid -0.275042 -0.275042)
							(end -0.3048 -0.2032)
						)
						(arc
							(start -0.3048 0.2032)
							(mid -0.275042 0.275042)
							(end -0.2032 0.3048)
						)
						(arc
							(start 0.2032 0.3048)
							(mid 0.275042 0.275042)
							(end 0.3048 0.2032)
						)
					)
					(width 0)
					(fill yes)
				)
			)
		)
		(pad "2" smd custom
			(at 0 0.4445 180)
			(size 0.1524 0.1524)
			(layers "F.Cu" "F.Mask" "F.Paste")
			(net "PCIE_TX_N29")
			(options
				(clearance outline)
				(anchor circle)
			)
			(primitives
				(gr_poly
					(pts
						(arc
							(start 0.3048 -0.2032)
							(mid 0.275042 -0.275042)
							(end 0.2032 -0.3048)
						)
						(arc
							(start -0.2032 -0.3048)
							(mid -0.275042 -0.275042)
							(end -0.3048 -0.2032)
						)
						(arc
							(start -0.3048 0.2032)
							(mid -0.275042 0.275042)
							(end -0.2032 0.3048)
						)
						(arc
							(start 0.2032 0.3048)
							(mid 0.275042 0.275042)
							(end 0.3048 0.2032)
						)
					)
					(width 0)
					(fill yes)
				)
			)
		)
	)
	(footprint ""
		(layer "F.Cu")
		(at 225.909124 -190.601092)
		(property "Reference" "R7957"
			(at 0 0 0)
			(layer "F.SilkS")
			(hide yes)
			(effects
				(font
					(size 1.27 1.27)
				)
			)
		)
		(property "Value" "0R2J-2-GP"
			(at 0.064008 -3.993896 0)
			(unlocked yes)
			(layer "F.Fab")
			(hide yes)
			(effects
				(font
					(size 1.016 1.016)
					(thickness 0.1524)
				)
			)
		)
		(property "Device Type" "R402H16"
			(at 0.064008 -5.517896 0)
			(unlocked yes)
			(layer "F.Fab")
			(hide yes)
			(effects
				(font
					(size 1.016 1.016)
					(thickness 0.1524)
				)
			)
		)
		(duplicate_pad_numbers_are_jumpers no)
		(fp_line
			(start -0.508 -0.9398)
			(end -0.508 0.9398)
			(stroke
				(width 0.1524)
				(type default)
			)
			(layer "F.SilkS")
		)
		(fp_line
			(start 0.508 -0.9398)
			(end -0.508 -0.9398)
			(stroke
				(width 0.1524)
				(type default)
			)
			(layer "F.SilkS")
		)
		(fp_rect
			(start -0.508 0.9398)
			(end 0.508 -0.9398)
			(stroke
				(width 0)
				(type default)
			)
			(fill no)
			(layer "F.CrtYd")
		)
		(fp_rect
			(start -0.508 0.9398)
			(end 0.508 -0.9398)
			(stroke
				(width 0)
				(type default)
			)
			(fill no)
			(layer "F.Fab")
		)
		(pad "1" smd custom
			(at 0 -0.4445)
			(size 0.1397 0.1397)
			(layers "F.Cu" "F.Mask" "F.Paste")
			(net "SSD_PWREN8")
			(options
				(clearance outline)
				(anchor circle)
			)
			(primitives
				(gr_poly
					(pts
						(arc
							(start -0.1778 -0.2794)
							(mid -0.249642 -0.249642)
							(end -0.2794 -0.1778)
						)
						(arc
							(start -0.2794 0.1778)
							(mid -0.249642 0.249642)
							(end -0.1778 0.2794)
						)
						(arc
							(start 0.1778 0.2794)
							(mid 0.249642 0.249642)
							(end 0.2794 0.1778)
						)
						(arc
							(start 0.2794 -0.1778)
							(mid 0.249642 -0.249642)
							(end 0.1778 -0.2794)
						)
					)
					(width 0)
					(fill yes)
				)
			)
		)
		(pad "2" smd custom
			(at 0 0.4445)
			(size 0.1397 0.1397)
			(layers "F.Cu" "F.Mask" "F.Paste")
			(net "SSD_PWREN8_R")
			(options
				(clearance outline)
				(anchor circle)
			)
			(primitives
				(gr_poly
					(pts
						(arc
							(start -0.1778 -0.2794)
							(mid -0.249642 -0.249642)
							(end -0.2794 -0.1778)
						)
						(arc
							(start -0.2794 0.1778)
							(mid -0.249642 0.249642)
							(end -0.1778 0.2794)
						)
						(arc
							(start 0.1778 0.2794)
							(mid 0.249642 0.249642)
							(end 0.2794 0.1778)
						)
						(arc
							(start 0.2794 -0.1778)
							(mid 0.249642 -0.249642)
							(end 0.1778 -0.2794)
						)
					)
					(width 0)
					(fill yes)
				)
			)
		)
	)
	(footprint ""
		(layer "F.Cu")
		(at 262.919464 -8.525002 -90)
		(property "Reference" "R7905"
			(at 0 0 270)
			(layer "F.SilkS")
			(hide yes)
			(effects
				(font
					(size 1.27 1.27)
				)
			)
		)
		(property "Value" "0R2J-2-GP"
			(at 0.064008 -3.993896 270)
			(unlocked yes)
			(layer "F.Fab")
			(hide yes)
			(effects
				(font
					(size 1.016 1.016)
					(thickness 0.1524)
				)
			)
		)
		(property "Device Type" "R402H16"
			(at 0.064008 -5.517896 270)
			(unlocked yes)
			(layer "F.Fab")
			(hide yes)
			(effects
				(font
					(size 1.016 1.016)
					(thickness 0.1524)
				)
			)
		)
		(duplicate_pad_numbers_are_jumpers no)
		(fp_line
			(start -0.508 -0.9398)
			(end -0.508 0.9398)
			(stroke
				(width 0.1524)
				(type default)
			)
			(layer "F.SilkS")
		)
		(fp_line
			(start 0.508 -0.9398)
			(end -0.508 -0.9398)
			(stroke
				(width 0.1524)
				(type default)
			)
			(layer "F.SilkS")
		)
		(fp_rect
			(start -0.508 0.9398)
			(end 0.508 -0.9398)
			(stroke
				(width 0)
				(type default)
			)
			(fill no)
			(layer "F.CrtYd")
		)
		(fp_rect
			(start -0.508 0.9398)
			(end 0.508 -0.9398)
			(stroke
				(width 0)
				(type default)
			)
			(fill no)
			(layer "F.Fab")
		)
		(pad "1" smd custom
			(at 0 -0.4445 270)
			(size 0.1397 0.1397)
			(layers "F.Cu" "F.Mask" "F.Paste")
			(net "ADM6315_PM8536_RST#")
			(options
				(clearance outline)
				(anchor circle)
			)
			(primitives
				(gr_poly
					(pts
						(arc
							(start -0.1778 -0.2794)
							(mid -0.249642 -0.249642)
							(end -0.2794 -0.1778)
						)
						(arc
							(start -0.2794 0.1778)
							(mid -0.249642 0.249642)
							(end -0.1778 0.2794)
						)
						(arc
							(start 0.1778 0.2794)
							(mid 0.249642 0.249642)
							(end 0.2794 0.1778)
						)
						(arc
							(start 0.2794 -0.1778)
							(mid 0.249642 -0.249642)
							(end 0.1778 -0.2794)
						)
					)
					(width 0)
					(fill yes)
				)
			)
		)
		(pad "2" smd custom
			(at 0 0.4445 270)
			(size 0.1397 0.1397)
			(layers "F.Cu" "F.Mask" "F.Paste")
			(net "PQ21_G")
			(options
				(clearance outline)
				(anchor circle)
			)
			(primitives
				(gr_poly
					(pts
						(arc
							(start -0.1778 -0.2794)
							(mid -0.249642 -0.249642)
							(end -0.2794 -0.1778)
						)
						(arc
							(start -0.2794 0.1778)
							(mid -0.249642 0.249642)
							(end -0.1778 0.2794)
						)
						(arc
							(start 0.1778 0.2794)
							(mid 0.249642 0.249642)
							(end 0.2794 0.1778)
						)
						(arc
							(start 0.2794 -0.1778)
							(mid 0.249642 -0.249642)
							(end 0.1778 -0.2794)
						)
					)
					(width 0)
					(fill yes)
				)
			)
		)
	)
	(footprint ""
		(layer "F.Cu")
		(at 71.731124 -183.235092)
		(property "Reference" "R7935"
			(at 0 0 0)
			(layer "F.SilkS")
			(hide yes)
			(effects
				(font
					(size 1.27 1.27)
				)
			)
		)
		(property "Value" "0R2J-2-GP"
			(at 0.064008 -3.993896 0)
			(unlocked yes)
			(layer "F.Fab")
			(hide yes)
			(effects
				(font
					(size 1.016 1.016)
					(thickness 0.1524)
				)
			)
		)
		(property "Device Type" "R402H16"
			(at 0.064008 -5.517896 0)
			(unlocked yes)
			(layer "F.Fab")
			(hide yes)
			(effects
				(font
					(size 1.016 1.016)
					(thickness 0.1524)
				)
			)
		)
		(duplicate_pad_numbers_are_jumpers no)
		(fp_line
			(start -0.508 -0.9398)
			(end -0.508 0.9398)
			(stroke
				(width 0.1524)
				(type default)
			)
			(layer "F.SilkS")
		)
		(fp_line
			(start 0.508 -0.9398)
			(end -0.508 -0.9398)
			(stroke
				(width 0.1524)
				(type default)
			)
			(layer "F.SilkS")
		)
		(fp_rect
			(start -0.508 0.9398)
			(end 0.508 -0.9398)
			(stroke
				(width 0)
				(type default)
			)
			(fill no)
			(layer "F.CrtYd")
		)
		(fp_rect
			(start -0.508 0.9398)
			(end 0.508 -0.9398)
			(stroke
				(width 0)
				(type default)
			)
			(fill no)
			(layer "F.Fab")
		)
		(pad "1" smd custom
			(at 0 -0.4445)
			(size 0.1397 0.1397)
			(layers "F.Cu" "F.Mask" "F.Paste")
			(net "SSD_PRSNT#0")
			(options
				(clearance outline)
				(anchor circle)
			)
			(primitives
				(gr_poly
					(pts
						(arc
							(start -0.1778 -0.2794)
							(mid -0.249642 -0.249642)
							(end -0.2794 -0.1778)
						)
						(arc
							(start -0.2794 0.1778)
							(mid -0.249642 0.249642)
							(end -0.1778 0.2794)
						)
						(arc
							(start 0.1778 0.2794)
							(mid 0.249642 0.249642)
							(end 0.2794 0.1778)
						)
						(arc
							(start 0.2794 -0.1778)
							(mid 0.249642 -0.249642)
							(end 0.1778 -0.2794)
						)
					)
					(width 0)
					(fill yes)
				)
			)
		)
		(pad "2" smd custom
			(at 0 0.4445)
			(size 0.1397 0.1397)
			(layers "F.Cu" "F.Mask" "F.Paste")
			(net "SSD_PRSNT#0_R")
			(options
				(clearance outline)
				(anchor circle)
			)
			(primitives
				(gr_poly
					(pts
						(arc
							(start -0.1778 -0.2794)
							(mid -0.249642 -0.249642)
							(end -0.2794 -0.1778)
						)
						(arc
							(start -0.2794 0.1778)
							(mid -0.249642 0.249642)
							(end -0.1778 0.2794)
						)
						(arc
							(start 0.1778 0.2794)
							(mid 0.249642 0.249642)
							(end 0.2794 0.1778)
						)
						(arc
							(start 0.2794 -0.1778)
							(mid 0.249642 -0.249642)
							(end 0.1778 -0.2794)
						)
					)
					(width 0)
					(fill yes)
				)
			)
		)
	)
	(footprint ""
		(layer "F.Cu")
		(at 49.657 -148.59)
		(property "Reference" "R590"
			(at 0 0 0)
			(layer "F.SilkS")
			(hide yes)
			(effects
				(font
					(size 1.27 1.27)
				)
			)
		)
		(property "Value" "4K7R2F-GP"
			(at 0.064008 -3.993896 0)
			(unlocked yes)
			(layer "F.Fab")
			(hide yes)
			(effects
				(font
					(size 1.016 1.016)
					(thickness 0.1524)
				)
			)
		)
		(property "Device Type" "R402H16"
			(at 0.064008 -5.517896 0)
			(unlocked yes)
			(layer "F.Fab")
			(hide yes)
			(effects
				(font
					(size 1.016 1.016)
					(thickness 0.1524)
				)
			)
		)
		(duplicate_pad_numbers_are_jumpers no)
		(fp_line
			(start -0.508 -0.9398)
			(end -0.508 0.9398)
			(stroke
				(width 0.1524)
				(type default)
			)
			(layer "F.SilkS")
		)
		(fp_line
			(start 0.508 -0.9398)
			(end -0.508 -0.9398)
			(stroke
				(width 0.1524)
				(type default)
			)
			(layer "F.SilkS")
		)
		(fp_rect
			(start -0.508 0.9398)
			(end 0.508 -0.9398)
			(stroke
				(width 0)
				(type default)
			)
			(fill no)
			(layer "F.CrtYd")
		)
		(fp_rect
			(start -0.508 0.9398)
			(end 0.508 -0.9398)
			(stroke
				(width 0)
				(type default)
			)
			(fill no)
			(layer "F.Fab")
		)
		(pad "1" smd custom
			(at 0 -0.4445)
			(size 0.1397 0.1397)
			(layers "F.Cu" "F.Mask" "F.Paste")
			(net "TEMP_2_A0")
			(options
				(clearance outline)
				(anchor circle)
			)
			(primitives
				(gr_poly
					(pts
						(arc
							(start -0.1778 -0.2794)
							(mid -0.249642 -0.249642)
							(end -0.2794 -0.1778)
						)
						(arc
							(start -0.2794 0.1778)
							(mid -0.249642 0.249642)
							(end -0.1778 0.2794)
						)
						(arc
							(start 0.1778 0.2794)
							(mid 0.249642 0.249642)
							(end 0.2794 0.1778)
						)
						(arc
							(start 0.2794 -0.1778)
							(mid 0.249642 -0.249642)
							(end 0.1778 -0.2794)
						)
					)
					(width 0)
					(fill yes)
				)
			)
		)
		(pad "2" smd custom
			(at 0 0.4445)
			(size 0.1397 0.1397)
			(layers "F.Cu" "F.Mask" "F.Paste")
			(net "GND")
			(options
				(clearance outline)
				(anchor circle)
			)
			(primitives
				(gr_poly
					(pts
						(arc
							(start -0.1778 -0.2794)
							(mid -0.249642 -0.249642)
							(end -0.2794 -0.1778)
						)
						(arc
							(start -0.2794 0.1778)
							(mid -0.249642 0.249642)
							(end -0.1778 0.2794)
						)
						(arc
							(start 0.1778 0.2794)
							(mid 0.249642 0.249642)
							(end 0.2794 0.1778)
						)
						(arc
							(start 0.2794 -0.1778)
							(mid 0.249642 -0.249642)
							(end 0.1778 -0.2794)
						)
					)
					(width 0)
					(fill yes)
				)
			)
		)
	)
	(footprint ""
		(layer "F.Cu")
		(at 21.5138 -83.82 180)
		(property "Reference" "C642"
			(at 0 0 180)
			(layer "F.SilkS")
			(hide yes)
			(effects
				(font
					(size 1.27 1.27)
				)
			)
		)
		(property "Value" "SCD22U10V2KX-1GP"
			(at 1.1811 -2.7051 180)
			(unlocked yes)
			(layer "F.Fab")
			(hide yes)
			(effects
				(font
					(size 1.016 1.016)
					(thickness 0.1524)
				)
			)
		)
		(property "Device Type" "C402H22"
			(at 1.1811 -4.2291 180)
			(unlocked yes)
			(layer "F.Fab")
			(hide yes)
			(effects
				(font
					(size 1.016 1.016)
					(thickness 0.1524)
				)
			)
		)
		(duplicate_pad_numbers_are_jumpers no)
		(fp_rect
			(start -0.4318 0.9525)
			(end 0.4318 -0.9525)
			(stroke
				(width 0)
				(type default)
			)
			(fill no)
			(layer "F.CrtYd")
		)
		(fp_rect
			(start -0.4318 0.9525)
			(end 0.4318 -0.9525)
			(stroke
				(width 0)
				(type default)
			)
			(fill no)
			(layer "F.Fab")
		)
		(pad "1" smd custom
			(at 0 -0.4445 180)
			(size 0.1524 0.1524)
			(layers "F.Cu" "F.Mask" "F.Paste")
			(net "PCIE_RX_CAP_N78")
			(options
				(clearance outline)
				(anchor circle)
			)
			(primitives
				(gr_poly
					(pts
						(arc
							(start 0.3048 -0.2032)
							(mid 0.275042 -0.275042)
							(end 0.2032 -0.3048)
						)
						(arc
							(start -0.2032 -0.3048)
							(mid -0.275042 -0.275042)
							(end -0.3048 -0.2032)
						)
						(arc
							(start -0.3048 0.2032)
							(mid -0.275042 0.275042)
							(end -0.2032 0.3048)
						)
						(arc
							(start 0.2032 0.3048)
							(mid 0.275042 0.275042)
							(end 0.3048 0.2032)
						)
					)
					(width 0)
					(fill yes)
				)
			)
		)
		(pad "2" smd custom
			(at 0 0.4445 180)
			(size 0.1524 0.1524)
			(layers "F.Cu" "F.Mask" "F.Paste")
			(net "PCIE_RX_N78")
			(options
				(clearance outline)
				(anchor circle)
			)
			(primitives
				(gr_poly
					(pts
						(arc
							(start 0.3048 -0.2032)
							(mid 0.275042 -0.275042)
							(end 0.2032 -0.3048)
						)
						(arc
							(start -0.2032 -0.3048)
							(mid -0.275042 -0.275042)
							(end -0.3048 -0.2032)
						)
						(arc
							(start -0.3048 0.2032)
							(mid -0.275042 0.275042)
							(end -0.2032 0.3048)
						)
						(arc
							(start 0.2032 0.3048)
							(mid 0.275042 0.275042)
							(end 0.3048 0.2032)
						)
					)
					(width 0)
					(fill yes)
				)
			)
		)
	)
	(footprint ""
		(layer "F.Cu")
		(at 33.032954 -165.137084 180)
		(property "Reference" "C172"
			(at 0 0 180)
			(layer "F.SilkS")
			(hide yes)
			(effects
				(font
					(size 1.27 1.27)
				)
			)
		)
		(property "Value" "SCD1U16V2KX-3GP"
			(at 1.1811 -2.7051 180)
			(unlocked yes)
			(layer "F.Fab")
			(hide yes)
			(effects
				(font
					(size 1.016 1.016)
					(thickness 0.1524)
				)
			)
		)
		(property "Device Type" "C402H22"
			(at 1.1811 -4.2291 180)
			(unlocked yes)
			(layer "F.Fab")
			(hide yes)
			(effects
				(font
					(size 1.016 1.016)
					(thickness 0.1524)
				)
			)
		)
		(duplicate_pad_numbers_are_jumpers no)
		(fp_rect
			(start -0.4318 0.9525)
			(end 0.4318 -0.9525)
			(stroke
				(width 0)
				(type default)
			)
			(fill no)
			(layer "F.CrtYd")
		)
		(fp_rect
			(start -0.4318 0.9525)
			(end 0.4318 -0.9525)
			(stroke
				(width 0)
				(type default)
			)
			(fill no)
			(layer "F.Fab")
		)
		(pad "1" smd custom
			(at 0 -0.4445 180)
			(size 0.1524 0.1524)
			(layers "F.Cu" "F.Mask" "F.Paste")
			(net "P1V53_STBY")
			(options
				(clearance outline)
				(anchor circle)
			)
			(primitives
				(gr_poly
					(pts
						(arc
							(start 0.3048 -0.2032)
							(mid 0.275042 -0.275042)
							(end 0.2032 -0.3048)
						)
						(arc
							(start -0.2032 -0.3048)
							(mid -0.275042 -0.275042)
							(end -0.3048 -0.2032)
						)
						(arc
							(start -0.3048 0.2032)
							(mid -0.275042 0.275042)
							(end -0.2032 0.3048)
						)
						(arc
							(start 0.2032 0.3048)
							(mid 0.275042 0.275042)
							(end 0.3048 0.2032)
						)
					)
					(width 0)
					(fill yes)
				)
			)
		)
		(pad "2" smd custom
			(at 0 0.4445 180)
			(size 0.1524 0.1524)
			(layers "F.Cu" "F.Mask" "F.Paste")
			(net "GND")
			(options
				(clearance outline)
				(anchor circle)
			)
			(primitives
				(gr_poly
					(pts
						(arc
							(start 0.3048 -0.2032)
							(mid 0.275042 -0.275042)
							(end 0.2032 -0.3048)
						)
						(arc
							(start -0.2032 -0.3048)
							(mid -0.275042 -0.275042)
							(end -0.3048 -0.2032)
						)
						(arc
							(start -0.3048 0.2032)
							(mid -0.275042 0.275042)
							(end -0.2032 0.3048)
						)
						(arc
							(start 0.2032 0.3048)
							(mid 0.275042 0.275042)
							(end 0.3048 0.2032)
						)
					)
					(width 0)
					(fill yes)
				)
			)
		)
	)
	(footprint ""
		(layer "F.Cu")
		(at 10.8966 -194.31 180)
		(property "Reference" "C7273"
			(at 0 0 180)
			(layer "F.SilkS")
			(hide yes)
			(effects
				(font
					(size 1.27 1.27)
				)
			)
		)
		(property "Value" "SCD01U16V2KX-3GP"
			(at 1.1811 -2.7051 180)
			(unlocked yes)
			(layer "F.Fab")
			(hide yes)
			(effects
				(font
					(size 1.016 1.016)
					(thickness 0.1524)
				)
			)
		)
		(property "Device Type" "C402H22"
			(at 1.1811 -4.2291 180)
			(unlocked yes)
			(layer "F.Fab")
			(hide yes)
			(effects
				(font
					(size 1.016 1.016)
					(thickness 0.1524)
				)
			)
		)
		(duplicate_pad_numbers_are_jumpers no)
		(fp_rect
			(start -0.4318 0.9525)
			(end 0.4318 -0.9525)
			(stroke
				(width 0)
				(type default)
			)
			(fill no)
			(layer "F.CrtYd")
		)
		(fp_rect
			(start -0.4318 0.9525)
			(end 0.4318 -0.9525)
			(stroke
				(width 0)
				(type default)
			)
			(fill no)
			(layer "F.Fab")
		)
		(pad "1" smd custom
			(at 0 -0.4445 180)
			(size 0.1524 0.1524)
			(layers "F.Cu" "F.Mask" "F.Paste")
			(net "MB0_TIME_R")
			(options
				(clearance outline)
				(anchor circle)
			)
			(primitives
				(gr_poly
					(pts
						(arc
							(start 0.3048 -0.2032)
							(mid 0.275042 -0.275042)
							(end 0.2032 -0.3048)
						)
						(arc
							(start -0.2032 -0.3048)
							(mid -0.275042 -0.275042)
							(end -0.3048 -0.2032)
						)
						(arc
							(start -0.3048 0.2032)
							(mid -0.275042 0.275042)
							(end -0.2032 0.3048)
						)
						(arc
							(start 0.2032 0.3048)
							(mid 0.275042 0.275042)
							(end 0.3048 0.2032)
						)
					)
					(width 0)
					(fill yes)
				)
			)
		)
		(pad "2" smd custom
			(at 0 0.4445 180)
			(size 0.1524 0.1524)
			(layers "F.Cu" "F.Mask" "F.Paste")
			(net "AGND_CURRENT_MON")
			(options
				(clearance outline)
				(anchor circle)
			)
			(primitives
				(gr_poly
					(pts
						(arc
							(start 0.3048 -0.2032)
							(mid 0.275042 -0.275042)
							(end 0.2032 -0.3048)
						)
						(arc
							(start -0.2032 -0.3048)
							(mid -0.275042 -0.275042)
							(end -0.3048 -0.2032)
						)
						(arc
							(start -0.3048 0.2032)
							(mid -0.275042 0.275042)
							(end -0.2032 0.3048)
						)
						(arc
							(start 0.2032 0.3048)
							(mid 0.275042 0.275042)
							(end 0.3048 0.2032)
						)
					)
					(width 0)
					(fill yes)
				)
			)
		)
	)
	(footprint ""
		(layer "F.Cu")
		(at 19.7612 -56.5404 180)
		(property "Reference" "R611"
			(at 0 0 180)
			(layer "F.SilkS")
			(hide yes)
			(effects
				(font
					(size 1.27 1.27)
				)
			)
		)
		(property "Value" "0R2J-2-GP"
			(at 0.064008 -3.993896 180)
			(unlocked yes)
			(layer "F.Fab")
			(hide yes)
			(effects
				(font
					(size 1.016 1.016)
					(thickness 0.1524)
				)
			)
		)
		(property "Device Type" "R402H16"
			(at 0.064008 -5.517896 180)
			(unlocked yes)
			(layer "F.Fab")
			(hide yes)
			(effects
				(font
					(size 1.016 1.016)
					(thickness 0.1524)
				)
			)
		)
		(duplicate_pad_numbers_are_jumpers no)
		(fp_line
			(start 0.508 -0.9398)
			(end -0.508 -0.9398)
			(stroke
				(width 0.1524)
				(type default)
			)
			(layer "F.SilkS")
		)
		(fp_line
			(start -0.508 -0.9398)
			(end -0.508 0.9398)
			(stroke
				(width 0.1524)
				(type default)
			)
			(layer "F.SilkS")
		)
		(fp_rect
			(start -0.508 0.9398)
			(end 0.508 -0.9398)
			(stroke
				(width 0)
				(type default)
			)
			(fill no)
			(layer "F.CrtYd")
		)
		(fp_rect
			(start -0.508 0.9398)
			(end 0.508 -0.9398)
			(stroke
				(width 0)
				(type default)
			)
			(fill no)
			(layer "F.Fab")
		)
		(pad "1" smd custom
			(at 0 -0.4445 180)
			(size 0.1397 0.1397)
			(layers "F.Cu" "F.Mask" "F.Paste")
			(net "NIC0_MDI0_N2")
			(options
				(clearance outline)
				(anchor circle)
			)
			(primitives
				(gr_poly
					(pts
						(arc
							(start -0.1778 -0.2794)
							(mid -0.249642 -0.249642)
							(end -0.2794 -0.1778)
						)
						(arc
							(start -0.2794 0.1778)
							(mid -0.249642 0.249642)
							(end -0.1778 0.2794)
						)
						(arc
							(start 0.1778 0.2794)
							(mid 0.249642 0.249642)
							(end 0.2794 0.1778)
						)
						(arc
							(start 0.2794 -0.1778)
							(mid 0.249642 -0.249642)
							(end 0.1778 -0.2794)
						)
					)
					(width 0)
					(fill yes)
				)
			)
		)
		(pad "2" smd custom
			(at 0 0.4445 180)
			(size 0.1397 0.1397)
			(layers "F.Cu" "F.Mask" "F.Paste")
			(net "MNG_TX_DN")
			(options
				(clearance outline)
				(anchor circle)
			)
			(primitives
				(gr_poly
					(pts
						(arc
							(start -0.1778 -0.2794)
							(mid -0.249642 -0.249642)
							(end -0.2794 -0.1778)
						)
						(arc
							(start -0.2794 0.1778)
							(mid -0.249642 0.249642)
							(end -0.1778 0.2794)
						)
						(arc
							(start 0.1778 0.2794)
							(mid 0.249642 0.249642)
							(end 0.2794 0.1778)
						)
						(arc
							(start 0.2794 -0.1778)
							(mid 0.249642 -0.249642)
							(end 0.1778 -0.2794)
						)
					)
					(width 0)
					(fill yes)
				)
			)
		)
	)
	(footprint ""
		(layer "F.Cu")
		(at 67.8942 -74.93 180)
		(property "Reference" "C186"
			(at 0 0 180)
			(layer "F.SilkS")
			(hide yes)
			(effects
				(font
					(size 1.27 1.27)
				)
			)
		)
		(property "Value" "SCD1U16V2KX-3GP"
			(at 1.1811 -2.7051 180)
			(unlocked yes)
			(layer "F.Fab")
			(hide yes)
			(effects
				(font
					(size 1.016 1.016)
					(thickness 0.1524)
				)
			)
		)
		(property "Device Type" "C402H22"
			(at 1.1811 -4.2291 180)
			(unlocked yes)
			(layer "F.Fab")
			(hide yes)
			(effects
				(font
					(size 1.016 1.016)
					(thickness 0.1524)
				)
			)
		)
		(duplicate_pad_numbers_are_jumpers no)
		(fp_rect
			(start -0.4318 0.9525)
			(end 0.4318 -0.9525)
			(stroke
				(width 0)
				(type default)
			)
			(fill no)
			(layer "F.CrtYd")
		)
		(fp_rect
			(start -0.4318 0.9525)
			(end 0.4318 -0.9525)
			(stroke
				(width 0)
				(type default)
			)
			(fill no)
			(layer "F.Fab")
		)
		(pad "1" smd custom
			(at 0 -0.4445 180)
			(size 0.1524 0.1524)
			(layers "F.Cu" "F.Mask" "F.Paste")
			(net "P3V3_STBY")
			(options
				(clearance outline)
				(anchor circle)
			)
			(primitives
				(gr_poly
					(pts
						(arc
							(start 0.3048 -0.2032)
							(mid 0.275042 -0.275042)
							(end 0.2032 -0.3048)
						)
						(arc
							(start -0.2032 -0.3048)
							(mid -0.275042 -0.275042)
							(end -0.3048 -0.2032)
						)
						(arc
							(start -0.3048 0.2032)
							(mid -0.275042 0.275042)
							(end -0.2032 0.3048)
						)
						(arc
							(start 0.2032 0.3048)
							(mid 0.275042 0.275042)
							(end 0.3048 0.2032)
						)
					)
					(width 0)
					(fill yes)
				)
			)
		)
		(pad "2" smd custom
			(at 0 0.4445 180)
			(size 0.1524 0.1524)
			(layers "F.Cu" "F.Mask" "F.Paste")
			(net "GND")
			(options
				(clearance outline)
				(anchor circle)
			)
			(primitives
				(gr_poly
					(pts
						(arc
							(start 0.3048 -0.2032)
							(mid 0.275042 -0.275042)
							(end 0.2032 -0.3048)
						)
						(arc
							(start -0.2032 -0.3048)
							(mid -0.275042 -0.275042)
							(end -0.3048 -0.2032)
						)
						(arc
							(start -0.3048 0.2032)
							(mid -0.275042 0.275042)
							(end -0.2032 0.3048)
						)
						(arc
							(start 0.2032 0.3048)
							(mid 0.275042 0.275042)
							(end 0.3048 0.2032)
						)
					)
					(width 0)
					(fill yes)
				)
			)
		)
	)
	(footprint ""
		(layer "F.Cu")
		(at 334.518 -69.723 -90)
		(property "Reference" "R610"
			(at 0 0 270)
			(layer "F.SilkS")
			(hide yes)
			(effects
				(font
					(size 1.27 1.27)
				)
			)
		)
		(property "Value" "4K7R2F-GP"
			(at 0.064008 -3.993896 270)
			(unlocked yes)
			(layer "F.Fab")
			(hide yes)
			(effects
				(font
					(size 1.016 1.016)
					(thickness 0.1524)
				)
			)
		)
		(property "Device Type" "R402H16"
			(at 0.064008 -5.517896 270)
			(unlocked yes)
			(layer "F.Fab")
			(hide yes)
			(effects
				(font
					(size 1.016 1.016)
					(thickness 0.1524)
				)
			)
		)
		(duplicate_pad_numbers_are_jumpers no)
		(fp_line
			(start -0.508 -0.9398)
			(end -0.508 0.9398)
			(stroke
				(width 0.1524)
				(type default)
			)
			(layer "F.SilkS")
		)
		(fp_line
			(start 0.508 -0.9398)
			(end -0.508 -0.9398)
			(stroke
				(width 0.1524)
				(type default)
			)
			(layer "F.SilkS")
		)
		(fp_rect
			(start -0.508 0.9398)
			(end 0.508 -0.9398)
			(stroke
				(width 0)
				(type default)
			)
			(fill no)
			(layer "F.CrtYd")
		)
		(fp_rect
			(start -0.508 0.9398)
			(end 0.508 -0.9398)
			(stroke
				(width 0)
				(type default)
			)
			(fill no)
			(layer "F.Fab")
		)
		(pad "1" smd custom
			(at 0 -0.4445 270)
			(size 0.1397 0.1397)
			(layers "F.Cu" "F.Mask" "F.Paste")
			(net "P0V9_E_PG")
			(options
				(clearance outline)
				(anchor circle)
			)
			(primitives
				(gr_poly
					(pts
						(arc
							(start -0.1778 -0.2794)
							(mid -0.249642 -0.249642)
							(end -0.2794 -0.1778)
						)
						(arc
							(start -0.2794 0.1778)
							(mid -0.249642 0.249642)
							(end -0.1778 0.2794)
						)
						(arc
							(start 0.1778 0.2794)
							(mid 0.249642 0.249642)
							(end 0.2794 0.1778)
						)
						(arc
							(start 0.2794 -0.1778)
							(mid 0.249642 -0.249642)
							(end 0.1778 -0.2794)
						)
					)
					(width 0)
					(fill yes)
				)
			)
		)
		(pad "2" smd custom
			(at 0 0.4445 270)
			(size 0.1397 0.1397)
			(layers "F.Cu" "F.Mask" "F.Paste")
			(net "P3V3_STBY")
			(options
				(clearance outline)
				(anchor circle)
			)
			(primitives
				(gr_poly
					(pts
						(arc
							(start -0.1778 -0.2794)
							(mid -0.249642 -0.249642)
							(end -0.2794 -0.1778)
						)
						(arc
							(start -0.2794 0.1778)
							(mid -0.249642 0.249642)
							(end -0.1778 0.2794)
						)
						(arc
							(start 0.1778 0.2794)
							(mid 0.249642 0.249642)
							(end 0.2794 0.1778)
						)
						(arc
							(start 0.2794 -0.1778)
							(mid 0.249642 -0.249642)
							(end 0.1778 -0.2794)
						)
					)
					(width 0)
					(fill yes)
				)
			)
		)
	)
	(footprint ""
		(layer "F.Cu")
		(at 53.721 -121.412 90)
		(property "Reference" "R336"
			(at 0 0 90)
			(layer "F.SilkS")
			(hide yes)
			(effects
				(font
					(size 1.27 1.27)
				)
			)
		)
		(property "Value" "0R2J-2-GP"
			(at 0.064008 -3.993896 90)
			(unlocked yes)
			(layer "F.Fab")
			(hide yes)
			(effects
				(font
					(size 1.016 1.016)
					(thickness 0.1524)
				)
			)
		)
		(property "Device Type" "R402H16"
			(at 0.064008 -5.517896 90)
			(unlocked yes)
			(layer "F.Fab")
			(hide yes)
			(effects
				(font
					(size 1.016 1.016)
					(thickness 0.1524)
				)
			)
		)
		(duplicate_pad_numbers_are_jumpers no)
		(fp_line
			(start 0.508 -0.9398)
			(end -0.508 -0.9398)
			(stroke
				(width 0.1524)
				(type default)
			)
			(layer "F.SilkS")
		)
		(fp_line
			(start -0.508 -0.9398)
			(end -0.508 0.9398)
			(stroke
				(width 0.1524)
				(type default)
			)
			(layer "F.SilkS")
		)
		(fp_rect
			(start -0.508 0.9398)
			(end 0.508 -0.9398)
			(stroke
				(width 0)
				(type default)
			)
			(fill no)
			(layer "F.CrtYd")
		)
		(fp_rect
			(start -0.508 0.9398)
			(end 0.508 -0.9398)
			(stroke
				(width 0)
				(type default)
			)
			(fill no)
			(layer "F.Fab")
		)
		(pad "1" smd custom
			(at 0 -0.4445 90)
			(size 0.1397 0.1397)
			(layers "F.Cu" "F.Mask" "F.Paste")
			(net "JTAG_BMC_TRST_N")
			(options
				(clearance outline)
				(anchor circle)
			)
			(primitives
				(gr_poly
					(pts
						(arc
							(start -0.1778 -0.2794)
							(mid -0.249642 -0.249642)
							(end -0.2794 -0.1778)
						)
						(arc
							(start -0.2794 0.1778)
							(mid -0.249642 0.249642)
							(end -0.1778 0.2794)
						)
						(arc
							(start 0.1778 0.2794)
							(mid 0.249642 0.249642)
							(end 0.2794 0.1778)
						)
						(arc
							(start 0.2794 -0.1778)
							(mid 0.249642 -0.249642)
							(end 0.1778 -0.2794)
						)
					)
					(width 0)
					(fill yes)
				)
			)
		)
		(pad "2" smd custom
			(at 0 0.4445 90)
			(size 0.1397 0.1397)
			(layers "F.Cu" "F.Mask" "F.Paste")
			(net "GND")
			(options
				(clearance outline)
				(anchor circle)
			)
			(primitives
				(gr_poly
					(pts
						(arc
							(start -0.1778 -0.2794)
							(mid -0.249642 -0.249642)
							(end -0.2794 -0.1778)
						)
						(arc
							(start -0.2794 0.1778)
							(mid -0.249642 0.249642)
							(end -0.1778 0.2794)
						)
						(arc
							(start 0.1778 0.2794)
							(mid 0.249642 0.249642)
							(end 0.2794 0.1778)
						)
						(arc
							(start 0.2794 -0.1778)
							(mid 0.249642 -0.249642)
							(end 0.1778 -0.2794)
						)
					)
					(width 0)
					(fill yes)
				)
			)
		)
	)
	(footprint ""
		(layer "F.Cu")
		(at 43.379136 -47.418244 -90)
		(property "Reference" "R410"
			(at 0 0 270)
			(layer "F.SilkS")
			(hide yes)
			(effects
				(font
					(size 1.27 1.27)
				)
			)
		)
		(property "Value" "0R2J-2-GP"
			(at 0.064008 -3.993896 270)
			(unlocked yes)
			(layer "F.Fab")
			(hide yes)
			(effects
				(font
					(size 1.016 1.016)
					(thickness 0.1524)
				)
			)
		)
		(property "Device Type" "R402H16"
			(at 0.064008 -5.517896 270)
			(unlocked yes)
			(layer "F.Fab")
			(hide yes)
			(effects
				(font
					(size 1.016 1.016)
					(thickness 0.1524)
				)
			)
		)
		(duplicate_pad_numbers_are_jumpers no)
		(fp_line
			(start -0.508 -0.9398)
			(end -0.508 0.9398)
			(stroke
				(width 0.1524)
				(type default)
			)
			(layer "F.SilkS")
		)
		(fp_line
			(start 0.508 -0.9398)
			(end -0.508 -0.9398)
			(stroke
				(width 0.1524)
				(type default)
			)
			(layer "F.SilkS")
		)
		(fp_rect
			(start -0.508 0.9398)
			(end 0.508 -0.9398)
			(stroke
				(width 0)
				(type default)
			)
			(fill no)
			(layer "F.CrtYd")
		)
		(fp_rect
			(start -0.508 0.9398)
			(end 0.508 -0.9398)
			(stroke
				(width 0)
				(type default)
			)
			(fill no)
			(layer "F.Fab")
		)
		(pad "1" smd custom
			(at 0 -0.4445 270)
			(size 0.1397 0.1397)
			(layers "F.Cu" "F.Mask" "F.Paste")
			(net "USB_DN_R")
			(options
				(clearance outline)
				(anchor circle)
			)
			(primitives
				(gr_poly
					(pts
						(arc
							(start -0.1778 -0.2794)
							(mid -0.249642 -0.249642)
							(end -0.2794 -0.1778)
						)
						(arc
							(start -0.2794 0.1778)
							(mid -0.249642 0.249642)
							(end -0.1778 0.2794)
						)
						(arc
							(start 0.1778 0.2794)
							(mid 0.249642 0.249642)
							(end 0.2794 0.1778)
						)
						(arc
							(start 0.2794 -0.1778)
							(mid 0.249642 -0.249642)
							(end 0.1778 -0.2794)
						)
					)
					(width 0)
					(fill yes)
				)
			)
		)
		(pad "2" smd custom
			(at 0 0.4445 270)
			(size 0.1397 0.1397)
			(layers "F.Cu" "F.Mask" "F.Paste")
			(net "USB_P1_F_DN1")
			(options
				(clearance outline)
				(anchor circle)
			)
			(primitives
				(gr_poly
					(pts
						(arc
							(start -0.1778 -0.2794)
							(mid -0.249642 -0.249642)
							(end -0.2794 -0.1778)
						)
						(arc
							(start -0.2794 0.1778)
							(mid -0.249642 0.249642)
							(end -0.1778 0.2794)
						)
						(arc
							(start 0.1778 0.2794)
							(mid 0.249642 0.249642)
							(end 0.2794 0.1778)
						)
						(arc
							(start 0.2794 -0.1778)
							(mid 0.249642 -0.249642)
							(end 0.1778 -0.2794)
						)
					)
					(width 0)
					(fill yes)
				)
			)
		)
	)
	(footprint ""
		(layer "F.Cu")
		(at 334.5942 -76.1746 180)
		(property "Reference" "R80"
			(at 0 0 180)
			(layer "F.SilkS")
			(hide yes)
			(effects
				(font
					(size 1.27 1.27)
				)
			)
		)
		(property "Value" "0R2J-2-GP"
			(at 0.064008 -3.993896 180)
			(unlocked yes)
			(layer "F.Fab")
			(hide yes)
			(effects
				(font
					(size 1.016 1.016)
					(thickness 0.1524)
				)
			)
		)
		(property "Device Type" "R402H16"
			(at 0.064008 -5.517896 180)
			(unlocked yes)
			(layer "F.Fab")
			(hide yes)
			(effects
				(font
					(size 1.016 1.016)
					(thickness 0.1524)
				)
			)
		)
		(duplicate_pad_numbers_are_jumpers no)
		(fp_line
			(start 0.508 -0.9398)
			(end -0.508 -0.9398)
			(stroke
				(width 0.1524)
				(type default)
			)
			(layer "F.SilkS")
		)
		(fp_line
			(start -0.508 -0.9398)
			(end -0.508 0.9398)
			(stroke
				(width 0.1524)
				(type default)
			)
			(layer "F.SilkS")
		)
		(fp_rect
			(start -0.508 0.9398)
			(end 0.508 -0.9398)
			(stroke
				(width 0)
				(type default)
			)
			(fill no)
			(layer "F.CrtYd")
		)
		(fp_rect
			(start -0.508 0.9398)
			(end 0.508 -0.9398)
			(stroke
				(width 0)
				(type default)
			)
			(fill no)
			(layer "F.Fab")
		)
		(pad "1" smd custom
			(at 0 -0.4445 180)
			(size 0.1397 0.1397)
			(layers "F.Cu" "F.Mask" "F.Paste")
			(net "P0V9_E_VFB_R")
			(options
				(clearance outline)
				(anchor circle)
			)
			(primitives
				(gr_poly
					(pts
						(arc
							(start -0.1778 -0.2794)
							(mid -0.249642 -0.249642)
							(end -0.2794 -0.1778)
						)
						(arc
							(start -0.2794 0.1778)
							(mid -0.249642 0.249642)
							(end -0.1778 0.2794)
						)
						(arc
							(start 0.1778 0.2794)
							(mid 0.249642 0.249642)
							(end 0.2794 0.1778)
						)
						(arc
							(start 0.2794 -0.1778)
							(mid 0.249642 -0.249642)
							(end 0.1778 -0.2794)
						)
					)
					(width 0)
					(fill yes)
				)
			)
		)
		(pad "2" smd custom
			(at 0 0.4445 180)
			(size 0.1397 0.1397)
			(layers "F.Cu" "F.Mask" "F.Paste")
			(net "DUT_VDD")
			(options
				(clearance outline)
				(anchor circle)
			)
			(primitives
				(gr_poly
					(pts
						(arc
							(start -0.1778 -0.2794)
							(mid -0.249642 -0.249642)
							(end -0.2794 -0.1778)
						)
						(arc
							(start -0.2794 0.1778)
							(mid -0.249642 0.249642)
							(end -0.1778 0.2794)
						)
						(arc
							(start 0.1778 0.2794)
							(mid 0.249642 0.249642)
							(end 0.2794 0.1778)
						)
						(arc
							(start 0.2794 -0.1778)
							(mid 0.249642 -0.249642)
							(end 0.1778 -0.2794)
						)
					)
					(width 0)
					(fill yes)
				)
			)
		)
	)
	(footprint ""
		(layer "F.Cu")
		(at 197.2564 -18.796 -90)
		(property "Reference" "R703"
			(at 0 0 270)
			(layer "F.SilkS")
			(hide yes)
			(effects
				(font
					(size 1.27 1.27)
				)
			)
		)
		(property "Value" "4K7R2F-GP"
			(at 0.064008 -3.993896 270)
			(unlocked yes)
			(layer "F.Fab")
			(hide yes)
			(effects
				(font
					(size 1.016 1.016)
					(thickness 0.1524)
				)
			)
		)
		(property "Device Type" "R402H16"
			(at 0.064008 -5.517896 270)
			(unlocked yes)
			(layer "F.Fab")
			(hide yes)
			(effects
				(font
					(size 1.016 1.016)
					(thickness 0.1524)
				)
			)
		)
		(duplicate_pad_numbers_are_jumpers no)
		(fp_line
			(start -0.508 -0.9398)
			(end -0.508 0.9398)
			(stroke
				(width 0.1524)
				(type default)
			)
			(layer "F.SilkS")
		)
		(fp_line
			(start 0.508 -0.9398)
			(end -0.508 -0.9398)
			(stroke
				(width 0.1524)
				(type default)
			)
			(layer "F.SilkS")
		)
		(fp_rect
			(start -0.508 0.9398)
			(end 0.508 -0.9398)
			(stroke
				(width 0)
				(type default)
			)
			(fill no)
			(layer "F.CrtYd")
		)
		(fp_rect
			(start -0.508 0.9398)
			(end 0.508 -0.9398)
			(stroke
				(width 0)
				(type default)
			)
			(fill no)
			(layer "F.Fab")
		)
		(pad "1" smd custom
			(at 0 -0.4445 270)
			(size 0.1397 0.1397)
			(layers "F.Cu" "F.Mask" "F.Paste")
			(net "MINISAS_CN16_A_I2C_INT#")
			(options
				(clearance outline)
				(anchor circle)
			)
			(primitives
				(gr_poly
					(pts
						(arc
							(start -0.1778 -0.2794)
							(mid -0.249642 -0.249642)
							(end -0.2794 -0.1778)
						)
						(arc
							(start -0.2794 0.1778)
							(mid -0.249642 0.249642)
							(end -0.1778 0.2794)
						)
						(arc
							(start 0.1778 0.2794)
							(mid 0.249642 0.249642)
							(end 0.2794 0.1778)
						)
						(arc
							(start 0.2794 -0.1778)
							(mid 0.249642 -0.249642)
							(end 0.1778 -0.2794)
						)
					)
					(width 0)
					(fill yes)
				)
			)
		)
		(pad "2" smd custom
			(at 0 0.4445 270)
			(size 0.1397 0.1397)
			(layers "F.Cu" "F.Mask" "F.Paste")
			(net "P3V3_STBY")
			(options
				(clearance outline)
				(anchor circle)
			)
			(primitives
				(gr_poly
					(pts
						(arc
							(start -0.1778 -0.2794)
							(mid -0.249642 -0.249642)
							(end -0.2794 -0.1778)
						)
						(arc
							(start -0.2794 0.1778)
							(mid -0.249642 0.249642)
							(end -0.1778 0.2794)
						)
						(arc
							(start 0.1778 0.2794)
							(mid 0.249642 0.249642)
							(end 0.2794 0.1778)
						)
						(arc
							(start 0.2794 -0.1778)
							(mid 0.249642 -0.249642)
							(end 0.1778 -0.2794)
						)
					)
					(width 0)
					(fill yes)
				)
			)
		)
	)
	(footprint ""
		(layer "F.Cu")
		(at 20.864576 -128.227074 90)
		(property "Reference" "R368"
			(at 0 0 90)
			(layer "F.SilkS")
			(hide yes)
			(effects
				(font
					(size 1.27 1.27)
				)
			)
		)
		(property "Value" "3K3R2F-2-GP"
			(at 0.064008 -3.993896 90)
			(unlocked yes)
			(layer "F.Fab")
			(hide yes)
			(effects
				(font
					(size 1.016 1.016)
					(thickness 0.1524)
				)
			)
		)
		(property "Device Type" "R402H16"
			(at 0.064008 -5.517896 90)
			(unlocked yes)
			(layer "F.Fab")
			(hide yes)
			(effects
				(font
					(size 1.016 1.016)
					(thickness 0.1524)
				)
			)
		)
		(duplicate_pad_numbers_are_jumpers no)
		(fp_line
			(start 0.508 -0.9398)
			(end -0.508 -0.9398)
			(stroke
				(width 0.1524)
				(type default)
			)
			(layer "F.SilkS")
		)
		(fp_line
			(start -0.508 -0.9398)
			(end -0.508 0.9398)
			(stroke
				(width 0.1524)
				(type default)
			)
			(layer "F.SilkS")
		)
		(fp_rect
			(start -0.508 0.9398)
			(end 0.508 -0.9398)
			(stroke
				(width 0)
				(type default)
			)
			(fill no)
			(layer "F.CrtYd")
		)
		(fp_rect
			(start -0.508 0.9398)
			(end 0.508 -0.9398)
			(stroke
				(width 0)
				(type default)
			)
			(fill no)
			(layer "F.Fab")
		)
		(pad "1" smd custom
			(at 0 -0.4445 90)
			(size 0.1397 0.1397)
			(layers "F.Cu" "F.Mask" "F.Paste")
			(net "P3V3_STBY")
			(options
				(clearance outline)
				(anchor circle)
			)
			(primitives
				(gr_poly
					(pts
						(arc
							(start -0.1778 -0.2794)
							(mid -0.249642 -0.249642)
							(end -0.2794 -0.1778)
						)
						(arc
							(start -0.2794 0.1778)
							(mid -0.249642 0.249642)
							(end -0.1778 0.2794)
						)
						(arc
							(start 0.1778 0.2794)
							(mid 0.249642 0.249642)
							(end 0.2794 0.1778)
						)
						(arc
							(start 0.2794 -0.1778)
							(mid 0.249642 -0.249642)
							(end 0.1778 -0.2794)
						)
					)
					(width 0)
					(fill yes)
				)
			)
		)
		(pad "2" smd custom
			(at 0 0.4445 90)
			(size 0.1397 0.1397)
			(layers "F.Cu" "F.Mask" "F.Paste")
			(net "ROMA15")
			(options
				(clearance outline)
				(anchor circle)
			)
			(primitives
				(gr_poly
					(pts
						(arc
							(start -0.1778 -0.2794)
							(mid -0.249642 -0.249642)
							(end -0.2794 -0.1778)
						)
						(arc
							(start -0.2794 0.1778)
							(mid -0.249642 0.249642)
							(end -0.1778 0.2794)
						)
						(arc
							(start 0.1778 0.2794)
							(mid 0.249642 0.249642)
							(end 0.2794 0.1778)
						)
						(arc
							(start 0.2794 -0.1778)
							(mid 0.249642 -0.249642)
							(end 0.1778 -0.2794)
						)
					)
					(width 0)
					(fill yes)
				)
			)
		)
	)
	(footprint ""
		(layer "F.Cu")
		(at 339.884512 -184.878218 180)
		(property "Reference" "R7930"
			(at 0 0 180)
			(layer "F.SilkS")
			(hide yes)
			(effects
				(font
					(size 1.27 1.27)
				)
			)
		)
		(property "Value" "0R2J-2-GP"
			(at 0.064008 -3.993896 180)
			(unlocked yes)
			(layer "F.Fab")
			(hide yes)
			(effects
				(font
					(size 1.016 1.016)
					(thickness 0.1524)
				)
			)
		)
		(property "Device Type" "R402H16"
			(at 0.064008 -5.517896 180)
			(unlocked yes)
			(layer "F.Fab")
			(hide yes)
			(effects
				(font
					(size 1.016 1.016)
					(thickness 0.1524)
				)
			)
		)
		(duplicate_pad_numbers_are_jumpers no)
		(fp_line
			(start 0.508 -0.9398)
			(end -0.508 -0.9398)
			(stroke
				(width 0.1524)
				(type default)
			)
			(layer "F.SilkS")
		)
		(fp_line
			(start -0.508 -0.9398)
			(end -0.508 0.9398)
			(stroke
				(width 0.1524)
				(type default)
			)
			(layer "F.SilkS")
		)
		(fp_rect
			(start -0.508 0.9398)
			(end 0.508 -0.9398)
			(stroke
				(width 0)
				(type default)
			)
			(fill no)
			(layer "F.CrtYd")
		)
		(fp_rect
			(start -0.508 0.9398)
			(end 0.508 -0.9398)
			(stroke
				(width 0)
				(type default)
			)
			(fill no)
			(layer "F.Fab")
		)
		(pad "1" smd custom
			(at 0 -0.4445 180)
			(size 0.1397 0.1397)
			(layers "F.Cu" "F.Mask" "F.Paste")
			(net "SSD_PRSNT#14")
			(options
				(clearance outline)
				(anchor circle)
			)
			(primitives
				(gr_poly
					(pts
						(arc
							(start -0.1778 -0.2794)
							(mid -0.249642 -0.249642)
							(end -0.2794 -0.1778)
						)
						(arc
							(start -0.2794 0.1778)
							(mid -0.249642 0.249642)
							(end -0.1778 0.2794)
						)
						(arc
							(start 0.1778 0.2794)
							(mid 0.249642 0.249642)
							(end 0.2794 0.1778)
						)
						(arc
							(start 0.2794 -0.1778)
							(mid 0.249642 -0.249642)
							(end 0.1778 -0.2794)
						)
					)
					(width 0)
					(fill yes)
				)
			)
		)
		(pad "2" smd custom
			(at 0 0.4445 180)
			(size 0.1397 0.1397)
			(layers "F.Cu" "F.Mask" "F.Paste")
			(net "SSD_PRSNT#14_R")
			(options
				(clearance outline)
				(anchor circle)
			)
			(primitives
				(gr_poly
					(pts
						(arc
							(start -0.1778 -0.2794)
							(mid -0.249642 -0.249642)
							(end -0.2794 -0.1778)
						)
						(arc
							(start -0.2794 0.1778)
							(mid -0.249642 0.249642)
							(end -0.1778 0.2794)
						)
						(arc
							(start 0.1778 0.2794)
							(mid 0.249642 0.249642)
							(end 0.2794 0.1778)
						)
						(arc
							(start 0.2794 -0.1778)
							(mid 0.249642 -0.249642)
							(end 0.1778 -0.2794)
						)
					)
					(width 0)
					(fill yes)
				)
			)
		)
	)
	(footprint ""
		(layer "F.Cu")
		(at 119.806974 -78.285848)
		(property "Reference" "R5202"
			(at 0 0 0)
			(layer "F.SilkS")
			(hide yes)
			(effects
				(font
					(size 1.27 1.27)
				)
			)
		)
		(property "Value" "1KR2J-1-GP"
			(at 0.064008 -3.993896 0)
			(unlocked yes)
			(layer "F.Fab")
			(hide yes)
			(effects
				(font
					(size 1.016 1.016)
					(thickness 0.1524)
				)
			)
		)
		(property "Device Type" "R402H16"
			(at 0.064008 -5.517896 0)
			(unlocked yes)
			(layer "F.Fab")
			(hide yes)
			(effects
				(font
					(size 1.016 1.016)
					(thickness 0.1524)
				)
			)
		)
		(duplicate_pad_numbers_are_jumpers no)
		(fp_line
			(start -0.508 -0.9398)
			(end -0.508 0.9398)
			(stroke
				(width 0.1524)
				(type default)
			)
			(layer "F.SilkS")
		)
		(fp_line
			(start 0.508 -0.9398)
			(end -0.508 -0.9398)
			(stroke
				(width 0.1524)
				(type default)
			)
			(layer "F.SilkS")
		)
		(fp_rect
			(start -0.508 0.9398)
			(end 0.508 -0.9398)
			(stroke
				(width 0)
				(type default)
			)
			(fill no)
			(layer "F.CrtYd")
		)
		(fp_rect
			(start -0.508 0.9398)
			(end 0.508 -0.9398)
			(stroke
				(width 0)
				(type default)
			)
			(fill no)
			(layer "F.Fab")
		)
		(pad "1" smd custom
			(at 0 -0.4445)
			(size 0.1397 0.1397)
			(layers "F.Cu" "F.Mask" "F.Paste")
			(net "P3V0_BAT_R")
			(options
				(clearance outline)
				(anchor circle)
			)
			(primitives
				(gr_poly
					(pts
						(arc
							(start -0.1778 -0.2794)
							(mid -0.249642 -0.249642)
							(end -0.2794 -0.1778)
						)
						(arc
							(start -0.2794 0.1778)
							(mid -0.249642 0.249642)
							(end -0.1778 0.2794)
						)
						(arc
							(start 0.1778 0.2794)
							(mid 0.249642 0.249642)
							(end 0.2794 0.1778)
						)
						(arc
							(start 0.2794 -0.1778)
							(mid 0.249642 -0.249642)
							(end 0.1778 -0.2794)
						)
					)
					(width 0)
					(fill yes)
				)
			)
		)
		(pad "2" smd custom
			(at 0 0.4445)
			(size 0.1397 0.1397)
			(layers "F.Cu" "F.Mask" "F.Paste")
			(net "P3V0_BAT")
			(options
				(clearance outline)
				(anchor circle)
			)
			(primitives
				(gr_poly
					(pts
						(arc
							(start -0.1778 -0.2794)
							(mid -0.249642 -0.249642)
							(end -0.2794 -0.1778)
						)
						(arc
							(start -0.2794 0.1778)
							(mid -0.249642 0.249642)
							(end -0.1778 0.2794)
						)
						(arc
							(start 0.1778 0.2794)
							(mid 0.249642 0.249642)
							(end 0.2794 0.1778)
						)
						(arc
							(start 0.2794 -0.1778)
							(mid 0.249642 -0.249642)
							(end 0.1778 -0.2794)
						)
					)
					(width 0)
					(fill yes)
				)
			)
		)
	)
	(footprint ""
		(layer "F.Cu")
		(at 324.485 -101.473 180)
		(property "Reference" "R4178"
			(at 0 0 180)
			(layer "F.SilkS")
			(hide yes)
			(effects
				(font
					(size 1.27 1.27)
				)
			)
		)
		(property "Value" "4K7R2F-GP"
			(at 0.064008 -3.993896 180)
			(unlocked yes)
			(layer "F.Fab")
			(hide yes)
			(effects
				(font
					(size 1.016 1.016)
					(thickness 0.1524)
				)
			)
		)
		(property "Device Type" "R402H16"
			(at 0.064008 -5.517896 180)
			(unlocked yes)
			(layer "F.Fab")
			(hide yes)
			(effects
				(font
					(size 1.016 1.016)
					(thickness 0.1524)
				)
			)
		)
		(duplicate_pad_numbers_are_jumpers no)
		(fp_line
			(start 0.508 -0.9398)
			(end -0.508 -0.9398)
			(stroke
				(width 0.1524)
				(type default)
			)
			(layer "F.SilkS")
		)
		(fp_line
			(start -0.508 -0.9398)
			(end -0.508 0.9398)
			(stroke
				(width 0.1524)
				(type default)
			)
			(layer "F.SilkS")
		)
		(fp_rect
			(start -0.508 0.9398)
			(end 0.508 -0.9398)
			(stroke
				(width 0)
				(type default)
			)
			(fill no)
			(layer "F.CrtYd")
		)
		(fp_rect
			(start -0.508 0.9398)
			(end 0.508 -0.9398)
			(stroke
				(width 0)
				(type default)
			)
			(fill no)
			(layer "F.Fab")
		)
		(pad "1" smd custom
			(at 0 -0.4445 180)
			(size 0.1397 0.1397)
			(layers "F.Cu" "F.Mask" "F.Paste")
			(net "PEWAKE#")
			(options
				(clearance outline)
				(anchor circle)
			)
			(primitives
				(gr_poly
					(pts
						(arc
							(start -0.1778 -0.2794)
							(mid -0.249642 -0.249642)
							(end -0.2794 -0.1778)
						)
						(arc
							(start -0.2794 0.1778)
							(mid -0.249642 0.249642)
							(end -0.1778 0.2794)
						)
						(arc
							(start 0.1778 0.2794)
							(mid 0.249642 0.249642)
							(end 0.2794 0.1778)
						)
						(arc
							(start 0.2794 -0.1778)
							(mid 0.249642 -0.249642)
							(end 0.1778 -0.2794)
						)
					)
					(width 0)
					(fill yes)
				)
			)
		)
		(pad "2" smd custom
			(at 0 0.4445 180)
			(size 0.1397 0.1397)
			(layers "F.Cu" "F.Mask" "F.Paste")
			(net "P3V3_STBY")
			(options
				(clearance outline)
				(anchor circle)
			)
			(primitives
				(gr_poly
					(pts
						(arc
							(start -0.1778 -0.2794)
							(mid -0.249642 -0.249642)
							(end -0.2794 -0.1778)
						)
						(arc
							(start -0.2794 0.1778)
							(mid -0.249642 0.249642)
							(end -0.1778 0.2794)
						)
						(arc
							(start 0.1778 0.2794)
							(mid 0.249642 0.249642)
							(end 0.2794 0.1778)
						)
						(arc
							(start 0.2794 -0.1778)
							(mid 0.249642 -0.249642)
							(end 0.1778 -0.2794)
						)
					)
					(width 0)
					(fill yes)
				)
			)
		)
	)
	(footprint ""
		(layer "F.Cu")
		(at 310.007 -60.1726)
		(property "Reference" "PG49"
			(at 0 0 0)
			(layer "F.SilkS")
			(hide yes)
			(effects
				(font
					(size 1.27 1.27)
				)
			)
		)
		(property "Value" "GAP-CLOSE-PWR-3-GP"
			(at 0.0254 -6.5786 0)
			(unlocked yes)
			(layer "F.Fab")
			(hide yes)
			(effects
				(font
					(size 1.016 1.016)
					(thickness 0.1524)
				)
			)
		)
		(property "Device Type" "GAP-CLOSE-PWR-3"
			(at 0.0254 -8.255 0)
			(unlocked yes)
			(layer "F.Fab")
			(hide yes)
			(effects
				(font
					(size 1.016 1.016)
					(thickness 0.1524)
				)
			)
		)
		(duplicate_pad_numbers_are_jumpers no)
		(fp_rect
			(start -0.7112 0.4572)
			(end 0.7112 -0.4572)
			(stroke
				(width 0)
				(type default)
			)
			(fill no)
			(layer "F.CrtYd")
		)
		(fp_poly
			(pts
				(xy -0.7112 -0.4572) (xy 0.7112 -0.4572) (xy 0.7112 0.4572) (xy -0.7112 0.4572)
			)
			(stroke
				(width 0)
				(type default)
			)
			(fill no)
			(layer "F.Fab")
		)
		(pad "1" smd rect
			(at -0.3048 0)
			(size 0.6604 0.762)
			(layers "F.Cu" "F.Mask" "F.Paste")
			(net "DUT_VDD")
		)
		(pad "2" smd rect
			(at 0.3048 0)
			(size 0.6604 0.762)
			(layers "F.Cu" "F.Mask" "F.Paste")
			(net "P0V9_E")
		)
	)
	(footprint ""
		(layer "F.Cu")
		(at 187.231528 -0.001524 -90)
		(property "Reference" "Q21"
			(at 0 0 270)
			(layer "F.SilkS")
			(hide yes)
			(effects
				(font
					(size 1.27 1.27)
				)
			)
		)
		(property "Value" "2N7002K-1-GP"
			(at 0.127 -8.9662 270)
			(unlocked yes)
			(layer "F.Fab")
			(hide yes)
			(effects
				(font
					(size 1.016 1.016)
					(thickness 0.1524)
				)
			)
		)
		(property "Device Type" "SOT23DGS2D4H44"
			(at 0.127 -10.4902 270)
			(unlocked yes)
			(layer "F.Fab")
			(hide yes)
			(effects
				(font
					(size 1.016 1.016)
					(thickness 0.1524)
				)
			)
		)
		(duplicate_pad_numbers_are_jumpers no)
		(fp_line
			(start -1.651 1.778)
			(end 1.651 1.778)
			(stroke
				(width 0.1524)
				(type default)
			)
			(layer "F.SilkS")
		)
		(fp_line
			(start 1.651 1.778)
			(end 1.651 -1.778)
			(stroke
				(width 0.1524)
				(type default)
			)
			(layer "F.SilkS")
		)
		(fp_line
			(start -1.651 -1.778)
			(end -1.651 1.778)
			(stroke
				(width 0.1524)
				(type default)
			)
			(layer "F.SilkS")
		)
		(fp_line
			(start 1.651 -1.778)
			(end -1.651 -1.778)
			(stroke
				(width 0.1524)
				(type default)
			)
			(layer "F.SilkS")
		)
		(fp_poly
			(pts
				(xy -1.778 1.8796) (xy -1.778 -1.8796) (xy 1.778 -1.8796) (xy 1.778 1.8796)
			)
			(stroke
				(width 0)
				(type default)
			)
			(fill no)
			(layer "F.CrtYd")
		)
		(fp_poly
			(pts
				(xy -1.778 1.8796) (xy -1.778 -1.8796) (xy 1.778 -1.8796) (xy 1.778 1.8796)
			)
			(stroke
				(width 0)
				(type default)
			)
			(fill no)
			(layer "F.Fab")
		)
		(pad "D" smd custom
			(at 0 -0.9525 270)
			(size 0.1905 0.1905)
			(layers "F.Cu" "F.Mask" "F.Paste")
			(net "EXP_BMC_HB_LED_D")
			(options
				(clearance outline)
				(anchor circle)
			)
			(primitives
				(gr_poly
					(pts
						(arc
							(start -0.1778 0.5715)
							(mid -0.321484 0.511984)
							(end -0.381 0.3683)
						)
						(arc
							(start -0.381 -0.3683)
							(mid -0.321484 -0.511984)
							(end -0.1778 -0.5715)
						)
						(arc
							(start 0.1778 -0.5715)
							(mid 0.321484 -0.511984)
							(end 0.381 -0.3683)
						)
						(arc
							(start 0.381 0.3683)
							(mid 0.321484 0.511984)
							(end 0.1778 0.5715)
						)
					)
					(width 0)
					(fill yes)
				)
			)
		)
		(pad "G" smd custom
			(at -0.98425 0.9525 270)
			(size 0.1905 0.1905)
			(layers "F.Cu" "F.Mask" "F.Paste")
			(net "Q21_G")
			(options
				(clearance outline)
				(anchor circle)
			)
			(primitives
				(gr_poly
					(pts
						(arc
							(start -0.1778 0.5715)
							(mid -0.321484 0.511984)
							(end -0.381 0.3683)
						)
						(arc
							(start -0.381 -0.3683)
							(mid -0.321484 -0.511984)
							(end -0.1778 -0.5715)
						)
						(arc
							(start 0.1778 -0.5715)
							(mid 0.321484 -0.511984)
							(end 0.381 -0.3683)
						)
						(arc
							(start 0.381 0.3683)
							(mid 0.321484 0.511984)
							(end 0.1778 0.5715)
						)
					)
					(width 0)
					(fill yes)
				)
			)
		)
		(pad "S" smd custom
			(at 0.98425 0.9525 270)
			(size 0.1905 0.1905)
			(layers "F.Cu" "F.Mask" "F.Paste")
			(net "GND")
			(options
				(clearance outline)
				(anchor circle)
			)
			(primitives
				(gr_poly
					(pts
						(arc
							(start -0.1778 0.5715)
							(mid -0.321484 0.511984)
							(end -0.381 0.3683)
						)
						(arc
							(start -0.381 -0.3683)
							(mid -0.321484 -0.511984)
							(end -0.1778 -0.5715)
						)
						(arc
							(start 0.1778 -0.5715)
							(mid 0.321484 -0.511984)
							(end 0.381 -0.3683)
						)
						(arc
							(start 0.381 0.3683)
							(mid 0.321484 0.511984)
							(end 0.1778 0.5715)
						)
					)
					(width 0)
					(fill yes)
				)
			)
		)
	)
	(footprint ""
		(layer "F.Cu")
		(at 194.8688 -32.8676 90)
		(property "Reference" "R778"
			(at 0 0 90)
			(layer "F.SilkS")
			(hide yes)
			(effects
				(font
					(size 1.27 1.27)
				)
			)
		)
		(property "Value" "4K7R2F-GP"
			(at 0.064008 -3.993896 90)
			(unlocked yes)
			(layer "F.Fab")
			(hide yes)
			(effects
				(font
					(size 1.016 1.016)
					(thickness 0.1524)
				)
			)
		)
		(property "Device Type" "R402H16"
			(at 0.064008 -5.517896 90)
			(unlocked yes)
			(layer "F.Fab")
			(hide yes)
			(effects
				(font
					(size 1.016 1.016)
					(thickness 0.1524)
				)
			)
		)
		(duplicate_pad_numbers_are_jumpers no)
		(fp_line
			(start 0.508 -0.9398)
			(end -0.508 -0.9398)
			(stroke
				(width 0.1524)
				(type default)
			)
			(layer "F.SilkS")
		)
		(fp_line
			(start -0.508 -0.9398)
			(end -0.508 0.9398)
			(stroke
				(width 0.1524)
				(type default)
			)
			(layer "F.SilkS")
		)
		(fp_rect
			(start -0.508 0.9398)
			(end 0.508 -0.9398)
			(stroke
				(width 0)
				(type default)
			)
			(fill no)
			(layer "F.CrtYd")
		)
		(fp_rect
			(start -0.508 0.9398)
			(end 0.508 -0.9398)
			(stroke
				(width 0)
				(type default)
			)
			(fill no)
			(layer "F.Fab")
		)
		(pad "1" smd custom
			(at 0 -0.4445 90)
			(size 0.1397 0.1397)
			(layers "F.Cu" "F.Mask" "F.Paste")
			(net "GND")
			(options
				(clearance outline)
				(anchor circle)
			)
			(primitives
				(gr_poly
					(pts
						(arc
							(start -0.1778 -0.2794)
							(mid -0.249642 -0.249642)
							(end -0.2794 -0.1778)
						)
						(arc
							(start -0.2794 0.1778)
							(mid -0.249642 0.249642)
							(end -0.1778 0.2794)
						)
						(arc
							(start 0.1778 0.2794)
							(mid 0.249642 0.249642)
							(end 0.2794 0.1778)
						)
						(arc
							(start 0.2794 -0.1778)
							(mid 0.249642 -0.249642)
							(end 0.1778 -0.2794)
						)
					)
					(width 0)
					(fill yes)
				)
			)
		)
		(pad "2" smd custom
			(at 0 0.4445 90)
			(size 0.1397 0.1397)
			(layers "F.Cu" "F.Mask" "F.Paste")
			(net "U55_A1")
			(options
				(clearance outline)
				(anchor circle)
			)
			(primitives
				(gr_poly
					(pts
						(arc
							(start -0.1778 -0.2794)
							(mid -0.249642 -0.249642)
							(end -0.2794 -0.1778)
						)
						(arc
							(start -0.2794 0.1778)
							(mid -0.249642 0.249642)
							(end -0.1778 0.2794)
						)
						(arc
							(start 0.1778 0.2794)
							(mid 0.249642 0.249642)
							(end 0.2794 0.1778)
						)
						(arc
							(start 0.2794 -0.1778)
							(mid 0.249642 -0.249642)
							(end 0.1778 -0.2794)
						)
					)
					(width 0)
					(fill yes)
				)
			)
		)
	)
	(footprint ""
		(layer "F.Cu")
		(at 208.099914 -69.939916 -90)
		(property "Reference" "CN7"
			(at 0 0 270)
			(layer "F.SilkS")
			(hide yes)
			(effects
				(font
					(size 1.27 1.27)
				)
			)
		)
		(property "Value" "FOX-CON2-S23-GP"
			(at 5.334 1.4478 270)
			(unlocked yes)
			(layer "F.Fab")
			(hide yes)
			(effects
				(font
					(size 1.016 1.016)
					(thickness 0.1524)
				)
			)
		)
		(property "Device Type" "HBA1030-H300R-EF"
			(at 5.334 -0.0762 270)
			(unlocked yes)
			(layer "F.Fab")
			(hide yes)
			(effects
				(font
					(size 1.016 1.016)
					(thickness 0.1524)
				)
			)
		)
		(duplicate_pad_numbers_are_jumpers no)
		(fp_line
			(start -3.937 1.4859)
			(end -3.937 -1.4859)
			(stroke
				(width 0.1524)
				(type default)
			)
			(layer "F.SilkS")
		)
		(fp_line
			(start 3.937 1.4859)
			(end -3.937 1.4859)
			(stroke
				(width 0.1524)
				(type default)
			)
			(layer "F.SilkS")
		)
		(fp_line
			(start -4.082288 -0.36576)
			(end -4.082288 -1.63576)
			(stroke
				(width 0.4064)
				(type default)
			)
			(layer "F.SilkS")
		)
		(fp_line
			(start -3.937 -1.4859)
			(end 3.937 -1.4859)
			(stroke
				(width 0.1524)
				(type default)
			)
			(layer "F.SilkS")
		)
		(fp_line
			(start 3.937 -1.4859)
			(end 3.937 1.4859)
			(stroke
				(width 0.1524)
				(type default)
			)
			(layer "F.SilkS")
		)
		(fp_line
			(start -4.082288 -1.63576)
			(end -2.812288 -1.63576)
			(stroke
				(width 0.4064)
				(type default)
			)
			(layer "F.SilkS")
		)
		(fp_circle
			(center -2.54 0)
			(end -2.54 -1.0668)
			(stroke
				(width 0.3048)
				(type default)
			)
			(fill no)
			(layer "F.SilkS")
		)
		(fp_circle
			(center 2.54 0)
			(end 2.54 -1.0668)
			(stroke
				(width 0.3048)
				(type default)
			)
			(fill no)
			(layer "F.SilkS")
		)
		(fp_rect
			(start -3.683 1.2319)
			(end 3.683 -1.2319)
			(stroke
				(width 0)
				(type default)
			)
			(fill no)
			(layer "F.CrtYd")
		)
		(fp_poly
			(pts
				(xy -4.191 1.7399) (xy -4.191 -1.7399) (xy 4.191 -1.7399) (xy 4.191 1.7399) (xy -0.2413 1.7399)
				(xy -0.2413 1.2319) (xy 3.683 1.2319) (xy 3.683 -1.2319) (xy -3.683 -1.2319) (xy -3.683 1.2319)
				(xy -0.254 1.2319) (xy -0.254 1.7399)
			)
			(stroke
				(width 0)
				(type default)
			)
			(fill no)
			(layer "F.CrtYd")
		)
		(fp_rect
			(start -4.191 1.7399)
			(end 4.191 -1.7399)
			(stroke
				(width 0)
				(type default)
			)
			(fill no)
			(layer "F.Fab")
		)
		(pad "1" thru_hole circle
			(at -2.54 0 270)
			(size 1.4224 1.4224)
			(drill 1.016)
			(layers "*.Cu" "*.Mask")
			(remove_unused_layers no)
			(net "GND")
			(clearance 0.1524)
			(thermal_gap 0.1524)
		)
		(pad "2" thru_hole circle
			(at 2.54 0 270)
			(size 1.4224 1.4224)
			(drill 1.016)
			(layers "*.Cu" "*.Mask")
			(remove_unused_layers no)
			(net "GND")
			(clearance 0.1524)
			(thermal_gap 0.1524)
		)
	)
	(footprint ""
		(layer "F.Cu")
		(at 20.3962 -66.2686)
		(property "Reference" "R419"
			(at 0 0 0)
			(layer "F.SilkS")
			(hide yes)
			(effects
				(font
					(size 1.27 1.27)
				)
			)
		)
		(property "Value" "10KR2F-2-GP"
			(at 0.064008 -3.993896 0)
			(unlocked yes)
			(layer "F.Fab")
			(hide yes)
			(effects
				(font
					(size 1.016 1.016)
					(thickness 0.1524)
				)
			)
		)
		(property "Device Type" "R402H16"
			(at 0.064008 -5.517896 0)
			(unlocked yes)
			(layer "F.Fab")
			(hide yes)
			(effects
				(font
					(size 1.016 1.016)
					(thickness 0.1524)
				)
			)
		)
		(duplicate_pad_numbers_are_jumpers no)
		(fp_line
			(start -0.508 -0.9398)
			(end -0.508 0.9398)
			(stroke
				(width 0.1524)
				(type default)
			)
			(layer "F.SilkS")
		)
		(fp_line
			(start 0.508 -0.9398)
			(end -0.508 -0.9398)
			(stroke
				(width 0.1524)
				(type default)
			)
			(layer "F.SilkS")
		)
		(fp_rect
			(start -0.508 0.9398)
			(end 0.508 -0.9398)
			(stroke
				(width 0)
				(type default)
			)
			(fill no)
			(layer "F.CrtYd")
		)
		(fp_rect
			(start -0.508 0.9398)
			(end 0.508 -0.9398)
			(stroke
				(width 0)
				(type default)
			)
			(fill no)
			(layer "F.Fab")
		)
		(pad "1" smd custom
			(at 0 -0.4445)
			(size 0.1397 0.1397)
			(layers "F.Cu" "F.Mask" "F.Paste")
			(net "PCIE_DIS")
			(options
				(clearance outline)
				(anchor circle)
			)
			(primitives
				(gr_poly
					(pts
						(arc
							(start -0.1778 -0.2794)
							(mid -0.249642 -0.249642)
							(end -0.2794 -0.1778)
						)
						(arc
							(start -0.2794 0.1778)
							(mid -0.249642 0.249642)
							(end -0.1778 0.2794)
						)
						(arc
							(start 0.1778 0.2794)
							(mid 0.249642 0.249642)
							(end 0.2794 0.1778)
						)
						(arc
							(start 0.2794 -0.1778)
							(mid 0.249642 -0.249642)
							(end 0.1778 -0.2794)
						)
					)
					(width 0)
					(fill yes)
				)
			)
		)
		(pad "2" smd custom
			(at 0 0.4445)
			(size 0.1397 0.1397)
			(layers "F.Cu" "F.Mask" "F.Paste")
			(net "P3V3_STBY")
			(options
				(clearance outline)
				(anchor circle)
			)
			(primitives
				(gr_poly
					(pts
						(arc
							(start -0.1778 -0.2794)
							(mid -0.249642 -0.249642)
							(end -0.2794 -0.1778)
						)
						(arc
							(start -0.2794 0.1778)
							(mid -0.249642 0.249642)
							(end -0.1778 0.2794)
						)
						(arc
							(start 0.1778 0.2794)
							(mid 0.249642 0.249642)
							(end 0.2794 0.1778)
						)
						(arc
							(start 0.2794 -0.1778)
							(mid 0.249642 -0.249642)
							(end 0.1778 -0.2794)
						)
					)
					(width 0)
					(fill yes)
				)
			)
		)
	)
	(footprint ""
		(layer "F.Cu")
		(at 217.007948 -212.420454 180)
		(property "Reference" "C108"
			(at 0 0 180)
			(layer "F.SilkS")
			(hide yes)
			(effects
				(font
					(size 1.27 1.27)
				)
			)
		)
		(property "Value" "SCD22U10V2KX-1GP"
			(at 1.1811 -2.7051 180)
			(unlocked yes)
			(layer "F.Fab")
			(hide yes)
			(effects
				(font
					(size 1.016 1.016)
					(thickness 0.1524)
				)
			)
		)
		(property "Device Type" "C402H22"
			(at 1.1811 -4.2291 180)
			(unlocked yes)
			(layer "F.Fab")
			(hide yes)
			(effects
				(font
					(size 1.016 1.016)
					(thickness 0.1524)
				)
			)
		)
		(duplicate_pad_numbers_are_jumpers no)
		(fp_rect
			(start -0.4318 0.9525)
			(end 0.4318 -0.9525)
			(stroke
				(width 0)
				(type default)
			)
			(fill no)
			(layer "F.CrtYd")
		)
		(fp_rect
			(start -0.4318 0.9525)
			(end 0.4318 -0.9525)
			(stroke
				(width 0)
				(type default)
			)
			(fill no)
			(layer "F.Fab")
		)
		(pad "1" smd custom
			(at 0 -0.4445 180)
			(size 0.1524 0.1524)
			(layers "F.Cu" "F.Mask" "F.Paste")
			(net "PCIE_TX_CAP_N38")
			(options
				(clearance outline)
				(anchor circle)
			)
			(primitives
				(gr_poly
					(pts
						(arc
							(start 0.3048 -0.2032)
							(mid 0.275042 -0.275042)
							(end 0.2032 -0.3048)
						)
						(arc
							(start -0.2032 -0.3048)
							(mid -0.275042 -0.275042)
							(end -0.3048 -0.2032)
						)
						(arc
							(start -0.3048 0.2032)
							(mid -0.275042 0.275042)
							(end -0.2032 0.3048)
						)
						(arc
							(start 0.2032 0.3048)
							(mid 0.275042 0.275042)
							(end 0.3048 0.2032)
						)
					)
					(width 0)
					(fill yes)
				)
			)
		)
		(pad "2" smd custom
			(at 0 0.4445 180)
			(size 0.1524 0.1524)
			(layers "F.Cu" "F.Mask" "F.Paste")
			(net "PCIE_TX_N38")
			(options
				(clearance outline)
				(anchor circle)
			)
			(primitives
				(gr_poly
					(pts
						(arc
							(start 0.3048 -0.2032)
							(mid 0.275042 -0.275042)
							(end 0.2032 -0.3048)
						)
						(arc
							(start -0.2032 -0.3048)
							(mid -0.275042 -0.275042)
							(end -0.3048 -0.2032)
						)
						(arc
							(start -0.3048 0.2032)
							(mid -0.275042 0.275042)
							(end -0.2032 0.3048)
						)
						(arc
							(start 0.2032 0.3048)
							(mid 0.275042 0.275042)
							(end 0.3048 0.2032)
						)
					)
					(width 0)
					(fill yes)
				)
			)
		)
	)
	(footprint ""
		(layer "F.Cu")
		(at 318.77 -69.215 180)
		(property "Reference" "PTC6"
			(at 0 0 180)
			(layer "F.SilkS")
			(hide yes)
			(effects
				(font
					(size 1.27 1.27)
				)
			)
		)
		(property "Value" "SE470UF2VDM-GP"
			(at 0 -9.6012 180)
			(unlocked yes)
			(layer "F.Fab")
			(hide yes)
			(effects
				(font
					(size 1.016 1.016)
					(thickness 0.1524)
				)
			)
		)
		(property "Device Type" "CT7343H83"
			(at 0 -11.1252 180)
			(unlocked yes)
			(layer "F.Fab")
			(hide yes)
			(effects
				(font
					(size 1.016 1.016)
					(thickness 0.1524)
				)
			)
		)
		(duplicate_pad_numbers_are_jumpers no)
		(fp_line
			(start 2.286 4.8768)
			(end -2.286 4.8768)
			(stroke
				(width 0.1524)
				(type default)
			)
			(layer "F.SilkS")
		)
		(fp_line
			(start 2.286 2.032)
			(end 2.286 4.8768)
			(stroke
				(width 0.1524)
				(type default)
			)
			(layer "F.SilkS")
		)
		(fp_line
			(start 2.286 -2.032)
			(end 2.286 -4.8768)
			(stroke
				(width 0.1524)
				(type default)
			)
			(layer "F.SilkS")
		)
		(fp_line
			(start 2.286 -4.8768)
			(end -2.286 -4.8768)
			(stroke
				(width 0.1524)
				(type default)
			)
			(layer "F.SilkS")
		)
		(fp_line
			(start 2.1082 -4.699)
			(end -2.1082 -4.699)
			(stroke
				(width 0.508)
				(type default)
			)
			(layer "F.SilkS")
		)
		(fp_line
			(start -2.286 4.8768)
			(end -2.286 2.032)
			(stroke
				(width 0.1524)
				(type default)
			)
			(layer "F.SilkS")
		)
		(fp_line
			(start -2.286 -4.8768)
			(end -2.286 -2.032)
			(stroke
				(width 0.1524)
				(type default)
			)
			(layer "F.SilkS")
		)
		(fp_rect
			(start -2.1463 3.6449)
			(end 2.1463 -3.6449)
			(stroke
				(width 0)
				(type default)
			)
			(fill no)
			(layer "F.CrtYd")
		)
		(fp_poly
			(pts
				(xy -2.54 4.953) (xy -2.54 4.2926) (xy -3.81 4.2926) (xy -3.81 -4.2926) (xy -2.54 -4.2926) (xy -2.54 -4.953)
				(xy 2.54 -4.953) (xy 2.54 -4.2926) (xy 3.81 -4.2926) (xy 3.81 -1.6256) (xy 2.1463 -1.6256) (xy 2.1463 -3.6449)
				(xy -2.1463 -3.6449) (xy -2.1463 3.6449) (xy 2.1463 3.6449) (xy 2.1463 -1.6129) (xy 3.81 -1.6129)
				(xy 3.81 4.2926) (xy 2.54 4.2926) (xy 2.54 4.953)
			)
			(stroke
				(width 0)
				(type default)
			)
			(fill no)
			(layer "F.CrtYd")
		)
		(fp_rect
			(start 2.54 4.2926)
			(end 3.81 -4.2926)
			(stroke
				(width 0)
				(type default)
			)
			(fill no)
			(layer "F.Fab")
		)
		(fp_rect
			(start -2.54 4.953)
			(end 2.54 -4.953)
			(stroke
				(width 0)
				(type default)
			)
			(fill no)
			(layer "F.Fab")
		)
		(fp_rect
			(start -3.81 4.2926)
			(end -2.54 -4.2926)
			(stroke
				(width 0)
				(type default)
			)
			(fill no)
			(layer "F.Fab")
		)
		(pad "1" smd rect
			(at 0 -3.1496 180)
			(size 2.413 2.286)
			(layers "F.Cu" "F.Mask" "F.Paste")
			(net "P0V9_E")
		)
		(pad "2" smd rect
			(at 0 3.1496 180)
			(size 2.413 2.286)
			(layers "F.Cu" "F.Mask" "F.Paste")
			(net "GND")
		)
		(zone
			(layer "F.Cu")
			(hatch none 0.5)
			(connect_pads
				(clearance 0)
			)
			(min_thickness 0.25)
			(keepout
				(tracks allowed)
				(vias not_allowed)
				(pads allowed)
				(copperpour not_allowed)
				(footprints allowed)
			)
			(placement
				(enabled no)
				(sheetname "")
			)
			(fill
				(thermal_gap 0.5)
				(thermal_bridge_width 0.5)
				(island_removal_mode 0)
			)
			(polygon
				(pts
					(xy 317.2587 -67.5259) (xy 317.2587 -64.6176) (xy 320.2813 -64.6176) (xy 320.2813 -67.5132) (xy 320.2813 -67.8434)
					(xy 317.2587 -67.8434)
				)
			)
		)
		(zone
			(layer "F.Cu")
			(hatch none 0.5)
			(connect_pads
				(clearance 0)
			)
			(min_thickness 0.25)
			(keepout
				(tracks allowed)
				(vias not_allowed)
				(pads allowed)
				(copperpour not_allowed)
				(footprints allowed)
			)
			(placement
				(enabled no)
				(sheetname "")
			)
			(fill
				(thermal_gap 0.5)
				(thermal_bridge_width 0.5)
				(island_removal_mode 0)
			)
			(polygon
				(pts
					(xy 320.2813 -73.8124) (xy 317.2587 -73.8124) (xy 317.2587 -70.9168) (xy 317.2587 -70.5866) (xy 320.2813 -70.5866)
					(xy 320.2813 -70.9168)
				)
			)
		)
	)
	(footprint ""
		(layer "F.Cu")
		(at 138.392154 -212.420454 180)
		(property "Reference" "C344"
			(at 0 0 180)
			(layer "F.SilkS")
			(hide yes)
			(effects
				(font
					(size 1.27 1.27)
				)
			)
		)
		(property "Value" "SCD22U10V2KX-1GP"
			(at 1.1811 -2.7051 180)
			(unlocked yes)
			(layer "F.Fab")
			(hide yes)
			(effects
				(font
					(size 1.016 1.016)
					(thickness 0.1524)
				)
			)
		)
		(property "Device Type" "C402H22"
			(at 1.1811 -4.2291 180)
			(unlocked yes)
			(layer "F.Fab")
			(hide yes)
			(effects
				(font
					(size 1.016 1.016)
					(thickness 0.1524)
				)
			)
		)
		(duplicate_pad_numbers_are_jumpers no)
		(fp_rect
			(start -0.4318 0.9525)
			(end 0.4318 -0.9525)
			(stroke
				(width 0)
				(type default)
			)
			(fill no)
			(layer "F.CrtYd")
		)
		(fp_rect
			(start -0.4318 0.9525)
			(end 0.4318 -0.9525)
			(stroke
				(width 0)
				(type default)
			)
			(fill no)
			(layer "F.Fab")
		)
		(pad "1" smd custom
			(at 0 -0.4445 180)
			(size 0.1524 0.1524)
			(layers "F.Cu" "F.Mask" "F.Paste")
			(net "PCIE_TX_CAP_P59")
			(options
				(clearance outline)
				(anchor circle)
			)
			(primitives
				(gr_poly
					(pts
						(arc
							(start 0.3048 -0.2032)
							(mid 0.275042 -0.275042)
							(end 0.2032 -0.3048)
						)
						(arc
							(start -0.2032 -0.3048)
							(mid -0.275042 -0.275042)
							(end -0.3048 -0.2032)
						)
						(arc
							(start -0.3048 0.2032)
							(mid -0.275042 0.275042)
							(end -0.2032 0.3048)
						)
						(arc
							(start 0.2032 0.3048)
							(mid 0.275042 0.275042)
							(end 0.3048 0.2032)
						)
					)
					(width 0)
					(fill yes)
				)
			)
		)
		(pad "2" smd custom
			(at 0 0.4445 180)
			(size 0.1524 0.1524)
			(layers "F.Cu" "F.Mask" "F.Paste")
			(net "PCIE_TX_P59")
			(options
				(clearance outline)
				(anchor circle)
			)
			(primitives
				(gr_poly
					(pts
						(arc
							(start 0.3048 -0.2032)
							(mid 0.275042 -0.275042)
							(end 0.2032 -0.3048)
						)
						(arc
							(start -0.2032 -0.3048)
							(mid -0.275042 -0.275042)
							(end -0.3048 -0.2032)
						)
						(arc
							(start -0.3048 0.2032)
							(mid -0.275042 0.275042)
							(end -0.2032 0.3048)
						)
						(arc
							(start 0.2032 0.3048)
							(mid 0.275042 0.275042)
							(end 0.3048 0.2032)
						)
					)
					(width 0)
					(fill yes)
				)
			)
		)
	)
	(footprint ""
		(layer "F.Cu")
		(at 296.672 -57.0992)
		(property "Reference" "C424"
			(at 0 0 0)
			(layer "F.SilkS")
			(hide yes)
			(effects
				(font
					(size 1.27 1.27)
				)
			)
		)
		(property "Value" "SC10U16V5KX-1-GP"
			(at -0.0762 -6.1214 0)
			(unlocked yes)
			(layer "F.Fab")
			(hide yes)
			(effects
				(font
					(size 1.016 1.016)
					(thickness 0.1524)
				)
			)
		)
		(property "Device Type" "C805H54"
			(at -0.0762 -8.1534 0)
			(unlocked yes)
			(layer "F.Fab")
			(hide yes)
			(effects
				(font
					(size 1.016 1.016)
					(thickness 0.1524)
				)
			)
		)
		(duplicate_pad_numbers_are_jumpers no)
		(fp_line
			(start 0.635 0)
			(end -0.635 0)
			(stroke
				(width 0.508)
				(type default)
			)
			(layer "F.SilkS")
		)
		(fp_rect
			(start -0.9652 1.778)
			(end 0.9652 -1.778)
			(stroke
				(width 0)
				(type default)
			)
			(fill no)
			(layer "F.CrtYd")
		)
		(fp_poly
			(pts
				(xy -0.9652 -1.778) (xy 0.9652 -1.778) (xy 0.9652 1.778) (xy -0.9652 1.778)
			)
			(stroke
				(width 0)
				(type default)
			)
			(fill no)
			(layer "F.Fab")
		)
		(pad "1" smd rect
			(at 0 -0.9652)
			(size 1.397 1.143)
			(layers "F.Cu" "F.Mask" "F.Paste")
			(net "DUT_VDD")
		)
		(pad "2" smd rect
			(at 0 0.9652)
			(size 1.397 1.143)
			(layers "F.Cu" "F.Mask" "F.Paste")
			(net "GND")
		)
	)
	(footprint ""
		(layer "F.Cu")
		(at 181.19725 -6.655308)
		(property "Reference" "R717"
			(at 0 0 0)
			(layer "F.SilkS")
			(hide yes)
			(effects
				(font
					(size 1.27 1.27)
				)
			)
		)
		(property "Value" "0R2J-2-GP"
			(at 0.064008 -3.993896 0)
			(unlocked yes)
			(layer "F.Fab")
			(hide yes)
			(effects
				(font
					(size 1.016 1.016)
					(thickness 0.1524)
				)
			)
		)
		(property "Device Type" "R402H16"
			(at 0.064008 -5.517896 0)
			(unlocked yes)
			(layer "F.Fab")
			(hide yes)
			(effects
				(font
					(size 1.016 1.016)
					(thickness 0.1524)
				)
			)
		)
		(duplicate_pad_numbers_are_jumpers no)
		(fp_line
			(start -0.508 -0.9398)
			(end -0.508 0.9398)
			(stroke
				(width 0.1524)
				(type default)
			)
			(layer "F.SilkS")
		)
		(fp_line
			(start 0.508 -0.9398)
			(end -0.508 -0.9398)
			(stroke
				(width 0.1524)
				(type default)
			)
			(layer "F.SilkS")
		)
		(fp_rect
			(start -0.508 0.9398)
			(end 0.508 -0.9398)
			(stroke
				(width 0)
				(type default)
			)
			(fill no)
			(layer "F.CrtYd")
		)
		(fp_rect
			(start -0.508 0.9398)
			(end 0.508 -0.9398)
			(stroke
				(width 0)
				(type default)
			)
			(fill no)
			(layer "F.Fab")
		)
		(pad "1" smd custom
			(at 0 -0.4445)
			(size 0.1397 0.1397)
			(layers "F.Cu" "F.Mask" "F.Paste")
			(net "HOST4_RST_N_C")
			(options
				(clearance outline)
				(anchor circle)
			)
			(primitives
				(gr_poly
					(pts
						(arc
							(start -0.1778 -0.2794)
							(mid -0.249642 -0.249642)
							(end -0.2794 -0.1778)
						)
						(arc
							(start -0.2794 0.1778)
							(mid -0.249642 0.249642)
							(end -0.1778 0.2794)
						)
						(arc
							(start 0.1778 0.2794)
							(mid 0.249642 0.249642)
							(end 0.2794 0.1778)
						)
						(arc
							(start 0.2794 -0.1778)
							(mid 0.249642 -0.249642)
							(end 0.1778 -0.2794)
						)
					)
					(width 0)
					(fill yes)
				)
			)
		)
		(pad "2" smd custom
			(at 0 0.4445)
			(size 0.1397 0.1397)
			(layers "F.Cu" "F.Mask" "F.Paste")
			(net "P3V3_STBY")
			(options
				(clearance outline)
				(anchor circle)
			)
			(primitives
				(gr_poly
					(pts
						(arc
							(start -0.1778 -0.2794)
							(mid -0.249642 -0.249642)
							(end -0.2794 -0.1778)
						)
						(arc
							(start -0.2794 0.1778)
							(mid -0.249642 0.249642)
							(end -0.1778 0.2794)
						)
						(arc
							(start 0.1778 0.2794)
							(mid 0.249642 0.249642)
							(end 0.2794 0.1778)
						)
						(arc
							(start 0.2794 -0.1778)
							(mid 0.249642 -0.249642)
							(end 0.1778 -0.2794)
						)
					)
					(width 0)
					(fill yes)
				)
			)
		)
	)
	(footprint ""
		(layer "F.Cu")
		(at 7.493 -133.873748 -90)
		(property "Reference" "D1403"
			(at 0 0 270)
			(layer "F.SilkS")
			(hide yes)
			(effects
				(font
					(size 1.27 1.27)
				)
			)
		)
		(property "Value" "RB551V30-GP"
			(at 0 -6.7818 270)
			(unlocked yes)
			(layer "F.Fab")
			(hide yes)
			(effects
				(font
					(size 1.016 1.016)
					(thickness 0.1524)
				)
			)
		)
		(property "Device Type" "SOD323AKH38"
			(at 0 -8.6868 270)
			(unlocked yes)
			(layer "F.Fab")
			(hide yes)
			(effects
				(font
					(size 1.016 1.016)
					(thickness 0.1524)
				)
			)
		)
		(duplicate_pad_numbers_are_jumpers no)
		(fp_line
			(start -0.889 2.159)
			(end -0.889 -1.9304)
			(stroke
				(width 0.1524)
				(type default)
			)
			(layer "F.SilkS")
		)
		(fp_line
			(start 0.889 2.159)
			(end -0.889 2.159)
			(stroke
				(width 0.1524)
				(type default)
			)
			(layer "F.SilkS")
		)
		(fp_line
			(start 0.762 2.0574)
			(end -0.762 2.0574)
			(stroke
				(width 0.508)
				(type default)
			)
			(layer "F.SilkS")
		)
		(fp_line
			(start -0.889 -1.9304)
			(end 0.889 -1.9304)
			(stroke
				(width 0.1524)
				(type default)
			)
			(layer "F.SilkS")
		)
		(fp_line
			(start 0.889 -1.9304)
			(end 0.889 2.159)
			(stroke
				(width 0.1524)
				(type default)
			)
			(layer "F.SilkS")
		)
		(fp_rect
			(start -1.016 2.3114)
			(end 1.016 -2.0066)
			(stroke
				(width 0)
				(type default)
			)
			(fill no)
			(layer "F.CrtYd")
		)
		(fp_poly
			(pts
				(xy -1.016 -2.0066) (xy 1.016 -2.0066) (xy 1.016 2.3114) (xy -1.016 2.3114)
			)
			(stroke
				(width 0)
				(type default)
			)
			(fill no)
			(layer "F.Fab")
		)
		(pad "A" smd rect
			(at 0 -1.143 270)
			(size 0.5588 1.016)
			(layers "F.Cu" "F.Mask" "F.Paste")
			(net "TRAY_RESET_N_R")
		)
		(pad "K" smd rect
			(at 0 1.143 270)
			(size 0.5588 1.016)
			(layers "F.Cu" "F.Mask" "F.Paste")
			(net "TRAY_RESET_N")
		)
	)
	(footprint ""
		(layer "F.Cu")
		(at 19.7612 -53.6194 180)
		(property "Reference" "R515"
			(at 0 0 180)
			(layer "F.SilkS")
			(hide yes)
			(effects
				(font
					(size 1.27 1.27)
				)
			)
		)
		(property "Value" "0R2J-2-GP"
			(at 0.064008 -3.993896 180)
			(unlocked yes)
			(layer "F.Fab")
			(hide yes)
			(effects
				(font
					(size 1.016 1.016)
					(thickness 0.1524)
				)
			)
		)
		(property "Device Type" "R402H16"
			(at 0.064008 -5.517896 180)
			(unlocked yes)
			(layer "F.Fab")
			(hide yes)
			(effects
				(font
					(size 1.016 1.016)
					(thickness 0.1524)
				)
			)
		)
		(duplicate_pad_numbers_are_jumpers no)
		(fp_line
			(start 0.508 -0.9398)
			(end -0.508 -0.9398)
			(stroke
				(width 0.1524)
				(type default)
			)
			(layer "F.SilkS")
		)
		(fp_line
			(start -0.508 -0.9398)
			(end -0.508 0.9398)
			(stroke
				(width 0.1524)
				(type default)
			)
			(layer "F.SilkS")
		)
		(fp_rect
			(start -0.508 0.9398)
			(end 0.508 -0.9398)
			(stroke
				(width 0)
				(type default)
			)
			(fill no)
			(layer "F.CrtYd")
		)
		(fp_rect
			(start -0.508 0.9398)
			(end 0.508 -0.9398)
			(stroke
				(width 0)
				(type default)
			)
			(fill no)
			(layer "F.Fab")
		)
		(pad "1" smd custom
			(at 0 -0.4445 180)
			(size 0.1397 0.1397)
			(layers "F.Cu" "F.Mask" "F.Paste")
			(net "NIC0_MDI0_N2_R")
			(options
				(clearance outline)
				(anchor circle)
			)
			(primitives
				(gr_poly
					(pts
						(arc
							(start -0.1778 -0.2794)
							(mid -0.249642 -0.249642)
							(end -0.2794 -0.1778)
						)
						(arc
							(start -0.2794 0.1778)
							(mid -0.249642 0.249642)
							(end -0.1778 0.2794)
						)
						(arc
							(start 0.1778 0.2794)
							(mid 0.249642 0.249642)
							(end 0.2794 0.1778)
						)
						(arc
							(start 0.2794 -0.1778)
							(mid 0.249642 -0.249642)
							(end 0.1778 -0.2794)
						)
					)
					(width 0)
					(fill yes)
				)
			)
		)
		(pad "2" smd custom
			(at 0 0.4445 180)
			(size 0.1397 0.1397)
			(layers "F.Cu" "F.Mask" "F.Paste")
			(net "NIC0_MDI0_N2")
			(options
				(clearance outline)
				(anchor circle)
			)
			(primitives
				(gr_poly
					(pts
						(arc
							(start -0.1778 -0.2794)
							(mid -0.249642 -0.249642)
							(end -0.2794 -0.1778)
						)
						(arc
							(start -0.2794 0.1778)
							(mid -0.249642 0.249642)
							(end -0.1778 0.2794)
						)
						(arc
							(start 0.1778 0.2794)
							(mid 0.249642 0.249642)
							(end 0.2794 0.1778)
						)
						(arc
							(start 0.2794 -0.1778)
							(mid 0.249642 -0.249642)
							(end 0.1778 -0.2794)
						)
					)
					(width 0)
					(fill yes)
				)
			)
		)
	)
	(footprint ""
		(layer "F.Cu")
		(at 52.578 -198.247 90)
		(property "Reference" "C705"
			(at 0 0 90)
			(layer "F.SilkS")
			(hide yes)
			(effects
				(font
					(size 1.27 1.27)
				)
			)
		)
		(property "Value" "SC220P50V3JN-GP"
			(at 0 -2.8194 90)
			(unlocked yes)
			(layer "F.Fab")
			(hide yes)
			(effects
				(font
					(size 1.016 1.016)
					(thickness 0.1524)
				)
			)
		)
		(property "Device Type" "C603H36"
			(at 0 -4.3434 90)
			(unlocked yes)
			(layer "F.Fab")
			(hide yes)
			(effects
				(font
					(size 1.016 1.016)
					(thickness 0.1524)
				)
			)
		)
		(duplicate_pad_numbers_are_jumpers no)
		(fp_line
			(start 0.508 0)
			(end -0.508 0)
			(stroke
				(width 0.2032)
				(type default)
			)
			(layer "F.SilkS")
		)
		(fp_rect
			(start -0.5842 1.3335)
			(end 0.5842 -1.3335)
			(stroke
				(width 0)
				(type default)
			)
			(fill no)
			(layer "F.CrtYd")
		)
		(fp_rect
			(start -0.5842 1.3335)
			(end 0.5842 -1.3335)
			(stroke
				(width 0)
				(type default)
			)
			(fill no)
			(layer "F.Fab")
		)
		(pad "1" smd custom
			(at 0 -0.762 90)
			(size 0.2159 0.2159)
			(layers "F.Cu" "F.Mask" "F.Paste")
			(net "BUF_I2C7_B_DBP_SCL_R")
			(options
				(clearance outline)
				(anchor circle)
			)
			(primitives
				(gr_poly
					(pts
						(arc
							(start -0.3302 -0.4318)
							(mid -0.402042 -0.402042)
							(end -0.4318 -0.3302)
						)
						(arc
							(start -0.4318 0.3302)
							(mid -0.402042 0.402042)
							(end -0.3302 0.4318)
						)
						(arc
							(start 0.3302 0.4318)
							(mid 0.402042 0.402042)
							(end 0.4318 0.3302)
						)
						(arc
							(start 0.4318 -0.3302)
							(mid 0.402042 -0.402042)
							(end 0.3302 -0.4318)
						)
					)
					(width 0)
					(fill yes)
				)
			)
		)
		(pad "2" smd custom
			(at 0 0.762 90)
			(size 0.2159 0.2159)
			(layers "F.Cu" "F.Mask" "F.Paste")
			(net "GND")
			(options
				(clearance outline)
				(anchor circle)
			)
			(primitives
				(gr_poly
					(pts
						(arc
							(start -0.3302 -0.4318)
							(mid -0.402042 -0.402042)
							(end -0.4318 -0.3302)
						)
						(arc
							(start -0.4318 0.3302)
							(mid -0.402042 0.402042)
							(end -0.3302 0.4318)
						)
						(arc
							(start 0.3302 0.4318)
							(mid 0.402042 0.402042)
							(end 0.4318 0.3302)
						)
						(arc
							(start 0.4318 -0.3302)
							(mid 0.402042 -0.402042)
							(end 0.3302 -0.4318)
						)
					)
					(width 0)
					(fill yes)
				)
			)
		)
	)
	(footprint ""
		(layer "F.Cu")
		(at 54.229 -114.7572)
		(property "Reference" "R642"
			(at 0 0 0)
			(layer "F.SilkS")
			(hide yes)
			(effects
				(font
					(size 1.27 1.27)
				)
			)
		)
		(property "Value" "0R2J-2-GP"
			(at 0.064008 -3.993896 0)
			(unlocked yes)
			(layer "F.Fab")
			(hide yes)
			(effects
				(font
					(size 1.016 1.016)
					(thickness 0.1524)
				)
			)
		)
		(property "Device Type" "R402H16"
			(at 0.064008 -5.517896 0)
			(unlocked yes)
			(layer "F.Fab")
			(hide yes)
			(effects
				(font
					(size 1.016 1.016)
					(thickness 0.1524)
				)
			)
		)
		(duplicate_pad_numbers_are_jumpers no)
		(fp_line
			(start -0.508 -0.9398)
			(end -0.508 0.9398)
			(stroke
				(width 0.1524)
				(type default)
			)
			(layer "F.SilkS")
		)
		(fp_line
			(start 0.508 -0.9398)
			(end -0.508 -0.9398)
			(stroke
				(width 0.1524)
				(type default)
			)
			(layer "F.SilkS")
		)
		(fp_rect
			(start -0.508 0.9398)
			(end 0.508 -0.9398)
			(stroke
				(width 0)
				(type default)
			)
			(fill no)
			(layer "F.CrtYd")
		)
		(fp_rect
			(start -0.508 0.9398)
			(end 0.508 -0.9398)
			(stroke
				(width 0)
				(type default)
			)
			(fill no)
			(layer "F.Fab")
		)
		(pad "1" smd custom
			(at 0 -0.4445)
			(size 0.1397 0.1397)
			(layers "F.Cu" "F.Mask" "F.Paste")
			(net "BMC0_SCL13_R")
			(options
				(clearance outline)
				(anchor circle)
			)
			(primitives
				(gr_poly
					(pts
						(arc
							(start -0.1778 -0.2794)
							(mid -0.249642 -0.249642)
							(end -0.2794 -0.1778)
						)
						(arc
							(start -0.2794 0.1778)
							(mid -0.249642 0.249642)
							(end -0.1778 0.2794)
						)
						(arc
							(start 0.1778 0.2794)
							(mid 0.249642 0.249642)
							(end 0.2794 0.1778)
						)
						(arc
							(start 0.2794 -0.1778)
							(mid 0.249642 -0.249642)
							(end 0.1778 -0.2794)
						)
					)
					(width 0)
					(fill yes)
				)
			)
		)
		(pad "2" smd custom
			(at 0 0.4445)
			(size 0.1397 0.1397)
			(layers "F.Cu" "F.Mask" "F.Paste")
			(net "BMC_I2C13_MINI7_SCL_S")
			(options
				(clearance outline)
				(anchor circle)
			)
			(primitives
				(gr_poly
					(pts
						(arc
							(start -0.1778 -0.2794)
							(mid -0.249642 -0.249642)
							(end -0.2794 -0.1778)
						)
						(arc
							(start -0.2794 0.1778)
							(mid -0.249642 0.249642)
							(end -0.1778 0.2794)
						)
						(arc
							(start 0.1778 0.2794)
							(mid 0.249642 0.249642)
							(end 0.2794 0.1778)
						)
						(arc
							(start 0.2794 -0.1778)
							(mid 0.249642 -0.249642)
							(end 0.1778 -0.2794)
						)
					)
					(width 0)
					(fill yes)
				)
			)
		)
	)
	(footprint ""
		(layer "F.Cu")
		(at 80.0862 -86.106)
		(property "Reference" "R484"
			(at 0 0 0)
			(layer "F.SilkS")
			(hide yes)
			(effects
				(font
					(size 1.27 1.27)
				)
			)
		)
		(property "Value" "1KR2F-3-GP"
			(at 0.064008 -3.993896 0)
			(unlocked yes)
			(layer "F.Fab")
			(hide yes)
			(effects
				(font
					(size 1.016 1.016)
					(thickness 0.1524)
				)
			)
		)
		(property "Device Type" "R402H16"
			(at 0.064008 -5.517896 0)
			(unlocked yes)
			(layer "F.Fab")
			(hide yes)
			(effects
				(font
					(size 1.016 1.016)
					(thickness 0.1524)
				)
			)
		)
		(duplicate_pad_numbers_are_jumpers no)
		(fp_line
			(start -0.508 -0.9398)
			(end -0.508 0.9398)
			(stroke
				(width 0.1524)
				(type default)
			)
			(layer "F.SilkS")
		)
		(fp_line
			(start 0.508 -0.9398)
			(end -0.508 -0.9398)
			(stroke
				(width 0.1524)
				(type default)
			)
			(layer "F.SilkS")
		)
		(fp_rect
			(start -0.508 0.9398)
			(end 0.508 -0.9398)
			(stroke
				(width 0)
				(type default)
			)
			(fill no)
			(layer "F.CrtYd")
		)
		(fp_rect
			(start -0.508 0.9398)
			(end 0.508 -0.9398)
			(stroke
				(width 0)
				(type default)
			)
			(fill no)
			(layer "F.Fab")
		)
		(pad "1" smd custom
			(at 0 -0.4445)
			(size 0.1397 0.1397)
			(layers "F.Cu" "F.Mask" "F.Paste")
			(net "P3V3_STBY")
			(options
				(clearance outline)
				(anchor circle)
			)
			(primitives
				(gr_poly
					(pts
						(arc
							(start -0.1778 -0.2794)
							(mid -0.249642 -0.249642)
							(end -0.2794 -0.1778)
						)
						(arc
							(start -0.2794 0.1778)
							(mid -0.249642 0.249642)
							(end -0.1778 0.2794)
						)
						(arc
							(start 0.1778 0.2794)
							(mid 0.249642 0.249642)
							(end 0.2794 0.1778)
						)
						(arc
							(start 0.2794 -0.1778)
							(mid 0.249642 -0.249642)
							(end 0.1778 -0.2794)
						)
					)
					(width 0)
					(fill yes)
				)
			)
		)
		(pad "2" smd custom
			(at 0 0.4445)
			(size 0.1397 0.1397)
			(layers "F.Cu" "F.Mask" "F.Paste")
			(net "DIVIDER_1_IN")
			(options
				(clearance outline)
				(anchor circle)
			)
			(primitives
				(gr_poly
					(pts
						(arc
							(start -0.1778 -0.2794)
							(mid -0.249642 -0.249642)
							(end -0.2794 -0.1778)
						)
						(arc
							(start -0.2794 0.1778)
							(mid -0.249642 0.249642)
							(end -0.1778 0.2794)
						)
						(arc
							(start 0.1778 0.2794)
							(mid 0.249642 0.249642)
							(end 0.2794 0.1778)
						)
						(arc
							(start 0.2794 -0.1778)
							(mid 0.249642 -0.249642)
							(end 0.1778 -0.2794)
						)
					)
					(width 0)
					(fill yes)
				)
			)
		)
	)
	(footprint ""
		(layer "F.Cu")
		(at 65.913 -38.608 -90)
		(property "Reference" "PU2"
			(at 0 0 270)
			(layer "F.SilkS")
			(hide yes)
			(effects
				(font
					(size 1.27 1.27)
				)
			)
		)
		(property "Value" "TPS53319DQPR-GP"
			(at 4.7498 -5.6896 270)
			(unlocked yes)
			(layer "F.Fab")
			(hide yes)
			(effects
				(font
					(size 1.016 1.016)
					(thickness 0.1524)
				)
			)
		)
		(property "Device Type" "QFN22G6050-G6133H60"
			(at 4.7498 -7.2136 270)
			(unlocked yes)
			(layer "F.Fab")
			(hide yes)
			(effects
				(font
					(size 1.016 1.016)
					(thickness 0.1524)
				)
			)
		)
		(duplicate_pad_numbers_are_jumpers no)
		(fp_line
			(start -3.556 3.5179)
			(end -2.286 3.5179)
			(stroke
				(width 0.1524)
				(type default)
			)
			(layer "F.SilkS")
		)
		(fp_line
			(start 2.286 3.5179)
			(end 3.556 3.5179)
			(stroke
				(width 0.1524)
				(type default)
			)
			(layer "F.SilkS")
		)
		(fp_line
			(start 3.556 3.5179)
			(end 3.556 2.2479)
			(stroke
				(width 0.1524)
				(type default)
			)
			(layer "F.SilkS")
		)
		(fp_line
			(start -0.999998 3.262122)
			(end -0.999998 3.770122)
			(stroke
				(width 0.1524)
				(type default)
			)
			(layer "F.SilkS")
		)
		(fp_line
			(start 1.500124 3.262122)
			(end 1.500124 4.024122)
			(stroke
				(width 0.1524)
				(type default)
			)
			(layer "F.SilkS")
		)
		(fp_line
			(start -3.556 2.2479)
			(end -3.556 3.5179)
			(stroke
				(width 0.1524)
				(type default)
			)
			(layer "F.SilkS")
		)
		(fp_line
			(start -1.999996 -3.262122)
			(end -1.999996 -4.024122)
			(stroke
				(width 0.1524)
				(type default)
			)
			(layer "F.SilkS")
		)
		(fp_line
			(start 0.500126 -3.262122)
			(end 0.500126 -3.770122)
			(stroke
				(width 0.1524)
				(type default)
			)
			(layer "F.SilkS")
		)
		(fp_line
			(start -3.556 -3.5179)
			(end -3.556 -2.2479)
			(stroke
				(width 0.1524)
				(type default)
			)
			(layer "F.SilkS")
		)
		(fp_line
			(start -2.286 -3.5179)
			(end -3.556 -3.5179)
			(stroke
				(width 0.1524)
				(type default)
			)
			(layer "F.SilkS")
		)
		(fp_poly
			(pts
				(xy 3.556 -3.5179) (xy 2.5273 -3.5179) (xy 3.556 -2.4892)
			)
			(stroke
				(width 0)
				(type default)
			)
			(fill yes)
			(layer "F.SilkS")
		)
		(fp_rect
			(start -2.9972 2.5019)
			(end 2.9972 -2.5019)
			(stroke
				(width 0)
				(type default)
			)
			(fill no)
			(layer "F.CrtYd")
		)
		(fp_poly
			(pts
				(xy 3.556 -2.5019) (xy -2.9972 -2.5019) (xy -2.9972 2.5019) (xy 2.9972 2.5019) (xy 2.9972 -2.4892)
				(xy 3.556 -2.4892) (xy 3.556 3.5179) (xy -3.556 3.5179) (xy -3.556 -3.5179) (xy 3.556 -3.5179)
			)
			(stroke
				(width 0)
				(type default)
			)
			(fill no)
			(layer "F.CrtYd")
		)
		(fp_rect
			(start -3.556 3.5179)
			(end 3.556 -3.5179)
			(stroke
				(width 0)
				(type default)
			)
			(fill no)
			(layer "F.Fab")
		)
		(pad "1" smd rect
			(at 2.500122 -2.449322 270)
			(size 0.3048 1.1176)
			(layers "F.Cu" "F.Mask" "F.Paste")
			(net "P3V3_STBY_VFB")
		)
		(pad "2" smd rect
			(at 1.999996 -2.449322 270)
			(size 0.3048 1.1176)
			(layers "F.Cu" "F.Mask" "F.Paste")
			(net "P3V3_STBY_EN")
		)
		(pad "3" smd rect
			(at 1.500124 -2.449322 270)
			(size 0.3048 1.1176)
			(layers "F.Cu" "F.Mask" "F.Paste")
			(net "P3V3_STBY_PG")
		)
		(pad "4" smd rect
			(at 0.999998 -2.449322 270)
			(size 0.3048 1.1176)
			(layers "F.Cu" "F.Mask" "F.Paste")
			(net "P3V3_STBY_VBST")
		)
		(pad "5" smd rect
			(at 0.500126 -2.449322 270)
			(size 0.3048 1.1176)
			(layers "F.Cu" "F.Mask" "F.Paste")
			(net "P3V3_STBY_ROVP")
		)
		(pad "6" smd rect
			(at 0 -2.449322 270)
			(size 0.3048 1.1176)
			(layers "F.Cu" "F.Mask" "F.Paste")
			(net "P3V3_STBY_LL")
		)
		(pad "7" smd rect
			(at -0.500126 -2.449322 270)
			(size 0.3048 1.1176)
			(layers "F.Cu" "F.Mask" "F.Paste")
			(net "P3V3_STBY_LL")
		)
		(pad "8" smd rect
			(at -0.999998 -2.449322 270)
			(size 0.3048 1.1176)
			(layers "F.Cu" "F.Mask" "F.Paste")
			(net "P3V3_STBY_LL")
		)
		(pad "9" smd rect
			(at -1.500124 -2.449322 270)
			(size 0.3048 1.1176)
			(layers "F.Cu" "F.Mask" "F.Paste")
			(net "P3V3_STBY_LL")
		)
		(pad "10" smd rect
			(at -1.999996 -2.449322 270)
			(size 0.3048 1.1176)
			(layers "F.Cu" "F.Mask" "F.Paste")
			(net "P3V3_STBY_LL")
		)
		(pad "11" smd rect
			(at -2.500122 -2.449322 270)
			(size 0.3048 1.1176)
			(layers "F.Cu" "F.Mask" "F.Paste")
			(net "P3V3_STBY_LL")
		)
		(pad "12" smd rect
			(at -2.500122 2.449322 270)
			(size 0.3048 1.1176)
			(layers "F.Cu" "F.Mask" "F.Paste")
			(net "P3V3_STBY_VIN")
		)
		(pad "13" smd rect
			(at -1.999996 2.449322 270)
			(size 0.3048 1.1176)
			(layers "F.Cu" "F.Mask" "F.Paste")
			(net "P3V3_STBY_VIN")
		)
		(pad "14" smd rect
			(at -1.500124 2.449322 270)
			(size 0.3048 1.1176)
			(layers "F.Cu" "F.Mask" "F.Paste")
			(net "P3V3_STBY_VIN")
		)
		(pad "15" smd rect
			(at -0.999998 2.449322 270)
			(size 0.3048 1.1176)
			(layers "F.Cu" "F.Mask" "F.Paste")
			(net "P3V3_STBY_VIN")
		)
		(pad "16" smd rect
			(at -0.500126 2.449322 270)
			(size 0.3048 1.1176)
			(layers "F.Cu" "F.Mask" "F.Paste")
			(net "P3V3_STBY_VIN")
		)
		(pad "17" smd rect
			(at 0 2.449322 270)
			(size 0.3048 1.1176)
			(layers "F.Cu" "F.Mask" "F.Paste")
			(net "P3V3_STBY_VIN")
		)
		(pad "18" smd rect
			(at 0.500126 2.449322 270)
			(size 0.3048 1.1176)
			(layers "F.Cu" "F.Mask" "F.Paste")
			(net "P3V3_STBY_VREG")
		)
		(pad "19" smd rect
			(at 0.999998 2.449322 270)
			(size 0.3048 1.1176)
			(layers "F.Cu" "F.Mask" "F.Paste")
			(net "P3V3_STBY_VDD")
		)
		(pad "20" smd rect
			(at 1.500124 2.449322 270)
			(size 0.3048 1.1176)
			(layers "F.Cu" "F.Mask" "F.Paste")
			(net "P3V3_STBY_MODE")
		)
		(pad "21" smd rect
			(at 1.999996 2.449322 270)
			(size 0.3048 1.1176)
			(layers "F.Cu" "F.Mask" "F.Paste")
			(net "P3V3_STBY_TRIP")
		)
		(pad "22" smd rect
			(at 2.500122 2.449322 270)
			(size 0.3048 1.1176)
			(layers "F.Cu" "F.Mask" "F.Paste")
			(net "P3V3_STBY_RF")
		)
		(pad "23" smd custom
			(at 0 0 270)
			(size 0.83185 0.83185)
			(layers "F.Cu" "F.Mask" "F.Paste")
			(net "GND")
			(options
				(clearance outline)
				(anchor circle)
			)
			(primitives
				(gr_poly
					(pts
						(xy -2.7813 1.6637) (xy -2.7813 1.2954) (xy -3.048 1.2954) (xy -3.048 0.9525) (xy -2.7813 0.9525)
						(xy -2.7813 -0.9525) (xy -3.048 -0.9525) (xy -3.048 -1.2954) (xy -2.7813 -1.2954) (xy -2.7813 -1.6637)
						(xy 2.7813 -1.6637) (xy 2.7813 -1.2954) (xy 3.048 -1.2954) (xy 3.048 -0.9525) (xy 2.7813 -0.9525)
						(xy 2.7813 0.9525) (xy 3.048 0.9525) (xy 3.048 1.2954) (xy 2.7813 1.2954) (xy 2.7813 1.6637)
					)
					(width 0)
					(fill yes)
				)
			)
		)
	)
	(footprint ""
		(layer "F.Cu")
		(at 25.6286 -45.6184)
		(property "Reference" "C334"
			(at 0 0 0)
			(layer "F.SilkS")
			(hide yes)
			(effects
				(font
					(size 1.27 1.27)
				)
			)
		)
		(property "Value" "SCD1U16V2KX-3GP"
			(at 1.1811 -2.7051 0)
			(unlocked yes)
			(layer "F.Fab")
			(hide yes)
			(effects
				(font
					(size 1.016 1.016)
					(thickness 0.1524)
				)
			)
		)
		(property "Device Type" "C402H22"
			(at 1.1811 -4.2291 0)
			(unlocked yes)
			(layer "F.Fab")
			(hide yes)
			(effects
				(font
					(size 1.016 1.016)
					(thickness 0.1524)
				)
			)
		)
		(duplicate_pad_numbers_are_jumpers no)
		(fp_rect
			(start -0.4318 0.9525)
			(end 0.4318 -0.9525)
			(stroke
				(width 0)
				(type default)
			)
			(fill no)
			(layer "F.CrtYd")
		)
		(fp_rect
			(start -0.4318 0.9525)
			(end 0.4318 -0.9525)
			(stroke
				(width 0)
				(type default)
			)
			(fill no)
			(layer "F.Fab")
		)
		(pad "1" smd custom
			(at 0 -0.4445)
			(size 0.1524 0.1524)
			(layers "F.Cu" "F.Mask" "F.Paste")
			(net "NIC0_CT_POWER")
			(options
				(clearance outline)
				(anchor circle)
			)
			(primitives
				(gr_poly
					(pts
						(arc
							(start 0.3048 -0.2032)
							(mid 0.275042 -0.275042)
							(end 0.2032 -0.3048)
						)
						(arc
							(start -0.2032 -0.3048)
							(mid -0.275042 -0.275042)
							(end -0.3048 -0.2032)
						)
						(arc
							(start -0.3048 0.2032)
							(mid -0.275042 0.275042)
							(end -0.2032 0.3048)
						)
						(arc
							(start 0.2032 0.3048)
							(mid 0.275042 0.275042)
							(end 0.3048 0.2032)
						)
					)
					(width 0)
					(fill yes)
				)
			)
		)
		(pad "2" smd custom
			(at 0 0.4445)
			(size 0.1524 0.1524)
			(layers "F.Cu" "F.Mask" "F.Paste")
			(net "GND")
			(options
				(clearance outline)
				(anchor circle)
			)
			(primitives
				(gr_poly
					(pts
						(arc
							(start 0.3048 -0.2032)
							(mid 0.275042 -0.275042)
							(end 0.2032 -0.3048)
						)
						(arc
							(start -0.2032 -0.3048)
							(mid -0.275042 -0.275042)
							(end -0.3048 -0.2032)
						)
						(arc
							(start -0.3048 0.2032)
							(mid -0.275042 0.275042)
							(end -0.2032 0.3048)
						)
						(arc
							(start 0.2032 0.3048)
							(mid 0.275042 0.275042)
							(end 0.3048 0.2032)
						)
					)
					(width 0)
					(fill yes)
				)
			)
		)
	)
	(footprint ""
		(layer "F.Cu")
		(at 38.968934 -77.560932 180)
		(property "Reference" "PC66"
			(at 0 0 180)
			(layer "F.SilkS")
			(hide yes)
			(effects
				(font
					(size 1.27 1.27)
				)
			)
		)
		(property "Value" "SC22U16V5MX-4-GP"
			(at -0.0762 -6.1214 180)
			(unlocked yes)
			(layer "F.Fab")
			(hide yes)
			(effects
				(font
					(size 1.016 1.016)
					(thickness 0.1524)
				)
			)
		)
		(property "Device Type" "C805H58"
			(at -0.0762 -8.1534 180)
			(unlocked yes)
			(layer "F.Fab")
			(hide yes)
			(effects
				(font
					(size 1.016 1.016)
					(thickness 0.1524)
				)
			)
		)
		(duplicate_pad_numbers_are_jumpers no)
		(fp_line
			(start 0.635 0)
			(end -0.635 0)
			(stroke
				(width 0.508)
				(type default)
			)
			(layer "F.SilkS")
		)
		(fp_rect
			(start -0.9652 1.778)
			(end 0.9652 -1.778)
			(stroke
				(width 0)
				(type default)
			)
			(fill no)
			(layer "F.CrtYd")
		)
		(fp_poly
			(pts
				(xy -0.9652 -1.778) (xy 0.9652 -1.778) (xy 0.9652 1.778) (xy -0.9652 1.778)
			)
			(stroke
				(width 0)
				(type default)
			)
			(fill no)
			(layer "F.Fab")
		)
		(pad "1" smd rect
			(at 0 -0.9652 180)
			(size 1.397 1.143)
			(layers "F.Cu" "F.Mask" "F.Paste")
			(net "P5V_STBY_LR")
		)
		(pad "2" smd rect
			(at 0 0.9652 180)
			(size 1.397 1.143)
			(layers "F.Cu" "F.Mask" "F.Paste")
			(net "GND")
		)
	)
	(footprint ""
		(layer "F.Cu")
		(at 49.657 -152.4 180)
		(property "Reference" "R160"
			(at 0 0 180)
			(layer "F.SilkS")
			(hide yes)
			(effects
				(font
					(size 1.27 1.27)
				)
			)
		)
		(property "Value" "4K7R2F-GP"
			(at 0.064008 -3.993896 180)
			(unlocked yes)
			(layer "F.Fab")
			(hide yes)
			(effects
				(font
					(size 1.016 1.016)
					(thickness 0.1524)
				)
			)
		)
		(property "Device Type" "R402H16"
			(at 0.064008 -5.517896 180)
			(unlocked yes)
			(layer "F.Fab")
			(hide yes)
			(effects
				(font
					(size 1.016 1.016)
					(thickness 0.1524)
				)
			)
		)
		(duplicate_pad_numbers_are_jumpers no)
		(fp_line
			(start 0.508 -0.9398)
			(end -0.508 -0.9398)
			(stroke
				(width 0.1524)
				(type default)
			)
			(layer "F.SilkS")
		)
		(fp_line
			(start -0.508 -0.9398)
			(end -0.508 0.9398)
			(stroke
				(width 0.1524)
				(type default)
			)
			(layer "F.SilkS")
		)
		(fp_rect
			(start -0.508 0.9398)
			(end 0.508 -0.9398)
			(stroke
				(width 0)
				(type default)
			)
			(fill no)
			(layer "F.CrtYd")
		)
		(fp_rect
			(start -0.508 0.9398)
			(end 0.508 -0.9398)
			(stroke
				(width 0)
				(type default)
			)
			(fill no)
			(layer "F.Fab")
		)
		(pad "1" smd custom
			(at 0 -0.4445 180)
			(size 0.1397 0.1397)
			(layers "F.Cu" "F.Mask" "F.Paste")
			(net "TEMP_2_A2")
			(options
				(clearance outline)
				(anchor circle)
			)
			(primitives
				(gr_poly
					(pts
						(arc
							(start -0.1778 -0.2794)
							(mid -0.249642 -0.249642)
							(end -0.2794 -0.1778)
						)
						(arc
							(start -0.2794 0.1778)
							(mid -0.249642 0.249642)
							(end -0.1778 0.2794)
						)
						(arc
							(start 0.1778 0.2794)
							(mid 0.249642 0.249642)
							(end 0.2794 0.1778)
						)
						(arc
							(start 0.2794 -0.1778)
							(mid 0.249642 -0.249642)
							(end 0.1778 -0.2794)
						)
					)
					(width 0)
					(fill yes)
				)
			)
		)
		(pad "2" smd custom
			(at 0 0.4445 180)
			(size 0.1397 0.1397)
			(layers "F.Cu" "F.Mask" "F.Paste")
			(net "GND")
			(options
				(clearance outline)
				(anchor circle)
			)
			(primitives
				(gr_poly
					(pts
						(arc
							(start -0.1778 -0.2794)
							(mid -0.249642 -0.249642)
							(end -0.2794 -0.1778)
						)
						(arc
							(start -0.2794 0.1778)
							(mid -0.249642 0.249642)
							(end -0.1778 0.2794)
						)
						(arc
							(start 0.1778 0.2794)
							(mid 0.249642 0.249642)
							(end 0.2794 0.1778)
						)
						(arc
							(start 0.2794 -0.1778)
							(mid 0.249642 -0.249642)
							(end 0.1778 -0.2794)
						)
					)
					(width 0)
					(fill yes)
				)
			)
		)
	)
	(footprint ""
		(layer "F.Cu")
		(at 261.239 -17.272 180)
		(property "Reference" "PC222"
			(at 0 0 180)
			(layer "F.SilkS")
			(hide yes)
			(effects
				(font
					(size 1.27 1.27)
				)
			)
		)
		(property "Value" "SC1U16V3KX-5GP"
			(at 0 -2.8194 180)
			(unlocked yes)
			(layer "F.Fab")
			(hide yes)
			(effects
				(font
					(size 1.016 1.016)
					(thickness 0.1524)
				)
			)
		)
		(property "Device Type" "C603H36"
			(at 0 -4.3434 180)
			(unlocked yes)
			(layer "F.Fab")
			(hide yes)
			(effects
				(font
					(size 1.016 1.016)
					(thickness 0.1524)
				)
			)
		)
		(duplicate_pad_numbers_are_jumpers no)
		(fp_line
			(start 0.508 0)
			(end -0.508 0)
			(stroke
				(width 0.2032)
				(type default)
			)
			(layer "F.SilkS")
		)
		(fp_rect
			(start -0.5842 1.3335)
			(end 0.5842 -1.3335)
			(stroke
				(width 0)
				(type default)
			)
			(fill no)
			(layer "F.CrtYd")
		)
		(fp_rect
			(start -0.5842 1.3335)
			(end 0.5842 -1.3335)
			(stroke
				(width 0)
				(type default)
			)
			(fill no)
			(layer "F.Fab")
		)
		(pad "1" smd custom
			(at 0 -0.762 180)
			(size 0.2159 0.2159)
			(layers "F.Cu" "F.Mask" "F.Paste")
			(net "P3V3_STBY")
			(options
				(clearance outline)
				(anchor circle)
			)
			(primitives
				(gr_poly
					(pts
						(arc
							(start -0.3302 -0.4318)
							(mid -0.402042 -0.402042)
							(end -0.4318 -0.3302)
						)
						(arc
							(start -0.4318 0.3302)
							(mid -0.402042 0.402042)
							(end -0.3302 0.4318)
						)
						(arc
							(start 0.3302 0.4318)
							(mid 0.402042 0.402042)
							(end 0.4318 0.3302)
						)
						(arc
							(start 0.4318 -0.3302)
							(mid 0.402042 -0.402042)
							(end 0.3302 -0.4318)
						)
					)
					(width 0)
					(fill yes)
				)
			)
		)
		(pad "2" smd custom
			(at 0 0.762 180)
			(size 0.2159 0.2159)
			(layers "F.Cu" "F.Mask" "F.Paste")
			(net "Q3203_G")
			(options
				(clearance outline)
				(anchor circle)
			)
			(primitives
				(gr_poly
					(pts
						(arc
							(start -0.3302 -0.4318)
							(mid -0.402042 -0.402042)
							(end -0.4318 -0.3302)
						)
						(arc
							(start -0.4318 0.3302)
							(mid -0.402042 0.402042)
							(end -0.3302 0.4318)
						)
						(arc
							(start 0.3302 0.4318)
							(mid 0.402042 0.402042)
							(end 0.4318 0.3302)
						)
						(arc
							(start 0.4318 -0.3302)
							(mid 0.402042 -0.402042)
							(end 0.3302 -0.4318)
						)
					)
					(width 0)
					(fill yes)
				)
			)
		)
	)
	(footprint ""
		(layer "F.Cu")
		(at 219.456 -2.032 90)
		(property "Reference" "R435"
			(at 0 0 90)
			(layer "F.SilkS")
			(hide yes)
			(effects
				(font
					(size 1.27 1.27)
				)
			)
		)
		(property "Value" "0R2J-2-GP"
			(at 0.064008 -3.993896 90)
			(unlocked yes)
			(layer "F.Fab")
			(hide yes)
			(effects
				(font
					(size 1.016 1.016)
					(thickness 0.1524)
				)
			)
		)
		(property "Device Type" "R402H16"
			(at 0.064008 -5.517896 90)
			(unlocked yes)
			(layer "F.Fab")
			(hide yes)
			(effects
				(font
					(size 1.016 1.016)
					(thickness 0.1524)
				)
			)
		)
		(duplicate_pad_numbers_are_jumpers no)
		(fp_line
			(start 0.508 -0.9398)
			(end -0.508 -0.9398)
			(stroke
				(width 0.1524)
				(type default)
			)
			(layer "F.SilkS")
		)
		(fp_line
			(start -0.508 -0.9398)
			(end -0.508 0.9398)
			(stroke
				(width 0.1524)
				(type default)
			)
			(layer "F.SilkS")
		)
		(fp_rect
			(start -0.508 0.9398)
			(end 0.508 -0.9398)
			(stroke
				(width 0)
				(type default)
			)
			(fill no)
			(layer "F.CrtYd")
		)
		(fp_rect
			(start -0.508 0.9398)
			(end 0.508 -0.9398)
			(stroke
				(width 0)
				(type default)
			)
			(fill no)
			(layer "F.Fab")
		)
		(pad "1" smd custom
			(at 0 -0.4445 90)
			(size 0.1397 0.1397)
			(layers "F.Cu" "F.Mask" "F.Paste")
			(net "EXP_SMART_TX")
			(options
				(clearance outline)
				(anchor circle)
			)
			(primitives
				(gr_poly
					(pts
						(arc
							(start -0.1778 -0.2794)
							(mid -0.249642 -0.249642)
							(end -0.2794 -0.1778)
						)
						(arc
							(start -0.2794 0.1778)
							(mid -0.249642 0.249642)
							(end -0.1778 0.2794)
						)
						(arc
							(start 0.1778 0.2794)
							(mid 0.249642 0.249642)
							(end 0.2794 0.1778)
						)
						(arc
							(start 0.2794 -0.1778)
							(mid 0.249642 -0.249642)
							(end 0.1778 -0.2794)
						)
					)
					(width 0)
					(fill yes)
				)
			)
		)
		(pad "2" smd custom
			(at 0 0.4445 90)
			(size 0.1397 0.1397)
			(layers "F.Cu" "F.Mask" "F.Paste")
			(net "EXP_UART_TX_R")
			(options
				(clearance outline)
				(anchor circle)
			)
			(primitives
				(gr_poly
					(pts
						(arc
							(start -0.1778 -0.2794)
							(mid -0.249642 -0.249642)
							(end -0.2794 -0.1778)
						)
						(arc
							(start -0.2794 0.1778)
							(mid -0.249642 0.249642)
							(end -0.1778 0.2794)
						)
						(arc
							(start 0.1778 0.2794)
							(mid 0.249642 0.249642)
							(end 0.2794 0.1778)
						)
						(arc
							(start 0.2794 -0.1778)
							(mid 0.249642 -0.249642)
							(end 0.1778 -0.2794)
						)
					)
					(width 0)
					(fill yes)
				)
			)
		)
	)
	(footprint ""
		(layer "F.Cu")
		(at 33.782 -116.713)
		(property "Reference" "R20"
			(at 0 0 0)
			(layer "F.SilkS")
			(hide yes)
			(effects
				(font
					(size 1.27 1.27)
				)
			)
		)
		(property "Value" "100R2F-L1-GP-U"
			(at 0.064008 -3.993896 0)
			(unlocked yes)
			(layer "F.Fab")
			(hide yes)
			(effects
				(font
					(size 1.016 1.016)
					(thickness 0.1524)
				)
			)
		)
		(property "Device Type" "R402H14"
			(at 0.064008 -5.517896 0)
			(unlocked yes)
			(layer "F.Fab")
			(hide yes)
			(effects
				(font
					(size 1.016 1.016)
					(thickness 0.1524)
				)
			)
		)
		(duplicate_pad_numbers_are_jumpers no)
		(fp_line
			(start -0.508 -0.9398)
			(end -0.508 0.9398)
			(stroke
				(width 0.1524)
				(type default)
			)
			(layer "F.SilkS")
		)
		(fp_line
			(start 0.508 -0.9398)
			(end -0.508 -0.9398)
			(stroke
				(width 0.1524)
				(type default)
			)
			(layer "F.SilkS")
		)
		(fp_rect
			(start -0.508 0.9398)
			(end 0.508 -0.9398)
			(stroke
				(width 0)
				(type default)
			)
			(fill no)
			(layer "F.CrtYd")
		)
		(fp_rect
			(start -0.508 0.9398)
			(end 0.508 -0.9398)
			(stroke
				(width 0)
				(type default)
			)
			(fill no)
			(layer "F.Fab")
		)
		(pad "1" smd custom
			(at 0 -0.4445)
			(size 0.1397 0.1397)
			(layers "F.Cu" "F.Mask" "F.Paste")
			(net "PMC_PLX_BOARD")
			(options
				(clearance outline)
				(anchor circle)
			)
			(primitives
				(gr_poly
					(pts
						(arc
							(start -0.1778 -0.2794)
							(mid -0.249642 -0.249642)
							(end -0.2794 -0.1778)
						)
						(arc
							(start -0.2794 0.1778)
							(mid -0.249642 0.249642)
							(end -0.1778 0.2794)
						)
						(arc
							(start 0.1778 0.2794)
							(mid 0.249642 0.249642)
							(end 0.2794 0.1778)
						)
						(arc
							(start 0.2794 -0.1778)
							(mid 0.249642 -0.249642)
							(end 0.1778 -0.2794)
						)
					)
					(width 0)
					(fill yes)
				)
			)
		)
		(pad "2" smd custom
			(at 0 0.4445)
			(size 0.1397 0.1397)
			(layers "F.Cu" "F.Mask" "F.Paste")
			(net "GND")
			(options
				(clearance outline)
				(anchor circle)
			)
			(primitives
				(gr_poly
					(pts
						(arc
							(start -0.1778 -0.2794)
							(mid -0.249642 -0.249642)
							(end -0.2794 -0.1778)
						)
						(arc
							(start -0.2794 0.1778)
							(mid -0.249642 0.249642)
							(end -0.1778 0.2794)
						)
						(arc
							(start 0.1778 0.2794)
							(mid 0.249642 0.249642)
							(end 0.2794 0.1778)
						)
						(arc
							(start 0.2794 -0.1778)
							(mid 0.249642 -0.249642)
							(end 0.1778 -0.2794)
						)
					)
					(width 0)
					(fill yes)
				)
			)
		)
	)
	(footprint ""
		(layer "F.Cu")
		(at 175.4886 -53.8988 -90)
		(property "Reference" "R608"
			(at 0 0 270)
			(layer "F.SilkS")
			(hide yes)
			(effects
				(font
					(size 1.27 1.27)
				)
			)
		)
		(property "Value" "0R2J-2-GP"
			(at 0.064008 -3.993896 270)
			(unlocked yes)
			(layer "F.Fab")
			(hide yes)
			(effects
				(font
					(size 1.016 1.016)
					(thickness 0.1524)
				)
			)
		)
		(property "Device Type" "R402H16"
			(at 0.064008 -5.517896 270)
			(unlocked yes)
			(layer "F.Fab")
			(hide yes)
			(effects
				(font
					(size 1.016 1.016)
					(thickness 0.1524)
				)
			)
		)
		(duplicate_pad_numbers_are_jumpers no)
		(fp_line
			(start -0.508 -0.9398)
			(end -0.508 0.9398)
			(stroke
				(width 0.1524)
				(type default)
			)
			(layer "F.SilkS")
		)
		(fp_line
			(start 0.508 -0.9398)
			(end -0.508 -0.9398)
			(stroke
				(width 0.1524)
				(type default)
			)
			(layer "F.SilkS")
		)
		(fp_rect
			(start -0.508 0.9398)
			(end 0.508 -0.9398)
			(stroke
				(width 0)
				(type default)
			)
			(fill no)
			(layer "F.CrtYd")
		)
		(fp_rect
			(start -0.508 0.9398)
			(end 0.508 -0.9398)
			(stroke
				(width 0)
				(type default)
			)
			(fill no)
			(layer "F.Fab")
		)
		(pad "1" smd custom
			(at 0 -0.4445 270)
			(size 0.1397 0.1397)
			(layers "F.Cu" "F.Mask" "F.Paste")
			(net "VS3_LED_R")
			(options
				(clearance outline)
				(anchor circle)
			)
			(primitives
				(gr_poly
					(pts
						(arc
							(start -0.1778 -0.2794)
							(mid -0.249642 -0.249642)
							(end -0.2794 -0.1778)
						)
						(arc
							(start -0.2794 0.1778)
							(mid -0.249642 0.249642)
							(end -0.1778 0.2794)
						)
						(arc
							(start 0.1778 0.2794)
							(mid 0.249642 0.249642)
							(end 0.2794 0.1778)
						)
						(arc
							(start 0.2794 -0.1778)
							(mid 0.249642 -0.249642)
							(end 0.1778 -0.2794)
						)
					)
					(width 0)
					(fill yes)
				)
			)
		)
		(pad "2" smd custom
			(at 0 0.4445 270)
			(size 0.1397 0.1397)
			(layers "F.Cu" "F.Mask" "F.Paste")
			(net "VS3_LED")
			(options
				(clearance outline)
				(anchor circle)
			)
			(primitives
				(gr_poly
					(pts
						(arc
							(start -0.1778 -0.2794)
							(mid -0.249642 -0.249642)
							(end -0.2794 -0.1778)
						)
						(arc
							(start -0.2794 0.1778)
							(mid -0.249642 0.249642)
							(end -0.1778 0.2794)
						)
						(arc
							(start 0.1778 0.2794)
							(mid 0.249642 0.249642)
							(end 0.2794 0.1778)
						)
						(arc
							(start 0.2794 -0.1778)
							(mid 0.249642 -0.249642)
							(end 0.1778 -0.2794)
						)
					)
					(width 0)
					(fill yes)
				)
			)
		)
	)
	(footprint ""
		(layer "F.Cu")
		(at 36.842954 -164.702744 90)
		(property "Reference" "C180"
			(at 0 0 90)
			(layer "F.SilkS")
			(hide yes)
			(effects
				(font
					(size 1.27 1.27)
				)
			)
		)
		(property "Value" "SC1U10V2KX-4-GP"
			(at 1.1811 -2.7051 90)
			(unlocked yes)
			(layer "F.Fab")
			(hide yes)
			(effects
				(font
					(size 1.016 1.016)
					(thickness 0.1524)
				)
			)
		)
		(property "Device Type" "C402H22"
			(at 1.1811 -4.2291 90)
			(unlocked yes)
			(layer "F.Fab")
			(hide yes)
			(effects
				(font
					(size 1.016 1.016)
					(thickness 0.1524)
				)
			)
		)
		(duplicate_pad_numbers_are_jumpers no)
		(fp_rect
			(start -0.4318 0.9525)
			(end 0.4318 -0.9525)
			(stroke
				(width 0)
				(type default)
			)
			(fill no)
			(layer "F.CrtYd")
		)
		(fp_rect
			(start -0.4318 0.9525)
			(end 0.4318 -0.9525)
			(stroke
				(width 0)
				(type default)
			)
			(fill no)
			(layer "F.Fab")
		)
		(pad "1" smd custom
			(at 0 -0.4445 90)
			(size 0.1524 0.1524)
			(layers "F.Cu" "F.Mask" "F.Paste")
			(net "DDR_VREF")
			(options
				(clearance outline)
				(anchor circle)
			)
			(primitives
				(gr_poly
					(pts
						(arc
							(start 0.3048 -0.2032)
							(mid 0.275042 -0.275042)
							(end 0.2032 -0.3048)
						)
						(arc
							(start -0.2032 -0.3048)
							(mid -0.275042 -0.275042)
							(end -0.3048 -0.2032)
						)
						(arc
							(start -0.3048 0.2032)
							(mid -0.275042 0.275042)
							(end -0.2032 0.3048)
						)
						(arc
							(start 0.2032 0.3048)
							(mid 0.275042 0.275042)
							(end 0.3048 0.2032)
						)
					)
					(width 0)
					(fill yes)
				)
			)
		)
		(pad "2" smd custom
			(at 0 0.4445 90)
			(size 0.1524 0.1524)
			(layers "F.Cu" "F.Mask" "F.Paste")
			(net "GND")
			(options
				(clearance outline)
				(anchor circle)
			)
			(primitives
				(gr_poly
					(pts
						(arc
							(start 0.3048 -0.2032)
							(mid 0.275042 -0.275042)
							(end 0.2032 -0.3048)
						)
						(arc
							(start -0.2032 -0.3048)
							(mid -0.275042 -0.275042)
							(end -0.3048 -0.2032)
						)
						(arc
							(start -0.3048 0.2032)
							(mid -0.275042 0.275042)
							(end -0.2032 0.3048)
						)
						(arc
							(start 0.2032 0.3048)
							(mid 0.275042 0.275042)
							(end 0.3048 0.2032)
						)
					)
					(width 0)
					(fill yes)
				)
			)
		)
	)
	(footprint ""
		(layer "F.Cu")
		(at 340.995 -60.96 -90)
		(property "Reference" "PC175"
			(at 0 0 270)
			(layer "F.SilkS")
			(hide yes)
			(effects
				(font
					(size 1.27 1.27)
				)
			)
		)
		(property "Value" "SC10U25V5KX-GP"
			(at -0.0762 -6.1214 270)
			(unlocked yes)
			(layer "F.Fab")
			(hide yes)
			(effects
				(font
					(size 1.016 1.016)
					(thickness 0.1524)
				)
			)
		)
		(property "Device Type" "C805H56"
			(at -0.0762 -8.1534 270)
			(unlocked yes)
			(layer "F.Fab")
			(hide yes)
			(effects
				(font
					(size 1.016 1.016)
					(thickness 0.1524)
				)
			)
		)
		(duplicate_pad_numbers_are_jumpers no)
		(fp_line
			(start 0.635 0)
			(end -0.635 0)
			(stroke
				(width 0.508)
				(type default)
			)
			(layer "F.SilkS")
		)
		(fp_rect
			(start -0.9652 1.778)
			(end 0.9652 -1.778)
			(stroke
				(width 0)
				(type default)
			)
			(fill no)
			(layer "F.CrtYd")
		)
		(fp_poly
			(pts
				(xy -0.9652 -1.778) (xy 0.9652 -1.778) (xy 0.9652 1.778) (xy -0.9652 1.778)
			)
			(stroke
				(width 0)
				(type default)
			)
			(fill no)
			(layer "F.Fab")
		)
		(pad "1" smd rect
			(at 0 -0.9652 270)
			(size 1.397 1.143)
			(layers "F.Cu" "F.Mask" "F.Paste")
			(net "P0V9_E_VIN")
		)
		(pad "2" smd rect
			(at 0 0.9652 270)
			(size 1.397 1.143)
			(layers "F.Cu" "F.Mask" "F.Paste")
			(net "GND")
		)
	)
	(footprint ""
		(layer "F.Cu")
		(at 81.364836 -67.109594 180)
		(property "Reference" "U36"
			(at 0 0 180)
			(layer "F.SilkS")
			(hide yes)
			(effects
				(font
					(size 1.27 1.27)
				)
			)
		)
		(property "Value" "MX25L25635FMI-10G-GP"
			(at 0 -14.6812 180)
			(unlocked yes)
			(layer "F.Fab")
			(hide yes)
			(effects
				(font
					(size 1.016 1.016)
					(thickness 0.1524)
				)
			)
		)
		(property "Device Type" "SOIC16-6H105"
			(at 0 -16.2052 180)
			(unlocked yes)
			(layer "F.Fab")
			(hide yes)
			(effects
				(font
					(size 1.016 1.016)
					(thickness 0.1524)
				)
			)
		)
		(duplicate_pad_numbers_are_jumpers no)
		(fp_line
			(start 4.7498 3.2258)
			(end -5.588 3.2258)
			(stroke
				(width 0.1524)
				(type default)
			)
			(layer "F.SilkS")
		)
		(fp_line
			(start 4.7498 -3.2258)
			(end 4.7498 3.2258)
			(stroke
				(width 0.1524)
				(type default)
			)
			(layer "F.SilkS")
		)
		(fp_line
			(start -5.08762 0)
			(end -5.588 0.50038)
			(stroke
				(width 0.1524)
				(type default)
			)
			(layer "F.SilkS")
		)
		(fp_line
			(start -5.4102 3.2258)
			(end -5.4102 5.7912)
			(stroke
				(width 0.508)
				(type default)
			)
			(layer "F.SilkS")
		)
		(fp_line
			(start -5.588 3.2258)
			(end -5.588 -3.2258)
			(stroke
				(width 0.1524)
				(type default)
			)
			(layer "F.SilkS")
		)
		(fp_line
			(start -5.588 -0.50038)
			(end -5.08762 0)
			(stroke
				(width 0.1524)
				(type default)
			)
			(layer "F.SilkS")
		)
		(fp_line
			(start -5.588 -3.2258)
			(end 4.7498 -3.2258)
			(stroke
				(width 0.1524)
				(type default)
			)
			(layer "F.SilkS")
		)
		(fp_poly
			(pts
				(xy -4.764786 -3.2258) (xy 4.7625 -3.2258) (xy 4.7625 3.2258) (xy -4.764786 3.2258)
			)
			(stroke
				(width 0)
				(type default)
			)
			(fill yes)
			(layer "F.SilkS")
		)
		(fp_poly
			(pts
				(xy -5.6642 6.0452) (xy 5.6642 6.0452) (xy 5.6642 -6.0452) (xy -5.6642 -6.0452)
			)
			(stroke
				(width 0)
				(type default)
			)
			(fill no)
			(layer "F.CrtYd")
		)
		(fp_poly
			(pts
				(xy -5.6642 -6.0452) (xy 5.6642 -6.0452) (xy 5.6642 6.0452) (xy -5.6642 6.0452)
			)
			(stroke
				(width 0)
				(type default)
			)
			(fill no)
			(layer "F.Fab")
		)
		(pad "1" smd rect
			(at -4.445 4.71805 180)
			(size 0.635 1.651)
			(layers "F.Cu" "F.Mask" "F.Paste")
			(net "SEC_SPI_HOLD_N")
		)
		(pad "2" smd rect
			(at -3.175 4.71805 180)
			(size 0.635 1.651)
			(layers "F.Cu" "F.Mask" "F.Paste")
			(net "P3V3_STBY")
		)
		(pad "3" smd rect
			(at -1.905 4.71805 180)
			(size 0.635 1.651)
			(layers "F.Cu" "F.Mask" "F.Paste")
			(net "SEC_RST_N_R")
		)
		(pad "4" smd rect
			(at -0.635 4.71805 180)
			(size 0.635 1.651)
			(layers "F.Cu" "F.Mask" "F.Paste")
			(net "Net_25")
		)
		(pad "5" smd rect
			(at 0.635 4.71805 180)
			(size 0.635 1.651)
			(layers "F.Cu" "F.Mask" "F.Paste")
			(net "Net_24")
		)
		(pad "6" smd rect
			(at 1.905 4.71805 180)
			(size 0.635 1.651)
			(layers "F.Cu" "F.Mask" "F.Paste")
			(net "Net_23")
		)
		(pad "7" smd rect
			(at 3.175 4.71805 180)
			(size 0.635 1.651)
			(layers "F.Cu" "F.Mask" "F.Paste")
			(net "FLA_CS_R")
		)
		(pad "8" smd rect
			(at 4.445 4.71805 180)
			(size 0.635 1.651)
			(layers "F.Cu" "F.Mask" "F.Paste")
			(net "ROMD2_SEC")
		)
		(pad "9" smd rect
			(at 4.445 -4.71805 180)
			(size 0.635 1.651)
			(layers "F.Cu" "F.Mask" "F.Paste")
			(net "FLA1_WPN")
		)
		(pad "10" smd rect
			(at 3.175 -4.71805 180)
			(size 0.635 1.651)
			(layers "F.Cu" "F.Mask" "F.Paste")
			(net "GND")
		)
		(pad "11" smd rect
			(at 1.905 -4.71805 180)
			(size 0.635 1.651)
			(layers "F.Cu" "F.Mask" "F.Paste")
			(net "Net_22")
		)
		(pad "12" smd rect
			(at 0.635 -4.71805 180)
			(size 0.635 1.651)
			(layers "F.Cu" "F.Mask" "F.Paste")
			(net "Net_21")
		)
		(pad "13" smd rect
			(at -0.635 -4.71805 180)
			(size 0.635 1.651)
			(layers "F.Cu" "F.Mask" "F.Paste")
			(net "Net_20")
		)
		(pad "14" smd rect
			(at -1.905 -4.71805 180)
			(size 0.635 1.651)
			(layers "F.Cu" "F.Mask" "F.Paste")
			(net "Net_19")
		)
		(pad "15" smd rect
			(at -3.175 -4.71805 180)
			(size 0.635 1.651)
			(layers "F.Cu" "F.Mask" "F.Paste")
			(net "ROMD1_R")
		)
		(pad "16" smd rect
			(at -4.445 -4.71805 180)
			(size 0.635 1.651)
			(layers "F.Cu" "F.Mask" "F.Paste")
			(net "ROMD0_R")
		)
	)
	(footprint ""
		(layer "F.Cu")
		(at 50.251614 -109.764068)
		(property "Reference" "R330"
			(at 0 0 0)
			(layer "F.SilkS")
			(hide yes)
			(effects
				(font
					(size 1.27 1.27)
				)
			)
		)
		(property "Value" "4K7R2F-GP"
			(at 0.064008 -3.993896 0)
			(unlocked yes)
			(layer "F.Fab")
			(hide yes)
			(effects
				(font
					(size 1.016 1.016)
					(thickness 0.1524)
				)
			)
		)
		(property "Device Type" "R402H16"
			(at 0.064008 -5.517896 0)
			(unlocked yes)
			(layer "F.Fab")
			(hide yes)
			(effects
				(font
					(size 1.016 1.016)
					(thickness 0.1524)
				)
			)
		)
		(duplicate_pad_numbers_are_jumpers no)
		(fp_line
			(start -0.508 -0.9398)
			(end -0.508 0.9398)
			(stroke
				(width 0.1524)
				(type default)
			)
			(layer "F.SilkS")
		)
		(fp_line
			(start 0.508 -0.9398)
			(end -0.508 -0.9398)
			(stroke
				(width 0.1524)
				(type default)
			)
			(layer "F.SilkS")
		)
		(fp_rect
			(start -0.508 0.9398)
			(end 0.508 -0.9398)
			(stroke
				(width 0)
				(type default)
			)
			(fill no)
			(layer "F.CrtYd")
		)
		(fp_rect
			(start -0.508 0.9398)
			(end 0.508 -0.9398)
			(stroke
				(width 0)
				(type default)
			)
			(fill no)
			(layer "F.Fab")
		)
		(pad "1" smd custom
			(at 0 -0.4445)
			(size 0.1397 0.1397)
			(layers "F.Cu" "F.Mask" "F.Paste")
			(net "P3V3_STBY")
			(options
				(clearance outline)
				(anchor circle)
			)
			(primitives
				(gr_poly
					(pts
						(arc
							(start -0.1778 -0.2794)
							(mid -0.249642 -0.249642)
							(end -0.2794 -0.1778)
						)
						(arc
							(start -0.2794 0.1778)
							(mid -0.249642 0.249642)
							(end -0.1778 0.2794)
						)
						(arc
							(start 0.1778 0.2794)
							(mid 0.249642 0.249642)
							(end 0.2794 0.1778)
						)
						(arc
							(start 0.2794 -0.1778)
							(mid 0.249642 -0.249642)
							(end 0.1778 -0.2794)
						)
					)
					(width 0)
					(fill yes)
				)
			)
		)
		(pad "2" smd custom
			(at 0 0.4445)
			(size 0.1397 0.1397)
			(layers "F.Cu" "F.Mask" "F.Paste")
			(net "I2C7_LS_G1")
			(options
				(clearance outline)
				(anchor circle)
			)
			(primitives
				(gr_poly
					(pts
						(arc
							(start -0.1778 -0.2794)
							(mid -0.249642 -0.249642)
							(end -0.2794 -0.1778)
						)
						(arc
							(start -0.2794 0.1778)
							(mid -0.249642 0.249642)
							(end -0.1778 0.2794)
						)
						(arc
							(start 0.1778 0.2794)
							(mid 0.249642 0.249642)
							(end 0.2794 0.1778)
						)
						(arc
							(start 0.2794 -0.1778)
							(mid 0.249642 -0.249642)
							(end 0.1778 -0.2794)
						)
					)
					(width 0)
					(fill yes)
				)
			)
		)
	)
	(footprint ""
		(layer "F.Cu")
		(at 116.604034 -30.617414 180)
		(property "Reference" "C132"
			(at 0 0 180)
			(layer "F.SilkS")
			(hide yes)
			(effects
				(font
					(size 1.27 1.27)
				)
			)
		)
		(property "Value" "SCD047U25V2KX-GP"
			(at 1.1811 -2.7051 180)
			(unlocked yes)
			(layer "F.Fab")
			(hide yes)
			(effects
				(font
					(size 1.016 1.016)
					(thickness 0.1524)
				)
			)
		)
		(property "Device Type" "C402H22"
			(at 1.1811 -4.2291 180)
			(unlocked yes)
			(layer "F.Fab")
			(hide yes)
			(effects
				(font
					(size 1.016 1.016)
					(thickness 0.1524)
				)
			)
		)
		(duplicate_pad_numbers_are_jumpers no)
		(fp_rect
			(start -0.4318 0.9525)
			(end 0.4318 -0.9525)
			(stroke
				(width 0)
				(type default)
			)
			(fill no)
			(layer "F.CrtYd")
		)
		(fp_rect
			(start -0.4318 0.9525)
			(end 0.4318 -0.9525)
			(stroke
				(width 0)
				(type default)
			)
			(fill no)
			(layer "F.Fab")
		)
		(pad "1" smd custom
			(at 0 -0.4445 180)
			(size 0.1524 0.1524)
			(layers "F.Cu" "F.Mask" "F.Paste")
			(net "P3V3_STBY")
			(options
				(clearance outline)
				(anchor circle)
			)
			(primitives
				(gr_poly
					(pts
						(arc
							(start 0.3048 -0.2032)
							(mid 0.275042 -0.275042)
							(end 0.2032 -0.3048)
						)
						(arc
							(start -0.2032 -0.3048)
							(mid -0.275042 -0.275042)
							(end -0.3048 -0.2032)
						)
						(arc
							(start -0.3048 0.2032)
							(mid -0.275042 0.275042)
							(end -0.2032 0.3048)
						)
						(arc
							(start 0.2032 0.3048)
							(mid 0.275042 0.275042)
							(end 0.3048 0.2032)
						)
					)
					(width 0)
					(fill yes)
				)
			)
		)
		(pad "2" smd custom
			(at 0 0.4445 180)
			(size 0.1524 0.1524)
			(layers "F.Cu" "F.Mask" "F.Paste")
			(net "GND")
			(options
				(clearance outline)
				(anchor circle)
			)
			(primitives
				(gr_poly
					(pts
						(arc
							(start 0.3048 -0.2032)
							(mid 0.275042 -0.275042)
							(end 0.2032 -0.3048)
						)
						(arc
							(start -0.2032 -0.3048)
							(mid -0.275042 -0.275042)
							(end -0.3048 -0.2032)
						)
						(arc
							(start -0.3048 0.2032)
							(mid -0.275042 0.275042)
							(end -0.2032 0.3048)
						)
						(arc
							(start 0.2032 0.3048)
							(mid 0.275042 0.275042)
							(end 0.3048 0.2032)
						)
					)
					(width 0)
					(fill yes)
				)
			)
		)
	)
	(footprint ""
		(layer "F.Cu")
		(at 221.845124 -190.582296)
		(property "Reference" "R7965"
			(at 0 0 0)
			(layer "F.SilkS")
			(hide yes)
			(effects
				(font
					(size 1.27 1.27)
				)
			)
		)
		(property "Value" "0R2J-2-GP"
			(at 0.064008 -3.993896 0)
			(unlocked yes)
			(layer "F.Fab")
			(hide yes)
			(effects
				(font
					(size 1.016 1.016)
					(thickness 0.1524)
				)
			)
		)
		(property "Device Type" "R402H16"
			(at 0.064008 -5.517896 0)
			(unlocked yes)
			(layer "F.Fab")
			(hide yes)
			(effects
				(font
					(size 1.016 1.016)
					(thickness 0.1524)
				)
			)
		)
		(duplicate_pad_numbers_are_jumpers no)
		(fp_line
			(start -0.508 -0.9398)
			(end -0.508 0.9398)
			(stroke
				(width 0.1524)
				(type default)
			)
			(layer "F.SilkS")
		)
		(fp_line
			(start 0.508 -0.9398)
			(end -0.508 -0.9398)
			(stroke
				(width 0.1524)
				(type default)
			)
			(layer "F.SilkS")
		)
		(fp_rect
			(start -0.508 0.9398)
			(end 0.508 -0.9398)
			(stroke
				(width 0)
				(type default)
			)
			(fill no)
			(layer "F.CrtYd")
		)
		(fp_rect
			(start -0.508 0.9398)
			(end 0.508 -0.9398)
			(stroke
				(width 0)
				(type default)
			)
			(fill no)
			(layer "F.Fab")
		)
		(pad "1" smd custom
			(at 0 -0.4445)
			(size 0.1397 0.1397)
			(layers "F.Cu" "F.Mask" "F.Paste")
			(net "SSD_PWREN3")
			(options
				(clearance outline)
				(anchor circle)
			)
			(primitives
				(gr_poly
					(pts
						(arc
							(start -0.1778 -0.2794)
							(mid -0.249642 -0.249642)
							(end -0.2794 -0.1778)
						)
						(arc
							(start -0.2794 0.1778)
							(mid -0.249642 0.249642)
							(end -0.1778 0.2794)
						)
						(arc
							(start 0.1778 0.2794)
							(mid 0.249642 0.249642)
							(end 0.2794 0.1778)
						)
						(arc
							(start 0.2794 -0.1778)
							(mid 0.249642 -0.249642)
							(end 0.1778 -0.2794)
						)
					)
					(width 0)
					(fill yes)
				)
			)
		)
		(pad "2" smd custom
			(at 0 0.4445)
			(size 0.1397 0.1397)
			(layers "F.Cu" "F.Mask" "F.Paste")
			(net "SSD_PWREN3_R")
			(options
				(clearance outline)
				(anchor circle)
			)
			(primitives
				(gr_poly
					(pts
						(arc
							(start -0.1778 -0.2794)
							(mid -0.249642 -0.249642)
							(end -0.2794 -0.1778)
						)
						(arc
							(start -0.2794 0.1778)
							(mid -0.249642 0.249642)
							(end -0.1778 0.2794)
						)
						(arc
							(start 0.1778 0.2794)
							(mid 0.249642 0.249642)
							(end 0.2794 0.1778)
						)
						(arc
							(start 0.2794 -0.1778)
							(mid 0.249642 -0.249642)
							(end 0.1778 -0.2794)
						)
					)
					(width 0)
					(fill yes)
				)
			)
		)
	)
	(footprint ""
		(layer "F.Cu")
		(at 181.61 -24.511 -90)
		(property "Reference" "C409"
			(at 0 0 270)
			(layer "F.SilkS")
			(hide yes)
			(effects
				(font
					(size 1.27 1.27)
				)
			)
		)
		(property "Value" "SCD22U10V2KX-1GP"
			(at 1.1811 -2.7051 270)
			(unlocked yes)
			(layer "F.Fab")
			(hide yes)
			(effects
				(font
					(size 1.016 1.016)
					(thickness 0.1524)
				)
			)
		)
		(property "Device Type" "C402H22"
			(at 1.1811 -4.2291 270)
			(unlocked yes)
			(layer "F.Fab")
			(hide yes)
			(effects
				(font
					(size 1.016 1.016)
					(thickness 0.1524)
				)
			)
		)
		(duplicate_pad_numbers_are_jumpers no)
		(fp_rect
			(start -0.4318 0.9525)
			(end 0.4318 -0.9525)
			(stroke
				(width 0)
				(type default)
			)
			(fill no)
			(layer "F.CrtYd")
		)
		(fp_rect
			(start -0.4318 0.9525)
			(end 0.4318 -0.9525)
			(stroke
				(width 0)
				(type default)
			)
			(fill no)
			(layer "F.Fab")
		)
		(pad "1" smd custom
			(at 0 -0.4445 270)
			(size 0.1524 0.1524)
			(layers "F.Cu" "F.Mask" "F.Paste")
			(net "PCIE_TX_CAP_P94")
			(options
				(clearance outline)
				(anchor circle)
			)
			(primitives
				(gr_poly
					(pts
						(arc
							(start 0.3048 -0.2032)
							(mid 0.275042 -0.275042)
							(end 0.2032 -0.3048)
						)
						(arc
							(start -0.2032 -0.3048)
							(mid -0.275042 -0.275042)
							(end -0.3048 -0.2032)
						)
						(arc
							(start -0.3048 0.2032)
							(mid -0.275042 0.275042)
							(end -0.2032 0.3048)
						)
						(arc
							(start 0.2032 0.3048)
							(mid 0.275042 0.275042)
							(end 0.3048 0.2032)
						)
					)
					(width 0)
					(fill yes)
				)
			)
		)
		(pad "2" smd custom
			(at 0 0.4445 270)
			(size 0.1524 0.1524)
			(layers "F.Cu" "F.Mask" "F.Paste")
			(net "PCIE_TX_P94")
			(options
				(clearance outline)
				(anchor circle)
			)
			(primitives
				(gr_poly
					(pts
						(arc
							(start 0.3048 -0.2032)
							(mid 0.275042 -0.275042)
							(end 0.2032 -0.3048)
						)
						(arc
							(start -0.2032 -0.3048)
							(mid -0.275042 -0.275042)
							(end -0.3048 -0.2032)
						)
						(arc
							(start -0.3048 0.2032)
							(mid -0.275042 0.275042)
							(end -0.2032 0.3048)
						)
						(arc
							(start 0.2032 0.3048)
							(mid 0.275042 0.275042)
							(end 0.3048 0.2032)
						)
					)
					(width 0)
					(fill yes)
				)
			)
		)
	)
	(footprint ""
		(layer "F.Cu")
		(at 167.408098 -212.420454 180)
		(property "Reference" "C161"
			(at 0 0 180)
			(layer "F.SilkS")
			(hide yes)
			(effects
				(font
					(size 1.27 1.27)
				)
			)
		)
		(property "Value" "SCD22U10V2KX-1GP"
			(at 1.1811 -2.7051 180)
			(unlocked yes)
			(layer "F.Fab")
			(hide yes)
			(effects
				(font
					(size 1.016 1.016)
					(thickness 0.1524)
				)
			)
		)
		(property "Device Type" "C402H22"
			(at 1.1811 -4.2291 180)
			(unlocked yes)
			(layer "F.Fab")
			(hide yes)
			(effects
				(font
					(size 1.016 1.016)
					(thickness 0.1524)
				)
			)
		)
		(duplicate_pad_numbers_are_jumpers no)
		(fp_rect
			(start -0.4318 0.9525)
			(end 0.4318 -0.9525)
			(stroke
				(width 0)
				(type default)
			)
			(fill no)
			(layer "F.CrtYd")
		)
		(fp_rect
			(start -0.4318 0.9525)
			(end 0.4318 -0.9525)
			(stroke
				(width 0)
				(type default)
			)
			(fill no)
			(layer "F.Fab")
		)
		(pad "1" smd custom
			(at 0 -0.4445 180)
			(size 0.1524 0.1524)
			(layers "F.Cu" "F.Mask" "F.Paste")
			(net "PCIE_TX_CAP_N51")
			(options
				(clearance outline)
				(anchor circle)
			)
			(primitives
				(gr_poly
					(pts
						(arc
							(start 0.3048 -0.2032)
							(mid 0.275042 -0.275042)
							(end 0.2032 -0.3048)
						)
						(arc
							(start -0.2032 -0.3048)
							(mid -0.275042 -0.275042)
							(end -0.3048 -0.2032)
						)
						(arc
							(start -0.3048 0.2032)
							(mid -0.275042 0.275042)
							(end -0.2032 0.3048)
						)
						(arc
							(start 0.2032 0.3048)
							(mid 0.275042 0.275042)
							(end 0.3048 0.2032)
						)
					)
					(width 0)
					(fill yes)
				)
			)
		)
		(pad "2" smd custom
			(at 0 0.4445 180)
			(size 0.1524 0.1524)
			(layers "F.Cu" "F.Mask" "F.Paste")
			(net "PCIE_TX_N51")
			(options
				(clearance outline)
				(anchor circle)
			)
			(primitives
				(gr_poly
					(pts
						(arc
							(start 0.3048 -0.2032)
							(mid 0.275042 -0.275042)
							(end 0.2032 -0.3048)
						)
						(arc
							(start -0.2032 -0.3048)
							(mid -0.275042 -0.275042)
							(end -0.3048 -0.2032)
						)
						(arc
							(start -0.3048 0.2032)
							(mid -0.275042 0.275042)
							(end -0.2032 0.3048)
						)
						(arc
							(start 0.2032 0.3048)
							(mid 0.275042 0.275042)
							(end 0.3048 0.2032)
						)
					)
					(width 0)
					(fill yes)
				)
			)
		)
	)
	(footprint ""
		(layer "F.Cu")
		(at 64.389 -89.2556 -90)
		(property "Reference" "Q10"
			(at 0 0 270)
			(layer "F.SilkS")
			(hide yes)
			(effects
				(font
					(size 1.27 1.27)
				)
			)
		)
		(property "Value" "2N7002DW-7F-GP"
			(at -2.3622 -8.2042 270)
			(unlocked yes)
			(layer "F.Fab")
			(hide yes)
			(effects
				(font
					(size 1.016 1.016)
					(thickness 0.1524)
				)
			)
		)
		(property "Device Type" "SOT-363H44"
			(at -2.3622 -10.1092 270)
			(unlocked yes)
			(layer "F.Fab")
			(hide yes)
			(effects
				(font
					(size 1.016 1.016)
					(thickness 0.1524)
				)
			)
		)
		(duplicate_pad_numbers_are_jumpers no)
		(fp_line
			(start -1.4478 1.7018)
			(end 1.4478 1.7018)
			(stroke
				(width 0.1524)
				(type default)
			)
			(layer "F.SilkS")
		)
		(fp_line
			(start 1.4478 1.7018)
			(end 1.4478 -1.7018)
			(stroke
				(width 0.1524)
				(type default)
			)
			(layer "F.SilkS")
		)
		(fp_line
			(start -1.27 1.524)
			(end -1.27 0.6604)
			(stroke
				(width 0.4826)
				(type default)
			)
			(layer "F.SilkS")
		)
		(fp_line
			(start -1.4478 -1.7018)
			(end -1.4478 1.7018)
			(stroke
				(width 0.1524)
				(type default)
			)
			(layer "F.SilkS")
		)
		(fp_line
			(start 1.4478 -1.7018)
			(end -1.4478 -1.7018)
			(stroke
				(width 0.1524)
				(type default)
			)
			(layer "F.SilkS")
		)
		(fp_poly
			(pts
				(xy -1.524 -1.778) (xy 1.524 -1.778) (xy 1.524 1.778) (xy -1.524 1.778)
			)
			(stroke
				(width 0)
				(type default)
			)
			(fill no)
			(layer "F.CrtYd")
		)
		(fp_poly
			(pts
				(xy -1.524 -1.778) (xy 1.524 -1.778) (xy 1.524 1.778) (xy -1.524 1.778)
			)
			(stroke
				(width 0)
				(type default)
			)
			(fill no)
			(layer "F.Fab")
		)
		(pad "1" smd rect
			(at -0.65024 0.9398 270)
			(size 0.4064 1.016)
			(layers "F.Cu" "F.Mask" "F.Paste")
			(net "GND")
		)
		(pad "2" smd rect
			(at 0 0.9398 270)
			(size 0.4064 1.016)
			(layers "F.Cu" "F.Mask" "F.Paste")
			(net "INVERTER_G2")
		)
		(pad "3" smd rect
			(at 0.65024 0.9398 270)
			(size 0.4064 1.016)
			(layers "F.Cu" "F.Mask" "F.Paste")
			(net "INVERTER_G2")
		)
		(pad "4" smd rect
			(at 0.65024 -0.9398 270)
			(size 0.4064 1.016)
			(layers "F.Cu" "F.Mask" "F.Paste")
			(net "GND")
		)
		(pad "5" smd rect
			(at 0 -0.9398 270)
			(size 0.4064 1.016)
			(layers "F.Cu" "F.Mask" "F.Paste")
			(net "INVERTER_G1")
		)
		(pad "6" smd rect
			(at -0.65024 -0.9398 270)
			(size 0.4064 1.016)
			(layers "F.Cu" "F.Mask" "F.Paste")
			(net "HB_OUT")
		)
	)
	(footprint ""
		(layer "F.Cu")
		(at 39.2938 -117.1194)
		(property "Reference" "TP325"
			(at 0 0 0)
			(layer "F.SilkS")
			(hide yes)
			(effects
				(font
					(size 1.27 1.27)
				)
			)
		)
		(property "Value" "TPAD28-2-GP"
			(at -0.0127 -1.6637 0)
			(unlocked yes)
			(layer "F.Fab")
			(hide yes)
			(effects
				(font
					(size 1.016 1.016)
					(thickness 0.1524)
				)
			)
		)
		(property "Device Type" "TPAD28"
			(at -0.0127 -3.1877 0)
			(unlocked yes)
			(layer "F.Fab")
			(hide yes)
			(effects
				(font
					(size 1.016 1.016)
					(thickness 0.1524)
				)
			)
		)
		(duplicate_pad_numbers_are_jumpers no)
		(fp_poly
			(pts
				(arc
					(start 0.3556 0)
					(mid -0.3556 0)
					(end 0.3556 0)
				)
			)
			(stroke
				(width 0)
				(type default)
			)
			(fill no)
			(layer "F.CrtYd")
		)
		(fp_poly
			(pts
				(arc
					(start 0.6096 0)
					(mid -0.6096 0)
					(end 0.6096 0)
				)
			)
			(stroke
				(width 0)
				(type default)
			)
			(fill no)
			(layer "F.Fab")
		)
		(pad "1" smd circle
			(at 0 0)
			(size 0.7112 0.7112)
			(layers "F.Cu" "F.Mask" "F.Paste")
			(net "TP_GPIOU0")
		)
	)
	(footprint ""
		(layer "F.Cu")
		(at 7.5692 -81.5848 90)
		(property "Reference" "C233"
			(at 0 0 90)
			(layer "F.SilkS")
			(hide yes)
			(effects
				(font
					(size 1.27 1.27)
				)
			)
		)
		(property "Value" "SC1U10V2KX-4-GP"
			(at 1.1811 -2.7051 90)
			(unlocked yes)
			(layer "F.Fab")
			(hide yes)
			(effects
				(font
					(size 1.016 1.016)
					(thickness 0.1524)
				)
			)
		)
		(property "Device Type" "C402H22"
			(at 1.1811 -4.2291 90)
			(unlocked yes)
			(layer "F.Fab")
			(hide yes)
			(effects
				(font
					(size 1.016 1.016)
					(thickness 0.1524)
				)
			)
		)
		(duplicate_pad_numbers_are_jumpers no)
		(fp_rect
			(start -0.4318 0.9525)
			(end 0.4318 -0.9525)
			(stroke
				(width 0)
				(type default)
			)
			(fill no)
			(layer "F.CrtYd")
		)
		(fp_rect
			(start -0.4318 0.9525)
			(end 0.4318 -0.9525)
			(stroke
				(width 0)
				(type default)
			)
			(fill no)
			(layer "F.Fab")
		)
		(pad "1" smd custom
			(at 0 -0.4445 90)
			(size 0.1524 0.1524)
			(layers "F.Cu" "F.Mask" "F.Paste")
			(net "P3V3_STBY")
			(options
				(clearance outline)
				(anchor circle)
			)
			(primitives
				(gr_poly
					(pts
						(arc
							(start 0.3048 -0.2032)
							(mid 0.275042 -0.275042)
							(end 0.2032 -0.3048)
						)
						(arc
							(start -0.2032 -0.3048)
							(mid -0.275042 -0.275042)
							(end -0.3048 -0.2032)
						)
						(arc
							(start -0.3048 0.2032)
							(mid -0.275042 0.275042)
							(end -0.2032 0.3048)
						)
						(arc
							(start 0.2032 0.3048)
							(mid 0.275042 0.275042)
							(end 0.3048 0.2032)
						)
					)
					(width 0)
					(fill yes)
				)
			)
		)
		(pad "2" smd custom
			(at 0 0.4445 90)
			(size 0.1524 0.1524)
			(layers "F.Cu" "F.Mask" "F.Paste")
			(net "GND")
			(options
				(clearance outline)
				(anchor circle)
			)
			(primitives
				(gr_poly
					(pts
						(arc
							(start 0.3048 -0.2032)
							(mid 0.275042 -0.275042)
							(end 0.2032 -0.3048)
						)
						(arc
							(start -0.2032 -0.3048)
							(mid -0.275042 -0.275042)
							(end -0.3048 -0.2032)
						)
						(arc
							(start -0.3048 0.2032)
							(mid -0.275042 0.275042)
							(end -0.2032 0.3048)
						)
						(arc
							(start 0.2032 0.3048)
							(mid 0.275042 0.275042)
							(end 0.3048 0.2032)
						)
					)
					(width 0)
					(fill yes)
				)
			)
		)
	)
	(footprint ""
		(layer "F.Cu")
		(at 302.49749 -33.540192)
		(property "Reference" "C24"
			(at 0 0 0)
			(layer "F.SilkS")
			(hide yes)
			(effects
				(font
					(size 1.27 1.27)
				)
			)
		)
		(property "Value" "SCD22U10V2KX-1GP"
			(at 1.1811 -2.7051 0)
			(unlocked yes)
			(layer "F.Fab")
			(hide yes)
			(effects
				(font
					(size 1.016 1.016)
					(thickness 0.1524)
				)
			)
		)
		(property "Device Type" "C402H22"
			(at 1.1811 -4.2291 0)
			(unlocked yes)
			(layer "F.Fab")
			(hide yes)
			(effects
				(font
					(size 1.016 1.016)
					(thickness 0.1524)
				)
			)
		)
		(duplicate_pad_numbers_are_jumpers no)
		(fp_rect
			(start -0.4318 0.9525)
			(end 0.4318 -0.9525)
			(stroke
				(width 0)
				(type default)
			)
			(fill no)
			(layer "F.CrtYd")
		)
		(fp_rect
			(start -0.4318 0.9525)
			(end 0.4318 -0.9525)
			(stroke
				(width 0)
				(type default)
			)
			(fill no)
			(layer "F.Fab")
		)
		(pad "1" smd custom
			(at 0 -0.4445)
			(size 0.1524 0.1524)
			(layers "F.Cu" "F.Mask" "F.Paste")
			(net "PCIE_TX_CAP_N6")
			(options
				(clearance outline)
				(anchor circle)
			)
			(primitives
				(gr_poly
					(pts
						(arc
							(start 0.3048 -0.2032)
							(mid 0.275042 -0.275042)
							(end 0.2032 -0.3048)
						)
						(arc
							(start -0.2032 -0.3048)
							(mid -0.275042 -0.275042)
							(end -0.3048 -0.2032)
						)
						(arc
							(start -0.3048 0.2032)
							(mid -0.275042 0.275042)
							(end -0.2032 0.3048)
						)
						(arc
							(start 0.2032 0.3048)
							(mid 0.275042 0.275042)
							(end 0.3048 0.2032)
						)
					)
					(width 0)
					(fill yes)
				)
			)
		)
		(pad "2" smd custom
			(at 0 0.4445)
			(size 0.1524 0.1524)
			(layers "F.Cu" "F.Mask" "F.Paste")
			(net "PCIE_TX_N6")
			(options
				(clearance outline)
				(anchor circle)
			)
			(primitives
				(gr_poly
					(pts
						(arc
							(start 0.3048 -0.2032)
							(mid 0.275042 -0.275042)
							(end 0.2032 -0.3048)
						)
						(arc
							(start -0.2032 -0.3048)
							(mid -0.275042 -0.275042)
							(end -0.3048 -0.2032)
						)
						(arc
							(start -0.3048 0.2032)
							(mid -0.275042 0.275042)
							(end -0.2032 0.3048)
						)
						(arc
							(start 0.2032 0.3048)
							(mid 0.275042 0.275042)
							(end 0.3048 0.2032)
						)
					)
					(width 0)
					(fill yes)
				)
			)
		)
	)
	(footprint ""
		(layer "F.Cu")
		(at 59.182 -42.926 -90)
		(property "Reference" "PC33"
			(at 0 0 270)
			(layer "F.SilkS")
			(hide yes)
			(effects
				(font
					(size 1.27 1.27)
				)
			)
		)
		(property "Value" "SC10U25V5KX-GP"
			(at -0.0762 -6.1214 270)
			(unlocked yes)
			(layer "F.Fab")
			(hide yes)
			(effects
				(font
					(size 1.016 1.016)
					(thickness 0.1524)
				)
			)
		)
		(property "Device Type" "C805H56"
			(at -0.0762 -8.1534 270)
			(unlocked yes)
			(layer "F.Fab")
			(hide yes)
			(effects
				(font
					(size 1.016 1.016)
					(thickness 0.1524)
				)
			)
		)
		(duplicate_pad_numbers_are_jumpers no)
		(fp_line
			(start 0.635 0)
			(end -0.635 0)
			(stroke
				(width 0.508)
				(type default)
			)
			(layer "F.SilkS")
		)
		(fp_rect
			(start -0.9652 1.778)
			(end 0.9652 -1.778)
			(stroke
				(width 0)
				(type default)
			)
			(fill no)
			(layer "F.CrtYd")
		)
		(fp_poly
			(pts
				(xy -0.9652 -1.778) (xy 0.9652 -1.778) (xy 0.9652 1.778) (xy -0.9652 1.778)
			)
			(stroke
				(width 0)
				(type default)
			)
			(fill no)
			(layer "F.Fab")
		)
		(pad "1" smd rect
			(at 0 -0.9652 270)
			(size 1.397 1.143)
			(layers "F.Cu" "F.Mask" "F.Paste")
			(net "P3V3_STBY_VIN")
		)
		(pad "2" smd rect
			(at 0 0.9652 270)
			(size 1.397 1.143)
			(layers "F.Cu" "F.Mask" "F.Paste")
			(net "GND")
		)
	)
	(footprint ""
		(layer "F.Cu")
		(at 39.878 -204.216 -90)
		(property "Reference" "C696"
			(at 0 0 270)
			(layer "F.SilkS")
			(hide yes)
			(effects
				(font
					(size 1.27 1.27)
				)
			)
		)
		(property "Value" "SC220P50V3JN-GP"
			(at 0 -2.8194 270)
			(unlocked yes)
			(layer "F.Fab")
			(hide yes)
			(effects
				(font
					(size 1.016 1.016)
					(thickness 0.1524)
				)
			)
		)
		(property "Device Type" "C603H36"
			(at 0 -4.3434 270)
			(unlocked yes)
			(layer "F.Fab")
			(hide yes)
			(effects
				(font
					(size 1.016 1.016)
					(thickness 0.1524)
				)
			)
		)
		(duplicate_pad_numbers_are_jumpers no)
		(fp_line
			(start 0.508 0)
			(end -0.508 0)
			(stroke
				(width 0.2032)
				(type default)
			)
			(layer "F.SilkS")
		)
		(fp_rect
			(start -0.5842 1.3335)
			(end 0.5842 -1.3335)
			(stroke
				(width 0)
				(type default)
			)
			(fill no)
			(layer "F.CrtYd")
		)
		(fp_rect
			(start -0.5842 1.3335)
			(end 0.5842 -1.3335)
			(stroke
				(width 0)
				(type default)
			)
			(fill no)
			(layer "F.Fab")
		)
		(pad "1" smd custom
			(at 0 -0.762 270)
			(size 0.2159 0.2159)
			(layers "F.Cu" "F.Mask" "F.Paste")
			(net "BUF_I2C6_C_FCB_SDA_R")
			(options
				(clearance outline)
				(anchor circle)
			)
			(primitives
				(gr_poly
					(pts
						(arc
							(start -0.3302 -0.4318)
							(mid -0.402042 -0.402042)
							(end -0.4318 -0.3302)
						)
						(arc
							(start -0.4318 0.3302)
							(mid -0.402042 0.402042)
							(end -0.3302 0.4318)
						)
						(arc
							(start 0.3302 0.4318)
							(mid 0.402042 0.402042)
							(end 0.4318 0.3302)
						)
						(arc
							(start 0.4318 -0.3302)
							(mid 0.402042 -0.402042)
							(end 0.3302 -0.4318)
						)
					)
					(width 0)
					(fill yes)
				)
			)
		)
		(pad "2" smd custom
			(at 0 0.762 270)
			(size 0.2159 0.2159)
			(layers "F.Cu" "F.Mask" "F.Paste")
			(net "GND")
			(options
				(clearance outline)
				(anchor circle)
			)
			(primitives
				(gr_poly
					(pts
						(arc
							(start -0.3302 -0.4318)
							(mid -0.402042 -0.402042)
							(end -0.4318 -0.3302)
						)
						(arc
							(start -0.4318 0.3302)
							(mid -0.402042 0.402042)
							(end -0.3302 0.4318)
						)
						(arc
							(start 0.3302 0.4318)
							(mid 0.402042 0.402042)
							(end 0.4318 0.3302)
						)
						(arc
							(start 0.4318 -0.3302)
							(mid 0.402042 -0.402042)
							(end 0.3302 -0.4318)
						)
					)
					(width 0)
					(fill yes)
				)
			)
		)
	)
	(footprint ""
		(layer "F.Cu")
		(at 20.6502 -192.5066 90)
		(property "Reference" "R2108"
			(at 0 0 90)
			(layer "F.SilkS")
			(hide yes)
			(effects
				(font
					(size 1.27 1.27)
				)
			)
		)
		(property "Value" "3K74R2F-GP"
			(at 0.064008 -3.993896 90)
			(unlocked yes)
			(layer "F.Fab")
			(hide yes)
			(effects
				(font
					(size 1.016 1.016)
					(thickness 0.1524)
				)
			)
		)
		(property "Device Type" "R402H16"
			(at 0.064008 -5.517896 90)
			(unlocked yes)
			(layer "F.Fab")
			(hide yes)
			(effects
				(font
					(size 1.016 1.016)
					(thickness 0.1524)
				)
			)
		)
		(duplicate_pad_numbers_are_jumpers no)
		(fp_line
			(start 0.508 -0.9398)
			(end -0.508 -0.9398)
			(stroke
				(width 0.1524)
				(type default)
			)
			(layer "F.SilkS")
		)
		(fp_line
			(start -0.508 -0.9398)
			(end -0.508 0.9398)
			(stroke
				(width 0.1524)
				(type default)
			)
			(layer "F.SilkS")
		)
		(fp_rect
			(start -0.508 0.9398)
			(end 0.508 -0.9398)
			(stroke
				(width 0)
				(type default)
			)
			(fill no)
			(layer "F.CrtYd")
		)
		(fp_rect
			(start -0.508 0.9398)
			(end 0.508 -0.9398)
			(stroke
				(width 0)
				(type default)
			)
			(fill no)
			(layer "F.Fab")
		)
		(pad "1" smd custom
			(at 0 -0.4445 90)
			(size 0.1397 0.1397)
			(layers "F.Cu" "F.Mask" "F.Paste")
			(net "MB0_CM_OV_R")
			(options
				(clearance outline)
				(anchor circle)
			)
			(primitives
				(gr_poly
					(pts
						(arc
							(start -0.1778 -0.2794)
							(mid -0.249642 -0.249642)
							(end -0.2794 -0.1778)
						)
						(arc
							(start -0.2794 0.1778)
							(mid -0.249642 0.249642)
							(end -0.1778 0.2794)
						)
						(arc
							(start 0.1778 0.2794)
							(mid 0.249642 0.249642)
							(end 0.2794 0.1778)
						)
						(arc
							(start 0.2794 -0.1778)
							(mid 0.249642 -0.249642)
							(end 0.1778 -0.2794)
						)
					)
					(width 0)
					(fill yes)
				)
			)
		)
		(pad "2" smd custom
			(at 0 0.4445 90)
			(size 0.1397 0.1397)
			(layers "F.Cu" "F.Mask" "F.Paste")
			(net "AGND_CURRENT_MON")
			(options
				(clearance outline)
				(anchor circle)
			)
			(primitives
				(gr_poly
					(pts
						(arc
							(start -0.1778 -0.2794)
							(mid -0.249642 -0.249642)
							(end -0.2794 -0.1778)
						)
						(arc
							(start -0.2794 0.1778)
							(mid -0.249642 0.249642)
							(end -0.1778 0.2794)
						)
						(arc
							(start 0.1778 0.2794)
							(mid 0.249642 0.249642)
							(end 0.2794 0.1778)
						)
						(arc
							(start 0.2794 -0.1778)
							(mid 0.249642 -0.249642)
							(end 0.1778 -0.2794)
						)
					)
					(width 0)
					(fill yes)
				)
			)
		)
	)
	(footprint ""
		(layer "F.Cu")
		(at 171.165774 -51.102768 180)
		(property "Reference" "Q35"
			(at 0 0 180)
			(layer "F.SilkS")
			(hide yes)
			(effects
				(font
					(size 1.27 1.27)
				)
			)
		)
		(property "Value" "2N7002K-1-GP"
			(at 0.127 -8.9662 180)
			(unlocked yes)
			(layer "F.Fab")
			(hide yes)
			(effects
				(font
					(size 1.016 1.016)
					(thickness 0.1524)
				)
			)
		)
		(property "Device Type" "SOT23DGS2D4H44"
			(at 0.127 -10.4902 180)
			(unlocked yes)
			(layer "F.Fab")
			(hide yes)
			(effects
				(font
					(size 1.016 1.016)
					(thickness 0.1524)
				)
			)
		)
		(duplicate_pad_numbers_are_jumpers no)
		(fp_line
			(start 1.651 1.778)
			(end 1.651 -1.778)
			(stroke
				(width 0.1524)
				(type default)
			)
			(layer "F.SilkS")
		)
		(fp_line
			(start 1.651 -1.778)
			(end -1.651 -1.778)
			(stroke
				(width 0.1524)
				(type default)
			)
			(layer "F.SilkS")
		)
		(fp_line
			(start -1.651 1.778)
			(end 1.651 1.778)
			(stroke
				(width 0.1524)
				(type default)
			)
			(layer "F.SilkS")
		)
		(fp_line
			(start -1.651 -1.778)
			(end -1.651 1.778)
			(stroke
				(width 0.1524)
				(type default)
			)
			(layer "F.SilkS")
		)
		(fp_poly
			(pts
				(xy -1.778 1.8796) (xy -1.778 -1.8796) (xy 1.778 -1.8796) (xy 1.778 1.8796)
			)
			(stroke
				(width 0)
				(type default)
			)
			(fill no)
			(layer "F.CrtYd")
		)
		(fp_poly
			(pts
				(xy -1.778 1.8796) (xy -1.778 -1.8796) (xy 1.778 -1.8796) (xy 1.778 1.8796)
			)
			(stroke
				(width 0)
				(type default)
			)
			(fill no)
			(layer "F.Fab")
		)
		(pad "D" smd custom
			(at 0 -0.9525 180)
			(size 0.1905 0.1905)
			(layers "F.Cu" "F.Mask" "F.Paste")
			(net "LED_Q_10")
			(options
				(clearance outline)
				(anchor circle)
			)
			(primitives
				(gr_poly
					(pts
						(arc
							(start -0.1778 0.5715)
							(mid -0.321484 0.511984)
							(end -0.381 0.3683)
						)
						(arc
							(start -0.381 -0.3683)
							(mid -0.321484 -0.511984)
							(end -0.1778 -0.5715)
						)
						(arc
							(start 0.1778 -0.5715)
							(mid 0.321484 -0.511984)
							(end 0.381 -0.3683)
						)
						(arc
							(start 0.381 0.3683)
							(mid 0.321484 0.511984)
							(end 0.1778 0.5715)
						)
					)
					(width 0)
					(fill yes)
				)
			)
		)
		(pad "G" smd custom
			(at -0.98425 0.9525 180)
			(size 0.1905 0.1905)
			(layers "F.Cu" "F.Mask" "F.Paste")
			(net "VS2_LED_R")
			(options
				(clearance outline)
				(anchor circle)
			)
			(primitives
				(gr_poly
					(pts
						(arc
							(start -0.1778 0.5715)
							(mid -0.321484 0.511984)
							(end -0.381 0.3683)
						)
						(arc
							(start -0.381 -0.3683)
							(mid -0.321484 -0.511984)
							(end -0.1778 -0.5715)
						)
						(arc
							(start 0.1778 -0.5715)
							(mid 0.321484 -0.511984)
							(end 0.381 -0.3683)
						)
						(arc
							(start 0.381 0.3683)
							(mid 0.321484 0.511984)
							(end 0.1778 0.5715)
						)
					)
					(width 0)
					(fill yes)
				)
			)
		)
		(pad "S" smd custom
			(at 0.98425 0.9525 180)
			(size 0.1905 0.1905)
			(layers "F.Cu" "F.Mask" "F.Paste")
			(net "GND")
			(options
				(clearance outline)
				(anchor circle)
			)
			(primitives
				(gr_poly
					(pts
						(arc
							(start -0.1778 0.5715)
							(mid -0.321484 0.511984)
							(end -0.381 0.3683)
						)
						(arc
							(start -0.381 -0.3683)
							(mid -0.321484 -0.511984)
							(end -0.1778 -0.5715)
						)
						(arc
							(start 0.1778 -0.5715)
							(mid 0.321484 -0.511984)
							(end 0.381 -0.3683)
						)
						(arc
							(start 0.381 0.3683)
							(mid 0.321484 0.511984)
							(end 0.1778 0.5715)
						)
					)
					(width 0)
					(fill yes)
				)
			)
		)
	)
	(footprint ""
		(layer "F.Cu")
		(at 318.444626 -33.42513)
		(property "Reference" "R413"
			(at 0 0 0)
			(layer "F.SilkS")
			(hide yes)
			(effects
				(font
					(size 1.27 1.27)
				)
			)
		)
		(property "Value" "0R2J-2-GP"
			(at 0.064008 -3.993896 0)
			(unlocked yes)
			(layer "F.Fab")
			(hide yes)
			(effects
				(font
					(size 1.016 1.016)
					(thickness 0.1524)
				)
			)
		)
		(property "Device Type" "R402H16"
			(at 0.064008 -5.517896 0)
			(unlocked yes)
			(layer "F.Fab")
			(hide yes)
			(effects
				(font
					(size 1.016 1.016)
					(thickness 0.1524)
				)
			)
		)
		(duplicate_pad_numbers_are_jumpers no)
		(fp_line
			(start -0.508 -0.9398)
			(end -0.508 0.9398)
			(stroke
				(width 0.1524)
				(type default)
			)
			(layer "F.SilkS")
		)
		(fp_line
			(start 0.508 -0.9398)
			(end -0.508 -0.9398)
			(stroke
				(width 0.1524)
				(type default)
			)
			(layer "F.SilkS")
		)
		(fp_rect
			(start -0.508 0.9398)
			(end 0.508 -0.9398)
			(stroke
				(width 0)
				(type default)
			)
			(fill no)
			(layer "F.CrtYd")
		)
		(fp_rect
			(start -0.508 0.9398)
			(end 0.508 -0.9398)
			(stroke
				(width 0)
				(type default)
			)
			(fill no)
			(layer "F.Fab")
		)
		(pad "1" smd custom
			(at 0 -0.4445)
			(size 0.1397 0.1397)
			(layers "F.Cu" "F.Mask" "F.Paste")
			(net "MINISAS_CN16_D_I2C_INT#")
			(options
				(clearance outline)
				(anchor circle)
			)
			(primitives
				(gr_poly
					(pts
						(arc
							(start -0.1778 -0.2794)
							(mid -0.249642 -0.249642)
							(end -0.2794 -0.1778)
						)
						(arc
							(start -0.2794 0.1778)
							(mid -0.249642 0.249642)
							(end -0.1778 0.2794)
						)
						(arc
							(start 0.1778 0.2794)
							(mid 0.249642 0.249642)
							(end 0.2794 0.1778)
						)
						(arc
							(start 0.2794 -0.1778)
							(mid 0.249642 -0.249642)
							(end 0.1778 -0.2794)
						)
					)
					(width 0)
					(fill yes)
				)
			)
		)
		(pad "2" smd custom
			(at 0 0.4445)
			(size 0.1397 0.1397)
			(layers "F.Cu" "F.Mask" "F.Paste")
			(net "CLK_N_8")
			(options
				(clearance outline)
				(anchor circle)
			)
			(primitives
				(gr_poly
					(pts
						(arc
							(start -0.1778 -0.2794)
							(mid -0.249642 -0.249642)
							(end -0.2794 -0.1778)
						)
						(arc
							(start -0.2794 0.1778)
							(mid -0.249642 0.249642)
							(end -0.1778 0.2794)
						)
						(arc
							(start 0.1778 0.2794)
							(mid 0.249642 0.249642)
							(end 0.2794 0.1778)
						)
						(arc
							(start 0.2794 -0.1778)
							(mid 0.249642 -0.249642)
							(end 0.1778 -0.2794)
						)
					)
					(width 0)
					(fill yes)
				)
			)
		)
	)
	(footprint ""
		(layer "F.Cu")
		(at 167.767 -93.2434 90)
		(property "Reference" "TP76"
			(at 0 0 90)
			(layer "F.SilkS")
			(hide yes)
			(effects
				(font
					(size 1.27 1.27)
				)
			)
		)
		(property "Value" "TPAD28-2-GP"
			(at -0.0127 -1.6637 90)
			(unlocked yes)
			(layer "F.Fab")
			(hide yes)
			(effects
				(font
					(size 1.016 1.016)
					(thickness 0.1524)
				)
			)
		)
		(property "Device Type" "TPAD28"
			(at -0.0127 -3.1877 90)
			(unlocked yes)
			(layer "F.Fab")
			(hide yes)
			(effects
				(font
					(size 1.016 1.016)
					(thickness 0.1524)
				)
			)
		)
		(duplicate_pad_numbers_are_jumpers no)
		(fp_poly
			(pts
				(arc
					(start 0 0.3556)
					(mid 0 -0.3556)
					(end 0 0.3556)
				)
			)
			(stroke
				(width 0)
				(type default)
			)
			(fill no)
			(layer "F.CrtYd")
		)
		(fp_poly
			(pts
				(arc
					(start 0 0.6096)
					(mid 0 -0.6096)
					(end 0 0.6096)
				)
			)
			(stroke
				(width 0)
				(type default)
			)
			(fill no)
			(layer "F.Fab")
		)
		(pad "1" smd circle
			(at 0 0 90)
			(size 0.7112 0.7112)
			(layers "F.Cu" "F.Mask" "F.Paste")
			(net "CLKGEN_N2")
		)
	)
	(footprint ""
		(layer "F.Cu")
		(at 240.538 -23.241 180)
		(property "Reference" "R783"
			(at 0 0 180)
			(layer "F.SilkS")
			(hide yes)
			(effects
				(font
					(size 1.27 1.27)
				)
			)
		)
		(property "Value" "4K7R2F-GP"
			(at 0.064008 -3.993896 180)
			(unlocked yes)
			(layer "F.Fab")
			(hide yes)
			(effects
				(font
					(size 1.016 1.016)
					(thickness 0.1524)
				)
			)
		)
		(property "Device Type" "R402H16"
			(at 0.064008 -5.517896 180)
			(unlocked yes)
			(layer "F.Fab")
			(hide yes)
			(effects
				(font
					(size 1.016 1.016)
					(thickness 0.1524)
				)
			)
		)
		(duplicate_pad_numbers_are_jumpers no)
		(fp_line
			(start 0.508 -0.9398)
			(end -0.508 -0.9398)
			(stroke
				(width 0.1524)
				(type default)
			)
			(layer "F.SilkS")
		)
		(fp_line
			(start -0.508 -0.9398)
			(end -0.508 0.9398)
			(stroke
				(width 0.1524)
				(type default)
			)
			(layer "F.SilkS")
		)
		(fp_rect
			(start -0.508 0.9398)
			(end 0.508 -0.9398)
			(stroke
				(width 0)
				(type default)
			)
			(fill no)
			(layer "F.CrtYd")
		)
		(fp_rect
			(start -0.508 0.9398)
			(end 0.508 -0.9398)
			(stroke
				(width 0)
				(type default)
			)
			(fill no)
			(layer "F.Fab")
		)
		(pad "1" smd custom
			(at 0 -0.4445 180)
			(size 0.1397 0.1397)
			(layers "F.Cu" "F.Mask" "F.Paste")
			(net "BOOTSTRAP3")
			(options
				(clearance outline)
				(anchor circle)
			)
			(primitives
				(gr_poly
					(pts
						(arc
							(start -0.1778 -0.2794)
							(mid -0.249642 -0.249642)
							(end -0.2794 -0.1778)
						)
						(arc
							(start -0.2794 0.1778)
							(mid -0.249642 0.249642)
							(end -0.1778 0.2794)
						)
						(arc
							(start 0.1778 0.2794)
							(mid 0.249642 0.249642)
							(end 0.2794 0.1778)
						)
						(arc
							(start 0.2794 -0.1778)
							(mid 0.249642 -0.249642)
							(end 0.1778 -0.2794)
						)
					)
					(width 0)
					(fill yes)
				)
			)
		)
		(pad "2" smd custom
			(at 0 0.4445 180)
			(size 0.1397 0.1397)
			(layers "F.Cu" "F.Mask" "F.Paste")
			(net "BOOTSTRAP_R_3")
			(options
				(clearance outline)
				(anchor circle)
			)
			(primitives
				(gr_poly
					(pts
						(arc
							(start -0.1778 -0.2794)
							(mid -0.249642 -0.249642)
							(end -0.2794 -0.1778)
						)
						(arc
							(start -0.2794 0.1778)
							(mid -0.249642 0.249642)
							(end -0.1778 0.2794)
						)
						(arc
							(start 0.1778 0.2794)
							(mid 0.249642 0.249642)
							(end 0.2794 0.1778)
						)
						(arc
							(start 0.2794 -0.1778)
							(mid 0.249642 -0.249642)
							(end 0.1778 -0.2794)
						)
					)
					(width 0)
					(fill yes)
				)
			)
		)
	)
	(footprint ""
		(layer "F.Cu")
		(at 77.216 -197.6628 180)
		(property "Reference" "R7978"
			(at 0 0 180)
			(layer "F.SilkS")
			(hide yes)
			(effects
				(font
					(size 1.27 1.27)
				)
			)
		)
		(property "Value" "0R2J-2-GP"
			(at 0.064008 -3.993896 180)
			(unlocked yes)
			(layer "F.Fab")
			(hide yes)
			(effects
				(font
					(size 1.016 1.016)
					(thickness 0.1524)
				)
			)
		)
		(property "Device Type" "R402H16"
			(at 0.064008 -5.517896 180)
			(unlocked yes)
			(layer "F.Fab")
			(hide yes)
			(effects
				(font
					(size 1.016 1.016)
					(thickness 0.1524)
				)
			)
		)
		(duplicate_pad_numbers_are_jumpers no)
		(fp_line
			(start 0.508 -0.9398)
			(end -0.508 -0.9398)
			(stroke
				(width 0.1524)
				(type default)
			)
			(layer "F.SilkS")
		)
		(fp_line
			(start -0.508 -0.9398)
			(end -0.508 0.9398)
			(stroke
				(width 0.1524)
				(type default)
			)
			(layer "F.SilkS")
		)
		(fp_rect
			(start -0.508 0.9398)
			(end 0.508 -0.9398)
			(stroke
				(width 0)
				(type default)
			)
			(fill no)
			(layer "F.CrtYd")
		)
		(fp_rect
			(start -0.508 0.9398)
			(end 0.508 -0.9398)
			(stroke
				(width 0)
				(type default)
			)
			(fill no)
			(layer "F.Fab")
		)
		(pad "1" smd custom
			(at 0 -0.4445 180)
			(size 0.1397 0.1397)
			(layers "F.Cu" "F.Mask" "F.Paste")
			(net "SSD_PERST#10")
			(options
				(clearance outline)
				(anchor circle)
			)
			(primitives
				(gr_poly
					(pts
						(arc
							(start -0.1778 -0.2794)
							(mid -0.249642 -0.249642)
							(end -0.2794 -0.1778)
						)
						(arc
							(start -0.2794 0.1778)
							(mid -0.249642 0.249642)
							(end -0.1778 0.2794)
						)
						(arc
							(start 0.1778 0.2794)
							(mid 0.249642 0.249642)
							(end 0.2794 0.1778)
						)
						(arc
							(start 0.2794 -0.1778)
							(mid 0.249642 -0.249642)
							(end 0.1778 -0.2794)
						)
					)
					(width 0)
					(fill yes)
				)
			)
		)
		(pad "2" smd custom
			(at 0 0.4445 180)
			(size 0.1397 0.1397)
			(layers "F.Cu" "F.Mask" "F.Paste")
			(net "SSD_PERST#10_R")
			(options
				(clearance outline)
				(anchor circle)
			)
			(primitives
				(gr_poly
					(pts
						(arc
							(start -0.1778 -0.2794)
							(mid -0.249642 -0.249642)
							(end -0.2794 -0.1778)
						)
						(arc
							(start -0.2794 0.1778)
							(mid -0.249642 0.249642)
							(end -0.1778 0.2794)
						)
						(arc
							(start 0.1778 0.2794)
							(mid 0.249642 0.249642)
							(end 0.2794 0.1778)
						)
						(arc
							(start 0.2794 -0.1778)
							(mid 0.249642 -0.249642)
							(end 0.1778 -0.2794)
						)
					)
					(width 0)
					(fill yes)
				)
			)
		)
	)
	(footprint ""
		(layer "F.Cu")
		(at 123.18238 -6.78688 90)
		(property "Reference" "SR710"
			(at 0 0 90)
			(layer "F.SilkS")
			(hide yes)
			(effects
				(font
					(size 1.27 1.27)
				)
			)
		)
		(property "Value" "150R2F-1-GP"
			(at 0.064008 -3.993896 90)
			(unlocked yes)
			(layer "F.Fab")
			(hide yes)
			(effects
				(font
					(size 1.016 1.016)
					(thickness 0.1524)
				)
			)
		)
		(property "Device Type" "R402H16"
			(at 0.064008 -5.517896 90)
			(unlocked yes)
			(layer "F.Fab")
			(hide yes)
			(effects
				(font
					(size 1.016 1.016)
					(thickness 0.1524)
				)
			)
		)
		(duplicate_pad_numbers_are_jumpers no)
		(fp_line
			(start 0.508 -0.9398)
			(end -0.508 -0.9398)
			(stroke
				(width 0.1524)
				(type default)
			)
			(layer "F.SilkS")
		)
		(fp_line
			(start -0.508 -0.9398)
			(end -0.508 0.9398)
			(stroke
				(width 0.1524)
				(type default)
			)
			(layer "F.SilkS")
		)
		(fp_rect
			(start -0.508 0.9398)
			(end 0.508 -0.9398)
			(stroke
				(width 0)
				(type default)
			)
			(fill no)
			(layer "F.CrtYd")
		)
		(fp_rect
			(start -0.508 0.9398)
			(end 0.508 -0.9398)
			(stroke
				(width 0)
				(type default)
			)
			(fill no)
			(layer "F.Fab")
		)
		(pad "1" smd custom
			(at 0 -0.4445 90)
			(size 0.1397 0.1397)
			(layers "F.Cu" "F.Mask" "F.Paste")
			(net "P3V3_STBY")
			(options
				(clearance outline)
				(anchor circle)
			)
			(primitives
				(gr_poly
					(pts
						(arc
							(start -0.1778 -0.2794)
							(mid -0.249642 -0.249642)
							(end -0.2794 -0.1778)
						)
						(arc
							(start -0.2794 0.1778)
							(mid -0.249642 0.249642)
							(end -0.1778 0.2794)
						)
						(arc
							(start 0.1778 0.2794)
							(mid 0.249642 0.249642)
							(end 0.2794 0.1778)
						)
						(arc
							(start 0.2794 -0.1778)
							(mid 0.249642 -0.249642)
							(end 0.1778 -0.2794)
						)
					)
					(width 0)
					(fill yes)
				)
			)
		)
		(pad "2" smd custom
			(at 0 0.4445 90)
			(size 0.1397 0.1397)
			(layers "F.Cu" "F.Mask" "F.Paste")
			(net "LED_R_3")
			(options
				(clearance outline)
				(anchor circle)
			)
			(primitives
				(gr_poly
					(pts
						(arc
							(start -0.1778 -0.2794)
							(mid -0.249642 -0.249642)
							(end -0.2794 -0.1778)
						)
						(arc
							(start -0.2794 0.1778)
							(mid -0.249642 0.249642)
							(end -0.1778 0.2794)
						)
						(arc
							(start 0.1778 0.2794)
							(mid 0.249642 0.249642)
							(end 0.2794 0.1778)
						)
						(arc
							(start 0.2794 -0.1778)
							(mid 0.249642 -0.249642)
							(end 0.1778 -0.2794)
						)
					)
					(width 0)
					(fill yes)
				)
			)
		)
	)
	(footprint ""
		(layer "F.Cu")
		(at 25.2984 -69.088 90)
		(property "Reference" "R2948"
			(at 0 0 90)
			(layer "F.SilkS")
			(hide yes)
			(effects
				(font
					(size 1.27 1.27)
				)
			)
		)
		(property "Value" "0R2J-2-GP"
			(at 0.064008 -3.993896 90)
			(unlocked yes)
			(layer "F.Fab")
			(hide yes)
			(effects
				(font
					(size 1.016 1.016)
					(thickness 0.1524)
				)
			)
		)
		(property "Device Type" "R402H16"
			(at 0.064008 -5.517896 90)
			(unlocked yes)
			(layer "F.Fab")
			(hide yes)
			(effects
				(font
					(size 1.016 1.016)
					(thickness 0.1524)
				)
			)
		)
		(duplicate_pad_numbers_are_jumpers no)
		(fp_line
			(start 0.508 -0.9398)
			(end -0.508 -0.9398)
			(stroke
				(width 0.1524)
				(type default)
			)
			(layer "F.SilkS")
		)
		(fp_line
			(start -0.508 -0.9398)
			(end -0.508 0.9398)
			(stroke
				(width 0.1524)
				(type default)
			)
			(layer "F.SilkS")
		)
		(fp_rect
			(start -0.508 0.9398)
			(end 0.508 -0.9398)
			(stroke
				(width 0)
				(type default)
			)
			(fill no)
			(layer "F.CrtYd")
		)
		(fp_rect
			(start -0.508 0.9398)
			(end 0.508 -0.9398)
			(stroke
				(width 0)
				(type default)
			)
			(fill no)
			(layer "F.Fab")
		)
		(pad "1" smd custom
			(at 0 -0.4445 90)
			(size 0.1397 0.1397)
			(layers "F.Cu" "F.Mask" "F.Paste")
			(net "BMC_I2C5_D_PEB_DEVICE_SCL")
			(options
				(clearance outline)
				(anchor circle)
			)
			(primitives
				(gr_poly
					(pts
						(arc
							(start -0.1778 -0.2794)
							(mid -0.249642 -0.249642)
							(end -0.2794 -0.1778)
						)
						(arc
							(start -0.2794 0.1778)
							(mid -0.249642 0.249642)
							(end -0.1778 0.2794)
						)
						(arc
							(start 0.1778 0.2794)
							(mid 0.249642 0.249642)
							(end 0.2794 0.1778)
						)
						(arc
							(start 0.2794 -0.1778)
							(mid 0.249642 -0.249642)
							(end 0.1778 -0.2794)
						)
					)
					(width 0)
					(fill yes)
				)
			)
		)
		(pad "2" smd custom
			(at 0 0.4445 90)
			(size 0.1397 0.1397)
			(layers "F.Cu" "F.Mask" "F.Paste")
			(net "I2C_TPM_SCL")
			(options
				(clearance outline)
				(anchor circle)
			)
			(primitives
				(gr_poly
					(pts
						(arc
							(start -0.1778 -0.2794)
							(mid -0.249642 -0.249642)
							(end -0.2794 -0.1778)
						)
						(arc
							(start -0.2794 0.1778)
							(mid -0.249642 0.249642)
							(end -0.1778 0.2794)
						)
						(arc
							(start 0.1778 0.2794)
							(mid 0.249642 0.249642)
							(end 0.2794 0.1778)
						)
						(arc
							(start 0.2794 -0.1778)
							(mid 0.249642 -0.249642)
							(end 0.1778 -0.2794)
						)
					)
					(width 0)
					(fill yes)
				)
			)
		)
	)
	(footprint ""
		(layer "F.Cu")
		(at 86.548214 -83.04022 -90)
		(property "Reference" "U187"
			(at 0 0 270)
			(layer "F.SilkS")
			(hide yes)
			(effects
				(font
					(size 1.27 1.27)
				)
			)
		)
		(property "Value" "TXS0102DCUR-1-GP"
			(at 0 -11.1252 270)
			(unlocked yes)
			(layer "F.Fab")
			(hide yes)
			(effects
				(font
					(size 1.016 1.016)
					(thickness 0.1524)
				)
			)
		)
		(property "Device Type" "SSOIC8-4H36"
			(at 0 -12.6492 270)
			(unlocked yes)
			(layer "F.Fab")
			(hide yes)
			(effects
				(font
					(size 1.016 1.016)
					(thickness 0.1524)
				)
			)
		)
		(duplicate_pad_numbers_are_jumpers no)
		(fp_line
			(start -1.2573 2.1844)
			(end -1.2573 -2.1844)
			(stroke
				(width 0.1524)
				(type default)
			)
			(layer "F.SilkS")
		)
		(fp_line
			(start 1.2573 2.1844)
			(end -1.2573 2.1844)
			(stroke
				(width 0.1524)
				(type default)
			)
			(layer "F.SilkS")
		)
		(fp_line
			(start -1.2954 0.4572)
			(end -1.2954 2.159)
			(stroke
				(width 0.4064)
				(type default)
			)
			(layer "F.SilkS")
		)
		(fp_line
			(start -1.2065 0.2667)
			(end -1.27 0.2667)
			(stroke
				(width 0.1524)
				(type default)
			)
			(layer "F.SilkS")
		)
		(fp_line
			(start -0.9017 -0.0381)
			(end -1.2065 0.2667)
			(stroke
				(width 0.1524)
				(type default)
			)
			(layer "F.SilkS")
		)
		(fp_line
			(start -1.2573 -0.3556)
			(end -1.2192 -0.3556)
			(stroke
				(width 0.1524)
				(type default)
			)
			(layer "F.SilkS")
		)
		(fp_line
			(start -1.2192 -0.3556)
			(end -0.9017 -0.0381)
			(stroke
				(width 0.1524)
				(type default)
			)
			(layer "F.SilkS")
		)
		(fp_line
			(start -1.2573 -2.1844)
			(end 1.2573 -2.1844)
			(stroke
				(width 0.1524)
				(type default)
			)
			(layer "F.SilkS")
		)
		(fp_line
			(start 1.2573 -2.1844)
			(end 1.2573 2.1844)
			(stroke
				(width 0.1524)
				(type default)
			)
			(layer "F.SilkS")
		)
		(fp_poly
			(pts
				(xy -1.5113 2.4384) (xy 1.5113 2.4384) (xy 1.5113 -2.4384) (xy -1.5113 -2.4384)
			)
			(stroke
				(width 0)
				(type default)
			)
			(fill no)
			(layer "F.CrtYd")
		)
		(fp_poly
			(pts
				(xy -1.5113 -2.4384) (xy 1.5113 -2.4384) (xy 1.5113 2.4384) (xy -1.5113 2.4384)
			)
			(stroke
				(width 0)
				(type default)
			)
			(fill no)
			(layer "F.Fab")
		)
		(pad "1" smd rect
			(at -0.75057 1.1684 270)
			(size 0.3048 1.524)
			(layers "F.Cu" "F.Mask" "F.Paste")
			(net "EXP_SMART_RX_R")
		)
		(pad "2" smd rect
			(at -0.25019 1.1684 270)
			(size 0.3048 1.524)
			(layers "F.Cu" "F.Mask" "F.Paste")
			(net "GND")
		)
		(pad "3" smd rect
			(at 0.25019 1.1684 270)
			(size 0.3048 1.524)
			(layers "F.Cu" "F.Mask" "F.Paste")
			(net "P1V8_STBY")
		)
		(pad "4" smd rect
			(at 0.75057 1.1684 270)
			(size 0.3048 1.524)
			(layers "F.Cu" "F.Mask" "F.Paste")
			(net "SAS_SMART_R_RX")
		)
		(pad "5" smd rect
			(at 0.75057 -1.1684 270)
			(size 0.3048 1.524)
			(layers "F.Cu" "F.Mask" "F.Paste")
			(net "SAS_SMART_R_TX")
		)
		(pad "6" smd rect
			(at 0.25019 -1.1684 270)
			(size 0.3048 1.524)
			(layers "F.Cu" "F.Mask" "F.Paste")
			(net "SMART_UART_EN")
		)
		(pad "7" smd rect
			(at -0.25019 -1.1684 270)
			(size 0.3048 1.524)
			(layers "F.Cu" "F.Mask" "F.Paste")
			(net "P3V3_STBY")
		)
		(pad "8" smd rect
			(at -0.75057 -1.1684 270)
			(size 0.3048 1.524)
			(layers "F.Cu" "F.Mask" "F.Paste")
			(net "EXP_SMART_TX_R")
		)
	)
	(footprint ""
		(layer "F.Cu")
		(at 153.101802 -61.177932 -90)
		(property "Reference" "PU1"
			(at 0 0 270)
			(layer "F.SilkS")
			(hide yes)
			(effects
				(font
					(size 1.27 1.27)
				)
			)
		)
		(property "Value" "TPS53355ADQPR-GP"
			(at 4.7498 -5.6896 270)
			(unlocked yes)
			(layer "F.Fab")
			(hide yes)
			(effects
				(font
					(size 1.016 1.016)
					(thickness 0.1524)
				)
			)
		)
		(property "Device Type" "QFN22G6050-G6133H60"
			(at 4.7498 -7.2136 270)
			(unlocked yes)
			(layer "F.Fab")
			(hide yes)
			(effects
				(font
					(size 1.016 1.016)
					(thickness 0.1524)
				)
			)
		)
		(duplicate_pad_numbers_are_jumpers no)
		(fp_line
			(start -3.556 3.5179)
			(end -2.286 3.5179)
			(stroke
				(width 0.1524)
				(type default)
			)
			(layer "F.SilkS")
		)
		(fp_line
			(start 2.286 3.5179)
			(end 3.556 3.5179)
			(stroke
				(width 0.1524)
				(type default)
			)
			(layer "F.SilkS")
		)
		(fp_line
			(start 3.556 3.5179)
			(end 3.556 2.2479)
			(stroke
				(width 0.1524)
				(type default)
			)
			(layer "F.SilkS")
		)
		(fp_line
			(start -0.999998 3.262122)
			(end -0.999998 3.770122)
			(stroke
				(width 0.1524)
				(type default)
			)
			(layer "F.SilkS")
		)
		(fp_line
			(start 1.500124 3.262122)
			(end 1.500124 4.024122)
			(stroke
				(width 0.1524)
				(type default)
			)
			(layer "F.SilkS")
		)
		(fp_line
			(start -3.556 2.2479)
			(end -3.556 3.5179)
			(stroke
				(width 0.1524)
				(type default)
			)
			(layer "F.SilkS")
		)
		(fp_line
			(start -1.999996 -3.262122)
			(end -1.999996 -4.024122)
			(stroke
				(width 0.1524)
				(type default)
			)
			(layer "F.SilkS")
		)
		(fp_line
			(start 0.500126 -3.262122)
			(end 0.500126 -3.770122)
			(stroke
				(width 0.1524)
				(type default)
			)
			(layer "F.SilkS")
		)
		(fp_line
			(start -3.556 -3.5179)
			(end -3.556 -2.2479)
			(stroke
				(width 0.1524)
				(type default)
			)
			(layer "F.SilkS")
		)
		(fp_line
			(start -2.286 -3.5179)
			(end -3.556 -3.5179)
			(stroke
				(width 0.1524)
				(type default)
			)
			(layer "F.SilkS")
		)
		(fp_poly
			(pts
				(xy 3.556 -3.5179) (xy 2.5273 -3.5179) (xy 3.556 -2.4892)
			)
			(stroke
				(width 0)
				(type default)
			)
			(fill yes)
			(layer "F.SilkS")
		)
		(fp_rect
			(start -2.9972 2.5019)
			(end 2.9972 -2.5019)
			(stroke
				(width 0)
				(type default)
			)
			(fill no)
			(layer "F.CrtYd")
		)
		(fp_poly
			(pts
				(xy 3.556 -2.5019) (xy -2.9972 -2.5019) (xy -2.9972 2.5019) (xy 2.9972 2.5019) (xy 2.9972 -2.4892)
				(xy 3.556 -2.4892) (xy 3.556 3.5179) (xy -3.556 3.5179) (xy -3.556 -3.5179) (xy 3.556 -3.5179)
			)
			(stroke
				(width 0)
				(type default)
			)
			(fill no)
			(layer "F.CrtYd")
		)
		(fp_rect
			(start -3.556 3.5179)
			(end 3.556 -3.5179)
			(stroke
				(width 0)
				(type default)
			)
			(fill no)
			(layer "F.Fab")
		)
		(pad "1" smd rect
			(at 2.500122 -2.449322 270)
			(size 0.3048 1.1176)
			(layers "F.Cu" "F.Mask" "F.Paste")
			(net "P0V9_VFB")
		)
		(pad "2" smd rect
			(at 1.999996 -2.449322 270)
			(size 0.3048 1.1176)
			(layers "F.Cu" "F.Mask" "F.Paste")
			(net "P0V9_EN")
		)
		(pad "3" smd rect
			(at 1.500124 -2.449322 270)
			(size 0.3048 1.1176)
			(layers "F.Cu" "F.Mask" "F.Paste")
			(net "P0V9_PG")
		)
		(pad "4" smd rect
			(at 0.999998 -2.449322 270)
			(size 0.3048 1.1176)
			(layers "F.Cu" "F.Mask" "F.Paste")
			(net "P0V9_VBST")
		)
		(pad "5" smd rect
			(at 0.500126 -2.449322 270)
			(size 0.3048 1.1176)
			(layers "F.Cu" "F.Mask" "F.Paste")
			(net "Net_2122")
		)
		(pad "6" smd rect
			(at 0 -2.449322 270)
			(size 0.3048 1.1176)
			(layers "F.Cu" "F.Mask" "F.Paste")
			(net "P0V9_LX")
		)
		(pad "7" smd rect
			(at -0.500126 -2.449322 270)
			(size 0.3048 1.1176)
			(layers "F.Cu" "F.Mask" "F.Paste")
			(net "P0V9_LX")
		)
		(pad "8" smd rect
			(at -0.999998 -2.449322 270)
			(size 0.3048 1.1176)
			(layers "F.Cu" "F.Mask" "F.Paste")
			(net "P0V9_LX")
		)
		(pad "9" smd rect
			(at -1.500124 -2.449322 270)
			(size 0.3048 1.1176)
			(layers "F.Cu" "F.Mask" "F.Paste")
			(net "P0V9_LX")
		)
		(pad "10" smd rect
			(at -1.999996 -2.449322 270)
			(size 0.3048 1.1176)
			(layers "F.Cu" "F.Mask" "F.Paste")
			(net "P0V9_LX")
		)
		(pad "11" smd rect
			(at -2.500122 -2.449322 270)
			(size 0.3048 1.1176)
			(layers "F.Cu" "F.Mask" "F.Paste")
			(net "P0V9_LX")
		)
		(pad "12" smd rect
			(at -2.500122 2.449322 270)
			(size 0.3048 1.1176)
			(layers "F.Cu" "F.Mask" "F.Paste")
			(net "P0V9_VIN")
		)
		(pad "13" smd rect
			(at -1.999996 2.449322 270)
			(size 0.3048 1.1176)
			(layers "F.Cu" "F.Mask" "F.Paste")
			(net "P0V9_VIN")
		)
		(pad "14" smd rect
			(at -1.500124 2.449322 270)
			(size 0.3048 1.1176)
			(layers "F.Cu" "F.Mask" "F.Paste")
			(net "P0V9_VIN")
		)
		(pad "15" smd rect
			(at -0.999998 2.449322 270)
			(size 0.3048 1.1176)
			(layers "F.Cu" "F.Mask" "F.Paste")
			(net "P0V9_VIN")
		)
		(pad "16" smd rect
			(at -0.500126 2.449322 270)
			(size 0.3048 1.1176)
			(layers "F.Cu" "F.Mask" "F.Paste")
			(net "P0V9_VIN")
		)
		(pad "17" smd rect
			(at 0 2.449322 270)
			(size 0.3048 1.1176)
			(layers "F.Cu" "F.Mask" "F.Paste")
			(net "P0V9_VIN")
		)
		(pad "18" smd rect
			(at 0.500126 2.449322 270)
			(size 0.3048 1.1176)
			(layers "F.Cu" "F.Mask" "F.Paste")
			(net "P0V9_VREG")
		)
		(pad "19" smd rect
			(at 0.999998 2.449322 270)
			(size 0.3048 1.1176)
			(layers "F.Cu" "F.Mask" "F.Paste")
			(net "P0V9_VDD")
		)
		(pad "20" smd rect
			(at 1.500124 2.449322 270)
			(size 0.3048 1.1176)
			(layers "F.Cu" "F.Mask" "F.Paste")
			(net "P0V9_MODE")
		)
		(pad "21" smd rect
			(at 1.999996 2.449322 270)
			(size 0.3048 1.1176)
			(layers "F.Cu" "F.Mask" "F.Paste")
			(net "P0V9_TRIP")
		)
		(pad "22" smd rect
			(at 2.500122 2.449322 270)
			(size 0.3048 1.1176)
			(layers "F.Cu" "F.Mask" "F.Paste")
			(net "P0V9_RF")
		)
		(pad "23" smd custom
			(at 0 0 270)
			(size 0.83185 0.83185)
			(layers "F.Cu" "F.Mask" "F.Paste")
			(net "GND")
			(options
				(clearance outline)
				(anchor circle)
			)
			(primitives
				(gr_poly
					(pts
						(xy -2.7813 1.6637) (xy -2.7813 1.2954) (xy -3.048 1.2954) (xy -3.048 0.9525) (xy -2.7813 0.9525)
						(xy -2.7813 -0.9525) (xy -3.048 -0.9525) (xy -3.048 -1.2954) (xy -2.7813 -1.2954) (xy -2.7813 -1.6637)
						(xy 2.7813 -1.6637) (xy 2.7813 -1.2954) (xy 3.048 -1.2954) (xy 3.048 -0.9525) (xy 2.7813 -0.9525)
						(xy 2.7813 0.9525) (xy 3.048 0.9525) (xy 3.048 1.2954) (xy 2.7813 1.2954) (xy 2.7813 1.6637)
					)
					(width 0)
					(fill yes)
				)
			)
		)
	)
	(footprint ""
		(layer "F.Cu")
		(at 268.3256 -11.2776 -90)
		(property "Reference" "C241"
			(at 0 0 270)
			(layer "F.SilkS")
			(hide yes)
			(effects
				(font
					(size 1.27 1.27)
				)
			)
		)
		(property "Value" "SC1U10V2KX-4-GP"
			(at 1.1811 -2.7051 270)
			(unlocked yes)
			(layer "F.Fab")
			(hide yes)
			(effects
				(font
					(size 1.016 1.016)
					(thickness 0.1524)
				)
			)
		)
		(property "Device Type" "C402H22"
			(at 1.1811 -4.2291 270)
			(unlocked yes)
			(layer "F.Fab")
			(hide yes)
			(effects
				(font
					(size 1.016 1.016)
					(thickness 0.1524)
				)
			)
		)
		(duplicate_pad_numbers_are_jumpers no)
		(fp_rect
			(start -0.4318 0.9525)
			(end 0.4318 -0.9525)
			(stroke
				(width 0)
				(type default)
			)
			(fill no)
			(layer "F.CrtYd")
		)
		(fp_rect
			(start -0.4318 0.9525)
			(end 0.4318 -0.9525)
			(stroke
				(width 0)
				(type default)
			)
			(fill no)
			(layer "F.Fab")
		)
		(pad "1" smd custom
			(at 0 -0.4445 270)
			(size 0.1524 0.1524)
			(layers "F.Cu" "F.Mask" "F.Paste")
			(net "PM8536_RST#_LS_R")
			(options
				(clearance outline)
				(anchor circle)
			)
			(primitives
				(gr_poly
					(pts
						(arc
							(start 0.3048 -0.2032)
							(mid 0.275042 -0.275042)
							(end 0.2032 -0.3048)
						)
						(arc
							(start -0.2032 -0.3048)
							(mid -0.275042 -0.275042)
							(end -0.3048 -0.2032)
						)
						(arc
							(start -0.3048 0.2032)
							(mid -0.275042 0.275042)
							(end -0.2032 0.3048)
						)
						(arc
							(start 0.2032 0.3048)
							(mid 0.275042 0.275042)
							(end 0.3048 0.2032)
						)
					)
					(width 0)
					(fill yes)
				)
			)
		)
		(pad "2" smd custom
			(at 0 0.4445 270)
			(size 0.1524 0.1524)
			(layers "F.Cu" "F.Mask" "F.Paste")
			(net "GND")
			(options
				(clearance outline)
				(anchor circle)
			)
			(primitives
				(gr_poly
					(pts
						(arc
							(start 0.3048 -0.2032)
							(mid 0.275042 -0.275042)
							(end 0.2032 -0.3048)
						)
						(arc
							(start -0.2032 -0.3048)
							(mid -0.275042 -0.275042)
							(end -0.3048 -0.2032)
						)
						(arc
							(start -0.3048 0.2032)
							(mid -0.275042 0.275042)
							(end -0.2032 0.3048)
						)
						(arc
							(start 0.2032 0.3048)
							(mid 0.275042 0.275042)
							(end 0.3048 0.2032)
						)
					)
					(width 0)
					(fill yes)
				)
			)
		)
	)
	(footprint ""
		(layer "F.Cu")
		(at 205.3844 -24.0284 90)
		(property "Reference" "R2969"
			(at 0 0 90)
			(layer "F.SilkS")
			(hide yes)
			(effects
				(font
					(size 1.27 1.27)
				)
			)
		)
		(property "Value" "0R2J-2-GP"
			(at 0.064008 -3.993896 90)
			(unlocked yes)
			(layer "F.Fab")
			(hide yes)
			(effects
				(font
					(size 1.016 1.016)
					(thickness 0.1524)
				)
			)
		)
		(property "Device Type" "R402H16"
			(at 0.064008 -5.517896 90)
			(unlocked yes)
			(layer "F.Fab")
			(hide yes)
			(effects
				(font
					(size 1.016 1.016)
					(thickness 0.1524)
				)
			)
		)
		(duplicate_pad_numbers_are_jumpers no)
		(fp_line
			(start 0.508 -0.9398)
			(end -0.508 -0.9398)
			(stroke
				(width 0.1524)
				(type default)
			)
			(layer "F.SilkS")
		)
		(fp_line
			(start -0.508 -0.9398)
			(end -0.508 0.9398)
			(stroke
				(width 0.1524)
				(type default)
			)
			(layer "F.SilkS")
		)
		(fp_rect
			(start -0.508 0.9398)
			(end 0.508 -0.9398)
			(stroke
				(width 0)
				(type default)
			)
			(fill no)
			(layer "F.CrtYd")
		)
		(fp_rect
			(start -0.508 0.9398)
			(end 0.508 -0.9398)
			(stroke
				(width 0)
				(type default)
			)
			(fill no)
			(layer "F.Fab")
		)
		(pad "1" smd custom
			(at 0 -0.4445 90)
			(size 0.1397 0.1397)
			(layers "F.Cu" "F.Mask" "F.Paste")
			(net "U56_SCL")
			(options
				(clearance outline)
				(anchor circle)
			)
			(primitives
				(gr_poly
					(pts
						(arc
							(start -0.1778 -0.2794)
							(mid -0.249642 -0.249642)
							(end -0.2794 -0.1778)
						)
						(arc
							(start -0.2794 0.1778)
							(mid -0.249642 0.249642)
							(end -0.1778 0.2794)
						)
						(arc
							(start 0.1778 0.2794)
							(mid 0.249642 0.249642)
							(end 0.2794 0.1778)
						)
						(arc
							(start 0.2794 -0.1778)
							(mid 0.249642 -0.249642)
							(end 0.1778 -0.2794)
						)
					)
					(width 0)
					(fill yes)
				)
			)
		)
		(pad "2" smd custom
			(at 0 0.4445 90)
			(size 0.1397 0.1397)
			(layers "F.Cu" "F.Mask" "F.Paste")
			(net "BMC_I2C8_CLKBUF1_SCL")
			(options
				(clearance outline)
				(anchor circle)
			)
			(primitives
				(gr_poly
					(pts
						(arc
							(start -0.1778 -0.2794)
							(mid -0.249642 -0.249642)
							(end -0.2794 -0.1778)
						)
						(arc
							(start -0.2794 0.1778)
							(mid -0.249642 0.249642)
							(end -0.1778 0.2794)
						)
						(arc
							(start 0.1778 0.2794)
							(mid 0.249642 0.249642)
							(end 0.2794 0.1778)
						)
						(arc
							(start 0.2794 -0.1778)
							(mid 0.249642 -0.249642)
							(end 0.1778 -0.2794)
						)
					)
					(width 0)
					(fill yes)
				)
			)
		)
	)
	(footprint ""
		(layer "F.Cu")
		(at 177.485802 -71.071232 -90)
		(property "Reference" "PG32"
			(at 0 0 270)
			(layer "F.SilkS")
			(hide yes)
			(effects
				(font
					(size 1.27 1.27)
				)
			)
		)
		(property "Value" "GAP-CLOSE-PWR-3-GP"
			(at 0.0254 -6.5786 270)
			(unlocked yes)
			(layer "F.Fab")
			(hide yes)
			(effects
				(font
					(size 1.016 1.016)
					(thickness 0.1524)
				)
			)
		)
		(property "Device Type" "GAP-CLOSE-PWR-3"
			(at 0.0254 -8.255 270)
			(unlocked yes)
			(layer "F.Fab")
			(hide yes)
			(effects
				(font
					(size 1.016 1.016)
					(thickness 0.1524)
				)
			)
		)
		(duplicate_pad_numbers_are_jumpers no)
		(fp_rect
			(start -0.7112 0.4572)
			(end 0.7112 -0.4572)
			(stroke
				(width 0)
				(type default)
			)
			(fill no)
			(layer "F.CrtYd")
		)
		(fp_poly
			(pts
				(xy -0.7112 -0.4572) (xy 0.7112 -0.4572) (xy 0.7112 0.4572) (xy -0.7112 0.4572)
			)
			(stroke
				(width 0)
				(type default)
			)
			(fill no)
			(layer "F.Fab")
		)
		(pad "1" smd rect
			(at -0.3048 0 270)
			(size 0.6604 0.762)
			(layers "F.Cu" "F.Mask" "F.Paste")
			(net "DUT_AVD_TX")
		)
		(pad "2" smd rect
			(at 0.3048 0 270)
			(size 0.6604 0.762)
			(layers "F.Cu" "F.Mask" "F.Paste")
			(net "P0V9")
		)
	)
	(footprint ""
		(layer "F.Cu")
		(at 327.787 -86.487)
		(property "Reference" "R4170"
			(at 0 0 0)
			(layer "F.SilkS")
			(hide yes)
			(effects
				(font
					(size 1.27 1.27)
				)
			)
		)
		(property "Value" "4K7R2F-GP"
			(at 0.064008 -3.993896 0)
			(unlocked yes)
			(layer "F.Fab")
			(hide yes)
			(effects
				(font
					(size 1.016 1.016)
					(thickness 0.1524)
				)
			)
		)
		(property "Device Type" "R402H16"
			(at 0.064008 -5.517896 0)
			(unlocked yes)
			(layer "F.Fab")
			(hide yes)
			(effects
				(font
					(size 1.016 1.016)
					(thickness 0.1524)
				)
			)
		)
		(duplicate_pad_numbers_are_jumpers no)
		(fp_line
			(start -0.508 -0.9398)
			(end -0.508 0.9398)
			(stroke
				(width 0.1524)
				(type default)
			)
			(layer "F.SilkS")
		)
		(fp_line
			(start 0.508 -0.9398)
			(end -0.508 -0.9398)
			(stroke
				(width 0.1524)
				(type default)
			)
			(layer "F.SilkS")
		)
		(fp_rect
			(start -0.508 0.9398)
			(end 0.508 -0.9398)
			(stroke
				(width 0)
				(type default)
			)
			(fill no)
			(layer "F.CrtYd")
		)
		(fp_rect
			(start -0.508 0.9398)
			(end 0.508 -0.9398)
			(stroke
				(width 0)
				(type default)
			)
			(fill no)
			(layer "F.Fab")
		)
		(pad "1" smd custom
			(at 0 -0.4445)
			(size 0.1397 0.1397)
			(layers "F.Cu" "F.Mask" "F.Paste")
			(net "UPLINK5")
			(options
				(clearance outline)
				(anchor circle)
			)
			(primitives
				(gr_poly
					(pts
						(arc
							(start -0.1778 -0.2794)
							(mid -0.249642 -0.249642)
							(end -0.2794 -0.1778)
						)
						(arc
							(start -0.2794 0.1778)
							(mid -0.249642 0.249642)
							(end -0.1778 0.2794)
						)
						(arc
							(start 0.1778 0.2794)
							(mid 0.249642 0.249642)
							(end 0.2794 0.1778)
						)
						(arc
							(start 0.2794 -0.1778)
							(mid 0.249642 -0.249642)
							(end 0.1778 -0.2794)
						)
					)
					(width 0)
					(fill yes)
				)
			)
		)
		(pad "2" smd custom
			(at 0 0.4445)
			(size 0.1397 0.1397)
			(layers "F.Cu" "F.Mask" "F.Paste")
			(net "P3V3_STBY")
			(options
				(clearance outline)
				(anchor circle)
			)
			(primitives
				(gr_poly
					(pts
						(arc
							(start -0.1778 -0.2794)
							(mid -0.249642 -0.249642)
							(end -0.2794 -0.1778)
						)
						(arc
							(start -0.2794 0.1778)
							(mid -0.249642 0.249642)
							(end -0.1778 0.2794)
						)
						(arc
							(start 0.1778 0.2794)
							(mid 0.249642 0.249642)
							(end 0.2794 0.1778)
						)
						(arc
							(start 0.2794 -0.1778)
							(mid 0.249642 -0.249642)
							(end 0.1778 -0.2794)
						)
					)
					(width 0)
					(fill yes)
				)
			)
		)
	)
	(footprint ""
		(layer "F.Cu")
		(at 217.04554 -31.15056)
		(property "Reference" "TP311"
			(at 0 0 0)
			(layer "F.SilkS")
			(hide yes)
			(effects
				(font
					(size 1.27 1.27)
				)
			)
		)
		(property "Value" "TPAD28-2-GP"
			(at -0.0127 -1.6637 0)
			(unlocked yes)
			(layer "F.Fab")
			(hide yes)
			(effects
				(font
					(size 1.016 1.016)
					(thickness 0.1524)
				)
			)
		)
		(property "Device Type" "TPAD28"
			(at -0.0127 -3.1877 0)
			(unlocked yes)
			(layer "F.Fab")
			(hide yes)
			(effects
				(font
					(size 1.016 1.016)
					(thickness 0.1524)
				)
			)
		)
		(duplicate_pad_numbers_are_jumpers no)
		(fp_poly
			(pts
				(arc
					(start 0.3556 0)
					(mid -0.3556 0)
					(end 0.3556 0)
				)
			)
			(stroke
				(width 0)
				(type default)
			)
			(fill no)
			(layer "F.CrtYd")
		)
		(fp_poly
			(pts
				(arc
					(start 0.6096 0)
					(mid -0.6096 0)
					(end 0.6096 0)
				)
			)
			(stroke
				(width 0)
				(type default)
			)
			(fill no)
			(layer "F.Fab")
		)
		(pad "1" smd circle
			(at 0 0)
			(size 0.7112 0.7112)
			(layers "F.Cu" "F.Mask" "F.Paste")
			(net "LBI_DATA14_R")
		)
	)
	(footprint ""
		(layer "F.Cu")
		(at 134.292086 -74.468482)
		(property "Reference" "R957"
			(at 0 0 0)
			(layer "F.SilkS")
			(hide yes)
			(effects
				(font
					(size 1.27 1.27)
				)
			)
		)
		(property "Value" "33R2J-2-GP"
			(at 0.064008 -3.993896 0)
			(unlocked yes)
			(layer "F.Fab")
			(hide yes)
			(effects
				(font
					(size 1.016 1.016)
					(thickness 0.1524)
				)
			)
		)
		(property "Device Type" "R402H16"
			(at 0.064008 -5.517896 0)
			(unlocked yes)
			(layer "F.Fab")
			(hide yes)
			(effects
				(font
					(size 1.016 1.016)
					(thickness 0.1524)
				)
			)
		)
		(duplicate_pad_numbers_are_jumpers no)
		(fp_line
			(start -0.508 -0.9398)
			(end -0.508 0.9398)
			(stroke
				(width 0.1524)
				(type default)
			)
			(layer "F.SilkS")
		)
		(fp_line
			(start 0.508 -0.9398)
			(end -0.508 -0.9398)
			(stroke
				(width 0.1524)
				(type default)
			)
			(layer "F.SilkS")
		)
		(fp_rect
			(start -0.508 0.9398)
			(end 0.508 -0.9398)
			(stroke
				(width 0)
				(type default)
			)
			(fill no)
			(layer "F.CrtYd")
		)
		(fp_rect
			(start -0.508 0.9398)
			(end 0.508 -0.9398)
			(stroke
				(width 0)
				(type default)
			)
			(fill no)
			(layer "F.Fab")
		)
		(pad "1" smd custom
			(at 0 -0.4445)
			(size 0.1397 0.1397)
			(layers "F.Cu" "F.Mask" "F.Paste")
			(net "SPI_DATA0_3_R")
			(options
				(clearance outline)
				(anchor circle)
			)
			(primitives
				(gr_poly
					(pts
						(arc
							(start -0.1778 -0.2794)
							(mid -0.249642 -0.249642)
							(end -0.2794 -0.1778)
						)
						(arc
							(start -0.2794 0.1778)
							(mid -0.249642 0.249642)
							(end -0.1778 0.2794)
						)
						(arc
							(start 0.1778 0.2794)
							(mid 0.249642 0.249642)
							(end 0.2794 0.1778)
						)
						(arc
							(start 0.2794 -0.1778)
							(mid 0.249642 -0.249642)
							(end 0.1778 -0.2794)
						)
					)
					(width 0)
					(fill yes)
				)
			)
		)
		(pad "2" smd custom
			(at 0 0.4445)
			(size 0.1397 0.1397)
			(layers "F.Cu" "F.Mask" "F.Paste")
			(net "SPI_DATA0_3")
			(options
				(clearance outline)
				(anchor circle)
			)
			(primitives
				(gr_poly
					(pts
						(arc
							(start -0.1778 -0.2794)
							(mid -0.249642 -0.249642)
							(end -0.2794 -0.1778)
						)
						(arc
							(start -0.2794 0.1778)
							(mid -0.249642 0.249642)
							(end -0.1778 0.2794)
						)
						(arc
							(start 0.1778 0.2794)
							(mid 0.249642 0.249642)
							(end 0.2794 0.1778)
						)
						(arc
							(start 0.2794 -0.1778)
							(mid 0.249642 -0.249642)
							(end 0.1778 -0.2794)
						)
					)
					(width 0)
					(fill yes)
				)
			)
		)
	)
	(footprint ""
		(layer "F.Cu")
		(at 323.469 -99.568)
		(property "Reference" "R513"
			(at 0 0 0)
			(layer "F.SilkS")
			(hide yes)
			(effects
				(font
					(size 1.27 1.27)
				)
			)
		)
		(property "Value" "10KR2F-2-GP"
			(at 0.064008 -3.993896 0)
			(unlocked yes)
			(layer "F.Fab")
			(hide yes)
			(effects
				(font
					(size 1.016 1.016)
					(thickness 0.1524)
				)
			)
		)
		(property "Device Type" "R402H16"
			(at 0.064008 -5.517896 0)
			(unlocked yes)
			(layer "F.Fab")
			(hide yes)
			(effects
				(font
					(size 1.016 1.016)
					(thickness 0.1524)
				)
			)
		)
		(duplicate_pad_numbers_are_jumpers no)
		(fp_line
			(start -0.508 -0.9398)
			(end -0.508 0.9398)
			(stroke
				(width 0.1524)
				(type default)
			)
			(layer "F.SilkS")
		)
		(fp_line
			(start 0.508 -0.9398)
			(end -0.508 -0.9398)
			(stroke
				(width 0.1524)
				(type default)
			)
			(layer "F.SilkS")
		)
		(fp_rect
			(start -0.508 0.9398)
			(end 0.508 -0.9398)
			(stroke
				(width 0)
				(type default)
			)
			(fill no)
			(layer "F.CrtYd")
		)
		(fp_rect
			(start -0.508 0.9398)
			(end 0.508 -0.9398)
			(stroke
				(width 0)
				(type default)
			)
			(fill no)
			(layer "F.Fab")
		)
		(pad "1" smd custom
			(at 0 -0.4445)
			(size 0.1397 0.1397)
			(layers "F.Cu" "F.Mask" "F.Paste")
			(net "GND")
			(options
				(clearance outline)
				(anchor circle)
			)
			(primitives
				(gr_poly
					(pts
						(arc
							(start -0.1778 -0.2794)
							(mid -0.249642 -0.249642)
							(end -0.2794 -0.1778)
						)
						(arc
							(start -0.2794 0.1778)
							(mid -0.249642 0.249642)
							(end -0.1778 0.2794)
						)
						(arc
							(start 0.1778 0.2794)
							(mid 0.249642 0.249642)
							(end 0.2794 0.1778)
						)
						(arc
							(start 0.2794 -0.1778)
							(mid 0.249642 -0.249642)
							(end 0.1778 -0.2794)
						)
					)
					(width 0)
					(fill yes)
				)
			)
		)
		(pad "2" smd custom
			(at 0 0.4445)
			(size 0.1397 0.1397)
			(layers "F.Cu" "F.Mask" "F.Paste")
			(net "IOEXP_PMC1_AD0")
			(options
				(clearance outline)
				(anchor circle)
			)
			(primitives
				(gr_poly
					(pts
						(arc
							(start -0.1778 -0.2794)
							(mid -0.249642 -0.249642)
							(end -0.2794 -0.1778)
						)
						(arc
							(start -0.2794 0.1778)
							(mid -0.249642 0.249642)
							(end -0.1778 0.2794)
						)
						(arc
							(start 0.1778 0.2794)
							(mid 0.249642 0.249642)
							(end 0.2794 0.1778)
						)
						(arc
							(start 0.2794 -0.1778)
							(mid 0.249642 -0.249642)
							(end 0.1778 -0.2794)
						)
					)
					(width 0)
					(fill yes)
				)
			)
		)
	)
	(footprint ""
		(layer "F.Cu")
		(at 222.25 -23.241 180)
		(property "Reference" "R3723"
			(at 0 0 180)
			(layer "F.SilkS")
			(hide yes)
			(effects
				(font
					(size 1.27 1.27)
				)
			)
		)
		(property "Value" "4K7R2F-GP"
			(at 0.064008 -3.993896 180)
			(unlocked yes)
			(layer "F.Fab")
			(hide yes)
			(effects
				(font
					(size 1.016 1.016)
					(thickness 0.1524)
				)
			)
		)
		(property "Device Type" "R402H16"
			(at 0.064008 -5.517896 180)
			(unlocked yes)
			(layer "F.Fab")
			(hide yes)
			(effects
				(font
					(size 1.016 1.016)
					(thickness 0.1524)
				)
			)
		)
		(duplicate_pad_numbers_are_jumpers no)
		(fp_line
			(start 0.508 -0.9398)
			(end -0.508 -0.9398)
			(stroke
				(width 0.1524)
				(type default)
			)
			(layer "F.SilkS")
		)
		(fp_line
			(start -0.508 -0.9398)
			(end -0.508 0.9398)
			(stroke
				(width 0.1524)
				(type default)
			)
			(layer "F.SilkS")
		)
		(fp_rect
			(start -0.508 0.9398)
			(end 0.508 -0.9398)
			(stroke
				(width 0)
				(type default)
			)
			(fill no)
			(layer "F.CrtYd")
		)
		(fp_rect
			(start -0.508 0.9398)
			(end 0.508 -0.9398)
			(stroke
				(width 0)
				(type default)
			)
			(fill no)
			(layer "F.Fab")
		)
		(pad "1" smd custom
			(at 0 -0.4445 180)
			(size 0.1397 0.1397)
			(layers "F.Cu" "F.Mask" "F.Paste")
			(net "HOST8_RST_N_LS")
			(options
				(clearance outline)
				(anchor circle)
			)
			(primitives
				(gr_poly
					(pts
						(arc
							(start -0.1778 -0.2794)
							(mid -0.249642 -0.249642)
							(end -0.2794 -0.1778)
						)
						(arc
							(start -0.2794 0.1778)
							(mid -0.249642 0.249642)
							(end -0.1778 0.2794)
						)
						(arc
							(start 0.1778 0.2794)
							(mid 0.249642 0.249642)
							(end 0.2794 0.1778)
						)
						(arc
							(start 0.2794 -0.1778)
							(mid 0.249642 -0.249642)
							(end 0.1778 -0.2794)
						)
					)
					(width 0)
					(fill yes)
				)
			)
		)
		(pad "2" smd custom
			(at 0 0.4445 180)
			(size 0.1397 0.1397)
			(layers "F.Cu" "F.Mask" "F.Paste")
			(net "GND")
			(options
				(clearance outline)
				(anchor circle)
			)
			(primitives
				(gr_poly
					(pts
						(arc
							(start -0.1778 -0.2794)
							(mid -0.249642 -0.249642)
							(end -0.2794 -0.1778)
						)
						(arc
							(start -0.2794 0.1778)
							(mid -0.249642 0.249642)
							(end -0.1778 0.2794)
						)
						(arc
							(start 0.1778 0.2794)
							(mid 0.249642 0.249642)
							(end 0.2794 0.1778)
						)
						(arc
							(start 0.2794 -0.1778)
							(mid 0.249642 -0.249642)
							(end 0.1778 -0.2794)
						)
					)
					(width 0)
					(fill yes)
				)
			)
		)
	)
	(footprint ""
		(layer "F.Cu")
		(at 264.583418 -2.869184 -90)
		(property "Reference" "R7917"
			(at 0 0 270)
			(layer "F.SilkS")
			(hide yes)
			(effects
				(font
					(size 1.27 1.27)
				)
			)
		)
		(property "Value" "0R2J-2-GP"
			(at 0.064008 -3.993896 270)
			(unlocked yes)
			(layer "F.Fab")
			(hide yes)
			(effects
				(font
					(size 1.016 1.016)
					(thickness 0.1524)
				)
			)
		)
		(property "Device Type" "R402H16"
			(at 0.064008 -5.517896 270)
			(unlocked yes)
			(layer "F.Fab")
			(hide yes)
			(effects
				(font
					(size 1.016 1.016)
					(thickness 0.1524)
				)
			)
		)
		(duplicate_pad_numbers_are_jumpers no)
		(fp_line
			(start -0.508 -0.9398)
			(end -0.508 0.9398)
			(stroke
				(width 0.1524)
				(type default)
			)
			(layer "F.SilkS")
		)
		(fp_line
			(start 0.508 -0.9398)
			(end -0.508 -0.9398)
			(stroke
				(width 0.1524)
				(type default)
			)
			(layer "F.SilkS")
		)
		(fp_rect
			(start -0.508 0.9398)
			(end 0.508 -0.9398)
			(stroke
				(width 0)
				(type default)
			)
			(fill no)
			(layer "F.CrtYd")
		)
		(fp_rect
			(start -0.508 0.9398)
			(end 0.508 -0.9398)
			(stroke
				(width 0)
				(type default)
			)
			(fill no)
			(layer "F.Fab")
		)
		(pad "1" smd custom
			(at 0 -0.4445 270)
			(size 0.1397 0.1397)
			(layers "F.Cu" "F.Mask" "F.Paste")
			(net "RST_BTN#_R")
			(options
				(clearance outline)
				(anchor circle)
			)
			(primitives
				(gr_poly
					(pts
						(arc
							(start -0.1778 -0.2794)
							(mid -0.249642 -0.249642)
							(end -0.2794 -0.1778)
						)
						(arc
							(start -0.2794 0.1778)
							(mid -0.249642 0.249642)
							(end -0.1778 0.2794)
						)
						(arc
							(start 0.1778 0.2794)
							(mid 0.249642 0.249642)
							(end 0.2794 0.1778)
						)
						(arc
							(start 0.2794 -0.1778)
							(mid 0.249642 -0.249642)
							(end 0.1778 -0.2794)
						)
					)
					(width 0)
					(fill yes)
				)
			)
		)
		(pad "2" smd custom
			(at 0 0.4445 270)
			(size 0.1397 0.1397)
			(layers "F.Cu" "F.Mask" "F.Paste")
			(net "RST_BTN#")
			(options
				(clearance outline)
				(anchor circle)
			)
			(primitives
				(gr_poly
					(pts
						(arc
							(start -0.1778 -0.2794)
							(mid -0.249642 -0.249642)
							(end -0.2794 -0.1778)
						)
						(arc
							(start -0.2794 0.1778)
							(mid -0.249642 0.249642)
							(end -0.1778 0.2794)
						)
						(arc
							(start 0.1778 0.2794)
							(mid 0.249642 0.249642)
							(end 0.2794 0.1778)
						)
						(arc
							(start 0.2794 -0.1778)
							(mid 0.249642 -0.249642)
							(end 0.1778 -0.2794)
						)
					)
					(width 0)
					(fill yes)
				)
			)
		)
	)
	(footprint ""
		(layer "F.Cu")
		(at 284.861 -57.15 180)
		(property "Reference" "Q33"
			(at 0 0 180)
			(layer "F.SilkS")
			(hide yes)
			(effects
				(font
					(size 1.27 1.27)
				)
			)
		)
		(property "Value" "2N7002K-1-GP"
			(at 0.127 -8.9662 180)
			(unlocked yes)
			(layer "F.Fab")
			(hide yes)
			(effects
				(font
					(size 1.016 1.016)
					(thickness 0.1524)
				)
			)
		)
		(property "Device Type" "SOT23DGS2D4H44"
			(at 0.127 -10.4902 180)
			(unlocked yes)
			(layer "F.Fab")
			(hide yes)
			(effects
				(font
					(size 1.016 1.016)
					(thickness 0.1524)
				)
			)
		)
		(duplicate_pad_numbers_are_jumpers no)
		(fp_line
			(start 1.651 1.778)
			(end 1.651 -1.778)
			(stroke
				(width 0.1524)
				(type default)
			)
			(layer "F.SilkS")
		)
		(fp_line
			(start 1.651 -1.778)
			(end -1.651 -1.778)
			(stroke
				(width 0.1524)
				(type default)
			)
			(layer "F.SilkS")
		)
		(fp_line
			(start -1.651 1.778)
			(end 1.651 1.778)
			(stroke
				(width 0.1524)
				(type default)
			)
			(layer "F.SilkS")
		)
		(fp_line
			(start -1.651 -1.778)
			(end -1.651 1.778)
			(stroke
				(width 0.1524)
				(type default)
			)
			(layer "F.SilkS")
		)
		(fp_poly
			(pts
				(xy -1.778 1.8796) (xy -1.778 -1.8796) (xy 1.778 -1.8796) (xy 1.778 1.8796)
			)
			(stroke
				(width 0)
				(type default)
			)
			(fill no)
			(layer "F.CrtYd")
		)
		(fp_poly
			(pts
				(xy -1.778 1.8796) (xy -1.778 -1.8796) (xy 1.778 -1.8796) (xy 1.778 1.8796)
			)
			(stroke
				(width 0)
				(type default)
			)
			(fill no)
			(layer "F.Fab")
		)
		(pad "D" smd custom
			(at 0 -0.9525 180)
			(size 0.1905 0.1905)
			(layers "F.Cu" "F.Mask" "F.Paste")
			(net "LED_Q_12")
			(options
				(clearance outline)
				(anchor circle)
			)
			(primitives
				(gr_poly
					(pts
						(arc
							(start -0.1778 0.5715)
							(mid -0.321484 0.511984)
							(end -0.381 0.3683)
						)
						(arc
							(start -0.381 -0.3683)
							(mid -0.321484 -0.511984)
							(end -0.1778 -0.5715)
						)
						(arc
							(start 0.1778 -0.5715)
							(mid 0.321484 -0.511984)
							(end 0.381 -0.3683)
						)
						(arc
							(start 0.381 0.3683)
							(mid 0.321484 0.511984)
							(end 0.1778 0.5715)
						)
					)
					(width 0)
					(fill yes)
				)
			)
		)
		(pad "G" smd custom
			(at -0.98425 0.9525 180)
			(size 0.1905 0.1905)
			(layers "F.Cu" "F.Mask" "F.Paste")
			(net "VS4_LED_R")
			(options
				(clearance outline)
				(anchor circle)
			)
			(primitives
				(gr_poly
					(pts
						(arc
							(start -0.1778 0.5715)
							(mid -0.321484 0.511984)
							(end -0.381 0.3683)
						)
						(arc
							(start -0.381 -0.3683)
							(mid -0.321484 -0.511984)
							(end -0.1778 -0.5715)
						)
						(arc
							(start 0.1778 -0.5715)
							(mid 0.321484 -0.511984)
							(end 0.381 -0.3683)
						)
						(arc
							(start 0.381 0.3683)
							(mid 0.321484 0.511984)
							(end 0.1778 0.5715)
						)
					)
					(width 0)
					(fill yes)
				)
			)
		)
		(pad "S" smd custom
			(at 0.98425 0.9525 180)
			(size 0.1905 0.1905)
			(layers "F.Cu" "F.Mask" "F.Paste")
			(net "GND")
			(options
				(clearance outline)
				(anchor circle)
			)
			(primitives
				(gr_poly
					(pts
						(arc
							(start -0.1778 0.5715)
							(mid -0.321484 0.511984)
							(end -0.381 0.3683)
						)
						(arc
							(start -0.381 -0.3683)
							(mid -0.321484 -0.511984)
							(end -0.1778 -0.5715)
						)
						(arc
							(start 0.1778 -0.5715)
							(mid 0.321484 -0.511984)
							(end 0.381 -0.3683)
						)
						(arc
							(start 0.381 0.3683)
							(mid 0.321484 0.511984)
							(end 0.1778 0.5715)
						)
					)
					(width 0)
					(fill yes)
				)
			)
		)
	)
	(footprint ""
		(layer "F.Cu")
		(at 145.542 -95.25 90)
		(property "Reference" "PC93"
			(at 0 0 90)
			(layer "F.SilkS")
			(hide yes)
			(effects
				(font
					(size 1.27 1.27)
				)
			)
		)
		(property "Value" "SC22U6D3V5MX-5-GP"
			(at -0.0762 -6.1214 90)
			(unlocked yes)
			(layer "F.Fab")
			(hide yes)
			(effects
				(font
					(size 1.016 1.016)
					(thickness 0.1524)
				)
			)
		)
		(property "Device Type" "C805H56"
			(at -0.0762 -8.1534 90)
			(unlocked yes)
			(layer "F.Fab")
			(hide yes)
			(effects
				(font
					(size 1.016 1.016)
					(thickness 0.1524)
				)
			)
		)
		(duplicate_pad_numbers_are_jumpers no)
		(fp_line
			(start 0.635 0)
			(end -0.635 0)
			(stroke
				(width 0.508)
				(type default)
			)
			(layer "F.SilkS")
		)
		(fp_rect
			(start -0.9652 1.778)
			(end 0.9652 -1.778)
			(stroke
				(width 0)
				(type default)
			)
			(fill no)
			(layer "F.CrtYd")
		)
		(fp_poly
			(pts
				(xy -0.9652 -1.778) (xy 0.9652 -1.778) (xy 0.9652 1.778) (xy -0.9652 1.778)
			)
			(stroke
				(width 0)
				(type default)
			)
			(fill no)
			(layer "F.Fab")
		)
		(pad "1" smd rect
			(at 0 -0.9652 90)
			(size 1.397 1.143)
			(layers "F.Cu" "F.Mask" "F.Paste")
			(net "VR_P1V8_STBY_IN")
		)
		(pad "2" smd rect
			(at 0 0.9652 90)
			(size 1.397 1.143)
			(layers "F.Cu" "F.Mask" "F.Paste")
			(net "GND")
		)
	)
	(footprint ""
		(layer "F.Cu")
		(at 40.64 -206.883 180)
		(property "Reference" "R880"
			(at 0 0 180)
			(layer "F.SilkS")
			(hide yes)
			(effects
				(font
					(size 1.27 1.27)
				)
			)
		)
		(property "Value" "0R2J-2-GP"
			(at 0.064008 -3.993896 180)
			(unlocked yes)
			(layer "F.Fab")
			(hide yes)
			(effects
				(font
					(size 1.016 1.016)
					(thickness 0.1524)
				)
			)
		)
		(property "Device Type" "R402H16"
			(at 0.064008 -5.517896 180)
			(unlocked yes)
			(layer "F.Fab")
			(hide yes)
			(effects
				(font
					(size 1.016 1.016)
					(thickness 0.1524)
				)
			)
		)
		(duplicate_pad_numbers_are_jumpers no)
		(fp_line
			(start 0.508 -0.9398)
			(end -0.508 -0.9398)
			(stroke
				(width 0.1524)
				(type default)
			)
			(layer "F.SilkS")
		)
		(fp_line
			(start -0.508 -0.9398)
			(end -0.508 0.9398)
			(stroke
				(width 0.1524)
				(type default)
			)
			(layer "F.SilkS")
		)
		(fp_rect
			(start -0.508 0.9398)
			(end 0.508 -0.9398)
			(stroke
				(width 0)
				(type default)
			)
			(fill no)
			(layer "F.CrtYd")
		)
		(fp_rect
			(start -0.508 0.9398)
			(end 0.508 -0.9398)
			(stroke
				(width 0)
				(type default)
			)
			(fill no)
			(layer "F.Fab")
		)
		(pad "1" smd custom
			(at 0 -0.4445 180)
			(size 0.1397 0.1397)
			(layers "F.Cu" "F.Mask" "F.Paste")
			(net "BUF_I2C6_C_FCB_SDA_R")
			(options
				(clearance outline)
				(anchor circle)
			)
			(primitives
				(gr_poly
					(pts
						(arc
							(start -0.1778 -0.2794)
							(mid -0.249642 -0.249642)
							(end -0.2794 -0.1778)
						)
						(arc
							(start -0.2794 0.1778)
							(mid -0.249642 0.249642)
							(end -0.1778 0.2794)
						)
						(arc
							(start 0.1778 0.2794)
							(mid 0.249642 0.249642)
							(end 0.2794 0.1778)
						)
						(arc
							(start 0.2794 -0.1778)
							(mid 0.249642 -0.249642)
							(end 0.1778 -0.2794)
						)
					)
					(width 0)
					(fill yes)
				)
			)
		)
		(pad "2" smd custom
			(at 0 0.4445 180)
			(size 0.1397 0.1397)
			(layers "F.Cu" "F.Mask" "F.Paste")
			(net "BUF_I2C6_C_FCB_SDA")
			(options
				(clearance outline)
				(anchor circle)
			)
			(primitives
				(gr_poly
					(pts
						(arc
							(start -0.1778 -0.2794)
							(mid -0.249642 -0.249642)
							(end -0.2794 -0.1778)
						)
						(arc
							(start -0.2794 0.1778)
							(mid -0.249642 0.249642)
							(end -0.1778 0.2794)
						)
						(arc
							(start 0.1778 0.2794)
							(mid 0.249642 0.249642)
							(end 0.2794 0.1778)
						)
						(arc
							(start 0.2794 -0.1778)
							(mid 0.249642 -0.249642)
							(end 0.1778 -0.2794)
						)
					)
					(width 0)
					(fill yes)
				)
			)
		)
	)
	(footprint ""
		(layer "F.Cu")
		(at 346.324174 -61.089286 90)
		(property "Reference" "PC169"
			(at 0 0 90)
			(layer "F.SilkS")
			(hide yes)
			(effects
				(font
					(size 1.27 1.27)
				)
			)
		)
		(property "Value" "SC10U25V5KX-GP"
			(at -0.0762 -6.1214 90)
			(unlocked yes)
			(layer "F.Fab")
			(hide yes)
			(effects
				(font
					(size 1.016 1.016)
					(thickness 0.1524)
				)
			)
		)
		(property "Device Type" "C805H56"
			(at -0.0762 -8.1534 90)
			(unlocked yes)
			(layer "F.Fab")
			(hide yes)
			(effects
				(font
					(size 1.016 1.016)
					(thickness 0.1524)
				)
			)
		)
		(duplicate_pad_numbers_are_jumpers no)
		(fp_line
			(start 0.635 0)
			(end -0.635 0)
			(stroke
				(width 0.508)
				(type default)
			)
			(layer "F.SilkS")
		)
		(fp_rect
			(start -0.9652 1.778)
			(end 0.9652 -1.778)
			(stroke
				(width 0)
				(type default)
			)
			(fill no)
			(layer "F.CrtYd")
		)
		(fp_poly
			(pts
				(xy -0.9652 -1.778) (xy 0.9652 -1.778) (xy 0.9652 1.778) (xy -0.9652 1.778)
			)
			(stroke
				(width 0)
				(type default)
			)
			(fill no)
			(layer "F.Fab")
		)
		(pad "1" smd rect
			(at 0 -0.9652 90)
			(size 1.397 1.143)
			(layers "F.Cu" "F.Mask" "F.Paste")
			(net "P0V9_E_VIN")
		)
		(pad "2" smd rect
			(at 0 0.9652 90)
			(size 1.397 1.143)
			(layers "F.Cu" "F.Mask" "F.Paste")
			(net "GND")
		)
	)
	(footprint ""
		(layer "F.Cu")
		(at 26.035 -73.8886 90)
		(property "Reference" "R375"
			(at 0 0 90)
			(layer "F.SilkS")
			(hide yes)
			(effects
				(font
					(size 1.27 1.27)
				)
			)
		)
		(property "Value" "0R2J-2-GP"
			(at 0.064008 -3.993896 90)
			(unlocked yes)
			(layer "F.Fab")
			(hide yes)
			(effects
				(font
					(size 1.016 1.016)
					(thickness 0.1524)
				)
			)
		)
		(property "Device Type" "R402H16"
			(at 0.064008 -5.517896 90)
			(unlocked yes)
			(layer "F.Fab")
			(hide yes)
			(effects
				(font
					(size 1.016 1.016)
					(thickness 0.1524)
				)
			)
		)
		(duplicate_pad_numbers_are_jumpers no)
		(fp_line
			(start 0.508 -0.9398)
			(end -0.508 -0.9398)
			(stroke
				(width 0.1524)
				(type default)
			)
			(layer "F.SilkS")
		)
		(fp_line
			(start -0.508 -0.9398)
			(end -0.508 0.9398)
			(stroke
				(width 0.1524)
				(type default)
			)
			(layer "F.SilkS")
		)
		(fp_rect
			(start -0.508 0.9398)
			(end 0.508 -0.9398)
			(stroke
				(width 0)
				(type default)
			)
			(fill no)
			(layer "F.CrtYd")
		)
		(fp_rect
			(start -0.508 0.9398)
			(end 0.508 -0.9398)
			(stroke
				(width 0)
				(type default)
			)
			(fill no)
			(layer "F.Fab")
		)
		(pad "1" smd custom
			(at 0 -0.4445 90)
			(size 0.1397 0.1397)
			(layers "F.Cu" "F.Mask" "F.Paste")
			(net "RMII_PHY_BMC_RXD1_R")
			(options
				(clearance outline)
				(anchor circle)
			)
			(primitives
				(gr_poly
					(pts
						(arc
							(start -0.1778 -0.2794)
							(mid -0.249642 -0.249642)
							(end -0.2794 -0.1778)
						)
						(arc
							(start -0.2794 0.1778)
							(mid -0.249642 0.249642)
							(end -0.1778 0.2794)
						)
						(arc
							(start 0.1778 0.2794)
							(mid 0.249642 0.249642)
							(end 0.2794 0.1778)
						)
						(arc
							(start 0.2794 -0.1778)
							(mid 0.249642 -0.249642)
							(end 0.1778 -0.2794)
						)
					)
					(width 0)
					(fill yes)
				)
			)
		)
		(pad "2" smd custom
			(at 0 0.4445 90)
			(size 0.1397 0.1397)
			(layers "F.Cu" "F.Mask" "F.Paste")
			(net "RMII_PHY_BMC_RXD1")
			(options
				(clearance outline)
				(anchor circle)
			)
			(primitives
				(gr_poly
					(pts
						(arc
							(start -0.1778 -0.2794)
							(mid -0.249642 -0.249642)
							(end -0.2794 -0.1778)
						)
						(arc
							(start -0.2794 0.1778)
							(mid -0.249642 0.249642)
							(end -0.1778 0.2794)
						)
						(arc
							(start 0.1778 0.2794)
							(mid 0.249642 0.249642)
							(end 0.2794 0.1778)
						)
						(arc
							(start 0.2794 -0.1778)
							(mid 0.249642 -0.249642)
							(end 0.1778 -0.2794)
						)
					)
					(width 0)
					(fill yes)
				)
			)
		)
	)
	(footprint ""
		(layer "F.Cu")
		(at 62.611 -131.953 180)
		(property "Reference" "C8084"
			(at 0 0 180)
			(layer "F.SilkS")
			(hide yes)
			(effects
				(font
					(size 1.27 1.27)
				)
			)
		)
		(property "Value" "SCD1U25V2KX-2-GP"
			(at 1.1811 -2.7051 180)
			(unlocked yes)
			(layer "F.Fab")
			(hide yes)
			(effects
				(font
					(size 1.016 1.016)
					(thickness 0.1524)
				)
			)
		)
		(property "Device Type" "C402H22"
			(at 1.1811 -4.2291 180)
			(unlocked yes)
			(layer "F.Fab")
			(hide yes)
			(effects
				(font
					(size 1.016 1.016)
					(thickness 0.1524)
				)
			)
		)
		(duplicate_pad_numbers_are_jumpers no)
		(fp_rect
			(start -0.4318 0.9525)
			(end 0.4318 -0.9525)
			(stroke
				(width 0)
				(type default)
			)
			(fill no)
			(layer "F.CrtYd")
		)
		(fp_rect
			(start -0.4318 0.9525)
			(end 0.4318 -0.9525)
			(stroke
				(width 0)
				(type default)
			)
			(fill no)
			(layer "F.Fab")
		)
		(pad "1" smd custom
			(at 0 -0.4445 180)
			(size 0.1524 0.1524)
			(layers "F.Cu" "F.Mask" "F.Paste")
			(net "ADC_12V")
			(options
				(clearance outline)
				(anchor circle)
			)
			(primitives
				(gr_poly
					(pts
						(arc
							(start 0.3048 -0.2032)
							(mid 0.275042 -0.275042)
							(end 0.2032 -0.3048)
						)
						(arc
							(start -0.2032 -0.3048)
							(mid -0.275042 -0.275042)
							(end -0.3048 -0.2032)
						)
						(arc
							(start -0.3048 0.2032)
							(mid -0.275042 0.275042)
							(end -0.2032 0.3048)
						)
						(arc
							(start 0.2032 0.3048)
							(mid 0.275042 0.275042)
							(end 0.3048 0.2032)
						)
					)
					(width 0)
					(fill yes)
				)
			)
		)
		(pad "2" smd custom
			(at 0 0.4445 180)
			(size 0.1524 0.1524)
			(layers "F.Cu" "F.Mask" "F.Paste")
			(net "GND")
			(options
				(clearance outline)
				(anchor circle)
			)
			(primitives
				(gr_poly
					(pts
						(arc
							(start 0.3048 -0.2032)
							(mid 0.275042 -0.275042)
							(end 0.2032 -0.3048)
						)
						(arc
							(start -0.2032 -0.3048)
							(mid -0.275042 -0.275042)
							(end -0.3048 -0.2032)
						)
						(arc
							(start -0.3048 0.2032)
							(mid -0.275042 0.275042)
							(end -0.2032 0.3048)
						)
						(arc
							(start 0.2032 0.3048)
							(mid 0.275042 0.275042)
							(end 0.3048 0.2032)
						)
					)
					(width 0)
					(fill yes)
				)
			)
		)
	)
	(footprint ""
		(layer "F.Cu")
		(at 26.035 -207.518 180)
		(property "Reference" "R9020"
			(at 0 0 180)
			(layer "F.SilkS")
			(hide yes)
			(effects
				(font
					(size 1.27 1.27)
				)
			)
		)
		(property "Value" "D002RL3115F-L-GP"
			(at 3.2258 1.2954 180)
			(unlocked yes)
			(layer "F.Fab")
			(hide yes)
			(effects
				(font
					(size 1.016 1.016)
					(thickness 0.1524)
				)
			)
		)
		(property "Device Type" "RL3115-4PH45"
			(at 3.2258 -0.2286 180)
			(unlocked yes)
			(layer "F.Fab")
			(hide yes)
			(effects
				(font
					(size 1.016 1.016)
					(thickness 0.1524)
				)
			)
		)
		(duplicate_pad_numbers_are_jumpers no)
		(fp_line
			(start 1.9685 1.651)
			(end -1.9685 1.651)
			(stroke
				(width 0.1524)
				(type default)
			)
			(layer "F.SilkS")
		)
		(fp_line
			(start 1.9685 -1.651)
			(end 1.9685 1.651)
			(stroke
				(width 0.1524)
				(type default)
			)
			(layer "F.SilkS")
		)
		(fp_line
			(start -0.5334 -1.7653)
			(end -2.0574 -1.7653)
			(stroke
				(width 0.3302)
				(type default)
			)
			(layer "F.SilkS")
		)
		(fp_line
			(start -1.9685 1.651)
			(end -1.9685 -1.651)
			(stroke
				(width 0.1524)
				(type default)
			)
			(layer "F.SilkS")
		)
		(fp_line
			(start -1.9685 -1.651)
			(end 1.9685 -1.651)
			(stroke
				(width 0.1524)
				(type default)
			)
			(layer "F.SilkS")
		)
		(fp_line
			(start -2.0574 -1.7653)
			(end -2.0574 -0.4064)
			(stroke
				(width 0.3302)
				(type default)
			)
			(layer "F.SilkS")
		)
		(fp_poly
			(pts
				(xy -0.561594 -1.726946) (xy -0.053594 -2.234946) (xy -1.069594 -2.234946)
			)
			(stroke
				(width 0)
				(type default)
			)
			(fill yes)
			(layer "F.SilkS")
		)
		(fp_rect
			(start -1.524 0.7493)
			(end 1.524 -0.7493)
			(stroke
				(width 0)
				(type default)
			)
			(fill no)
			(layer "F.CrtYd")
		)
		(fp_poly
			(pts
				(xy -2.2225 1.905) (xy -2.2225 -1.905) (xy 2.2225 -1.905) (xy 2.2225 -0.7493) (xy -1.524 -0.7493)
				(xy -1.524 0.7493) (xy 1.524 0.7493) (xy 1.524 -0.7366) (xy 2.2225 -0.7366) (xy 2.2225 1.905)
			)
			(stroke
				(width 0)
				(type default)
			)
			(fill no)
			(layer "F.CrtYd")
		)
		(fp_rect
			(start -2.2225 1.905)
			(end 2.2225 -1.905)
			(stroke
				(width 0)
				(type default)
			)
			(fill no)
			(layer "F.Fab")
		)
		(pad "1" smd rect
			(at -0.5715 -0.813562 180)
			(size 2.286 1.143)
			(layers "F.Cu" "F.Mask" "F.Paste")
			(net "MB0_P12V_MAIN_R")
		)
		(pad "2" smd rect
			(at -0.5715 0.813562 180)
			(size 2.286 1.143)
			(layers "F.Cu" "F.Mask" "F.Paste")
			(net "P12V_PCIE")
		)
		(pad "3" smd rect
			(at 1.334008 -0.813562 180)
			(size 0.762 1.143)
			(layers "F.Cu" "F.Mask" "F.Paste")
			(net "MB0_CM_SENSE_R1_N")
		)
		(pad "4" smd rect
			(at 1.334008 0.813562 180)
			(size 0.762 1.143)
			(layers "F.Cu" "F.Mask" "F.Paste")
			(net "MB0_CM_SENSE_R1_P")
		)
		(zone
			(layer "F.Cu")
			(hatch none 0.5)
			(connect_pads
				(clearance 0)
			)
			(min_thickness 0.25)
			(keepout
				(tracks not_allowed)
				(vias allowed)
				(pads allowed)
				(copperpour not_allowed)
				(footprints allowed)
			)
			(placement
				(enabled no)
				(sheetname "")
			)
			(fill
				(thermal_gap 0.5)
				(thermal_bridge_width 0.5)
				(island_removal_mode 0)
			)
			(polygon
				(pts
					(xy 25.4635 -208.2673) (xy 25.081992 -208.2673) (xy 25.081992 -207.760062) (xy 25.4635 -207.760062)
				)
			)
		)
		(zone
			(layer "F.Cu")
			(hatch none 0.5)
			(connect_pads
				(clearance 0)
			)
			(min_thickness 0.25)
			(keepout
				(tracks allowed)
				(vias not_allowed)
				(pads allowed)
				(copperpour not_allowed)
				(footprints allowed)
			)
			(placement
				(enabled no)
				(sheetname "")
			)
			(fill
				(thermal_gap 0.5)
				(thermal_bridge_width 0.5)
				(island_removal_mode 0)
			)
			(polygon
				(pts
					(xy 25.4635 -208.2673) (xy 25.081992 -208.2673) (xy 25.081992 -207.760062) (xy 25.4635 -207.760062)
				)
			)
		)
		(zone
			(layer "F.Cu")
			(hatch none 0.5)
			(connect_pads
				(clearance 0)
			)
			(min_thickness 0.25)
			(keepout
				(tracks not_allowed)
				(vias allowed)
				(pads allowed)
				(copperpour not_allowed)
				(footprints allowed)
			)
			(placement
				(enabled no)
				(sheetname "")
			)
			(fill
				(thermal_gap 0.5)
				(thermal_bridge_width 0.5)
				(island_removal_mode 0)
			)
			(polygon
				(pts
					(xy 25.4635 -207.275938) (xy 25.081992 -207.275938) (xy 25.081992 -206.7687) (xy 25.4635 -206.7687)
				)
			)
		)
		(zone
			(layer "F.Cu")
			(hatch none 0.5)
			(connect_pads
				(clearance 0)
			)
			(min_thickness 0.25)
			(keepout
				(tracks allowed)
				(vias not_allowed)
				(pads allowed)
				(copperpour not_allowed)
				(footprints allowed)
			)
			(placement
				(enabled no)
				(sheetname "")
			)
			(fill
				(thermal_gap 0.5)
				(thermal_bridge_width 0.5)
				(island_removal_mode 0)
			)
			(polygon
				(pts
					(xy 25.4635 -207.275938) (xy 25.081992 -207.275938) (xy 25.081992 -206.7687) (xy 25.4635 -206.7687)
				)
			)
		)
	)
	(footprint ""
		(layer "F.Cu")
		(at 70.485 -34.417)
		(property "Reference" "PR24"
			(at 0 0 0)
			(layer "F.SilkS")
			(hide yes)
			(effects
				(font
					(size 1.27 1.27)
				)
			)
		)
		(property "Value" "2K7R2J-GP"
			(at 0.064008 -3.993896 0)
			(unlocked yes)
			(layer "F.Fab")
			(hide yes)
			(effects
				(font
					(size 1.016 1.016)
					(thickness 0.1524)
				)
			)
		)
		(property "Device Type" "R402H16"
			(at 0.064008 -5.517896 0)
			(unlocked yes)
			(layer "F.Fab")
			(hide yes)
			(effects
				(font
					(size 1.016 1.016)
					(thickness 0.1524)
				)
			)
		)
		(duplicate_pad_numbers_are_jumpers no)
		(fp_line
			(start -0.508 -0.9398)
			(end -0.508 0.9398)
			(stroke
				(width 0.1524)
				(type default)
			)
			(layer "F.SilkS")
		)
		(fp_line
			(start 0.508 -0.9398)
			(end -0.508 -0.9398)
			(stroke
				(width 0.1524)
				(type default)
			)
			(layer "F.SilkS")
		)
		(fp_rect
			(start -0.508 0.9398)
			(end 0.508 -0.9398)
			(stroke
				(width 0)
				(type default)
			)
			(fill no)
			(layer "F.CrtYd")
		)
		(fp_rect
			(start -0.508 0.9398)
			(end 0.508 -0.9398)
			(stroke
				(width 0)
				(type default)
			)
			(fill no)
			(layer "F.Fab")
		)
		(pad "1" smd custom
			(at 0 -0.4445)
			(size 0.1397 0.1397)
			(layers "F.Cu" "F.Mask" "F.Paste")
			(net "P3V3_STBY_EN")
			(options
				(clearance outline)
				(anchor circle)
			)
			(primitives
				(gr_poly
					(pts
						(arc
							(start -0.1778 -0.2794)
							(mid -0.249642 -0.249642)
							(end -0.2794 -0.1778)
						)
						(arc
							(start -0.2794 0.1778)
							(mid -0.249642 0.249642)
							(end -0.1778 0.2794)
						)
						(arc
							(start 0.1778 0.2794)
							(mid 0.249642 0.249642)
							(end 0.2794 0.1778)
						)
						(arc
							(start 0.2794 -0.1778)
							(mid 0.249642 -0.249642)
							(end 0.1778 -0.2794)
						)
					)
					(width 0)
					(fill yes)
				)
			)
		)
		(pad "2" smd custom
			(at 0 0.4445)
			(size 0.1397 0.1397)
			(layers "F.Cu" "F.Mask" "F.Paste")
			(net "AGND_P3V3_STBY")
			(options
				(clearance outline)
				(anchor circle)
			)
			(primitives
				(gr_poly
					(pts
						(arc
							(start -0.1778 -0.2794)
							(mid -0.249642 -0.249642)
							(end -0.2794 -0.1778)
						)
						(arc
							(start -0.2794 0.1778)
							(mid -0.249642 0.249642)
							(end -0.1778 0.2794)
						)
						(arc
							(start 0.1778 0.2794)
							(mid 0.249642 0.249642)
							(end 0.2794 0.1778)
						)
						(arc
							(start 0.2794 -0.1778)
							(mid 0.249642 -0.249642)
							(end 0.1778 -0.2794)
						)
					)
					(width 0)
					(fill yes)
				)
			)
		)
	)
	(footprint ""
		(layer "F.Cu")
		(at 57.3151 -124.7648 90)
		(property "Reference" "R708"
			(at 0 0 90)
			(layer "F.SilkS")
			(hide yes)
			(effects
				(font
					(size 1.27 1.27)
				)
			)
		)
		(property "Value" "0R2J-2-GP"
			(at 0.064008 -3.993896 90)
			(unlocked yes)
			(layer "F.Fab")
			(hide yes)
			(effects
				(font
					(size 1.016 1.016)
					(thickness 0.1524)
				)
			)
		)
		(property "Device Type" "R402H16"
			(at 0.064008 -5.517896 90)
			(unlocked yes)
			(layer "F.Fab")
			(hide yes)
			(effects
				(font
					(size 1.016 1.016)
					(thickness 0.1524)
				)
			)
		)
		(duplicate_pad_numbers_are_jumpers no)
		(fp_line
			(start 0.508 -0.9398)
			(end -0.508 -0.9398)
			(stroke
				(width 0.1524)
				(type default)
			)
			(layer "F.SilkS")
		)
		(fp_line
			(start -0.508 -0.9398)
			(end -0.508 0.9398)
			(stroke
				(width 0.1524)
				(type default)
			)
			(layer "F.SilkS")
		)
		(fp_rect
			(start -0.508 0.9398)
			(end 0.508 -0.9398)
			(stroke
				(width 0)
				(type default)
			)
			(fill no)
			(layer "F.CrtYd")
		)
		(fp_rect
			(start -0.508 0.9398)
			(end 0.508 -0.9398)
			(stroke
				(width 0)
				(type default)
			)
			(fill no)
			(layer "F.Fab")
		)
		(pad "1" smd custom
			(at 0 -0.4445 90)
			(size 0.1397 0.1397)
			(layers "F.Cu" "F.Mask" "F.Paste")
			(net "TCA9554_INT_N_R")
			(options
				(clearance outline)
				(anchor circle)
			)
			(primitives
				(gr_poly
					(pts
						(arc
							(start -0.1778 -0.2794)
							(mid -0.249642 -0.249642)
							(end -0.2794 -0.1778)
						)
						(arc
							(start -0.2794 0.1778)
							(mid -0.249642 0.249642)
							(end -0.1778 0.2794)
						)
						(arc
							(start 0.1778 0.2794)
							(mid 0.249642 0.249642)
							(end 0.2794 0.1778)
						)
						(arc
							(start 0.2794 -0.1778)
							(mid 0.249642 -0.249642)
							(end 0.1778 -0.2794)
						)
					)
					(width 0)
					(fill yes)
				)
			)
		)
		(pad "2" smd custom
			(at 0 0.4445 90)
			(size 0.1397 0.1397)
			(layers "F.Cu" "F.Mask" "F.Paste")
			(net "TCA9554_INT_N")
			(options
				(clearance outline)
				(anchor circle)
			)
			(primitives
				(gr_poly
					(pts
						(arc
							(start -0.1778 -0.2794)
							(mid -0.249642 -0.249642)
							(end -0.2794 -0.1778)
						)
						(arc
							(start -0.2794 0.1778)
							(mid -0.249642 0.249642)
							(end -0.1778 0.2794)
						)
						(arc
							(start 0.1778 0.2794)
							(mid 0.249642 0.249642)
							(end 0.2794 0.1778)
						)
						(arc
							(start 0.2794 -0.1778)
							(mid 0.249642 -0.249642)
							(end 0.1778 -0.2794)
						)
					)
					(width 0)
					(fill yes)
				)
			)
		)
	)
	(footprint ""
		(layer "F.Cu")
		(at 30.061154 -146.414744)
		(property "Reference" "C176"
			(at 0 0 0)
			(layer "F.SilkS")
			(hide yes)
			(effects
				(font
					(size 1.27 1.27)
				)
			)
		)
		(property "Value" "SCD1U16V2KX-3GP"
			(at 1.1811 -2.7051 0)
			(unlocked yes)
			(layer "F.Fab")
			(hide yes)
			(effects
				(font
					(size 1.016 1.016)
					(thickness 0.1524)
				)
			)
		)
		(property "Device Type" "C402H22"
			(at 1.1811 -4.2291 0)
			(unlocked yes)
			(layer "F.Fab")
			(hide yes)
			(effects
				(font
					(size 1.016 1.016)
					(thickness 0.1524)
				)
			)
		)
		(duplicate_pad_numbers_are_jumpers no)
		(fp_rect
			(start -0.4318 0.9525)
			(end 0.4318 -0.9525)
			(stroke
				(width 0)
				(type default)
			)
			(fill no)
			(layer "F.CrtYd")
		)
		(fp_rect
			(start -0.4318 0.9525)
			(end 0.4318 -0.9525)
			(stroke
				(width 0)
				(type default)
			)
			(fill no)
			(layer "F.Fab")
		)
		(pad "1" smd custom
			(at 0 -0.4445)
			(size 0.1524 0.1524)
			(layers "F.Cu" "F.Mask" "F.Paste")
			(net "P1V53_STBY")
			(options
				(clearance outline)
				(anchor circle)
			)
			(primitives
				(gr_poly
					(pts
						(arc
							(start 0.3048 -0.2032)
							(mid 0.275042 -0.275042)
							(end 0.2032 -0.3048)
						)
						(arc
							(start -0.2032 -0.3048)
							(mid -0.275042 -0.275042)
							(end -0.3048 -0.2032)
						)
						(arc
							(start -0.3048 0.2032)
							(mid -0.275042 0.275042)
							(end -0.2032 0.3048)
						)
						(arc
							(start 0.2032 0.3048)
							(mid 0.275042 0.275042)
							(end 0.3048 0.2032)
						)
					)
					(width 0)
					(fill yes)
				)
			)
		)
		(pad "2" smd custom
			(at 0 0.4445)
			(size 0.1524 0.1524)
			(layers "F.Cu" "F.Mask" "F.Paste")
			(net "GND")
			(options
				(clearance outline)
				(anchor circle)
			)
			(primitives
				(gr_poly
					(pts
						(arc
							(start 0.3048 -0.2032)
							(mid 0.275042 -0.275042)
							(end 0.2032 -0.3048)
						)
						(arc
							(start -0.2032 -0.3048)
							(mid -0.275042 -0.275042)
							(end -0.3048 -0.2032)
						)
						(arc
							(start -0.3048 0.2032)
							(mid -0.275042 0.275042)
							(end -0.2032 0.3048)
						)
						(arc
							(start 0.2032 0.3048)
							(mid 0.275042 0.275042)
							(end 0.3048 0.2032)
						)
					)
					(width 0)
					(fill yes)
				)
			)
		)
	)
	(footprint ""
		(layer "F.Cu")
		(at 64.512952 -146.72691 -90)
		(property "Reference" "C152"
			(at 0 0 270)
			(layer "F.SilkS")
			(hide yes)
			(effects
				(font
					(size 1.27 1.27)
				)
			)
		)
		(property "Value" "SCD1U16V2JX-1-GP"
			(at 1.1811 -2.7051 270)
			(unlocked yes)
			(layer "F.Fab")
			(hide yes)
			(effects
				(font
					(size 1.016 1.016)
					(thickness 0.1524)
				)
			)
		)
		(property "Device Type" "C402H22"
			(at 1.1811 -4.2291 270)
			(unlocked yes)
			(layer "F.Fab")
			(hide yes)
			(effects
				(font
					(size 1.016 1.016)
					(thickness 0.1524)
				)
			)
		)
		(duplicate_pad_numbers_are_jumpers no)
		(fp_rect
			(start -0.4318 0.9525)
			(end 0.4318 -0.9525)
			(stroke
				(width 0)
				(type default)
			)
			(fill no)
			(layer "F.CrtYd")
		)
		(fp_rect
			(start -0.4318 0.9525)
			(end 0.4318 -0.9525)
			(stroke
				(width 0)
				(type default)
			)
			(fill no)
			(layer "F.Fab")
		)
		(pad "1" smd custom
			(at 0 -0.4445 270)
			(size 0.1524 0.1524)
			(layers "F.Cu" "F.Mask" "F.Paste")
			(net "P3V3_STBY")
			(options
				(clearance outline)
				(anchor circle)
			)
			(primitives
				(gr_poly
					(pts
						(arc
							(start 0.3048 -0.2032)
							(mid 0.275042 -0.275042)
							(end 0.2032 -0.3048)
						)
						(arc
							(start -0.2032 -0.3048)
							(mid -0.275042 -0.275042)
							(end -0.3048 -0.2032)
						)
						(arc
							(start -0.3048 0.2032)
							(mid -0.275042 0.275042)
							(end -0.2032 0.3048)
						)
						(arc
							(start 0.2032 0.3048)
							(mid 0.275042 0.275042)
							(end 0.3048 0.2032)
						)
					)
					(width 0)
					(fill yes)
				)
			)
		)
		(pad "2" smd custom
			(at 0 0.4445 270)
			(size 0.1524 0.1524)
			(layers "F.Cu" "F.Mask" "F.Paste")
			(net "GND")
			(options
				(clearance outline)
				(anchor circle)
			)
			(primitives
				(gr_poly
					(pts
						(arc
							(start 0.3048 -0.2032)
							(mid 0.275042 -0.275042)
							(end 0.2032 -0.3048)
						)
						(arc
							(start -0.2032 -0.3048)
							(mid -0.275042 -0.275042)
							(end -0.3048 -0.2032)
						)
						(arc
							(start -0.3048 0.2032)
							(mid -0.275042 0.275042)
							(end -0.2032 0.3048)
						)
						(arc
							(start 0.2032 0.3048)
							(mid 0.275042 0.275042)
							(end 0.3048 0.2032)
						)
					)
					(width 0)
					(fill yes)
				)
			)
		)
	)
	(footprint ""
		(layer "F.Cu")
		(at 61.7982 -163.4236 -90)
		(property "Reference" "PC17"
			(at 0 0 270)
			(layer "F.SilkS")
			(hide yes)
			(effects
				(font
					(size 1.27 1.27)
				)
			)
		)
		(property "Value" "SC820P50V2KX-1GP"
			(at 1.1811 -2.7051 270)
			(unlocked yes)
			(layer "F.Fab")
			(hide yes)
			(effects
				(font
					(size 1.016 1.016)
					(thickness 0.1524)
				)
			)
		)
		(property "Device Type" "C402H22"
			(at 1.1811 -4.2291 270)
			(unlocked yes)
			(layer "F.Fab")
			(hide yes)
			(effects
				(font
					(size 1.016 1.016)
					(thickness 0.1524)
				)
			)
		)
		(duplicate_pad_numbers_are_jumpers no)
		(fp_rect
			(start -0.4318 0.9525)
			(end 0.4318 -0.9525)
			(stroke
				(width 0)
				(type default)
			)
			(fill no)
			(layer "F.CrtYd")
		)
		(fp_rect
			(start -0.4318 0.9525)
			(end 0.4318 -0.9525)
			(stroke
				(width 0)
				(type default)
			)
			(fill no)
			(layer "F.Fab")
		)
		(pad "1" smd custom
			(at 0 -0.4445 270)
			(size 0.1524 0.1524)
			(layers "F.Cu" "F.Mask" "F.Paste")
			(net "VR_P1V538_STBY_SS_C")
			(options
				(clearance outline)
				(anchor circle)
			)
			(primitives
				(gr_poly
					(pts
						(arc
							(start 0.3048 -0.2032)
							(mid 0.275042 -0.275042)
							(end 0.2032 -0.3048)
						)
						(arc
							(start -0.2032 -0.3048)
							(mid -0.275042 -0.275042)
							(end -0.3048 -0.2032)
						)
						(arc
							(start -0.3048 0.2032)
							(mid -0.275042 0.275042)
							(end -0.2032 0.3048)
						)
						(arc
							(start 0.2032 0.3048)
							(mid 0.275042 0.275042)
							(end 0.3048 0.2032)
						)
					)
					(width 0)
					(fill yes)
				)
			)
		)
		(pad "2" smd custom
			(at 0 0.4445 270)
			(size 0.1524 0.1524)
			(layers "F.Cu" "F.Mask" "F.Paste")
			(net "GND")
			(options
				(clearance outline)
				(anchor circle)
			)
			(primitives
				(gr_poly
					(pts
						(arc
							(start 0.3048 -0.2032)
							(mid 0.275042 -0.275042)
							(end 0.2032 -0.3048)
						)
						(arc
							(start -0.2032 -0.3048)
							(mid -0.275042 -0.275042)
							(end -0.3048 -0.2032)
						)
						(arc
							(start -0.3048 0.2032)
							(mid -0.275042 0.275042)
							(end -0.2032 0.3048)
						)
						(arc
							(start 0.2032 0.3048)
							(mid 0.275042 0.275042)
							(end 0.3048 0.2032)
						)
					)
					(width 0)
					(fill yes)
				)
			)
		)
	)
	(footprint ""
		(layer "F.Cu")
		(at 133.864604 -67.223894 180)
		(property "Reference" "SKT4"
			(at 0 0 180)
			(layer "F.SilkS")
			(hide yes)
			(effects
				(font
					(size 1.27 1.27)
				)
			)
		)
		(property "Value" "SKT-SPI8P-9-GP"
			(at 6.989318 7.128764 180)
			(unlocked yes)
			(layer "F.Fab")
			(hide yes)
			(effects
				(font
					(size 1.016 1.016)
					(thickness 0.1524)
				)
			)
		)
		(property "Device Type" "SKT-SOIC8-104117H235"
			(at 6.989318 5.604764 180)
			(unlocked yes)
			(layer "F.Fab")
			(hide yes)
			(effects
				(font
					(size 1.016 1.016)
					(thickness 0.1524)
				)
			)
		)
		(duplicate_pad_numbers_are_jumpers no)
		(fp_line
			(start 5.4483 1.416304)
			(end 4.0513 3.334004)
			(stroke
				(width 0.1524)
				(type default)
			)
			(layer "F.SilkS")
		)
		(fp_line
			(start 5.4483 -1.416304)
			(end 5.4483 1.416304)
			(stroke
				(width 0.1524)
				(type default)
			)
			(layer "F.SilkS")
		)
		(fp_line
			(start 5.4356 0.762)
			(end 4.6736 0)
			(stroke
				(width 0.1524)
				(type default)
			)
			(layer "F.SilkS")
		)
		(fp_line
			(start 4.6736 0)
			(end 5.4356 -0.762)
			(stroke
				(width 0.1524)
				(type default)
			)
			(layer "F.SilkS")
		)
		(fp_line
			(start 4.0513 5.8293)
			(end -4.0513 5.8293)
			(stroke
				(width 0.1524)
				(type default)
			)
			(layer "F.SilkS")
		)
		(fp_line
			(start 4.0513 3.334004)
			(end 4.0513 5.8293)
			(stroke
				(width 0.1524)
				(type default)
			)
			(layer "F.SilkS")
		)
		(fp_line
			(start 4.0513 -3.334004)
			(end 5.4483 -1.416304)
			(stroke
				(width 0.1524)
				(type default)
			)
			(layer "F.SilkS")
		)
		(fp_line
			(start 4.0513 -5.8293)
			(end 4.0513 -3.334004)
			(stroke
				(width 0.1524)
				(type default)
			)
			(layer "F.SilkS")
		)
		(fp_line
			(start 3.8735 -5.6515)
			(end 3.8735 -3.6449)
			(stroke
				(width 0.508)
				(type default)
			)
			(layer "F.SilkS")
		)
		(fp_line
			(start -4.0513 5.8293)
			(end -4.0513 3.334004)
			(stroke
				(width 0.1524)
				(type default)
			)
			(layer "F.SilkS")
		)
		(fp_line
			(start -4.0513 3.334004)
			(end -5.4483 1.416304)
			(stroke
				(width 0.1524)
				(type default)
			)
			(layer "F.SilkS")
		)
		(fp_line
			(start -4.0513 -3.334004)
			(end -4.0513 -5.8293)
			(stroke
				(width 0.1524)
				(type default)
			)
			(layer "F.SilkS")
		)
		(fp_line
			(start -4.0513 -5.8293)
			(end 4.0513 -5.8293)
			(stroke
				(width 0.1524)
				(type default)
			)
			(layer "F.SilkS")
		)
		(fp_line
			(start -5.4483 1.416304)
			(end -5.4483 -1.416304)
			(stroke
				(width 0.1524)
				(type default)
			)
			(layer "F.SilkS")
		)
		(fp_line
			(start -5.4483 -1.416304)
			(end -4.0513 -3.334004)
			(stroke
				(width 0.1524)
				(type default)
			)
			(layer "F.SilkS")
		)
		(fp_poly
			(pts
				(xy -2.159 3.047492) (xy 2.159 3.047492) (xy 2.159 -3.047492) (xy -2.159 -3.047492)
			)
			(stroke
				(width 0)
				(type default)
			)
			(fill yes)
			(layer "F.SilkS")
		)
		(fp_rect
			(start -5.7023 9.7282)
			(end 5.7023 5.8293)
			(stroke
				(width 0)
				(type default)
			)
			(fill no)
			(layer "F.CrtYd")
		)
		(fp_rect
			(start -5.7023 -5.8293)
			(end 5.7023 -10.5156)
			(stroke
				(width 0)
				(type default)
			)
			(fill no)
			(layer "F.CrtYd")
		)
		(fp_poly
			(pts
				(xy 3.7973 5.8293) (xy 3.7973 3.2512) (xy 5.1943 1.3335) (xy 5.1943 -1.3335) (xy 3.7973 -3.2512)
				(xy 3.7973 -5.8293) (xy 5.7023 -5.8293) (xy 5.7023 5.8293)
			)
			(stroke
				(width 0)
				(type default)
			)
			(fill no)
			(layer "F.CrtYd")
		)
		(fp_poly
			(pts
				(xy -5.7023 5.8293) (xy -5.7023 -5.8293) (xy -3.7973 -5.8293) (xy -3.7973 -3.2512) (xy -5.1943 -1.3335)
				(xy -5.1943 1.3335) (xy -3.7973 3.2512) (xy -3.7973 5.8293)
			)
			(stroke
				(width 0)
				(type default)
			)
			(fill no)
			(layer "F.CrtYd")
		)
		(fp_poly
			(pts
				(xy -3.7973 5.8293) (xy -3.7973 3.2512) (xy -5.1943 1.3335) (xy -5.1943 -1.3335) (xy -3.7973 -3.2512)
				(xy -3.7973 -5.8293) (xy 3.7973 -5.8293) (xy 3.7973 -3.2512) (xy 5.1943 -1.3335) (xy 5.1943 1.3335)
				(xy 3.7973 3.2512) (xy 3.7973 5.8293)
			)
			(stroke
				(width 0)
				(type default)
			)
			(fill no)
			(layer "F.CrtYd")
		)
		(fp_rect
			(start -5.7023 9.7282)
			(end 5.7023 -10.5156)
			(stroke
				(width 0)
				(type default)
			)
			(fill no)
			(layer "F.Fab")
		)
		(pad "1" smd rect
			(at 1.905 -3.999992 180)
			(size 0.508 1.4986)
			(layers "F.Cu" "F.Mask" "F.Paste")
			(net "SPI_CSB0_0")
		)
		(pad "2" smd rect
			(at 0.635 -3.999992 180)
			(size 0.508 1.4986)
			(layers "F.Cu" "F.Mask" "F.Paste")
			(net "SPI_DATA0_1_R")
		)
		(pad "3" smd rect
			(at -0.635 -3.999992 180)
			(size 0.508 1.4986)
			(layers "F.Cu" "F.Mask" "F.Paste")
			(net "SPI_DATA0_2_R")
		)
		(pad "4" smd rect
			(at -1.905 -3.999992 180)
			(size 0.508 1.4986)
			(layers "F.Cu" "F.Mask" "F.Paste")
			(net "GND")
		)
		(pad "5" smd rect
			(at -1.905 3.999992 180)
			(size 0.508 1.4986)
			(layers "F.Cu" "F.Mask" "F.Paste")
			(net "SPI_DATA0_0_R")
		)
		(pad "6" smd rect
			(at -0.635 3.999992 180)
			(size 0.508 1.4986)
			(layers "F.Cu" "F.Mask" "F.Paste")
			(net "SPI_CLK0_R")
		)
		(pad "7" smd rect
			(at 0.635 3.999992 180)
			(size 0.508 1.4986)
			(layers "F.Cu" "F.Mask" "F.Paste")
			(net "SPI_DATA0_3_R")
		)
		(pad "8" smd rect
			(at 1.905 3.999992 180)
			(size 0.508 1.4986)
			(layers "F.Cu" "F.Mask" "F.Paste")
			(net "P1V8_STBY")
		)
		(zone
			(layer "F.Cu")
			(hatch none 0.5)
			(connect_pads
				(clearance 0)
			)
			(min_thickness 0.25)
			(keepout
				(tracks allowed)
				(vias not_allowed)
				(pads allowed)
				(copperpour not_allowed)
				(footprints allowed)
			)
			(placement
				(enabled no)
				(sheetname "")
			)
			(fill
				(thermal_gap 0.5)
				(thermal_bridge_width 0.5)
				(island_removal_mode 0)
			)
			(polygon
				(pts
					(xy 136.023604 -70.474586) (xy 131.705604 -70.474586) (xy 131.705604 -69.966586) (xy 136.023604 -69.966586)
				)
			)
		)
		(zone
			(layer "F.Cu")
			(hatch none 0.5)
			(connect_pads
				(clearance 0)
			)
			(min_thickness 0.25)
			(keepout
				(tracks allowed)
				(vias not_allowed)
				(pads allowed)
				(copperpour not_allowed)
				(footprints allowed)
			)
			(placement
				(enabled no)
				(sheetname "")
			)
			(fill
				(thermal_gap 0.5)
				(thermal_bridge_width 0.5)
				(island_removal_mode 0)
			)
			(polygon
				(pts
					(xy 136.023604 -70.474586) (xy 131.705604 -70.474586) (xy 131.705604 -63.973202) (xy 136.023604 -63.973202)
				)
			)
		)
		(zone
			(layer "F.Cu")
			(hatch none 0.5)
			(connect_pads
				(clearance 0)
			)
			(min_thickness 0.25)
			(keepout
				(tracks not_allowed)
				(vias allowed)
				(pads allowed)
				(copperpour not_allowed)
				(footprints allowed)
			)
			(placement
				(enabled no)
				(sheetname "")
			)
			(fill
				(thermal_gap 0.5)
				(thermal_bridge_width 0.5)
				(island_removal_mode 0)
			)
			(polygon
				(pts
					(xy 136.023604 -70.474586) (xy 131.705604 -70.474586) (xy 131.705604 -63.973202) (xy 136.023604 -63.973202)
				)
			)
		)
		(zone
			(layer "F.Cu")
			(hatch none 0.5)
			(connect_pads
				(clearance 0)
			)
			(min_thickness 0.25)
			(keepout
				(tracks allowed)
				(vias not_allowed)
				(pads allowed)
				(copperpour not_allowed)
				(footprints allowed)
			)
			(placement
				(enabled no)
				(sheetname "")
			)
			(fill
				(thermal_gap 0.5)
				(thermal_bridge_width 0.5)
				(island_removal_mode 0)
			)
			(polygon
				(pts
					(xy 136.023604 -64.481202) (xy 131.705604 -64.481202) (xy 131.705604 -63.973202) (xy 136.023604 -63.973202)
				)
			)
		)
	)
	(footprint ""
		(layer "F.Cu")
		(at 324.612 -97.917)
		(property "Reference" "TP301"
			(at 0 0 0)
			(layer "F.SilkS")
			(hide yes)
			(effects
				(font
					(size 1.27 1.27)
				)
			)
		)
		(property "Value" "TPAD28-2-GP"
			(at -0.0127 -1.6637 0)
			(unlocked yes)
			(layer "F.Fab")
			(hide yes)
			(effects
				(font
					(size 1.016 1.016)
					(thickness 0.1524)
				)
			)
		)
		(property "Device Type" "TPAD28"
			(at -0.0127 -3.1877 0)
			(unlocked yes)
			(layer "F.Fab")
			(hide yes)
			(effects
				(font
					(size 1.016 1.016)
					(thickness 0.1524)
				)
			)
		)
		(duplicate_pad_numbers_are_jumpers no)
		(fp_poly
			(pts
				(arc
					(start 0.3556 0)
					(mid -0.3556 0)
					(end 0.3556 0)
				)
			)
			(stroke
				(width 0)
				(type default)
			)
			(fill no)
			(layer "F.CrtYd")
		)
		(fp_poly
			(pts
				(arc
					(start 0.6096 0)
					(mid -0.6096 0)
					(end 0.6096 0)
				)
			)
			(stroke
				(width 0)
				(type default)
			)
			(fill no)
			(layer "F.Fab")
		)
		(pad "1" smd circle
			(at 0 0)
			(size 0.7112 0.7112)
			(layers "F.Cu" "F.Mask" "F.Paste")
			(net "MAX7311_TP301")
		)
	)
	(footprint ""
		(layer "F.Cu")
		(at 29.52369 -114.18189 180)
		(property "Reference" "R605"
			(at 0 0 180)
			(layer "F.SilkS")
			(hide yes)
			(effects
				(font
					(size 1.27 1.27)
				)
			)
		)
		(property "Value" "10KR2F-2-GP"
			(at 0.064008 -3.993896 180)
			(unlocked yes)
			(layer "F.Fab")
			(hide yes)
			(effects
				(font
					(size 1.016 1.016)
					(thickness 0.1524)
				)
			)
		)
		(property "Device Type" "R402H16"
			(at 0.064008 -5.517896 180)
			(unlocked yes)
			(layer "F.Fab")
			(hide yes)
			(effects
				(font
					(size 1.016 1.016)
					(thickness 0.1524)
				)
			)
		)
		(duplicate_pad_numbers_are_jumpers no)
		(fp_line
			(start 0.508 -0.9398)
			(end -0.508 -0.9398)
			(stroke
				(width 0.1524)
				(type default)
			)
			(layer "F.SilkS")
		)
		(fp_line
			(start -0.508 -0.9398)
			(end -0.508 0.9398)
			(stroke
				(width 0.1524)
				(type default)
			)
			(layer "F.SilkS")
		)
		(fp_rect
			(start -0.508 0.9398)
			(end 0.508 -0.9398)
			(stroke
				(width 0)
				(type default)
			)
			(fill no)
			(layer "F.CrtYd")
		)
		(fp_rect
			(start -0.508 0.9398)
			(end 0.508 -0.9398)
			(stroke
				(width 0)
				(type default)
			)
			(fill no)
			(layer "F.Fab")
		)
		(pad "1" smd custom
			(at 0 -0.4445 180)
			(size 0.1397 0.1397)
			(layers "F.Cu" "F.Mask" "F.Paste")
			(net "P3V3_STBY")
			(options
				(clearance outline)
				(anchor circle)
			)
			(primitives
				(gr_poly
					(pts
						(arc
							(start -0.1778 -0.2794)
							(mid -0.249642 -0.249642)
							(end -0.2794 -0.1778)
						)
						(arc
							(start -0.2794 0.1778)
							(mid -0.249642 0.249642)
							(end -0.1778 0.2794)
						)
						(arc
							(start 0.1778 0.2794)
							(mid 0.249642 0.249642)
							(end 0.2794 0.1778)
						)
						(arc
							(start 0.2794 -0.1778)
							(mid 0.249642 -0.249642)
							(end 0.1778 -0.2794)
						)
					)
					(width 0)
					(fill yes)
				)
			)
		)
		(pad "2" smd custom
			(at 0 0.4445 180)
			(size 0.1397 0.1397)
			(layers "F.Cu" "F.Mask" "F.Paste")
			(net "I2C_MUX_RESET_PEB")
			(options
				(clearance outline)
				(anchor circle)
			)
			(primitives
				(gr_poly
					(pts
						(arc
							(start -0.1778 -0.2794)
							(mid -0.249642 -0.249642)
							(end -0.2794 -0.1778)
						)
						(arc
							(start -0.2794 0.1778)
							(mid -0.249642 0.249642)
							(end -0.1778 0.2794)
						)
						(arc
							(start 0.1778 0.2794)
							(mid 0.249642 0.249642)
							(end 0.2794 0.1778)
						)
						(arc
							(start 0.2794 -0.1778)
							(mid 0.249642 -0.249642)
							(end 0.1778 -0.2794)
						)
					)
					(width 0)
					(fill yes)
				)
			)
		)
	)
	(footprint ""
		(layer "F.Cu")
		(at 64.447674 -67.12712)
		(property "Reference" "SKT3"
			(at 0 0 0)
			(layer "F.SilkS")
			(hide yes)
			(effects
				(font
					(size 1.27 1.27)
				)
			)
		)
		(property "Value" "SKT-SPI16P-GP-U"
			(at -8.9916 4.641596 0)
			(unlocked yes)
			(layer "F.Fab")
			(hide yes)
			(effects
				(font
					(size 1.016 1.016)
					(thickness 0.1524)
				)
			)
		)
		(property "Device Type" "SKT-SOIC16-153139H258"
			(at -8.9916 3.117596 0)
			(unlocked yes)
			(layer "F.Fab")
			(hide yes)
			(effects
				(font
					(size 1.016 1.016)
					(thickness 0.1524)
				)
			)
		)
		(duplicate_pad_numbers_are_jumpers no)
		(fp_line
			(start -7.8994 -6.4008)
			(end -7.8994 6.4008)
			(stroke
				(width 0.1524)
				(type default)
			)
			(layer "F.SilkS")
		)
		(fp_line
			(start -7.8994 6.4008)
			(end 7.8994 6.4008)
			(stroke
				(width 0.1524)
				(type default)
			)
			(layer "F.SilkS")
		)
		(fp_line
			(start 6.7183 0.0762)
			(end 7.8994 1.2573)
			(stroke
				(width 0.1524)
				(type default)
			)
			(layer "F.SilkS")
		)
		(fp_line
			(start 7.7216 -6.223)
			(end 7.7216 -3.6576)
			(stroke
				(width 0.508)
				(type default)
			)
			(layer "F.SilkS")
		)
		(fp_line
			(start 7.8867 -1.0922)
			(end 6.7183 0.0762)
			(stroke
				(width 0.1524)
				(type default)
			)
			(layer "F.SilkS")
		)
		(fp_line
			(start 7.8994 -6.4008)
			(end -7.8994 -6.4008)
			(stroke
				(width 0.1524)
				(type default)
			)
			(layer "F.SilkS")
		)
		(fp_line
			(start 7.8994 6.4008)
			(end 7.8994 -6.4008)
			(stroke
				(width 0.1524)
				(type default)
			)
			(layer "F.SilkS")
		)
		(fp_poly
			(pts
				(xy -4.699 -3.855466) (xy -4.699 3.855466) (xy 4.699 3.855466) (xy 4.699 -3.855466)
			)
			(stroke
				(width 0)
				(type default)
			)
			(fill yes)
			(layer "F.SilkS")
		)
		(fp_rect
			(start -8.1534 -6.4008)
			(end 8.1534 -12.5222)
			(stroke
				(width 0)
				(type default)
			)
			(fill no)
			(layer "F.CrtYd")
		)
		(fp_rect
			(start -8.1534 11.6078)
			(end 8.1534 6.4008)
			(stroke
				(width 0)
				(type default)
			)
			(fill no)
			(layer "F.CrtYd")
		)
		(fp_poly
			(pts
				(xy -8.1534 6.4008) (xy -8.1534 -6.4008) (xy -6.2484 -6.4008) (xy -6.2484 -2.6416) (xy -7.6454 -2.6416)
				(xy -7.6454 2.6416) (xy -6.2484 2.6416) (xy -6.2484 6.4008)
			)
			(stroke
				(width 0)
				(type default)
			)
			(fill no)
			(layer "F.CrtYd")
		)
		(fp_poly
			(pts
				(xy 6.2484 -6.4008) (xy 8.1534 -6.4008) (xy 8.1534 6.4008) (xy 6.2484 6.4008) (xy 6.2484 2.6416)
				(xy 7.6454 2.6416) (xy 7.6454 -2.6416) (xy 6.2484 -2.6416)
			)
			(stroke
				(width 0)
				(type default)
			)
			(fill no)
			(layer "F.CrtYd")
		)
		(fp_poly
			(pts
				(xy 6.2484 -6.4008) (xy -6.2484 -6.4008) (xy -6.2484 -2.6416) (xy -7.6454 -2.6416) (xy -7.6454 2.6416)
				(xy -6.2484 2.6416) (xy -6.2484 6.4008) (xy 6.2484 6.4008) (xy 6.2484 2.6416) (xy 7.6454 2.6416)
				(xy 7.6454 -2.6416) (xy 6.2484 -2.6416)
			)
			(stroke
				(width 0)
				(type default)
			)
			(fill no)
			(layer "F.CrtYd")
		)
		(fp_rect
			(start -8.1534 11.6078)
			(end 8.1534 -12.5222)
			(stroke
				(width 0)
				(type default)
			)
			(fill no)
			(layer "F.Fab")
		)
		(pad "1" smd rect
			(at 4.445 -4.896866)
			(size 0.508 1.6764)
			(layers "F.Cu" "F.Mask" "F.Paste")
			(net "PU_IBMC_BT_HOLD_N")
		)
		(pad "2" smd rect
			(at 3.175 -4.896866)
			(size 0.508 1.6764)
			(layers "F.Cu" "F.Mask" "F.Paste")
			(net "P3V3_STBY")
		)
		(pad "3" smd rect
			(at 1.905 -4.896866)
			(size 0.508 1.6764)
			(layers "F.Cu" "F.Mask" "F.Paste")
			(net "U19_PERST_N")
		)
		(pad "4" smd rect
			(at 0.635 -4.896866)
			(size 0.508 1.6764)
			(layers "F.Cu" "F.Mask" "F.Paste")
			(net "Net_2114")
		)
		(pad "5" smd rect
			(at -0.635 -4.896866)
			(size 0.508 1.6764)
			(layers "F.Cu" "F.Mask" "F.Paste")
			(net "Net_2113")
		)
		(pad "6" smd rect
			(at -1.905 -4.896866)
			(size 0.508 1.6764)
			(layers "F.Cu" "F.Mask" "F.Paste")
			(net "Net_2112")
		)
		(pad "7" smd rect
			(at -3.175 -4.896866)
			(size 0.508 1.6764)
			(layers "F.Cu" "F.Mask" "F.Paste")
			(net "FLA_CS1_R")
		)
		(pad "8" smd rect
			(at -4.445 -4.896866)
			(size 0.508 1.6764)
			(layers "F.Cu" "F.Mask" "F.Paste")
			(net "ROMD2_R")
		)
		(pad "9" smd rect
			(at -4.445 4.896866)
			(size 0.508 1.6764)
			(layers "F.Cu" "F.Mask" "F.Paste")
			(net "FLA_WPN")
		)
		(pad "10" smd rect
			(at -3.175 4.896866)
			(size 0.508 1.6764)
			(layers "F.Cu" "F.Mask" "F.Paste")
			(net "GND")
		)
		(pad "11" smd rect
			(at -1.905 4.896866)
			(size 0.508 1.6764)
			(layers "F.Cu" "F.Mask" "F.Paste")
			(net "Net_2118")
		)
		(pad "12" smd rect
			(at -0.635 4.896866)
			(size 0.508 1.6764)
			(layers "F.Cu" "F.Mask" "F.Paste")
			(net "Net_2117")
		)
		(pad "13" smd rect
			(at 0.635 4.896866)
			(size 0.508 1.6764)
			(layers "F.Cu" "F.Mask" "F.Paste")
			(net "Net_2116")
		)
		(pad "14" smd rect
			(at 1.905 4.896866)
			(size 0.508 1.6764)
			(layers "F.Cu" "F.Mask" "F.Paste")
			(net "Net_2115")
		)
		(pad "15" smd rect
			(at 3.175 4.896866)
			(size 0.508 1.6764)
			(layers "F.Cu" "F.Mask" "F.Paste")
			(net "ROMD1_R")
		)
		(pad "16" smd rect
			(at 4.445 4.896866)
			(size 0.508 1.6764)
			(layers "F.Cu" "F.Mask" "F.Paste")
			(net "ROMD0_R")
		)
	)
	(footprint ""
		(layer "F.Cu")
		(at 73.4822 -118.11 -90)
		(property "Reference" "C282"
			(at 0 0 270)
			(layer "F.SilkS")
			(hide yes)
			(effects
				(font
					(size 1.27 1.27)
				)
			)
		)
		(property "Value" "SCD1U16V2KX-3GP"
			(at 1.1811 -2.7051 270)
			(unlocked yes)
			(layer "F.Fab")
			(hide yes)
			(effects
				(font
					(size 1.016 1.016)
					(thickness 0.1524)
				)
			)
		)
		(property "Device Type" "C402H22"
			(at 1.1811 -4.2291 270)
			(unlocked yes)
			(layer "F.Fab")
			(hide yes)
			(effects
				(font
					(size 1.016 1.016)
					(thickness 0.1524)
				)
			)
		)
		(duplicate_pad_numbers_are_jumpers no)
		(fp_rect
			(start -0.4318 0.9525)
			(end 0.4318 -0.9525)
			(stroke
				(width 0)
				(type default)
			)
			(fill no)
			(layer "F.CrtYd")
		)
		(fp_rect
			(start -0.4318 0.9525)
			(end 0.4318 -0.9525)
			(stroke
				(width 0)
				(type default)
			)
			(fill no)
			(layer "F.Fab")
		)
		(pad "1" smd custom
			(at 0 -0.4445 270)
			(size 0.1524 0.1524)
			(layers "F.Cu" "F.Mask" "F.Paste")
			(net "P3V3_STBY")
			(options
				(clearance outline)
				(anchor circle)
			)
			(primitives
				(gr_poly
					(pts
						(arc
							(start 0.3048 -0.2032)
							(mid 0.275042 -0.275042)
							(end 0.2032 -0.3048)
						)
						(arc
							(start -0.2032 -0.3048)
							(mid -0.275042 -0.275042)
							(end -0.3048 -0.2032)
						)
						(arc
							(start -0.3048 0.2032)
							(mid -0.275042 0.275042)
							(end -0.2032 0.3048)
						)
						(arc
							(start 0.2032 0.3048)
							(mid 0.275042 0.275042)
							(end 0.3048 0.2032)
						)
					)
					(width 0)
					(fill yes)
				)
			)
		)
		(pad "2" smd custom
			(at 0 0.4445 270)
			(size 0.1524 0.1524)
			(layers "F.Cu" "F.Mask" "F.Paste")
			(net "GND")
			(options
				(clearance outline)
				(anchor circle)
			)
			(primitives
				(gr_poly
					(pts
						(arc
							(start 0.3048 -0.2032)
							(mid 0.275042 -0.275042)
							(end 0.2032 -0.3048)
						)
						(arc
							(start -0.2032 -0.3048)
							(mid -0.275042 -0.275042)
							(end -0.3048 -0.2032)
						)
						(arc
							(start -0.3048 0.2032)
							(mid -0.275042 0.275042)
							(end -0.2032 0.3048)
						)
						(arc
							(start 0.2032 0.3048)
							(mid 0.275042 0.275042)
							(end 0.3048 0.2032)
						)
					)
					(width 0)
					(fill yes)
				)
			)
		)
	)
	(footprint ""
		(layer "F.Cu")
		(at 226.314 -78.1304 180)
		(property "Reference" "R587"
			(at 0 0 180)
			(layer "F.SilkS")
			(hide yes)
			(effects
				(font
					(size 1.27 1.27)
				)
			)
		)
		(property "Value" "0R2J-2-GP"
			(at 0.064008 -3.993896 180)
			(unlocked yes)
			(layer "F.Fab")
			(hide yes)
			(effects
				(font
					(size 1.016 1.016)
					(thickness 0.1524)
				)
			)
		)
		(property "Device Type" "R402H16"
			(at 0.064008 -5.517896 180)
			(unlocked yes)
			(layer "F.Fab")
			(hide yes)
			(effects
				(font
					(size 1.016 1.016)
					(thickness 0.1524)
				)
			)
		)
		(duplicate_pad_numbers_are_jumpers no)
		(fp_line
			(start 0.508 -0.9398)
			(end -0.508 -0.9398)
			(stroke
				(width 0.1524)
				(type default)
			)
			(layer "F.SilkS")
		)
		(fp_line
			(start -0.508 -0.9398)
			(end -0.508 0.9398)
			(stroke
				(width 0.1524)
				(type default)
			)
			(layer "F.SilkS")
		)
		(fp_rect
			(start -0.508 0.9398)
			(end 0.508 -0.9398)
			(stroke
				(width 0)
				(type default)
			)
			(fill no)
			(layer "F.CrtYd")
		)
		(fp_rect
			(start -0.508 0.9398)
			(end 0.508 -0.9398)
			(stroke
				(width 0)
				(type default)
			)
			(fill no)
			(layer "F.Fab")
		)
		(pad "1" smd custom
			(at 0 -0.4445 180)
			(size 0.1397 0.1397)
			(layers "F.Cu" "F.Mask" "F.Paste")
			(net "BMC_I2C5_D_PEB_SDA")
			(options
				(clearance outline)
				(anchor circle)
			)
			(primitives
				(gr_poly
					(pts
						(arc
							(start -0.1778 -0.2794)
							(mid -0.249642 -0.249642)
							(end -0.2794 -0.1778)
						)
						(arc
							(start -0.2794 0.1778)
							(mid -0.249642 0.249642)
							(end -0.1778 0.2794)
						)
						(arc
							(start 0.1778 0.2794)
							(mid 0.249642 0.249642)
							(end 0.2794 0.1778)
						)
						(arc
							(start 0.2794 -0.1778)
							(mid 0.249642 -0.249642)
							(end 0.1778 -0.2794)
						)
					)
					(width 0)
					(fill yes)
				)
			)
		)
		(pad "2" smd custom
			(at 0 0.4445 180)
			(size 0.1397 0.1397)
			(layers "F.Cu" "F.Mask" "F.Paste")
			(net "TEMP_3_SDA")
			(options
				(clearance outline)
				(anchor circle)
			)
			(primitives
				(gr_poly
					(pts
						(arc
							(start -0.1778 -0.2794)
							(mid -0.249642 -0.249642)
							(end -0.2794 -0.1778)
						)
						(arc
							(start -0.2794 0.1778)
							(mid -0.249642 0.249642)
							(end -0.1778 0.2794)
						)
						(arc
							(start 0.1778 0.2794)
							(mid 0.249642 0.249642)
							(end 0.2794 0.1778)
						)
						(arc
							(start 0.2794 -0.1778)
							(mid 0.249642 -0.249642)
							(end 0.1778 -0.2794)
						)
					)
					(width 0)
					(fill yes)
				)
			)
		)
	)
	(footprint ""
		(layer "F.Cu")
		(at 70.993 -33.02 -90)
		(property "Reference" "PC31"
			(at 0 0 270)
			(layer "F.SilkS")
			(hide yes)
			(effects
				(font
					(size 1.27 1.27)
				)
			)
		)
		(property "Value" "SC1KP50V2KX-1GP"
			(at 1.1811 -2.7051 270)
			(unlocked yes)
			(layer "F.Fab")
			(hide yes)
			(effects
				(font
					(size 1.016 1.016)
					(thickness 0.1524)
				)
			)
		)
		(property "Device Type" "C402H22"
			(at 1.1811 -4.2291 270)
			(unlocked yes)
			(layer "F.Fab")
			(hide yes)
			(effects
				(font
					(size 1.016 1.016)
					(thickness 0.1524)
				)
			)
		)
		(duplicate_pad_numbers_are_jumpers no)
		(fp_rect
			(start -0.4318 0.9525)
			(end 0.4318 -0.9525)
			(stroke
				(width 0)
				(type default)
			)
			(fill no)
			(layer "F.CrtYd")
		)
		(fp_rect
			(start -0.4318 0.9525)
			(end 0.4318 -0.9525)
			(stroke
				(width 0)
				(type default)
			)
			(fill no)
			(layer "F.Fab")
		)
		(pad "1" smd custom
			(at 0 -0.4445 270)
			(size 0.1524 0.1524)
			(layers "F.Cu" "F.Mask" "F.Paste")
			(net "P3V3_STBY_LL_R")
			(options
				(clearance outline)
				(anchor circle)
			)
			(primitives
				(gr_poly
					(pts
						(arc
							(start 0.3048 -0.2032)
							(mid 0.275042 -0.275042)
							(end 0.2032 -0.3048)
						)
						(arc
							(start -0.2032 -0.3048)
							(mid -0.275042 -0.275042)
							(end -0.3048 -0.2032)
						)
						(arc
							(start -0.3048 0.2032)
							(mid -0.275042 0.275042)
							(end -0.2032 0.3048)
						)
						(arc
							(start 0.2032 0.3048)
							(mid 0.275042 0.275042)
							(end 0.3048 0.2032)
						)
					)
					(width 0)
					(fill yes)
				)
			)
		)
		(pad "2" smd custom
			(at 0 0.4445 270)
			(size 0.1524 0.1524)
			(layers "F.Cu" "F.Mask" "F.Paste")
			(net "P3V3_STBY_VFB")
			(options
				(clearance outline)
				(anchor circle)
			)
			(primitives
				(gr_poly
					(pts
						(arc
							(start 0.3048 -0.2032)
							(mid 0.275042 -0.275042)
							(end 0.2032 -0.3048)
						)
						(arc
							(start -0.2032 -0.3048)
							(mid -0.275042 -0.275042)
							(end -0.3048 -0.2032)
						)
						(arc
							(start -0.3048 0.2032)
							(mid -0.275042 0.275042)
							(end -0.2032 0.3048)
						)
						(arc
							(start 0.2032 0.3048)
							(mid 0.275042 0.275042)
							(end 0.3048 0.2032)
						)
					)
					(width 0)
					(fill yes)
				)
			)
		)
	)
	(footprint ""
		(layer "F.Cu")
		(at 147.7518 -89.535 180)
		(property "Reference" "PC90"
			(at 0 0 180)
			(layer "F.SilkS")
			(hide yes)
			(effects
				(font
					(size 1.27 1.27)
				)
			)
		)
		(property "Value" "SC22U6D3V5MX-5-GP"
			(at -0.0762 -6.1214 180)
			(unlocked yes)
			(layer "F.Fab")
			(hide yes)
			(effects
				(font
					(size 1.016 1.016)
					(thickness 0.1524)
				)
			)
		)
		(property "Device Type" "C805H56"
			(at -0.0762 -8.1534 180)
			(unlocked yes)
			(layer "F.Fab")
			(hide yes)
			(effects
				(font
					(size 1.016 1.016)
					(thickness 0.1524)
				)
			)
		)
		(duplicate_pad_numbers_are_jumpers no)
		(fp_line
			(start 0.635 0)
			(end -0.635 0)
			(stroke
				(width 0.508)
				(type default)
			)
			(layer "F.SilkS")
		)
		(fp_rect
			(start -0.9652 1.778)
			(end 0.9652 -1.778)
			(stroke
				(width 0)
				(type default)
			)
			(fill no)
			(layer "F.CrtYd")
		)
		(fp_poly
			(pts
				(xy -0.9652 -1.778) (xy 0.9652 -1.778) (xy 0.9652 1.778) (xy -0.9652 1.778)
			)
			(stroke
				(width 0)
				(type default)
			)
			(fill no)
			(layer "F.Fab")
		)
		(pad "1" smd rect
			(at 0 -0.9652 180)
			(size 1.397 1.143)
			(layers "F.Cu" "F.Mask" "F.Paste")
			(net "P1V8_PWR")
		)
		(pad "2" smd rect
			(at 0 0.9652 180)
			(size 1.397 1.143)
			(layers "F.Cu" "F.Mask" "F.Paste")
			(net "GND")
		)
	)
	(footprint ""
		(layer "F.Cu")
		(at 330.099924 -13.999972 -90)
		(property "Reference" "LED13"
			(at 0 0 270)
			(layer "F.SilkS")
			(hide yes)
			(effects
				(font
					(size 1.27 1.27)
				)
			)
		)
		(property "Value" "LED-YG-51-GP"
			(at -2.6924 -1.4224 270)
			(unlocked yes)
			(layer "F.Fab")
			(hide yes)
			(effects
				(font
					(size 1.016 1.016)
					(thickness 0.1524)
				)
			)
		)
		(property "Device Type" "LED1608AKH40"
			(at -2.6924 -2.9464 270)
			(unlocked yes)
			(layer "F.Fab")
			(hide yes)
			(effects
				(font
					(size 1.016 1.016)
					(thickness 0.1524)
				)
			)
		)
		(duplicate_pad_numbers_are_jumpers no)
		(fp_line
			(start -0.7493 1.651)
			(end -0.7493 1.1811)
			(stroke
				(width 0.3302)
				(type default)
			)
			(layer "F.SilkS")
		)
		(fp_line
			(start 0.7493 1.651)
			(end 0.7493 1.1811)
			(stroke
				(width 0.3302)
				(type default)
			)
			(layer "F.SilkS")
		)
		(fp_line
			(start -0.5969 1.5494)
			(end 0.5842 1.5494)
			(stroke
				(width 0.508)
				(type default)
			)
			(layer "F.SilkS")
		)
		(fp_line
			(start -0.6604 1.3716)
			(end -0.6604 -1.3716)
			(stroke
				(width 0.1524)
				(type default)
			)
			(layer "F.SilkS")
		)
		(fp_line
			(start 0.6604 1.3716)
			(end -0.6604 1.3716)
			(stroke
				(width 0.1524)
				(type default)
			)
			(layer "F.SilkS")
		)
		(fp_line
			(start -0.6604 -1.3716)
			(end 0.6604 -1.3716)
			(stroke
				(width 0.1524)
				(type default)
			)
			(layer "F.SilkS")
		)
		(fp_line
			(start 0.6604 -1.3716)
			(end 0.6604 1.3716)
			(stroke
				(width 0.1524)
				(type default)
			)
			(layer "F.SilkS")
		)
		(fp_rect
			(start -0.6223 1.3335)
			(end 0.6223 -1.3335)
			(stroke
				(width 0)
				(type default)
			)
			(fill no)
			(layer "F.CrtYd")
		)
		(fp_rect
			(start -0.6223 1.3335)
			(end 0.6223 -1.3335)
			(stroke
				(width 0)
				(type default)
			)
			(fill no)
			(layer "F.Fab")
		)
		(pad "A" smd custom
			(at 0 -0.762 270)
			(size 0.2159 0.2159)
			(layers "F.Cu" "F.Mask" "F.Paste")
			(net "LED_R_6")
			(options
				(clearance outline)
				(anchor circle)
			)
			(primitives
				(gr_poly
					(pts
						(arc
							(start -0.3302 -0.4318)
							(mid -0.402042 -0.402042)
							(end -0.4318 -0.3302)
						)
						(arc
							(start -0.4318 0.3302)
							(mid -0.402042 0.402042)
							(end -0.3302 0.4318)
						)
						(arc
							(start 0.3302 0.4318)
							(mid 0.402042 0.402042)
							(end 0.4318 0.3302)
						)
						(arc
							(start 0.4318 -0.3302)
							(mid 0.402042 -0.402042)
							(end 0.3302 -0.4318)
						)
					)
					(width 0)
					(fill yes)
				)
			)
		)
		(pad "K" smd custom
			(at 0 0.762 270)
			(size 0.2159 0.2159)
			(layers "F.Cu" "F.Mask" "F.Paste")
			(net "LED_Q_6")
			(options
				(clearance outline)
				(anchor circle)
			)
			(primitives
				(gr_poly
					(pts
						(arc
							(start -0.3302 -0.4318)
							(mid -0.402042 -0.402042)
							(end -0.4318 -0.3302)
						)
						(arc
							(start -0.4318 0.3302)
							(mid -0.402042 0.402042)
							(end -0.3302 0.4318)
						)
						(arc
							(start 0.3302 0.4318)
							(mid 0.402042 0.402042)
							(end 0.4318 0.3302)
						)
						(arc
							(start 0.4318 -0.3302)
							(mid 0.402042 -0.402042)
							(end 0.3302 -0.4318)
						)
					)
					(width 0)
					(fill yes)
				)
			)
		)
	)
	(footprint ""
		(layer "F.Cu")
		(at 31.9278 -193.3702 90)
		(property "Reference" "C7279"
			(at 0 0 90)
			(layer "F.SilkS")
			(hide yes)
			(effects
				(font
					(size 1.27 1.27)
				)
			)
		)
		(property "Value" "SCD033U50V3KX-1GP"
			(at 0 -2.8194 90)
			(unlocked yes)
			(layer "F.Fab")
			(hide yes)
			(effects
				(font
					(size 1.016 1.016)
					(thickness 0.1524)
				)
			)
		)
		(property "Device Type" "C603H36"
			(at 0 -4.3434 90)
			(unlocked yes)
			(layer "F.Fab")
			(hide yes)
			(effects
				(font
					(size 1.016 1.016)
					(thickness 0.1524)
				)
			)
		)
		(duplicate_pad_numbers_are_jumpers no)
		(fp_line
			(start 0.508 0)
			(end -0.508 0)
			(stroke
				(width 0.2032)
				(type default)
			)
			(layer "F.SilkS")
		)
		(fp_rect
			(start -0.5842 1.3335)
			(end 0.5842 -1.3335)
			(stroke
				(width 0)
				(type default)
			)
			(fill no)
			(layer "F.CrtYd")
		)
		(fp_rect
			(start -0.5842 1.3335)
			(end 0.5842 -1.3335)
			(stroke
				(width 0)
				(type default)
			)
			(fill no)
			(layer "F.Fab")
		)
		(pad "1" smd custom
			(at 0 -0.762 90)
			(size 0.2159 0.2159)
			(layers "F.Cu" "F.Mask" "F.Paste")
			(net "MB0_CM_GATE_R")
			(options
				(clearance outline)
				(anchor circle)
			)
			(primitives
				(gr_poly
					(pts
						(arc
							(start -0.3302 -0.4318)
							(mid -0.402042 -0.402042)
							(end -0.4318 -0.3302)
						)
						(arc
							(start -0.4318 0.3302)
							(mid -0.402042 0.402042)
							(end -0.3302 0.4318)
						)
						(arc
							(start 0.3302 0.4318)
							(mid 0.402042 0.402042)
							(end 0.4318 0.3302)
						)
						(arc
							(start 0.4318 -0.3302)
							(mid 0.402042 -0.402042)
							(end 0.3302 -0.4318)
						)
					)
					(width 0)
					(fill yes)
				)
			)
		)
		(pad "2" smd custom
			(at 0 0.762 90)
			(size 0.2159 0.2159)
			(layers "F.Cu" "F.Mask" "F.Paste")
			(net "GND")
			(options
				(clearance outline)
				(anchor circle)
			)
			(primitives
				(gr_poly
					(pts
						(arc
							(start -0.3302 -0.4318)
							(mid -0.402042 -0.402042)
							(end -0.4318 -0.3302)
						)
						(arc
							(start -0.4318 0.3302)
							(mid -0.402042 0.402042)
							(end -0.3302 0.4318)
						)
						(arc
							(start 0.3302 0.4318)
							(mid 0.402042 0.402042)
							(end 0.4318 0.3302)
						)
						(arc
							(start 0.4318 -0.3302)
							(mid 0.402042 -0.402042)
							(end 0.3302 -0.4318)
						)
					)
					(width 0)
					(fill yes)
				)
			)
		)
	)
	(footprint ""
		(layer "F.Cu")
		(at 22.479 -151.892 90)
		(property "Reference" "U80"
			(at 0 0 90)
			(layer "F.SilkS")
			(hide yes)
			(effects
				(font
					(size 1.27 1.27)
				)
			)
		)
		(property "Value" "SN74LVC1G08DCKR-GP"
			(at -2.3368 -8.6868 90)
			(unlocked yes)
			(layer "F.Fab")
			(hide yes)
			(effects
				(font
					(size 1.016 1.016)
					(thickness 0.1524)
				)
			)
		)
		(property "Device Type" "SC70-5H44"
			(at -2.3114 -10.414 90)
			(unlocked yes)
			(layer "F.Fab")
			(hide yes)
			(effects
				(font
					(size 1.016 1.016)
					(thickness 0.1524)
				)
			)
		)
		(duplicate_pad_numbers_are_jumpers no)
		(fp_line
			(start 1.3843 -1.8034)
			(end 1.3843 -1.1176)
			(stroke
				(width 0.3302)
				(type default)
			)
			(layer "F.SilkS")
		)
		(fp_line
			(start 0.6604 -1.8034)
			(end 1.3843 -1.8034)
			(stroke
				(width 0.3302)
				(type default)
			)
			(layer "F.SilkS")
		)
		(fp_line
			(start 1.27 -1.7018)
			(end 1.27 1.7018)
			(stroke
				(width 0.1524)
				(type default)
			)
			(layer "F.SilkS")
		)
		(fp_line
			(start -1.27 -1.7018)
			(end 1.27 -1.7018)
			(stroke
				(width 0.1524)
				(type default)
			)
			(layer "F.SilkS")
		)
		(fp_line
			(start 1.27 1.7018)
			(end -1.27 1.7018)
			(stroke
				(width 0.1524)
				(type default)
			)
			(layer "F.SilkS")
		)
		(fp_line
			(start -1.27 1.7018)
			(end -1.27 -1.7018)
			(stroke
				(width 0.1524)
				(type default)
			)
			(layer "F.SilkS")
		)
		(fp_rect
			(start -1.524 1.9558)
			(end 1.524 -1.9558)
			(stroke
				(width 0)
				(type default)
			)
			(fill no)
			(layer "F.CrtYd")
		)
		(fp_poly
			(pts
				(xy -1.524 -1.9558) (xy 1.524 -1.9558) (xy 1.524 1.9558) (xy -1.524 1.9558)
			)
			(stroke
				(width 0)
				(type default)
			)
			(fill no)
			(layer "F.Fab")
		)
		(pad "1" smd rect
			(at 0.65024 -0.8255 90)
			(size 0.4064 1.2192)
			(layers "F.Cu" "F.Mask" "F.Paste")
			(net "FM_BMC_RESET_Q36_R")
		)
		(pad "2" smd rect
			(at 0 -0.8255 90)
			(size 0.4064 1.2192)
			(layers "F.Cu" "F.Mask" "F.Paste")
			(net "U80_B")
		)
		(pad "3" smd rect
			(at -0.65024 -0.8255 90)
			(size 0.4064 1.2192)
			(layers "F.Cu" "F.Mask" "F.Paste")
			(net "GND")
		)
		(pad "4" smd rect
			(at -0.65024 0.8255 90)
			(size 0.4064 1.2192)
			(layers "F.Cu" "F.Mask" "F.Paste")
			(net "FM_BMC_RESET_N")
		)
		(pad "5" smd rect
			(at 0.65024 0.8255 90)
			(size 0.4064 1.2192)
			(layers "F.Cu" "F.Mask" "F.Paste")
			(net "P3V3_STBY")
		)
	)
	(footprint ""
		(layer "F.Cu")
		(at 16.51 -194.2592)
		(property "Reference" "R2171"
			(at 0 0 0)
			(layer "F.SilkS")
			(hide yes)
			(effects
				(font
					(size 1.27 1.27)
				)
			)
		)
		(property "Value" "100KR2J-4-GP"
			(at 0.064008 -3.993896 0)
			(unlocked yes)
			(layer "F.Fab")
			(hide yes)
			(effects
				(font
					(size 1.016 1.016)
					(thickness 0.1524)
				)
			)
		)
		(property "Device Type" "R402H15"
			(at 0.064008 -5.517896 0)
			(unlocked yes)
			(layer "F.Fab")
			(hide yes)
			(effects
				(font
					(size 1.016 1.016)
					(thickness 0.1524)
				)
			)
		)
		(duplicate_pad_numbers_are_jumpers no)
		(fp_line
			(start -0.508 -0.9398)
			(end -0.508 0.9398)
			(stroke
				(width 0.1524)
				(type default)
			)
			(layer "F.SilkS")
		)
		(fp_line
			(start 0.508 -0.9398)
			(end -0.508 -0.9398)
			(stroke
				(width 0.1524)
				(type default)
			)
			(layer "F.SilkS")
		)
		(fp_rect
			(start -0.508 0.9398)
			(end 0.508 -0.9398)
			(stroke
				(width 0)
				(type default)
			)
			(fill no)
			(layer "F.CrtYd")
		)
		(fp_rect
			(start -0.508 0.9398)
			(end 0.508 -0.9398)
			(stroke
				(width 0)
				(type default)
			)
			(fill no)
			(layer "F.Fab")
		)
		(pad "1" smd custom
			(at 0 -0.4445)
			(size 0.1397 0.1397)
			(layers "F.Cu" "F.Mask" "F.Paste")
			(net "MB0_VCAP_R")
			(options
				(clearance outline)
				(anchor circle)
			)
			(primitives
				(gr_poly
					(pts
						(arc
							(start -0.1778 -0.2794)
							(mid -0.249642 -0.249642)
							(end -0.2794 -0.1778)
						)
						(arc
							(start -0.2794 0.1778)
							(mid -0.249642 0.249642)
							(end -0.1778 0.2794)
						)
						(arc
							(start 0.1778 0.2794)
							(mid 0.249642 0.249642)
							(end 0.2794 0.1778)
						)
						(arc
							(start 0.2794 -0.1778)
							(mid 0.249642 -0.249642)
							(end 0.1778 -0.2794)
						)
					)
					(width 0)
					(fill yes)
				)
			)
		)
		(pad "2" smd custom
			(at 0 0.4445)
			(size 0.1397 0.1397)
			(layers "F.Cu" "F.Mask" "F.Paste")
			(net "MB0_PSET_R")
			(options
				(clearance outline)
				(anchor circle)
			)
			(primitives
				(gr_poly
					(pts
						(arc
							(start -0.1778 -0.2794)
							(mid -0.249642 -0.249642)
							(end -0.2794 -0.1778)
						)
						(arc
							(start -0.2794 0.1778)
							(mid -0.249642 0.249642)
							(end -0.1778 0.2794)
						)
						(arc
							(start 0.1778 0.2794)
							(mid 0.249642 0.249642)
							(end 0.2794 0.1778)
						)
						(arc
							(start 0.2794 -0.1778)
							(mid 0.249642 -0.249642)
							(end 0.1778 -0.2794)
						)
					)
					(width 0)
					(fill yes)
				)
			)
		)
	)
	(footprint ""
		(layer "F.Cu")
		(at 19.939 -157.48 180)
		(property "Reference" "D1401"
			(at 0 0 180)
			(layer "F.SilkS")
			(hide yes)
			(effects
				(font
					(size 1.27 1.27)
				)
			)
		)
		(property "Value" "RB551V30-GP"
			(at 0 -6.7818 180)
			(unlocked yes)
			(layer "F.Fab")
			(hide yes)
			(effects
				(font
					(size 1.016 1.016)
					(thickness 0.1524)
				)
			)
		)
		(property "Device Type" "SOD323AKH38"
			(at 0 -8.6868 180)
			(unlocked yes)
			(layer "F.Fab")
			(hide yes)
			(effects
				(font
					(size 1.016 1.016)
					(thickness 0.1524)
				)
			)
		)
		(duplicate_pad_numbers_are_jumpers no)
		(fp_line
			(start 0.889 2.159)
			(end -0.889 2.159)
			(stroke
				(width 0.1524)
				(type default)
			)
			(layer "F.SilkS")
		)
		(fp_line
			(start 0.889 -1.9304)
			(end 0.889 2.159)
			(stroke
				(width 0.1524)
				(type default)
			)
			(layer "F.SilkS")
		)
		(fp_line
			(start 0.762 2.0574)
			(end -0.762 2.0574)
			(stroke
				(width 0.508)
				(type default)
			)
			(layer "F.SilkS")
		)
		(fp_line
			(start -0.889 2.159)
			(end -0.889 -1.9304)
			(stroke
				(width 0.1524)
				(type default)
			)
			(layer "F.SilkS")
		)
		(fp_line
			(start -0.889 -1.9304)
			(end 0.889 -1.9304)
			(stroke
				(width 0.1524)
				(type default)
			)
			(layer "F.SilkS")
		)
		(fp_rect
			(start -1.016 2.3114)
			(end 1.016 -2.0066)
			(stroke
				(width 0)
				(type default)
			)
			(fill no)
			(layer "F.CrtYd")
		)
		(fp_poly
			(pts
				(xy -1.016 -2.0066) (xy 1.016 -2.0066) (xy 1.016 2.3114) (xy -1.016 2.3114)
			)
			(stroke
				(width 0)
				(type default)
			)
			(fill no)
			(layer "F.Fab")
		)
		(pad "A" smd rect
			(at 0 -1.143 180)
			(size 0.5588 1.016)
			(layers "F.Cu" "F.Mask" "F.Paste")
			(net "HOST_I2C_RESET_N_D")
		)
		(pad "K" smd rect
			(at 0 1.143 180)
			(size 0.5588 1.016)
			(layers "F.Cu" "F.Mask" "F.Paste")
			(net "HOST_I2C_RESET_N")
		)
	)
	(footprint ""
		(layer "F.Cu")
		(at 57.404 -130.048 180)
		(property "Reference" "C193"
			(at 0 0 180)
			(layer "F.SilkS")
			(hide yes)
			(effects
				(font
					(size 1.27 1.27)
				)
			)
		)
		(property "Value" "SC100P50V2JN-3GP"
			(at 1.1811 -2.7051 180)
			(unlocked yes)
			(layer "F.Fab")
			(hide yes)
			(effects
				(font
					(size 1.016 1.016)
					(thickness 0.1524)
				)
			)
		)
		(property "Device Type" "C402H22"
			(at 1.1811 -4.2291 180)
			(unlocked yes)
			(layer "F.Fab")
			(hide yes)
			(effects
				(font
					(size 1.016 1.016)
					(thickness 0.1524)
				)
			)
		)
		(duplicate_pad_numbers_are_jumpers no)
		(fp_rect
			(start -0.4318 0.9525)
			(end 0.4318 -0.9525)
			(stroke
				(width 0)
				(type default)
			)
			(fill no)
			(layer "F.CrtYd")
		)
		(fp_rect
			(start -0.4318 0.9525)
			(end 0.4318 -0.9525)
			(stroke
				(width 0)
				(type default)
			)
			(fill no)
			(layer "F.Fab")
		)
		(pad "1" smd custom
			(at 0 -0.4445 180)
			(size 0.1524 0.1524)
			(layers "F.Cu" "F.Mask" "F.Paste")
			(net "ADCAV33")
			(options
				(clearance outline)
				(anchor circle)
			)
			(primitives
				(gr_poly
					(pts
						(arc
							(start 0.3048 -0.2032)
							(mid 0.275042 -0.275042)
							(end 0.2032 -0.3048)
						)
						(arc
							(start -0.2032 -0.3048)
							(mid -0.275042 -0.275042)
							(end -0.3048 -0.2032)
						)
						(arc
							(start -0.3048 0.2032)
							(mid -0.275042 0.275042)
							(end -0.2032 0.3048)
						)
						(arc
							(start 0.2032 0.3048)
							(mid 0.275042 0.275042)
							(end 0.3048 0.2032)
						)
					)
					(width 0)
					(fill yes)
				)
			)
		)
		(pad "2" smd custom
			(at 0 0.4445 180)
			(size 0.1524 0.1524)
			(layers "F.Cu" "F.Mask" "F.Paste")
			(net "GND")
			(options
				(clearance outline)
				(anchor circle)
			)
			(primitives
				(gr_poly
					(pts
						(arc
							(start 0.3048 -0.2032)
							(mid 0.275042 -0.275042)
							(end 0.2032 -0.3048)
						)
						(arc
							(start -0.2032 -0.3048)
							(mid -0.275042 -0.275042)
							(end -0.3048 -0.2032)
						)
						(arc
							(start -0.3048 0.2032)
							(mid -0.275042 0.275042)
							(end -0.2032 0.3048)
						)
						(arc
							(start 0.2032 0.3048)
							(mid 0.275042 0.275042)
							(end 0.3048 0.2032)
						)
					)
					(width 0)
					(fill yes)
				)
			)
		)
	)
	(footprint ""
		(layer "F.Cu")
		(at 59.182 -45.085 -90)
		(property "Reference" "PC24"
			(at 0 0 270)
			(layer "F.SilkS")
			(hide yes)
			(effects
				(font
					(size 1.27 1.27)
				)
			)
		)
		(property "Value" "SC10U25V5KX-GP"
			(at -0.0762 -6.1214 270)
			(unlocked yes)
			(layer "F.Fab")
			(hide yes)
			(effects
				(font
					(size 1.016 1.016)
					(thickness 0.1524)
				)
			)
		)
		(property "Device Type" "C805H56"
			(at -0.0762 -8.1534 270)
			(unlocked yes)
			(layer "F.Fab")
			(hide yes)
			(effects
				(font
					(size 1.016 1.016)
					(thickness 0.1524)
				)
			)
		)
		(duplicate_pad_numbers_are_jumpers no)
		(fp_line
			(start 0.635 0)
			(end -0.635 0)
			(stroke
				(width 0.508)
				(type default)
			)
			(layer "F.SilkS")
		)
		(fp_rect
			(start -0.9652 1.778)
			(end 0.9652 -1.778)
			(stroke
				(width 0)
				(type default)
			)
			(fill no)
			(layer "F.CrtYd")
		)
		(fp_poly
			(pts
				(xy -0.9652 -1.778) (xy 0.9652 -1.778) (xy 0.9652 1.778) (xy -0.9652 1.778)
			)
			(stroke
				(width 0)
				(type default)
			)
			(fill no)
			(layer "F.Fab")
		)
		(pad "1" smd rect
			(at 0 -0.9652 270)
			(size 1.397 1.143)
			(layers "F.Cu" "F.Mask" "F.Paste")
			(net "P3V3_STBY_VIN")
		)
		(pad "2" smd rect
			(at 0 0.9652 270)
			(size 1.397 1.143)
			(layers "F.Cu" "F.Mask" "F.Paste")
			(net "GND")
		)
	)
	(footprint ""
		(layer "F.Cu")
		(at 39.67099 -84.279994 90)
		(property "Reference" "Q45"
			(at 0 0 90)
			(layer "F.SilkS")
			(hide yes)
			(effects
				(font
					(size 1.27 1.27)
				)
			)
		)
		(property "Value" "2N7002K-1-GP"
			(at 0.127 -8.9662 90)
			(unlocked yes)
			(layer "F.Fab")
			(hide yes)
			(effects
				(font
					(size 1.016 1.016)
					(thickness 0.1524)
				)
			)
		)
		(property "Device Type" "SOT23DGS2D4H44"
			(at 0.127 -10.4902 90)
			(unlocked yes)
			(layer "F.Fab")
			(hide yes)
			(effects
				(font
					(size 1.016 1.016)
					(thickness 0.1524)
				)
			)
		)
		(duplicate_pad_numbers_are_jumpers no)
		(fp_line
			(start 1.651 -1.778)
			(end -1.651 -1.778)
			(stroke
				(width 0.1524)
				(type default)
			)
			(layer "F.SilkS")
		)
		(fp_line
			(start -1.651 -1.778)
			(end -1.651 1.778)
			(stroke
				(width 0.1524)
				(type default)
			)
			(layer "F.SilkS")
		)
		(fp_line
			(start 1.651 1.778)
			(end 1.651 -1.778)
			(stroke
				(width 0.1524)
				(type default)
			)
			(layer "F.SilkS")
		)
		(fp_line
			(start -1.651 1.778)
			(end 1.651 1.778)
			(stroke
				(width 0.1524)
				(type default)
			)
			(layer "F.SilkS")
		)
		(fp_poly
			(pts
				(xy -1.778 1.8796) (xy -1.778 -1.8796) (xy 1.778 -1.8796) (xy 1.778 1.8796)
			)
			(stroke
				(width 0)
				(type default)
			)
			(fill no)
			(layer "F.CrtYd")
		)
		(fp_poly
			(pts
				(xy -1.778 1.8796) (xy -1.778 -1.8796) (xy 1.778 -1.8796) (xy 1.778 1.8796)
			)
			(stroke
				(width 0)
				(type default)
			)
			(fill no)
			(layer "F.Fab")
		)
		(pad "D" smd custom
			(at 0 -0.9525 90)
			(size 0.1905 0.1905)
			(layers "F.Cu" "F.Mask" "F.Paste")
			(net "Q45_D")
			(options
				(clearance outline)
				(anchor circle)
			)
			(primitives
				(gr_poly
					(pts
						(arc
							(start -0.1778 0.5715)
							(mid -0.321484 0.511984)
							(end -0.381 0.3683)
						)
						(arc
							(start -0.381 -0.3683)
							(mid -0.321484 -0.511984)
							(end -0.1778 -0.5715)
						)
						(arc
							(start 0.1778 -0.5715)
							(mid 0.321484 -0.511984)
							(end 0.381 -0.3683)
						)
						(arc
							(start 0.381 0.3683)
							(mid 0.321484 0.511984)
							(end 0.1778 0.5715)
						)
					)
					(width 0)
					(fill yes)
				)
			)
		)
		(pad "G" smd custom
			(at -0.98425 0.9525 90)
			(size 0.1905 0.1905)
			(layers "F.Cu" "F.Mask" "F.Paste")
			(net "MB0_P12V_PWRGOOD")
			(options
				(clearance outline)
				(anchor circle)
			)
			(primitives
				(gr_poly
					(pts
						(arc
							(start -0.1778 0.5715)
							(mid -0.321484 0.511984)
							(end -0.381 0.3683)
						)
						(arc
							(start -0.381 -0.3683)
							(mid -0.321484 -0.511984)
							(end -0.1778 -0.5715)
						)
						(arc
							(start 0.1778 -0.5715)
							(mid 0.321484 -0.511984)
							(end 0.381 -0.3683)
						)
						(arc
							(start 0.381 0.3683)
							(mid 0.321484 0.511984)
							(end 0.1778 0.5715)
						)
					)
					(width 0)
					(fill yes)
				)
			)
		)
		(pad "S" smd custom
			(at 0.98425 0.9525 90)
			(size 0.1905 0.1905)
			(layers "F.Cu" "F.Mask" "F.Paste")
			(net "GND")
			(options
				(clearance outline)
				(anchor circle)
			)
			(primitives
				(gr_poly
					(pts
						(arc
							(start -0.1778 0.5715)
							(mid -0.321484 0.511984)
							(end -0.381 0.3683)
						)
						(arc
							(start -0.381 -0.3683)
							(mid -0.321484 -0.511984)
							(end -0.1778 -0.5715)
						)
						(arc
							(start 0.1778 -0.5715)
							(mid 0.321484 -0.511984)
							(end 0.381 -0.3683)
						)
						(arc
							(start 0.381 0.3683)
							(mid 0.321484 0.511984)
							(end 0.1778 0.5715)
						)
					)
					(width 0)
					(fill yes)
				)
			)
		)
	)
	(footprint ""
		(layer "F.Cu")
		(at 140.850874 -95.27032 -90)
		(property "Reference" "PC91"
			(at 0 0 270)
			(layer "F.SilkS")
			(hide yes)
			(effects
				(font
					(size 1.27 1.27)
				)
			)
		)
		(property "Value" "SC10U10V5KX-6-GP-U"
			(at -0.0762 -6.1214 270)
			(unlocked yes)
			(layer "F.Fab")
			(hide yes)
			(effects
				(font
					(size 1.016 1.016)
					(thickness 0.1524)
				)
			)
		)
		(property "Device Type" "C805H58"
			(at -0.0762 -8.1534 270)
			(unlocked yes)
			(layer "F.Fab")
			(hide yes)
			(effects
				(font
					(size 1.016 1.016)
					(thickness 0.1524)
				)
			)
		)
		(duplicate_pad_numbers_are_jumpers no)
		(fp_line
			(start 0.635 0)
			(end -0.635 0)
			(stroke
				(width 0.508)
				(type default)
			)
			(layer "F.SilkS")
		)
		(fp_rect
			(start -0.9652 1.778)
			(end 0.9652 -1.778)
			(stroke
				(width 0)
				(type default)
			)
			(fill no)
			(layer "F.CrtYd")
		)
		(fp_poly
			(pts
				(xy -0.9652 -1.778) (xy 0.9652 -1.778) (xy 0.9652 1.778) (xy -0.9652 1.778)
			)
			(stroke
				(width 0)
				(type default)
			)
			(fill no)
			(layer "F.Fab")
		)
		(pad "1" smd rect
			(at 0 -0.9652 270)
			(size 1.397 1.143)
			(layers "F.Cu" "F.Mask" "F.Paste")
			(net "VR_P1V8_STBY_BIAS")
		)
		(pad "2" smd rect
			(at 0 0.9652 270)
			(size 1.397 1.143)
			(layers "F.Cu" "F.Mask" "F.Paste")
			(net "GND")
		)
	)
	(footprint ""
		(layer "F.Cu")
		(at 158.608268 -212.420454 180)
		(property "Reference" "C169"
			(at 0 0 180)
			(layer "F.SilkS")
			(hide yes)
			(effects
				(font
					(size 1.27 1.27)
				)
			)
		)
		(property "Value" "SCD22U10V2KX-1GP"
			(at 1.1811 -2.7051 180)
			(unlocked yes)
			(layer "F.Fab")
			(hide yes)
			(effects
				(font
					(size 1.016 1.016)
					(thickness 0.1524)
				)
			)
		)
		(property "Device Type" "C402H22"
			(at 1.1811 -4.2291 180)
			(unlocked yes)
			(layer "F.Fab")
			(hide yes)
			(effects
				(font
					(size 1.016 1.016)
					(thickness 0.1524)
				)
			)
		)
		(duplicate_pad_numbers_are_jumpers no)
		(fp_rect
			(start -0.4318 0.9525)
			(end 0.4318 -0.9525)
			(stroke
				(width 0)
				(type default)
			)
			(fill no)
			(layer "F.CrtYd")
		)
		(fp_rect
			(start -0.4318 0.9525)
			(end 0.4318 -0.9525)
			(stroke
				(width 0)
				(type default)
			)
			(fill no)
			(layer "F.Fab")
		)
		(pad "1" smd custom
			(at 0 -0.4445 180)
			(size 0.1524 0.1524)
			(layers "F.Cu" "F.Mask" "F.Paste")
			(net "PCIE_TX_CAP_N53")
			(options
				(clearance outline)
				(anchor circle)
			)
			(primitives
				(gr_poly
					(pts
						(arc
							(start 0.3048 -0.2032)
							(mid 0.275042 -0.275042)
							(end 0.2032 -0.3048)
						)
						(arc
							(start -0.2032 -0.3048)
							(mid -0.275042 -0.275042)
							(end -0.3048 -0.2032)
						)
						(arc
							(start -0.3048 0.2032)
							(mid -0.275042 0.275042)
							(end -0.2032 0.3048)
						)
						(arc
							(start 0.2032 0.3048)
							(mid 0.275042 0.275042)
							(end 0.3048 0.2032)
						)
					)
					(width 0)
					(fill yes)
				)
			)
		)
		(pad "2" smd custom
			(at 0 0.4445 180)
			(size 0.1524 0.1524)
			(layers "F.Cu" "F.Mask" "F.Paste")
			(net "PCIE_TX_N53")
			(options
				(clearance outline)
				(anchor circle)
			)
			(primitives
				(gr_poly
					(pts
						(arc
							(start 0.3048 -0.2032)
							(mid 0.275042 -0.275042)
							(end 0.2032 -0.3048)
						)
						(arc
							(start -0.2032 -0.3048)
							(mid -0.275042 -0.275042)
							(end -0.3048 -0.2032)
						)
						(arc
							(start -0.3048 0.2032)
							(mid -0.275042 0.275042)
							(end -0.2032 0.3048)
						)
						(arc
							(start 0.2032 0.3048)
							(mid 0.275042 0.275042)
							(end 0.3048 0.2032)
						)
					)
					(width 0)
					(fill yes)
				)
			)
		)
	)
	(footprint ""
		(layer "F.Cu")
		(at 66.3448 -26.3144)
		(property "Reference" "R737"
			(at 0 0 0)
			(layer "F.SilkS")
			(hide yes)
			(effects
				(font
					(size 1.27 1.27)
				)
			)
		)
		(property "Value" "0R2J-2-GP"
			(at 0.064008 -3.993896 0)
			(unlocked yes)
			(layer "F.Fab")
			(hide yes)
			(effects
				(font
					(size 1.016 1.016)
					(thickness 0.1524)
				)
			)
		)
		(property "Device Type" "R402H16"
			(at 0.064008 -5.517896 0)
			(unlocked yes)
			(layer "F.Fab")
			(hide yes)
			(effects
				(font
					(size 1.016 1.016)
					(thickness 0.1524)
				)
			)
		)
		(duplicate_pad_numbers_are_jumpers no)
		(fp_line
			(start -0.508 -0.9398)
			(end -0.508 0.9398)
			(stroke
				(width 0.1524)
				(type default)
			)
			(layer "F.SilkS")
		)
		(fp_line
			(start 0.508 -0.9398)
			(end -0.508 -0.9398)
			(stroke
				(width 0.1524)
				(type default)
			)
			(layer "F.SilkS")
		)
		(fp_rect
			(start -0.508 0.9398)
			(end 0.508 -0.9398)
			(stroke
				(width 0)
				(type default)
			)
			(fill no)
			(layer "F.CrtYd")
		)
		(fp_rect
			(start -0.508 0.9398)
			(end 0.508 -0.9398)
			(stroke
				(width 0)
				(type default)
			)
			(fill no)
			(layer "F.Fab")
		)
		(pad "1" smd custom
			(at 0 -0.4445)
			(size 0.1397 0.1397)
			(layers "F.Cu" "F.Mask" "F.Paste")
			(net "BMC_I2C14_MINI8_SCL_S")
			(options
				(clearance outline)
				(anchor circle)
			)
			(primitives
				(gr_poly
					(pts
						(arc
							(start -0.1778 -0.2794)
							(mid -0.249642 -0.249642)
							(end -0.2794 -0.1778)
						)
						(arc
							(start -0.2794 0.1778)
							(mid -0.249642 0.249642)
							(end -0.1778 0.2794)
						)
						(arc
							(start 0.1778 0.2794)
							(mid 0.249642 0.249642)
							(end 0.2794 0.1778)
						)
						(arc
							(start 0.2794 -0.1778)
							(mid 0.249642 -0.249642)
							(end 0.1778 -0.2794)
						)
					)
					(width 0)
					(fill yes)
				)
			)
		)
		(pad "2" smd custom
			(at 0 0.4445)
			(size 0.1397 0.1397)
			(layers "F.Cu" "F.Mask" "F.Paste")
			(net "IPMB_CLK")
			(options
				(clearance outline)
				(anchor circle)
			)
			(primitives
				(gr_poly
					(pts
						(arc
							(start -0.1778 -0.2794)
							(mid -0.249642 -0.249642)
							(end -0.2794 -0.1778)
						)
						(arc
							(start -0.2794 0.1778)
							(mid -0.249642 0.249642)
							(end -0.1778 0.2794)
						)
						(arc
							(start 0.1778 0.2794)
							(mid 0.249642 0.249642)
							(end 0.2794 0.1778)
						)
						(arc
							(start 0.2794 -0.1778)
							(mid 0.249642 -0.249642)
							(end 0.1778 -0.2794)
						)
					)
					(width 0)
					(fill yes)
				)
			)
		)
	)
	(footprint ""
		(layer "F.Cu")
		(at 310.007 -66.2686)
		(property "Reference" "PG42"
			(at 0 0 0)
			(layer "F.SilkS")
			(hide yes)
			(effects
				(font
					(size 1.27 1.27)
				)
			)
		)
		(property "Value" "GAP-CLOSE-PWR-3-GP"
			(at 0.0254 -6.5786 0)
			(unlocked yes)
			(layer "F.Fab")
			(hide yes)
			(effects
				(font
					(size 1.016 1.016)
					(thickness 0.1524)
				)
			)
		)
		(property "Device Type" "GAP-CLOSE-PWR-3"
			(at 0.0254 -8.255 0)
			(unlocked yes)
			(layer "F.Fab")
			(hide yes)
			(effects
				(font
					(size 1.016 1.016)
					(thickness 0.1524)
				)
			)
		)
		(duplicate_pad_numbers_are_jumpers no)
		(fp_rect
			(start -0.7112 0.4572)
			(end 0.7112 -0.4572)
			(stroke
				(width 0)
				(type default)
			)
			(fill no)
			(layer "F.CrtYd")
		)
		(fp_poly
			(pts
				(xy -0.7112 -0.4572) (xy 0.7112 -0.4572) (xy 0.7112 0.4572) (xy -0.7112 0.4572)
			)
			(stroke
				(width 0)
				(type default)
			)
			(fill no)
			(layer "F.Fab")
		)
		(pad "1" smd rect
			(at -0.3048 0)
			(size 0.6604 0.762)
			(layers "F.Cu" "F.Mask" "F.Paste")
			(net "DUT_VDD")
		)
		(pad "2" smd rect
			(at 0.3048 0)
			(size 0.6604 0.762)
			(layers "F.Cu" "F.Mask" "F.Paste")
			(net "P0V9_E")
		)
	)
	(footprint ""
		(layer "F.Cu")
		(at 54.983126 -44.20235)
		(property "Reference" "R698"
			(at 0 0 0)
			(layer "F.SilkS")
			(hide yes)
			(effects
				(font
					(size 1.27 1.27)
				)
			)
		)
		(property "Value" "56R6J-GP"
			(at -0.0508 -4.8514 0)
			(unlocked yes)
			(layer "F.Fab")
			(hide yes)
			(effects
				(font
					(size 1.016 1.016)
					(thickness 0.1524)
				)
			)
		)
		(property "Device Type" "R1206H26"
			(at 0 -6.3754 0)
			(unlocked yes)
			(layer "F.Fab")
			(hide yes)
			(effects
				(font
					(size 1.016 1.016)
					(thickness 0.1524)
				)
			)
		)
		(duplicate_pad_numbers_are_jumpers no)
		(fp_line
			(start -1.016 -2.2352)
			(end 1.016 -2.2352)
			(stroke
				(width 0.1524)
				(type default)
			)
			(layer "F.SilkS")
		)
		(fp_line
			(start -1.016 2.2352)
			(end -1.016 -2.2352)
			(stroke
				(width 0.1524)
				(type default)
			)
			(layer "F.SilkS")
		)
		(fp_line
			(start 1.016 -2.2352)
			(end 1.016 2.2352)
			(stroke
				(width 0.1524)
				(type default)
			)
			(layer "F.SilkS")
		)
		(fp_line
			(start 1.016 2.2352)
			(end -1.016 2.2352)
			(stroke
				(width 0.1524)
				(type default)
			)
			(layer "F.SilkS")
		)
		(fp_rect
			(start -1.0922 2.3114)
			(end 1.0922 -2.3114)
			(stroke
				(width 0)
				(type default)
			)
			(fill no)
			(layer "F.CrtYd")
		)
		(fp_poly
			(pts
				(xy -1.0922 -2.3114) (xy 1.0922 -2.3114) (xy 1.0922 2.3114) (xy -1.0922 2.3114)
			)
			(stroke
				(width 0)
				(type default)
			)
			(fill no)
			(layer "F.Fab")
		)
		(pad "1" smd rect
			(at 0 -1.397)
			(size 1.651 1.27)
			(layers "F.Cu" "F.Mask" "F.Paste")
			(net "P3V3_STBY")
		)
		(pad "2" smd rect
			(at 0 1.397)
			(size 1.651 1.27)
			(layers "F.Cu" "F.Mask" "F.Paste")
			(net "Q43_C")
		)
	)
	(footprint ""
		(layer "F.Cu")
		(at 208.852008 -4.064)
		(property "Reference" "R682"
			(at 0 0 0)
			(layer "F.SilkS")
			(hide yes)
			(effects
				(font
					(size 1.27 1.27)
				)
			)
		)
		(property "Value" "100KR2F-L1-GP"
			(at 0.064008 -3.993896 0)
			(unlocked yes)
			(layer "F.Fab")
			(hide yes)
			(effects
				(font
					(size 1.016 1.016)
					(thickness 0.1524)
				)
			)
		)
		(property "Device Type" "R402H16"
			(at 0.064008 -5.517896 0)
			(unlocked yes)
			(layer "F.Fab")
			(hide yes)
			(effects
				(font
					(size 1.016 1.016)
					(thickness 0.1524)
				)
			)
		)
		(duplicate_pad_numbers_are_jumpers no)
		(fp_line
			(start -0.508 -0.9398)
			(end -0.508 0.9398)
			(stroke
				(width 0.1524)
				(type default)
			)
			(layer "F.SilkS")
		)
		(fp_line
			(start 0.508 -0.9398)
			(end -0.508 -0.9398)
			(stroke
				(width 0.1524)
				(type default)
			)
			(layer "F.SilkS")
		)
		(fp_rect
			(start -0.508 0.9398)
			(end 0.508 -0.9398)
			(stroke
				(width 0)
				(type default)
			)
			(fill no)
			(layer "F.CrtYd")
		)
		(fp_rect
			(start -0.508 0.9398)
			(end 0.508 -0.9398)
			(stroke
				(width 0)
				(type default)
			)
			(fill no)
			(layer "F.Fab")
		)
		(pad "1" smd custom
			(at 0 -0.4445)
			(size 0.1397 0.1397)
			(layers "F.Cu" "F.Mask" "F.Paste")
			(net "HOST8_RST_N")
			(options
				(clearance outline)
				(anchor circle)
			)
			(primitives
				(gr_poly
					(pts
						(arc
							(start -0.1778 -0.2794)
							(mid -0.249642 -0.249642)
							(end -0.2794 -0.1778)
						)
						(arc
							(start -0.2794 0.1778)
							(mid -0.249642 0.249642)
							(end -0.1778 0.2794)
						)
						(arc
							(start 0.1778 0.2794)
							(mid 0.249642 0.249642)
							(end 0.2794 0.1778)
						)
						(arc
							(start 0.2794 -0.1778)
							(mid 0.249642 -0.249642)
							(end 0.1778 -0.2794)
						)
					)
					(width 0)
					(fill yes)
				)
			)
		)
		(pad "2" smd custom
			(at 0 0.4445)
			(size 0.1397 0.1397)
			(layers "F.Cu" "F.Mask" "F.Paste")
			(net "GND")
			(options
				(clearance outline)
				(anchor circle)
			)
			(primitives
				(gr_poly
					(pts
						(arc
							(start -0.1778 -0.2794)
							(mid -0.249642 -0.249642)
							(end -0.2794 -0.1778)
						)
						(arc
							(start -0.2794 0.1778)
							(mid -0.249642 0.249642)
							(end -0.1778 0.2794)
						)
						(arc
							(start 0.1778 0.2794)
							(mid 0.249642 0.249642)
							(end 0.2794 0.1778)
						)
						(arc
							(start 0.2794 -0.1778)
							(mid 0.249642 -0.249642)
							(end 0.1778 -0.2794)
						)
					)
					(width 0)
					(fill yes)
				)
			)
		)
	)
	(footprint ""
		(layer "F.Cu")
		(at 13.2842 -194.2846 180)
		(property "Reference" "R9023"
			(at 0 0 180)
			(layer "F.SilkS")
			(hide yes)
			(effects
				(font
					(size 1.27 1.27)
				)
			)
		)
		(property "Value" "22K6R2F-1-GP"
			(at 0.064008 -3.993896 180)
			(unlocked yes)
			(layer "F.Fab")
			(hide yes)
			(effects
				(font
					(size 1.016 1.016)
					(thickness 0.1524)
				)
			)
		)
		(property "Device Type" "R402H16"
			(at 0.064008 -5.517896 180)
			(unlocked yes)
			(layer "F.Fab")
			(hide yes)
			(effects
				(font
					(size 1.016 1.016)
					(thickness 0.1524)
				)
			)
		)
		(duplicate_pad_numbers_are_jumpers no)
		(fp_line
			(start 0.508 -0.9398)
			(end -0.508 -0.9398)
			(stroke
				(width 0.1524)
				(type default)
			)
			(layer "F.SilkS")
		)
		(fp_line
			(start -0.508 -0.9398)
			(end -0.508 0.9398)
			(stroke
				(width 0.1524)
				(type default)
			)
			(layer "F.SilkS")
		)
		(fp_rect
			(start -0.508 0.9398)
			(end 0.508 -0.9398)
			(stroke
				(width 0)
				(type default)
			)
			(fill no)
			(layer "F.CrtYd")
		)
		(fp_rect
			(start -0.508 0.9398)
			(end 0.508 -0.9398)
			(stroke
				(width 0)
				(type default)
			)
			(fill no)
			(layer "F.Fab")
		)
		(pad "1" smd custom
			(at 0 -0.4445 180)
			(size 0.1397 0.1397)
			(layers "F.Cu" "F.Mask" "F.Paste")
			(net "MB0_ISTART_R")
			(options
				(clearance outline)
				(anchor circle)
			)
			(primitives
				(gr_poly
					(pts
						(arc
							(start -0.1778 -0.2794)
							(mid -0.249642 -0.249642)
							(end -0.2794 -0.1778)
						)
						(arc
							(start -0.2794 0.1778)
							(mid -0.249642 0.249642)
							(end -0.1778 0.2794)
						)
						(arc
							(start 0.1778 0.2794)
							(mid 0.249642 0.249642)
							(end 0.2794 0.1778)
						)
						(arc
							(start 0.2794 -0.1778)
							(mid 0.249642 -0.249642)
							(end 0.1778 -0.2794)
						)
					)
					(width 0)
					(fill yes)
				)
			)
		)
		(pad "2" smd custom
			(at 0 0.4445 180)
			(size 0.1397 0.1397)
			(layers "F.Cu" "F.Mask" "F.Paste")
			(net "AGND_CURRENT_MON")
			(options
				(clearance outline)
				(anchor circle)
			)
			(primitives
				(gr_poly
					(pts
						(arc
							(start -0.1778 -0.2794)
							(mid -0.249642 -0.249642)
							(end -0.2794 -0.1778)
						)
						(arc
							(start -0.2794 0.1778)
							(mid -0.249642 0.249642)
							(end -0.1778 0.2794)
						)
						(arc
							(start 0.1778 0.2794)
							(mid 0.249642 0.249642)
							(end 0.2794 0.1778)
						)
						(arc
							(start 0.2794 -0.1778)
							(mid 0.249642 -0.249642)
							(end 0.1778 -0.2794)
						)
					)
					(width 0)
					(fill yes)
				)
			)
		)
	)
	(footprint ""
		(layer "F.Cu")
		(at 286.792162 -212.420454 180)
		(property "Reference" "C93"
			(at 0 0 180)
			(layer "F.SilkS")
			(hide yes)
			(effects
				(font
					(size 1.27 1.27)
				)
			)
		)
		(property "Value" "SCD22U10V2KX-1GP"
			(at 1.1811 -2.7051 180)
			(unlocked yes)
			(layer "F.Fab")
			(hide yes)
			(effects
				(font
					(size 1.016 1.016)
					(thickness 0.1524)
				)
			)
		)
		(property "Device Type" "C402H22"
			(at 1.1811 -4.2291 180)
			(unlocked yes)
			(layer "F.Fab")
			(hide yes)
			(effects
				(font
					(size 1.016 1.016)
					(thickness 0.1524)
				)
			)
		)
		(duplicate_pad_numbers_are_jumpers no)
		(fp_rect
			(start -0.4318 0.9525)
			(end 0.4318 -0.9525)
			(stroke
				(width 0)
				(type default)
			)
			(fill no)
			(layer "F.CrtYd")
		)
		(fp_rect
			(start -0.4318 0.9525)
			(end 0.4318 -0.9525)
			(stroke
				(width 0)
				(type default)
			)
			(fill no)
			(layer "F.Fab")
		)
		(pad "1" smd custom
			(at 0 -0.4445 180)
			(size 0.1524 0.1524)
			(layers "F.Cu" "F.Mask" "F.Paste")
			(net "PCIE_TX_CAP_P30")
			(options
				(clearance outline)
				(anchor circle)
			)
			(primitives
				(gr_poly
					(pts
						(arc
							(start 0.3048 -0.2032)
							(mid 0.275042 -0.275042)
							(end 0.2032 -0.3048)
						)
						(arc
							(start -0.2032 -0.3048)
							(mid -0.275042 -0.275042)
							(end -0.3048 -0.2032)
						)
						(arc
							(start -0.3048 0.2032)
							(mid -0.275042 0.275042)
							(end -0.2032 0.3048)
						)
						(arc
							(start 0.2032 0.3048)
							(mid 0.275042 0.275042)
							(end 0.3048 0.2032)
						)
					)
					(width 0)
					(fill yes)
				)
			)
		)
		(pad "2" smd custom
			(at 0 0.4445 180)
			(size 0.1524 0.1524)
			(layers "F.Cu" "F.Mask" "F.Paste")
			(net "PCIE_TX_P30")
			(options
				(clearance outline)
				(anchor circle)
			)
			(primitives
				(gr_poly
					(pts
						(arc
							(start 0.3048 -0.2032)
							(mid 0.275042 -0.275042)
							(end 0.2032 -0.3048)
						)
						(arc
							(start -0.2032 -0.3048)
							(mid -0.275042 -0.275042)
							(end -0.3048 -0.2032)
						)
						(arc
							(start -0.3048 0.2032)
							(mid -0.275042 0.275042)
							(end -0.2032 0.3048)
						)
						(arc
							(start 0.2032 0.3048)
							(mid 0.275042 0.275042)
							(end 0.3048 0.2032)
						)
					)
					(width 0)
					(fill yes)
				)
			)
		)
	)
	(footprint ""
		(layer "F.Cu")
		(at 160.79216 -212.420454 180)
		(property "Reference" "C164"
			(at 0 0 180)
			(layer "F.SilkS")
			(hide yes)
			(effects
				(font
					(size 1.27 1.27)
				)
			)
		)
		(property "Value" "SCD22U10V2KX-1GP"
			(at 1.1811 -2.7051 180)
			(unlocked yes)
			(layer "F.Fab")
			(hide yes)
			(effects
				(font
					(size 1.016 1.016)
					(thickness 0.1524)
				)
			)
		)
		(property "Device Type" "C402H22"
			(at 1.1811 -4.2291 180)
			(unlocked yes)
			(layer "F.Fab")
			(hide yes)
			(effects
				(font
					(size 1.016 1.016)
					(thickness 0.1524)
				)
			)
		)
		(duplicate_pad_numbers_are_jumpers no)
		(fp_rect
			(start -0.4318 0.9525)
			(end 0.4318 -0.9525)
			(stroke
				(width 0)
				(type default)
			)
			(fill no)
			(layer "F.CrtYd")
		)
		(fp_rect
			(start -0.4318 0.9525)
			(end 0.4318 -0.9525)
			(stroke
				(width 0)
				(type default)
			)
			(fill no)
			(layer "F.Fab")
		)
		(pad "1" smd custom
			(at 0 -0.4445 180)
			(size 0.1524 0.1524)
			(layers "F.Cu" "F.Mask" "F.Paste")
			(net "PCIE_TX_CAP_P52")
			(options
				(clearance outline)
				(anchor circle)
			)
			(primitives
				(gr_poly
					(pts
						(arc
							(start 0.3048 -0.2032)
							(mid 0.275042 -0.275042)
							(end 0.2032 -0.3048)
						)
						(arc
							(start -0.2032 -0.3048)
							(mid -0.275042 -0.275042)
							(end -0.3048 -0.2032)
						)
						(arc
							(start -0.3048 0.2032)
							(mid -0.275042 0.275042)
							(end -0.2032 0.3048)
						)
						(arc
							(start 0.2032 0.3048)
							(mid 0.275042 0.275042)
							(end 0.3048 0.2032)
						)
					)
					(width 0)
					(fill yes)
				)
			)
		)
		(pad "2" smd custom
			(at 0 0.4445 180)
			(size 0.1524 0.1524)
			(layers "F.Cu" "F.Mask" "F.Paste")
			(net "PCIE_TX_P52")
			(options
				(clearance outline)
				(anchor circle)
			)
			(primitives
				(gr_poly
					(pts
						(arc
							(start 0.3048 -0.2032)
							(mid 0.275042 -0.275042)
							(end 0.2032 -0.3048)
						)
						(arc
							(start -0.2032 -0.3048)
							(mid -0.275042 -0.275042)
							(end -0.3048 -0.2032)
						)
						(arc
							(start -0.3048 0.2032)
							(mid -0.275042 0.275042)
							(end -0.2032 0.3048)
						)
						(arc
							(start 0.2032 0.3048)
							(mid 0.275042 0.275042)
							(end 0.3048 0.2032)
						)
					)
					(width 0)
					(fill yes)
				)
			)
		)
	)
	(footprint ""
		(layer "F.Cu")
		(at 284.608016 -212.420454 180)
		(property "Reference" "C95"
			(at 0 0 180)
			(layer "F.SilkS")
			(hide yes)
			(effects
				(font
					(size 1.27 1.27)
				)
			)
		)
		(property "Value" "SCD22U10V2KX-1GP"
			(at 1.1811 -2.7051 180)
			(unlocked yes)
			(layer "F.Fab")
			(hide yes)
			(effects
				(font
					(size 1.016 1.016)
					(thickness 0.1524)
				)
			)
		)
		(property "Device Type" "C402H22"
			(at 1.1811 -4.2291 180)
			(unlocked yes)
			(layer "F.Fab")
			(hide yes)
			(effects
				(font
					(size 1.016 1.016)
					(thickness 0.1524)
				)
			)
		)
		(duplicate_pad_numbers_are_jumpers no)
		(fp_rect
			(start -0.4318 0.9525)
			(end 0.4318 -0.9525)
			(stroke
				(width 0)
				(type default)
			)
			(fill no)
			(layer "F.CrtYd")
		)
		(fp_rect
			(start -0.4318 0.9525)
			(end 0.4318 -0.9525)
			(stroke
				(width 0)
				(type default)
			)
			(fill no)
			(layer "F.Fab")
		)
		(pad "1" smd custom
			(at 0 -0.4445 180)
			(size 0.1524 0.1524)
			(layers "F.Cu" "F.Mask" "F.Paste")
			(net "PCIE_TX_CAP_N31")
			(options
				(clearance outline)
				(anchor circle)
			)
			(primitives
				(gr_poly
					(pts
						(arc
							(start 0.3048 -0.2032)
							(mid 0.275042 -0.275042)
							(end 0.2032 -0.3048)
						)
						(arc
							(start -0.2032 -0.3048)
							(mid -0.275042 -0.275042)
							(end -0.3048 -0.2032)
						)
						(arc
							(start -0.3048 0.2032)
							(mid -0.275042 0.275042)
							(end -0.2032 0.3048)
						)
						(arc
							(start 0.2032 0.3048)
							(mid 0.275042 0.275042)
							(end 0.3048 0.2032)
						)
					)
					(width 0)
					(fill yes)
				)
			)
		)
		(pad "2" smd custom
			(at 0 0.4445 180)
			(size 0.1524 0.1524)
			(layers "F.Cu" "F.Mask" "F.Paste")
			(net "PCIE_TX_N31")
			(options
				(clearance outline)
				(anchor circle)
			)
			(primitives
				(gr_poly
					(pts
						(arc
							(start 0.3048 -0.2032)
							(mid 0.275042 -0.275042)
							(end 0.2032 -0.3048)
						)
						(arc
							(start -0.2032 -0.3048)
							(mid -0.275042 -0.275042)
							(end -0.3048 -0.2032)
						)
						(arc
							(start -0.3048 0.2032)
							(mid -0.275042 0.275042)
							(end -0.2032 0.3048)
						)
						(arc
							(start 0.2032 0.3048)
							(mid 0.275042 0.275042)
							(end 0.3048 0.2032)
						)
					)
					(width 0)
					(fill yes)
				)
			)
		)
	)
	(footprint ""
		(layer "F.Cu")
		(at 6.8072 -189.7126 -90)
		(property "Reference" "R2113"
			(at 0 0 270)
			(layer "F.SilkS")
			(hide yes)
			(effects
				(font
					(size 1.27 1.27)
				)
			)
		)
		(property "Value" "0R2J-2-GP"
			(at 0.064008 -3.993896 270)
			(unlocked yes)
			(layer "F.Fab")
			(hide yes)
			(effects
				(font
					(size 1.016 1.016)
					(thickness 0.1524)
				)
			)
		)
		(property "Device Type" "R402H16"
			(at 0.064008 -5.517896 270)
			(unlocked yes)
			(layer "F.Fab")
			(hide yes)
			(effects
				(font
					(size 1.016 1.016)
					(thickness 0.1524)
				)
			)
		)
		(duplicate_pad_numbers_are_jumpers no)
		(fp_line
			(start -0.508 -0.9398)
			(end -0.508 0.9398)
			(stroke
				(width 0.1524)
				(type default)
			)
			(layer "F.SilkS")
		)
		(fp_line
			(start 0.508 -0.9398)
			(end -0.508 -0.9398)
			(stroke
				(width 0.1524)
				(type default)
			)
			(layer "F.SilkS")
		)
		(fp_rect
			(start -0.508 0.9398)
			(end 0.508 -0.9398)
			(stroke
				(width 0)
				(type default)
			)
			(fill no)
			(layer "F.CrtYd")
		)
		(fp_rect
			(start -0.508 0.9398)
			(end 0.508 -0.9398)
			(stroke
				(width 0)
				(type default)
			)
			(fill no)
			(layer "F.Fab")
		)
		(pad "1" smd custom
			(at 0 -0.4445 270)
			(size 0.1397 0.1397)
			(layers "F.Cu" "F.Mask" "F.Paste")
			(net "MB0_SPISS_PD")
			(options
				(clearance outline)
				(anchor circle)
			)
			(primitives
				(gr_poly
					(pts
						(arc
							(start -0.1778 -0.2794)
							(mid -0.249642 -0.249642)
							(end -0.2794 -0.1778)
						)
						(arc
							(start -0.2794 0.1778)
							(mid -0.249642 0.249642)
							(end -0.1778 0.2794)
						)
						(arc
							(start 0.1778 0.2794)
							(mid 0.249642 0.249642)
							(end 0.2794 0.1778)
						)
						(arc
							(start 0.2794 -0.1778)
							(mid 0.249642 -0.249642)
							(end 0.1778 -0.2794)
						)
					)
					(width 0)
					(fill yes)
				)
			)
		)
		(pad "2" smd custom
			(at 0 0.4445 270)
			(size 0.1397 0.1397)
			(layers "F.Cu" "F.Mask" "F.Paste")
			(net "AGND_CURRENT_MON")
			(options
				(clearance outline)
				(anchor circle)
			)
			(primitives
				(gr_poly
					(pts
						(arc
							(start -0.1778 -0.2794)
							(mid -0.249642 -0.249642)
							(end -0.2794 -0.1778)
						)
						(arc
							(start -0.2794 0.1778)
							(mid -0.249642 0.249642)
							(end -0.1778 0.2794)
						)
						(arc
							(start 0.1778 0.2794)
							(mid 0.249642 0.249642)
							(end 0.2794 0.1778)
						)
						(arc
							(start 0.2794 -0.1778)
							(mid 0.249642 -0.249642)
							(end 0.1778 -0.2794)
						)
					)
					(width 0)
					(fill yes)
				)
			)
		)
	)
	(footprint ""
		(layer "F.Cu")
		(at 40.4114 -96.3168 -90)
		(property "Reference" "R50"
			(at 0 0 270)
			(layer "F.SilkS")
			(hide yes)
			(effects
				(font
					(size 1.27 1.27)
				)
			)
		)
		(property "Value" "0R2J-2-GP"
			(at 0.064008 -3.993896 270)
			(unlocked yes)
			(layer "F.Fab")
			(hide yes)
			(effects
				(font
					(size 1.016 1.016)
					(thickness 0.1524)
				)
			)
		)
		(property "Device Type" "R402H16"
			(at 0.064008 -5.517896 270)
			(unlocked yes)
			(layer "F.Fab")
			(hide yes)
			(effects
				(font
					(size 1.016 1.016)
					(thickness 0.1524)
				)
			)
		)
		(duplicate_pad_numbers_are_jumpers no)
		(fp_line
			(start -0.508 -0.9398)
			(end -0.508 0.9398)
			(stroke
				(width 0.1524)
				(type default)
			)
			(layer "F.SilkS")
		)
		(fp_line
			(start 0.508 -0.9398)
			(end -0.508 -0.9398)
			(stroke
				(width 0.1524)
				(type default)
			)
			(layer "F.SilkS")
		)
		(fp_rect
			(start -0.508 0.9398)
			(end 0.508 -0.9398)
			(stroke
				(width 0)
				(type default)
			)
			(fill no)
			(layer "F.CrtYd")
		)
		(fp_rect
			(start -0.508 0.9398)
			(end 0.508 -0.9398)
			(stroke
				(width 0)
				(type default)
			)
			(fill no)
			(layer "F.Fab")
		)
		(pad "1" smd custom
			(at 0 -0.4445 270)
			(size 0.1397 0.1397)
			(layers "F.Cu" "F.Mask" "F.Paste")
			(net "NVM_SI_R")
			(options
				(clearance outline)
				(anchor circle)
			)
			(primitives
				(gr_poly
					(pts
						(arc
							(start -0.1778 -0.2794)
							(mid -0.249642 -0.249642)
							(end -0.2794 -0.1778)
						)
						(arc
							(start -0.2794 0.1778)
							(mid -0.249642 0.249642)
							(end -0.1778 0.2794)
						)
						(arc
							(start 0.1778 0.2794)
							(mid 0.249642 0.249642)
							(end 0.2794 0.1778)
						)
						(arc
							(start 0.2794 -0.1778)
							(mid 0.249642 -0.249642)
							(end 0.1778 -0.2794)
						)
					)
					(width 0)
					(fill yes)
				)
			)
		)
		(pad "2" smd custom
			(at 0 0.4445 270)
			(size 0.1397 0.1397)
			(layers "F.Cu" "F.Mask" "F.Paste")
			(net "I2C_MUX_4A")
			(options
				(clearance outline)
				(anchor circle)
			)
			(primitives
				(gr_poly
					(pts
						(arc
							(start -0.1778 -0.2794)
							(mid -0.249642 -0.249642)
							(end -0.2794 -0.1778)
						)
						(arc
							(start -0.2794 0.1778)
							(mid -0.249642 0.249642)
							(end -0.1778 0.2794)
						)
						(arc
							(start 0.1778 0.2794)
							(mid 0.249642 0.249642)
							(end 0.2794 0.1778)
						)
						(arc
							(start 0.2794 -0.1778)
							(mid 0.249642 -0.249642)
							(end 0.1778 -0.2794)
						)
					)
					(width 0)
					(fill yes)
				)
			)
		)
	)
	(footprint ""
		(layer "F.Cu")
		(at 299.379894 -33.560258)
		(property "Reference" "C15"
			(at 0 0 0)
			(layer "F.SilkS")
			(hide yes)
			(effects
				(font
					(size 1.27 1.27)
				)
			)
		)
		(property "Value" "SCD22U10V2KX-1GP"
			(at 1.1811 -2.7051 0)
			(unlocked yes)
			(layer "F.Fab")
			(hide yes)
			(effects
				(font
					(size 1.016 1.016)
					(thickness 0.1524)
				)
			)
		)
		(property "Device Type" "C402H22"
			(at 1.1811 -4.2291 0)
			(unlocked yes)
			(layer "F.Fab")
			(hide yes)
			(effects
				(font
					(size 1.016 1.016)
					(thickness 0.1524)
				)
			)
		)
		(duplicate_pad_numbers_are_jumpers no)
		(fp_rect
			(start -0.4318 0.9525)
			(end 0.4318 -0.9525)
			(stroke
				(width 0)
				(type default)
			)
			(fill no)
			(layer "F.CrtYd")
		)
		(fp_rect
			(start -0.4318 0.9525)
			(end 0.4318 -0.9525)
			(stroke
				(width 0)
				(type default)
			)
			(fill no)
			(layer "F.Fab")
		)
		(pad "1" smd custom
			(at 0 -0.4445)
			(size 0.1524 0.1524)
			(layers "F.Cu" "F.Mask" "F.Paste")
			(net "PCIE_TX_CAP_P5")
			(options
				(clearance outline)
				(anchor circle)
			)
			(primitives
				(gr_poly
					(pts
						(arc
							(start 0.3048 -0.2032)
							(mid 0.275042 -0.275042)
							(end 0.2032 -0.3048)
						)
						(arc
							(start -0.2032 -0.3048)
							(mid -0.275042 -0.275042)
							(end -0.3048 -0.2032)
						)
						(arc
							(start -0.3048 0.2032)
							(mid -0.275042 0.275042)
							(end -0.2032 0.3048)
						)
						(arc
							(start 0.2032 0.3048)
							(mid 0.275042 0.275042)
							(end 0.3048 0.2032)
						)
					)
					(width 0)
					(fill yes)
				)
			)
		)
		(pad "2" smd custom
			(at 0 0.4445)
			(size 0.1524 0.1524)
			(layers "F.Cu" "F.Mask" "F.Paste")
			(net "PCIE_TX_P5")
			(options
				(clearance outline)
				(anchor circle)
			)
			(primitives
				(gr_poly
					(pts
						(arc
							(start 0.3048 -0.2032)
							(mid 0.275042 -0.275042)
							(end 0.2032 -0.3048)
						)
						(arc
							(start -0.2032 -0.3048)
							(mid -0.275042 -0.275042)
							(end -0.3048 -0.2032)
						)
						(arc
							(start -0.3048 0.2032)
							(mid -0.275042 0.275042)
							(end -0.2032 0.3048)
						)
						(arc
							(start 0.2032 0.3048)
							(mid 0.275042 0.275042)
							(end 0.3048 0.2032)
						)
					)
					(width 0)
					(fill yes)
				)
			)
		)
	)
	(footprint ""
		(layer "F.Cu")
		(at 314.833 -33.528)
		(property "Reference" "C23"
			(at 0 0 0)
			(layer "F.SilkS")
			(hide yes)
			(effects
				(font
					(size 1.27 1.27)
				)
			)
		)
		(property "Value" "SCD22U10V2KX-1GP"
			(at 1.1811 -2.7051 0)
			(unlocked yes)
			(layer "F.Fab")
			(hide yes)
			(effects
				(font
					(size 1.016 1.016)
					(thickness 0.1524)
				)
			)
		)
		(property "Device Type" "C402H22"
			(at 1.1811 -4.2291 0)
			(unlocked yes)
			(layer "F.Fab")
			(hide yes)
			(effects
				(font
					(size 1.016 1.016)
					(thickness 0.1524)
				)
			)
		)
		(duplicate_pad_numbers_are_jumpers no)
		(fp_rect
			(start -0.4318 0.9525)
			(end 0.4318 -0.9525)
			(stroke
				(width 0)
				(type default)
			)
			(fill no)
			(layer "F.CrtYd")
		)
		(fp_rect
			(start -0.4318 0.9525)
			(end 0.4318 -0.9525)
			(stroke
				(width 0)
				(type default)
			)
			(fill no)
			(layer "F.Fab")
		)
		(pad "1" smd custom
			(at 0 -0.4445)
			(size 0.1524 0.1524)
			(layers "F.Cu" "F.Mask" "F.Paste")
			(net "PCIE_TX_CAP_P11")
			(options
				(clearance outline)
				(anchor circle)
			)
			(primitives
				(gr_poly
					(pts
						(arc
							(start 0.3048 -0.2032)
							(mid 0.275042 -0.275042)
							(end 0.2032 -0.3048)
						)
						(arc
							(start -0.2032 -0.3048)
							(mid -0.275042 -0.275042)
							(end -0.3048 -0.2032)
						)
						(arc
							(start -0.3048 0.2032)
							(mid -0.275042 0.275042)
							(end -0.2032 0.3048)
						)
						(arc
							(start 0.2032 0.3048)
							(mid 0.275042 0.275042)
							(end 0.3048 0.2032)
						)
					)
					(width 0)
					(fill yes)
				)
			)
		)
		(pad "2" smd custom
			(at 0 0.4445)
			(size 0.1524 0.1524)
			(layers "F.Cu" "F.Mask" "F.Paste")
			(net "PCIE_TX_P11")
			(options
				(clearance outline)
				(anchor circle)
			)
			(primitives
				(gr_poly
					(pts
						(arc
							(start 0.3048 -0.2032)
							(mid 0.275042 -0.275042)
							(end 0.2032 -0.3048)
						)
						(arc
							(start -0.2032 -0.3048)
							(mid -0.275042 -0.275042)
							(end -0.3048 -0.2032)
						)
						(arc
							(start -0.3048 0.2032)
							(mid -0.275042 0.275042)
							(end -0.2032 0.3048)
						)
						(arc
							(start 0.2032 0.3048)
							(mid 0.275042 0.275042)
							(end 0.3048 0.2032)
						)
					)
					(width 0)
					(fill yes)
				)
			)
		)
	)
	(footprint ""
		(layer "F.Cu")
		(at 136.2583 -33.54324)
		(property "Reference" "C380"
			(at 0 0 0)
			(layer "F.SilkS")
			(hide yes)
			(effects
				(font
					(size 1.27 1.27)
				)
			)
		)
		(property "Value" "SCD22U10V2KX-1GP"
			(at 1.1811 -2.7051 0)
			(unlocked yes)
			(layer "F.Fab")
			(hide yes)
			(effects
				(font
					(size 1.016 1.016)
					(thickness 0.1524)
				)
			)
		)
		(property "Device Type" "C402H22"
			(at 1.1811 -4.2291 0)
			(unlocked yes)
			(layer "F.Fab")
			(hide yes)
			(effects
				(font
					(size 1.016 1.016)
					(thickness 0.1524)
				)
			)
		)
		(duplicate_pad_numbers_are_jumpers no)
		(fp_rect
			(start -0.4318 0.9525)
			(end 0.4318 -0.9525)
			(stroke
				(width 0)
				(type default)
			)
			(fill no)
			(layer "F.CrtYd")
		)
		(fp_rect
			(start -0.4318 0.9525)
			(end 0.4318 -0.9525)
			(stroke
				(width 0)
				(type default)
			)
			(fill no)
			(layer "F.Fab")
		)
		(pad "1" smd custom
			(at 0 -0.4445)
			(size 0.1524 0.1524)
			(layers "F.Cu" "F.Mask" "F.Paste")
			(net "PCIE_TX_CAP_N80")
			(options
				(clearance outline)
				(anchor circle)
			)
			(primitives
				(gr_poly
					(pts
						(arc
							(start 0.3048 -0.2032)
							(mid 0.275042 -0.275042)
							(end 0.2032 -0.3048)
						)
						(arc
							(start -0.2032 -0.3048)
							(mid -0.275042 -0.275042)
							(end -0.3048 -0.2032)
						)
						(arc
							(start -0.3048 0.2032)
							(mid -0.275042 0.275042)
							(end -0.2032 0.3048)
						)
						(arc
							(start 0.2032 0.3048)
							(mid 0.275042 0.275042)
							(end 0.3048 0.2032)
						)
					)
					(width 0)
					(fill yes)
				)
			)
		)
		(pad "2" smd custom
			(at 0 0.4445)
			(size 0.1524 0.1524)
			(layers "F.Cu" "F.Mask" "F.Paste")
			(net "PCIE_TX_N80")
			(options
				(clearance outline)
				(anchor circle)
			)
			(primitives
				(gr_poly
					(pts
						(arc
							(start 0.3048 -0.2032)
							(mid 0.275042 -0.275042)
							(end 0.2032 -0.3048)
						)
						(arc
							(start -0.2032 -0.3048)
							(mid -0.275042 -0.275042)
							(end -0.3048 -0.2032)
						)
						(arc
							(start -0.3048 0.2032)
							(mid -0.275042 0.275042)
							(end -0.2032 0.3048)
						)
						(arc
							(start 0.2032 0.3048)
							(mid 0.275042 0.275042)
							(end 0.3048 0.2032)
						)
					)
					(width 0)
					(fill yes)
				)
			)
		)
	)
	(footprint ""
		(layer "F.Cu")
		(at 182.8546 -71.628 180)
		(property "Reference" "C553"
			(at 0 0 180)
			(layer "F.SilkS")
			(hide yes)
			(effects
				(font
					(size 1.27 1.27)
				)
			)
		)
		(property "Value" "SC4D7U16V5KX-1-GP"
			(at -0.0762 -6.1214 180)
			(unlocked yes)
			(layer "F.Fab")
			(hide yes)
			(effects
				(font
					(size 1.016 1.016)
					(thickness 0.1524)
				)
			)
		)
		(property "Device Type" "C805H56"
			(at -0.0762 -8.1534 180)
			(unlocked yes)
			(layer "F.Fab")
			(hide yes)
			(effects
				(font
					(size 1.016 1.016)
					(thickness 0.1524)
				)
			)
		)
		(duplicate_pad_numbers_are_jumpers no)
		(fp_line
			(start 0.635 0)
			(end -0.635 0)
			(stroke
				(width 0.508)
				(type default)
			)
			(layer "F.SilkS")
		)
		(fp_rect
			(start -0.9652 1.778)
			(end 0.9652 -1.778)
			(stroke
				(width 0)
				(type default)
			)
			(fill no)
			(layer "F.CrtYd")
		)
		(fp_poly
			(pts
				(xy -0.9652 -1.778) (xy 0.9652 -1.778) (xy 0.9652 1.778) (xy -0.9652 1.778)
			)
			(stroke
				(width 0)
				(type default)
			)
			(fill no)
			(layer "F.Fab")
		)
		(pad "1" smd rect
			(at 0 -0.9652 180)
			(size 1.397 1.143)
			(layers "F.Cu" "F.Mask" "F.Paste")
			(net "DUT_AVD_PCIE")
		)
		(pad "2" smd rect
			(at 0 0.9652 180)
			(size 1.397 1.143)
			(layers "F.Cu" "F.Mask" "F.Paste")
			(net "GND")
		)
	)
	(footprint ""
		(layer "F.Cu")
		(at 51.816 -186.817)
		(property "Reference" "R903"
			(at 0 0 0)
			(layer "F.SilkS")
			(hide yes)
			(effects
				(font
					(size 1.27 1.27)
				)
			)
		)
		(property "Value" "0R2J-2-GP"
			(at 0.064008 -3.993896 0)
			(unlocked yes)
			(layer "F.Fab")
			(hide yes)
			(effects
				(font
					(size 1.016 1.016)
					(thickness 0.1524)
				)
			)
		)
		(property "Device Type" "R402H16"
			(at 0.064008 -5.517896 0)
			(unlocked yes)
			(layer "F.Fab")
			(hide yes)
			(effects
				(font
					(size 1.016 1.016)
					(thickness 0.1524)
				)
			)
		)
		(duplicate_pad_numbers_are_jumpers no)
		(fp_line
			(start -0.508 -0.9398)
			(end -0.508 0.9398)
			(stroke
				(width 0.1524)
				(type default)
			)
			(layer "F.SilkS")
		)
		(fp_line
			(start 0.508 -0.9398)
			(end -0.508 -0.9398)
			(stroke
				(width 0.1524)
				(type default)
			)
			(layer "F.SilkS")
		)
		(fp_rect
			(start -0.508 0.9398)
			(end 0.508 -0.9398)
			(stroke
				(width 0)
				(type default)
			)
			(fill no)
			(layer "F.CrtYd")
		)
		(fp_rect
			(start -0.508 0.9398)
			(end 0.508 -0.9398)
			(stroke
				(width 0)
				(type default)
			)
			(fill no)
			(layer "F.Fab")
		)
		(pad "1" smd custom
			(at 0 -0.4445)
			(size 0.1397 0.1397)
			(layers "F.Cu" "F.Mask" "F.Paste")
			(net "BUF_I2C8_CLKBUF1_SCL")
			(options
				(clearance outline)
				(anchor circle)
			)
			(primitives
				(gr_poly
					(pts
						(arc
							(start -0.1778 -0.2794)
							(mid -0.249642 -0.249642)
							(end -0.2794 -0.1778)
						)
						(arc
							(start -0.2794 0.1778)
							(mid -0.249642 0.249642)
							(end -0.1778 0.2794)
						)
						(arc
							(start 0.1778 0.2794)
							(mid 0.249642 0.249642)
							(end 0.2794 0.1778)
						)
						(arc
							(start 0.2794 -0.1778)
							(mid 0.249642 -0.249642)
							(end 0.1778 -0.2794)
						)
					)
					(width 0)
					(fill yes)
				)
			)
		)
		(pad "2" smd custom
			(at 0 0.4445)
			(size 0.1397 0.1397)
			(layers "F.Cu" "F.Mask" "F.Paste")
			(net "BUF_I2C8_CLKBUF1_SCL_R")
			(options
				(clearance outline)
				(anchor circle)
			)
			(primitives
				(gr_poly
					(pts
						(arc
							(start -0.1778 -0.2794)
							(mid -0.249642 -0.249642)
							(end -0.2794 -0.1778)
						)
						(arc
							(start -0.2794 0.1778)
							(mid -0.249642 0.249642)
							(end -0.1778 0.2794)
						)
						(arc
							(start 0.1778 0.2794)
							(mid 0.249642 0.249642)
							(end 0.2794 0.1778)
						)
						(arc
							(start 0.2794 -0.1778)
							(mid 0.249642 -0.249642)
							(end 0.1778 -0.2794)
						)
					)
					(width 0)
					(fill yes)
				)
			)
		)
	)
	(footprint ""
		(layer "F.Cu")
		(at 17.653 -109.347 90)
		(property "Reference" "PC77"
			(at 0 0 90)
			(layer "F.SilkS")
			(hide yes)
			(effects
				(font
					(size 1.27 1.27)
				)
			)
		)
		(property "Value" "SC4D7U16V5KX-1-GP"
			(at -0.0762 -6.1214 90)
			(unlocked yes)
			(layer "F.Fab")
			(hide yes)
			(effects
				(font
					(size 1.016 1.016)
					(thickness 0.1524)
				)
			)
		)
		(property "Device Type" "C805H56"
			(at -0.0762 -8.1534 90)
			(unlocked yes)
			(layer "F.Fab")
			(hide yes)
			(effects
				(font
					(size 1.016 1.016)
					(thickness 0.1524)
				)
			)
		)
		(duplicate_pad_numbers_are_jumpers no)
		(fp_line
			(start 0.635 0)
			(end -0.635 0)
			(stroke
				(width 0.508)
				(type default)
			)
			(layer "F.SilkS")
		)
		(fp_rect
			(start -0.9652 1.778)
			(end 0.9652 -1.778)
			(stroke
				(width 0)
				(type default)
			)
			(fill no)
			(layer "F.CrtYd")
		)
		(fp_poly
			(pts
				(xy -0.9652 -1.778) (xy 0.9652 -1.778) (xy 0.9652 1.778) (xy -0.9652 1.778)
			)
			(stroke
				(width 0)
				(type default)
			)
			(fill no)
			(layer "F.Fab")
		)
		(pad "1" smd rect
			(at 0 -0.9652 90)
			(size 1.397 1.143)
			(layers "F.Cu" "F.Mask" "F.Paste")
			(net "P1V26_PWR")
		)
		(pad "2" smd rect
			(at 0 0.9652 90)
			(size 1.397 1.143)
			(layers "F.Cu" "F.Mask" "F.Paste")
			(net "GND")
		)
	)
	(footprint ""
		(layer "F.Cu")
		(at 190.052198 -51.356768)
		(property "Reference" "C518"
			(at 0 0 0)
			(layer "F.SilkS")
			(hide yes)
			(effects
				(font
					(size 1.27 1.27)
				)
			)
		)
		(property "Value" "SC47U4V5MX-2-GP"
			(at -0.0762 -6.1214 0)
			(unlocked yes)
			(layer "F.Fab")
			(hide yes)
			(effects
				(font
					(size 1.016 1.016)
					(thickness 0.1524)
				)
			)
		)
		(property "Device Type" "C805H58"
			(at -0.0762 -8.1534 0)
			(unlocked yes)
			(layer "F.Fab")
			(hide yes)
			(effects
				(font
					(size 1.016 1.016)
					(thickness 0.1524)
				)
			)
		)
		(duplicate_pad_numbers_are_jumpers no)
		(fp_line
			(start 0.635 0)
			(end -0.635 0)
			(stroke
				(width 0.508)
				(type default)
			)
			(layer "F.SilkS")
		)
		(fp_rect
			(start -0.9652 1.778)
			(end 0.9652 -1.778)
			(stroke
				(width 0)
				(type default)
			)
			(fill no)
			(layer "F.CrtYd")
		)
		(fp_poly
			(pts
				(xy -0.9652 -1.778) (xy 0.9652 -1.778) (xy 0.9652 1.778) (xy -0.9652 1.778)
			)
			(stroke
				(width 0)
				(type default)
			)
			(fill no)
			(layer "F.Fab")
		)
		(pad "1" smd rect
			(at 0 -0.9652)
			(size 1.397 1.143)
			(layers "F.Cu" "F.Mask" "F.Paste")
			(net "DUT_AVD_PCIE_Q")
		)
		(pad "2" smd rect
			(at 0 0.9652)
			(size 1.397 1.143)
			(layers "F.Cu" "F.Mask" "F.Paste")
			(net "GND")
		)
	)
	(footprint ""
		(layer "F.Cu")
		(at 42.545 -198.882 90)
		(property "Reference" "C698"
			(at 0 0 90)
			(layer "F.SilkS")
			(hide yes)
			(effects
				(font
					(size 1.27 1.27)
				)
			)
		)
		(property "Value" "SC220P50V3JN-GP"
			(at 0 -2.8194 90)
			(unlocked yes)
			(layer "F.Fab")
			(hide yes)
			(effects
				(font
					(size 1.016 1.016)
					(thickness 0.1524)
				)
			)
		)
		(property "Device Type" "C603H36"
			(at 0 -4.3434 90)
			(unlocked yes)
			(layer "F.Fab")
			(hide yes)
			(effects
				(font
					(size 1.016 1.016)
					(thickness 0.1524)
				)
			)
		)
		(duplicate_pad_numbers_are_jumpers no)
		(fp_line
			(start 0.508 0)
			(end -0.508 0)
			(stroke
				(width 0.2032)
				(type default)
			)
			(layer "F.SilkS")
		)
		(fp_rect
			(start -0.5842 1.3335)
			(end 0.5842 -1.3335)
			(stroke
				(width 0)
				(type default)
			)
			(fill no)
			(layer "F.CrtYd")
		)
		(fp_rect
			(start -0.5842 1.3335)
			(end 0.5842 -1.3335)
			(stroke
				(width 0)
				(type default)
			)
			(fill no)
			(layer "F.Fab")
		)
		(pad "1" smd custom
			(at 0 -0.762 90)
			(size 0.2159 0.2159)
			(layers "F.Cu" "F.Mask" "F.Paste")
			(net "BMC_I2C6_C_FCB_SCL_R")
			(options
				(clearance outline)
				(anchor circle)
			)
			(primitives
				(gr_poly
					(pts
						(arc
							(start -0.3302 -0.4318)
							(mid -0.402042 -0.402042)
							(end -0.4318 -0.3302)
						)
						(arc
							(start -0.4318 0.3302)
							(mid -0.402042 0.402042)
							(end -0.3302 0.4318)
						)
						(arc
							(start 0.3302 0.4318)
							(mid 0.402042 0.402042)
							(end 0.4318 0.3302)
						)
						(arc
							(start 0.4318 -0.3302)
							(mid 0.402042 -0.402042)
							(end 0.3302 -0.4318)
						)
					)
					(width 0)
					(fill yes)
				)
			)
		)
		(pad "2" smd custom
			(at 0 0.762 90)
			(size 0.2159 0.2159)
			(layers "F.Cu" "F.Mask" "F.Paste")
			(net "GND")
			(options
				(clearance outline)
				(anchor circle)
			)
			(primitives
				(gr_poly
					(pts
						(arc
							(start -0.3302 -0.4318)
							(mid -0.402042 -0.402042)
							(end -0.4318 -0.3302)
						)
						(arc
							(start -0.4318 0.3302)
							(mid -0.402042 0.402042)
							(end -0.3302 0.4318)
						)
						(arc
							(start 0.3302 0.4318)
							(mid 0.402042 0.402042)
							(end 0.4318 0.3302)
						)
						(arc
							(start 0.4318 -0.3302)
							(mid 0.402042 -0.402042)
							(end 0.3302 -0.4318)
						)
					)
					(width 0)
					(fill yes)
				)
			)
		)
	)
	(footprint ""
		(layer "F.Cu")
		(at 297.8658 -206.8068 -90)
		(property "Reference" "C4132"
			(at 0 0 270)
			(layer "F.SilkS")
			(hide yes)
			(effects
				(font
					(size 1.27 1.27)
				)
			)
		)
		(property "Value" "SCD1U25V3KX-GP"
			(at 0 -2.8194 270)
			(unlocked yes)
			(layer "F.Fab")
			(hide yes)
			(effects
				(font
					(size 1.016 1.016)
					(thickness 0.1524)
				)
			)
		)
		(property "Device Type" "C603H36"
			(at 0 -4.3434 270)
			(unlocked yes)
			(layer "F.Fab")
			(hide yes)
			(effects
				(font
					(size 1.016 1.016)
					(thickness 0.1524)
				)
			)
		)
		(duplicate_pad_numbers_are_jumpers no)
		(fp_line
			(start 0.508 0)
			(end -0.508 0)
			(stroke
				(width 0.2032)
				(type default)
			)
			(layer "F.SilkS")
		)
		(fp_rect
			(start -0.5842 1.3335)
			(end 0.5842 -1.3335)
			(stroke
				(width 0)
				(type default)
			)
			(fill no)
			(layer "F.CrtYd")
		)
		(fp_rect
			(start -0.5842 1.3335)
			(end 0.5842 -1.3335)
			(stroke
				(width 0)
				(type default)
			)
			(fill no)
			(layer "F.Fab")
		)
		(pad "1" smd custom
			(at 0 -0.762 270)
			(size 0.2159 0.2159)
			(layers "F.Cu" "F.Mask" "F.Paste")
			(net "GND")
			(options
				(clearance outline)
				(anchor circle)
			)
			(primitives
				(gr_poly
					(pts
						(arc
							(start -0.3302 -0.4318)
							(mid -0.402042 -0.402042)
							(end -0.4318 -0.3302)
						)
						(arc
							(start -0.4318 0.3302)
							(mid -0.402042 0.402042)
							(end -0.3302 0.4318)
						)
						(arc
							(start 0.3302 0.4318)
							(mid 0.402042 0.402042)
							(end 0.4318 0.3302)
						)
						(arc
							(start 0.4318 -0.3302)
							(mid 0.402042 -0.402042)
							(end 0.3302 -0.4318)
						)
					)
					(width 0)
					(fill yes)
				)
			)
		)
		(pad "2" smd custom
			(at 0 0.762 270)
			(size 0.2159 0.2159)
			(layers "F.Cu" "F.Mask" "F.Paste")
			(net "SSD_PWREN13_R")
			(options
				(clearance outline)
				(anchor circle)
			)
			(primitives
				(gr_poly
					(pts
						(arc
							(start -0.3302 -0.4318)
							(mid -0.402042 -0.402042)
							(end -0.4318 -0.3302)
						)
						(arc
							(start -0.4318 0.3302)
							(mid -0.402042 0.402042)
							(end -0.3302 0.4318)
						)
						(arc
							(start 0.3302 0.4318)
							(mid 0.402042 0.402042)
							(end 0.4318 0.3302)
						)
						(arc
							(start 0.4318 -0.3302)
							(mid 0.402042 -0.402042)
							(end 0.3302 -0.4318)
						)
					)
					(width 0)
					(fill yes)
				)
			)
		)
	)
	(footprint ""
		(layer "F.Cu")
		(at 70.6374 -120.9802 180)
		(property "Reference" "R22"
			(at 0 0 180)
			(layer "F.SilkS")
			(hide yes)
			(effects
				(font
					(size 1.27 1.27)
				)
			)
		)
		(property "Value" "0R2J-2-GP"
			(at 0.064008 -3.993896 180)
			(unlocked yes)
			(layer "F.Fab")
			(hide yes)
			(effects
				(font
					(size 1.016 1.016)
					(thickness 0.1524)
				)
			)
		)
		(property "Device Type" "R402H16"
			(at 0.064008 -5.517896 180)
			(unlocked yes)
			(layer "F.Fab")
			(hide yes)
			(effects
				(font
					(size 1.016 1.016)
					(thickness 0.1524)
				)
			)
		)
		(duplicate_pad_numbers_are_jumpers no)
		(fp_line
			(start 0.508 -0.9398)
			(end -0.508 -0.9398)
			(stroke
				(width 0.1524)
				(type default)
			)
			(layer "F.SilkS")
		)
		(fp_line
			(start -0.508 -0.9398)
			(end -0.508 0.9398)
			(stroke
				(width 0.1524)
				(type default)
			)
			(layer "F.SilkS")
		)
		(fp_rect
			(start -0.508 0.9398)
			(end 0.508 -0.9398)
			(stroke
				(width 0)
				(type default)
			)
			(fill no)
			(layer "F.CrtYd")
		)
		(fp_rect
			(start -0.508 0.9398)
			(end 0.508 -0.9398)
			(stroke
				(width 0)
				(type default)
			)
			(fill no)
			(layer "F.Fab")
		)
		(pad "1" smd custom
			(at 0 -0.4445 180)
			(size 0.1397 0.1397)
			(layers "F.Cu" "F.Mask" "F.Paste")
			(net "BMC_I2C4_MINI4_SDA")
			(options
				(clearance outline)
				(anchor circle)
			)
			(primitives
				(gr_poly
					(pts
						(arc
							(start -0.1778 -0.2794)
							(mid -0.249642 -0.249642)
							(end -0.2794 -0.1778)
						)
						(arc
							(start -0.2794 0.1778)
							(mid -0.249642 0.249642)
							(end -0.1778 0.2794)
						)
						(arc
							(start 0.1778 0.2794)
							(mid 0.249642 0.249642)
							(end 0.2794 0.1778)
						)
						(arc
							(start 0.2794 -0.1778)
							(mid 0.249642 -0.249642)
							(end 0.1778 -0.2794)
						)
					)
					(width 0)
					(fill yes)
				)
			)
		)
		(pad "2" smd custom
			(at 0 0.4445 180)
			(size 0.1397 0.1397)
			(layers "F.Cu" "F.Mask" "F.Paste")
			(net "BMC_I2C4_MINI4_SDA_S")
			(options
				(clearance outline)
				(anchor circle)
			)
			(primitives
				(gr_poly
					(pts
						(arc
							(start -0.1778 -0.2794)
							(mid -0.249642 -0.249642)
							(end -0.2794 -0.1778)
						)
						(arc
							(start -0.2794 0.1778)
							(mid -0.249642 0.249642)
							(end -0.1778 0.2794)
						)
						(arc
							(start 0.1778 0.2794)
							(mid 0.249642 0.249642)
							(end 0.2794 0.1778)
						)
						(arc
							(start 0.2794 -0.1778)
							(mid 0.249642 -0.249642)
							(end 0.1778 -0.2794)
						)
					)
					(width 0)
					(fill yes)
				)
			)
		)
	)
	(footprint ""
		(layer "F.Cu")
		(at 85.4964 -85.217 -90)
		(property "Reference" "SR949"
			(at 0 0 270)
			(layer "F.SilkS")
			(hide yes)
			(effects
				(font
					(size 1.27 1.27)
				)
			)
		)
		(property "Value" "0R2J-2-GP"
			(at 0.064008 -3.993896 270)
			(unlocked yes)
			(layer "F.Fab")
			(hide yes)
			(effects
				(font
					(size 1.016 1.016)
					(thickness 0.1524)
				)
			)
		)
		(property "Device Type" "R402H16"
			(at 0.064008 -5.517896 270)
			(unlocked yes)
			(layer "F.Fab")
			(hide yes)
			(effects
				(font
					(size 1.016 1.016)
					(thickness 0.1524)
				)
			)
		)
		(duplicate_pad_numbers_are_jumpers no)
		(fp_line
			(start -0.508 -0.9398)
			(end -0.508 0.9398)
			(stroke
				(width 0.1524)
				(type default)
			)
			(layer "F.SilkS")
		)
		(fp_line
			(start 0.508 -0.9398)
			(end -0.508 -0.9398)
			(stroke
				(width 0.1524)
				(type default)
			)
			(layer "F.SilkS")
		)
		(fp_rect
			(start -0.508 0.9398)
			(end 0.508 -0.9398)
			(stroke
				(width 0)
				(type default)
			)
			(fill no)
			(layer "F.CrtYd")
		)
		(fp_rect
			(start -0.508 0.9398)
			(end 0.508 -0.9398)
			(stroke
				(width 0)
				(type default)
			)
			(fill no)
			(layer "F.Fab")
		)
		(pad "1" smd custom
			(at 0 -0.4445 270)
			(size 0.1397 0.1397)
			(layers "F.Cu" "F.Mask" "F.Paste")
			(net "EXP_SMART_RX")
			(options
				(clearance outline)
				(anchor circle)
			)
			(primitives
				(gr_poly
					(pts
						(arc
							(start -0.1778 -0.2794)
							(mid -0.249642 -0.249642)
							(end -0.2794 -0.1778)
						)
						(arc
							(start -0.2794 0.1778)
							(mid -0.249642 0.249642)
							(end -0.1778 0.2794)
						)
						(arc
							(start 0.1778 0.2794)
							(mid 0.249642 0.249642)
							(end 0.2794 0.1778)
						)
						(arc
							(start 0.2794 -0.1778)
							(mid 0.249642 -0.249642)
							(end 0.1778 -0.2794)
						)
					)
					(width 0)
					(fill yes)
				)
			)
		)
		(pad "2" smd custom
			(at 0 0.4445 270)
			(size 0.1397 0.1397)
			(layers "F.Cu" "F.Mask" "F.Paste")
			(net "EXP_SMART_RX_R")
			(options
				(clearance outline)
				(anchor circle)
			)
			(primitives
				(gr_poly
					(pts
						(arc
							(start -0.1778 -0.2794)
							(mid -0.249642 -0.249642)
							(end -0.2794 -0.1778)
						)
						(arc
							(start -0.2794 0.1778)
							(mid -0.249642 0.249642)
							(end -0.1778 0.2794)
						)
						(arc
							(start 0.1778 0.2794)
							(mid 0.249642 0.249642)
							(end 0.2794 0.1778)
						)
						(arc
							(start 0.2794 -0.1778)
							(mid 0.249642 -0.249642)
							(end 0.1778 -0.2794)
						)
					)
					(width 0)
					(fill yes)
				)
			)
		)
	)
	(footprint ""
		(layer "F.Cu")
		(at 143.68526 -33.45942 180)
		(property "Reference" "R668"
			(at 0 0 180)
			(layer "F.SilkS")
			(hide yes)
			(effects
				(font
					(size 1.27 1.27)
				)
			)
		)
		(property "Value" "0R2J-2-GP"
			(at 0.064008 -3.993896 180)
			(unlocked yes)
			(layer "F.Fab")
			(hide yes)
			(effects
				(font
					(size 1.016 1.016)
					(thickness 0.1524)
				)
			)
		)
		(property "Device Type" "R402H16"
			(at 0.064008 -5.517896 180)
			(unlocked yes)
			(layer "F.Fab")
			(hide yes)
			(effects
				(font
					(size 1.016 1.016)
					(thickness 0.1524)
				)
			)
		)
		(duplicate_pad_numbers_are_jumpers no)
		(fp_line
			(start 0.508 -0.9398)
			(end -0.508 -0.9398)
			(stroke
				(width 0.1524)
				(type default)
			)
			(layer "F.SilkS")
		)
		(fp_line
			(start -0.508 -0.9398)
			(end -0.508 0.9398)
			(stroke
				(width 0.1524)
				(type default)
			)
			(layer "F.SilkS")
		)
		(fp_rect
			(start -0.508 0.9398)
			(end 0.508 -0.9398)
			(stroke
				(width 0)
				(type default)
			)
			(fill no)
			(layer "F.CrtYd")
		)
		(fp_rect
			(start -0.508 0.9398)
			(end 0.508 -0.9398)
			(stroke
				(width 0)
				(type default)
			)
			(fill no)
			(layer "F.Fab")
		)
		(pad "1" smd custom
			(at 0 -0.4445 180)
			(size 0.1397 0.1397)
			(layers "F.Cu" "F.Mask" "F.Paste")
			(net "8644_USB_DN2")
			(options
				(clearance outline)
				(anchor circle)
			)
			(primitives
				(gr_poly
					(pts
						(arc
							(start -0.1778 -0.2794)
							(mid -0.249642 -0.249642)
							(end -0.2794 -0.1778)
						)
						(arc
							(start -0.2794 0.1778)
							(mid -0.249642 0.249642)
							(end -0.1778 0.2794)
						)
						(arc
							(start 0.1778 0.2794)
							(mid 0.249642 0.249642)
							(end 0.2794 0.1778)
						)
						(arc
							(start 0.2794 -0.1778)
							(mid 0.249642 -0.249642)
							(end 0.1778 -0.2794)
						)
					)
					(width 0)
					(fill yes)
				)
			)
		)
		(pad "2" smd custom
			(at 0 0.4445 180)
			(size 0.1397 0.1397)
			(layers "F.Cu" "F.Mask" "F.Paste")
			(net "P3V3_STBY")
			(options
				(clearance outline)
				(anchor circle)
			)
			(primitives
				(gr_poly
					(pts
						(arc
							(start -0.1778 -0.2794)
							(mid -0.249642 -0.249642)
							(end -0.2794 -0.1778)
						)
						(arc
							(start -0.2794 0.1778)
							(mid -0.249642 0.249642)
							(end -0.1778 0.2794)
						)
						(arc
							(start 0.1778 0.2794)
							(mid 0.249642 0.249642)
							(end 0.2794 0.1778)
						)
						(arc
							(start 0.2794 -0.1778)
							(mid 0.249642 -0.249642)
							(end 0.1778 -0.2794)
						)
					)
					(width 0)
					(fill yes)
				)
			)
		)
	)
	(footprint ""
		(layer "F.Cu")
		(at 305.816 -57.0992)
		(property "Reference" "C431"
			(at 0 0 0)
			(layer "F.SilkS")
			(hide yes)
			(effects
				(font
					(size 1.27 1.27)
				)
			)
		)
		(property "Value" "SC10U16V5KX-1-GP"
			(at -0.0762 -6.1214 0)
			(unlocked yes)
			(layer "F.Fab")
			(hide yes)
			(effects
				(font
					(size 1.016 1.016)
					(thickness 0.1524)
				)
			)
		)
		(property "Device Type" "C805H54"
			(at -0.0762 -8.1534 0)
			(unlocked yes)
			(layer "F.Fab")
			(hide yes)
			(effects
				(font
					(size 1.016 1.016)
					(thickness 0.1524)
				)
			)
		)
		(duplicate_pad_numbers_are_jumpers no)
		(fp_line
			(start 0.635 0)
			(end -0.635 0)
			(stroke
				(width 0.508)
				(type default)
			)
			(layer "F.SilkS")
		)
		(fp_rect
			(start -0.9652 1.778)
			(end 0.9652 -1.778)
			(stroke
				(width 0)
				(type default)
			)
			(fill no)
			(layer "F.CrtYd")
		)
		(fp_poly
			(pts
				(xy -0.9652 -1.778) (xy 0.9652 -1.778) (xy 0.9652 1.778) (xy -0.9652 1.778)
			)
			(stroke
				(width 0)
				(type default)
			)
			(fill no)
			(layer "F.Fab")
		)
		(pad "1" smd rect
			(at 0 -0.9652)
			(size 1.397 1.143)
			(layers "F.Cu" "F.Mask" "F.Paste")
			(net "DUT_VDD")
		)
		(pad "2" smd rect
			(at 0 0.9652)
			(size 1.397 1.143)
			(layers "F.Cu" "F.Mask" "F.Paste")
			(net "GND")
		)
	)
	(footprint ""
		(layer "F.Cu")
		(at 9.5758 -175.387)
		(property "Reference" "R738"
			(at 0 0 0)
			(layer "F.SilkS")
			(hide yes)
			(effects
				(font
					(size 1.27 1.27)
				)
			)
		)
		(property "Value" "10KR3F-L-GP"
			(at -0.0254 -2.5146 0)
			(unlocked yes)
			(layer "F.Fab")
			(hide yes)
			(effects
				(font
					(size 1.016 1.016)
					(thickness 0.1524)
				)
			)
		)
		(property "Device Type" "R603H22"
			(at -0.0254 -4.0386 0)
			(unlocked yes)
			(layer "F.Fab")
			(hide yes)
			(effects
				(font
					(size 1.016 1.016)
					(thickness 0.1524)
				)
			)
		)
		(duplicate_pad_numbers_are_jumpers no)
		(fp_line
			(start -0.4826 0)
			(end -0.2032 0)
			(stroke
				(width 0.2032)
				(type default)
			)
			(layer "F.SilkS")
		)
		(fp_line
			(start 0.2032 0)
			(end 0.4826 0)
			(stroke
				(width 0.2032)
				(type default)
			)
			(layer "F.SilkS")
		)
		(fp_rect
			(start -0.5842 1.3335)
			(end 0.5842 -1.3335)
			(stroke
				(width 0)
				(type default)
			)
			(fill no)
			(layer "F.CrtYd")
		)
		(fp_rect
			(start -0.5842 1.3335)
			(end 0.5842 -1.3335)
			(stroke
				(width 0)
				(type default)
			)
			(fill no)
			(layer "F.Fab")
		)
		(pad "1" smd custom
			(at 0 -0.762)
			(size 0.2159 0.2159)
			(layers "F.Cu" "F.Mask" "F.Paste")
			(net "P12V_PCIE")
			(options
				(clearance outline)
				(anchor circle)
			)
			(primitives
				(gr_poly
					(pts
						(arc
							(start -0.3302 -0.4318)
							(mid -0.402042 -0.402042)
							(end -0.4318 -0.3302)
						)
						(arc
							(start -0.4318 0.3302)
							(mid -0.402042 0.402042)
							(end -0.3302 0.4318)
						)
						(arc
							(start 0.3302 0.4318)
							(mid 0.402042 0.402042)
							(end 0.4318 0.3302)
						)
						(arc
							(start 0.4318 -0.3302)
							(mid 0.402042 -0.402042)
							(end 0.3302 -0.4318)
						)
					)
					(width 0)
					(fill yes)
				)
			)
		)
		(pad "2" smd custom
			(at 0 0.762)
			(size 0.2159 0.2159)
			(layers "F.Cu" "F.Mask" "F.Paste")
			(net "Q95_G")
			(options
				(clearance outline)
				(anchor circle)
			)
			(primitives
				(gr_poly
					(pts
						(arc
							(start -0.3302 -0.4318)
							(mid -0.402042 -0.402042)
							(end -0.4318 -0.3302)
						)
						(arc
							(start -0.4318 0.3302)
							(mid -0.402042 0.402042)
							(end -0.3302 0.4318)
						)
						(arc
							(start 0.3302 0.4318)
							(mid 0.402042 0.402042)
							(end 0.4318 0.3302)
						)
						(arc
							(start 0.4318 -0.3302)
							(mid 0.402042 -0.402042)
							(end 0.3302 -0.4318)
						)
					)
					(width 0)
					(fill yes)
				)
			)
		)
	)
	(footprint ""
		(layer "F.Cu")
		(at 264.441432 2.31775)
		(property "Reference" "SW20"
			(at 0 0 0)
			(layer "F.SilkS")
			(hide yes)
			(effects
				(font
					(size 1.27 1.27)
				)
			)
		)
		(property "Value" "SW-SLIDE74-GP"
			(at -4.272534 -5.45465 0)
			(unlocked yes)
			(layer "F.Fab")
			(hide yes)
			(effects
				(font
					(size 1.016 1.016)
					(thickness 0.1524)
				)
			)
		)
		(property "Device Type" "LSSM12-P-V-TR"
			(at -4.272534 -6.97865 0)
			(unlocked yes)
			(layer "F.Fab")
			(hide yes)
			(effects
				(font
					(size 1.016 1.016)
					(thickness 0.1524)
				)
			)
		)
		(duplicate_pad_numbers_are_jumpers no)
		(fp_line
			(start -5.0038 -2.0066)
			(end -3.3528 -2.0066)
			(stroke
				(width 0.1524)
				(type default)
			)
			(layer "F.SilkS")
		)
		(fp_line
			(start -5.0038 2.2098)
			(end -5.0038 -2.0066)
			(stroke
				(width 0.1524)
				(type default)
			)
			(layer "F.SilkS")
		)
		(fp_line
			(start -3.3528 -4.2418)
			(end 3.3528 -4.2418)
			(stroke
				(width 0.1524)
				(type default)
			)
			(layer "F.SilkS")
		)
		(fp_line
			(start -3.3528 -2.0066)
			(end -3.3528 -4.2418)
			(stroke
				(width 0.1524)
				(type default)
			)
			(layer "F.SilkS")
		)
		(fp_line
			(start -2.2987 -4.3688)
			(end -2.6797 -4.3688)
			(stroke
				(width 0.3302)
				(type default)
			)
			(layer "F.SilkS")
		)
		(fp_line
			(start -2.0066 2.2098)
			(end -5.0038 2.2098)
			(stroke
				(width 0.1524)
				(type default)
			)
			(layer "F.SilkS")
		)
		(fp_line
			(start -2.0066 4.0132)
			(end -2.0066 2.2098)
			(stroke
				(width 0.1524)
				(type default)
			)
			(layer "F.SilkS")
		)
		(fp_line
			(start 2.0066 2.2098)
			(end 2.0066 4.0132)
			(stroke
				(width 0.1524)
				(type default)
			)
			(layer "F.SilkS")
		)
		(fp_line
			(start 2.0066 4.0132)
			(end -2.0066 4.0132)
			(stroke
				(width 0.1524)
				(type default)
			)
			(layer "F.SilkS")
		)
		(fp_line
			(start 3.3528 -4.2418)
			(end 3.3528 -2.0066)
			(stroke
				(width 0.1524)
				(type default)
			)
			(layer "F.SilkS")
		)
		(fp_line
			(start 3.3528 -2.0066)
			(end 5.0038 -2.0066)
			(stroke
				(width 0.1524)
				(type default)
			)
			(layer "F.SilkS")
		)
		(fp_line
			(start 5.0038 -2.0066)
			(end 5.0038 2.2098)
			(stroke
				(width 0.1524)
				(type default)
			)
			(layer "F.SilkS")
		)
		(fp_line
			(start 5.0038 2.2098)
			(end 2.0066 2.2098)
			(stroke
				(width 0.1524)
				(type default)
			)
			(layer "F.SilkS")
		)
		(fp_poly
			(pts
				(xy -2.500122 -4.318) (xy -3.008122 -4.826) (xy -1.992122 -4.826)
			)
			(stroke
				(width 0)
				(type default)
			)
			(fill yes)
			(layer "F.SilkS")
		)
		(fp_poly
			(pts
				(xy -1.7526 3.7592) (xy -1.7526 1.9558) (xy -4.7498 1.9558) (xy -4.7498 -1.7526) (xy -2.794 -1.7526)
				(xy -2.794 -3.7592) (xy 2.794 -3.7592) (xy 2.794 -1.7526) (xy 4.7498 -1.7526) (xy 4.7498 1.9558)
				(xy 1.7526 1.9558) (xy 1.7526 3.7592)
			)
			(stroke
				(width 0)
				(type default)
			)
			(fill no)
			(layer "F.CrtYd")
		)
		(fp_poly
			(pts
				(xy -2.2606 4.2672) (xy -2.2606 2.4638) (xy -5.2578 2.4638) (xy -5.2578 -0.1524) (xy -4.7498 -0.1524)
				(xy -4.7498 1.9558) (xy -1.7526 1.9558) (xy -1.7526 3.7592) (xy 1.7526 3.7592) (xy 1.7526 1.9558)
				(xy 4.7498 1.9558) (xy 4.7498 -1.7526) (xy 2.794 -1.7526) (xy 2.794 -3.7592) (xy -2.794 -3.7592)
				(xy -2.794 -1.7526) (xy -4.7498 -1.7526) (xy -4.7498 -0.15748) (xy -5.2578 -0.15748) (xy -5.2578 -2.2606)
				(xy -3.6068 -2.2606) (xy -3.6068 -4.4958) (xy 3.6068 -4.4958) (xy 3.6068 -2.2606) (xy 5.2578 -2.2606)
				(xy 5.2578 2.4638) (xy 2.2606 2.4638) (xy 2.2606 4.2672)
			)
			(stroke
				(width 0)
				(type default)
			)
			(fill no)
			(layer "F.CrtYd")
		)
		(fp_poly
			(pts
				(xy -2.2606 4.2672) (xy -2.2606 2.4638) (xy -5.2578 2.4638) (xy -5.2578 -2.2606) (xy -3.6068 -2.2606)
				(xy -3.6068 -4.4958) (xy 3.6068 -4.4958) (xy 3.6068 -2.2606) (xy 5.2578 -2.2606) (xy 5.2578 2.4638)
				(xy 2.2606 2.4638) (xy 2.2606 4.2672)
			)
			(stroke
				(width 0)
				(type default)
			)
			(fill no)
			(layer "F.Fab")
		)
		(pad "" np_thru_hole circle
			(at -3.400044 0)
			(size 0.254 0.254)
			(drill 0.9652)
			(layers "*.Cu" "*.Mask")
			(clearance 0.7112)
			(thermal_gap 0.7112)
		)
		(pad "" np_thru_hole circle
			(at 3.400044 0)
			(size 0.254 0.254)
			(drill 0.9652)
			(layers "*.Cu" "*.Mask")
			(clearance 0.7112)
			(thermal_gap 0.7112)
		)
		(pad "1" smd rect
			(at -2.500122 -2.750058)
			(size 1.1938 2.4892)
			(layers "F.Cu" "F.Mask" "F.Paste")
			(net "FM_BMC_RESET#_BTN")
		)
		(pad "2" smd rect
			(at 0 -2.750058)
			(size 1.1938 2.4892)
			(layers "F.Cu" "F.Mask" "F.Paste")
			(net "RST_BTN#_R")
		)
		(pad "3" smd rect
			(at 2.500122 -2.750058)
			(size 1.1938 2.4892)
			(layers "F.Cu" "F.Mask" "F.Paste")
			(net "SLIDE_SW_PMC_RST#")
		)
		(zone
			(layers "F.Cu" "B.Cu" "In1.Cu" "In2.Cu" "In3.Cu" "In4.Cu" "In5.Cu" "In6.Cu")
			(hatch none 0.5)
			(connect_pads
				(clearance 0)
			)
			(min_thickness 0.25)
			(keepout
				(tracks not_allowed)
				(vias allowed)
				(pads allowed)
				(copperpour not_allowed)
				(footprints allowed)
			)
			(placement
				(enabled no)
				(sheetname "")
			)
			(fill
				(thermal_gap 0.5)
				(thermal_bridge_width 0.5)
				(island_removal_mode 0)
			)
			(polygon
				(pts
					(arc
						(start 261.828788 2.31775)
						(mid 260.253988 2.31775)
						(end 261.828788 2.31775)
					)
				)
			)
		)
		(zone
			(layers "F.Cu" "B.Cu" "In1.Cu" "In2.Cu" "In3.Cu" "In4.Cu" "In5.Cu" "In6.Cu")
			(hatch none 0.5)
			(connect_pads
				(clearance 0)
			)
			(min_thickness 0.25)
			(keepout
				(tracks not_allowed)
				(vias allowed)
				(pads allowed)
				(copperpour not_allowed)
				(footprints allowed)
			)
			(placement
				(enabled no)
				(sheetname "")
			)
			(fill
				(thermal_gap 0.5)
				(thermal_bridge_width 0.5)
				(island_removal_mode 0)
			)
			(polygon
				(pts
					(arc
						(start 268.628876 2.31775)
						(mid 267.054076 2.31775)
						(end 268.628876 2.31775)
					)
				)
			)
		)
	)
	(footprint ""
		(layer "F.Cu")
		(at 61.0616 -58.9534 180)
		(property "Reference" "R265"
			(at 0 0 180)
			(layer "F.SilkS")
			(hide yes)
			(effects
				(font
					(size 1.27 1.27)
				)
			)
		)
		(property "Value" "0R2J-2-GP"
			(at 0.064008 -3.993896 180)
			(unlocked yes)
			(layer "F.Fab")
			(hide yes)
			(effects
				(font
					(size 1.016 1.016)
					(thickness 0.1524)
				)
			)
		)
		(property "Device Type" "R402H16"
			(at 0.064008 -5.517896 180)
			(unlocked yes)
			(layer "F.Fab")
			(hide yes)
			(effects
				(font
					(size 1.016 1.016)
					(thickness 0.1524)
				)
			)
		)
		(duplicate_pad_numbers_are_jumpers no)
		(fp_line
			(start 0.508 -0.9398)
			(end -0.508 -0.9398)
			(stroke
				(width 0.1524)
				(type default)
			)
			(layer "F.SilkS")
		)
		(fp_line
			(start -0.508 -0.9398)
			(end -0.508 0.9398)
			(stroke
				(width 0.1524)
				(type default)
			)
			(layer "F.SilkS")
		)
		(fp_rect
			(start -0.508 0.9398)
			(end 0.508 -0.9398)
			(stroke
				(width 0)
				(type default)
			)
			(fill no)
			(layer "F.CrtYd")
		)
		(fp_rect
			(start -0.508 0.9398)
			(end 0.508 -0.9398)
			(stroke
				(width 0)
				(type default)
			)
			(fill no)
			(layer "F.Fab")
		)
		(pad "1" smd custom
			(at 0 -0.4445 180)
			(size 0.1397 0.1397)
			(layers "F.Cu" "F.Mask" "F.Paste")
			(net "P3V3_STBY")
			(options
				(clearance outline)
				(anchor circle)
			)
			(primitives
				(gr_poly
					(pts
						(arc
							(start -0.1778 -0.2794)
							(mid -0.249642 -0.249642)
							(end -0.2794 -0.1778)
						)
						(arc
							(start -0.2794 0.1778)
							(mid -0.249642 0.249642)
							(end -0.1778 0.2794)
						)
						(arc
							(start 0.1778 0.2794)
							(mid 0.249642 0.249642)
							(end 0.2794 0.1778)
						)
						(arc
							(start 0.2794 -0.1778)
							(mid 0.249642 -0.249642)
							(end 0.1778 -0.2794)
						)
					)
					(width 0)
					(fill yes)
				)
			)
		)
		(pad "2" smd custom
			(at 0 0.4445 180)
			(size 0.1397 0.1397)
			(layers "F.Cu" "F.Mask" "F.Paste")
			(net "FLA_WPN")
			(options
				(clearance outline)
				(anchor circle)
			)
			(primitives
				(gr_poly
					(pts
						(arc
							(start -0.1778 -0.2794)
							(mid -0.249642 -0.249642)
							(end -0.2794 -0.1778)
						)
						(arc
							(start -0.2794 0.1778)
							(mid -0.249642 0.249642)
							(end -0.1778 0.2794)
						)
						(arc
							(start 0.1778 0.2794)
							(mid 0.249642 0.249642)
							(end 0.2794 0.1778)
						)
						(arc
							(start 0.2794 -0.1778)
							(mid 0.249642 -0.249642)
							(end 0.1778 -0.2794)
						)
					)
					(width 0)
					(fill yes)
				)
			)
		)
	)
	(footprint ""
		(layer "F.Cu")
		(at 313.514486 -33.556448)
		(property "Reference" "C22"
			(at 0 0 0)
			(layer "F.SilkS")
			(hide yes)
			(effects
				(font
					(size 1.27 1.27)
				)
			)
		)
		(property "Value" "SCD22U10V2KX-1GP"
			(at 1.1811 -2.7051 0)
			(unlocked yes)
			(layer "F.Fab")
			(hide yes)
			(effects
				(font
					(size 1.016 1.016)
					(thickness 0.1524)
				)
			)
		)
		(property "Device Type" "C402H22"
			(at 1.1811 -4.2291 0)
			(unlocked yes)
			(layer "F.Fab")
			(hide yes)
			(effects
				(font
					(size 1.016 1.016)
					(thickness 0.1524)
				)
			)
		)
		(duplicate_pad_numbers_are_jumpers no)
		(fp_rect
			(start -0.4318 0.9525)
			(end 0.4318 -0.9525)
			(stroke
				(width 0)
				(type default)
			)
			(fill no)
			(layer "F.CrtYd")
		)
		(fp_rect
			(start -0.4318 0.9525)
			(end 0.4318 -0.9525)
			(stroke
				(width 0)
				(type default)
			)
			(fill no)
			(layer "F.Fab")
		)
		(pad "1" smd custom
			(at 0 -0.4445)
			(size 0.1524 0.1524)
			(layers "F.Cu" "F.Mask" "F.Paste")
			(net "PCIE_TX_CAP_N10")
			(options
				(clearance outline)
				(anchor circle)
			)
			(primitives
				(gr_poly
					(pts
						(arc
							(start 0.3048 -0.2032)
							(mid 0.275042 -0.275042)
							(end 0.2032 -0.3048)
						)
						(arc
							(start -0.2032 -0.3048)
							(mid -0.275042 -0.275042)
							(end -0.3048 -0.2032)
						)
						(arc
							(start -0.3048 0.2032)
							(mid -0.275042 0.275042)
							(end -0.2032 0.3048)
						)
						(arc
							(start 0.2032 0.3048)
							(mid 0.275042 0.275042)
							(end 0.3048 0.2032)
						)
					)
					(width 0)
					(fill yes)
				)
			)
		)
		(pad "2" smd custom
			(at 0 0.4445)
			(size 0.1524 0.1524)
			(layers "F.Cu" "F.Mask" "F.Paste")
			(net "PCIE_TX_N10")
			(options
				(clearance outline)
				(anchor circle)
			)
			(primitives
				(gr_poly
					(pts
						(arc
							(start 0.3048 -0.2032)
							(mid 0.275042 -0.275042)
							(end 0.2032 -0.3048)
						)
						(arc
							(start -0.2032 -0.3048)
							(mid -0.275042 -0.275042)
							(end -0.3048 -0.2032)
						)
						(arc
							(start -0.3048 0.2032)
							(mid -0.275042 0.275042)
							(end -0.2032 0.3048)
						)
						(arc
							(start 0.2032 0.3048)
							(mid 0.275042 0.275042)
							(end 0.3048 0.2032)
						)
					)
					(width 0)
					(fill yes)
				)
			)
		)
	)
	(footprint ""
		(layer "F.Cu")
		(at 145.761202 -62.384432 -90)
		(property "Reference" "PC206"
			(at 0 0 270)
			(layer "F.SilkS")
			(hide yes)
			(effects
				(font
					(size 1.27 1.27)
				)
			)
		)
		(property "Value" "SC10U25V5KX-GP"
			(at -0.0762 -6.1214 270)
			(unlocked yes)
			(layer "F.Fab")
			(hide yes)
			(effects
				(font
					(size 1.016 1.016)
					(thickness 0.1524)
				)
			)
		)
		(property "Device Type" "C805H56"
			(at -0.0762 -8.1534 270)
			(unlocked yes)
			(layer "F.Fab")
			(hide yes)
			(effects
				(font
					(size 1.016 1.016)
					(thickness 0.1524)
				)
			)
		)
		(duplicate_pad_numbers_are_jumpers no)
		(fp_line
			(start 0.635 0)
			(end -0.635 0)
			(stroke
				(width 0.508)
				(type default)
			)
			(layer "F.SilkS")
		)
		(fp_rect
			(start -0.9652 1.778)
			(end 0.9652 -1.778)
			(stroke
				(width 0)
				(type default)
			)
			(fill no)
			(layer "F.CrtYd")
		)
		(fp_poly
			(pts
				(xy -0.9652 -1.778) (xy 0.9652 -1.778) (xy 0.9652 1.778) (xy -0.9652 1.778)
			)
			(stroke
				(width 0)
				(type default)
			)
			(fill no)
			(layer "F.Fab")
		)
		(pad "1" smd rect
			(at 0 -0.9652 270)
			(size 1.397 1.143)
			(layers "F.Cu" "F.Mask" "F.Paste")
			(net "P0V9_VIN")
		)
		(pad "2" smd rect
			(at 0 0.9652 270)
			(size 1.397 1.143)
			(layers "F.Cu" "F.Mask" "F.Paste")
			(net "GND")
		)
	)
	(footprint ""
		(layer "F.Cu")
		(at 9.779 -69.85 180)
		(property "Reference" "C234"
			(at 0 0 180)
			(layer "F.SilkS")
			(hide yes)
			(effects
				(font
					(size 1.27 1.27)
				)
			)
		)
		(property "Value" "SC12P50V2JN-3GP"
			(at 1.1811 -2.7051 180)
			(unlocked yes)
			(layer "F.Fab")
			(hide yes)
			(effects
				(font
					(size 1.016 1.016)
					(thickness 0.1524)
				)
			)
		)
		(property "Device Type" "C402H24"
			(at 1.1811 -4.2291 180)
			(unlocked yes)
			(layer "F.Fab")
			(hide yes)
			(effects
				(font
					(size 1.016 1.016)
					(thickness 0.1524)
				)
			)
		)
		(duplicate_pad_numbers_are_jumpers no)
		(fp_rect
			(start -0.4318 0.9525)
			(end 0.4318 -0.9525)
			(stroke
				(width 0)
				(type default)
			)
			(fill no)
			(layer "F.CrtYd")
		)
		(fp_rect
			(start -0.4318 0.9525)
			(end 0.4318 -0.9525)
			(stroke
				(width 0)
				(type default)
			)
			(fill no)
			(layer "F.Fab")
		)
		(pad "1" smd custom
			(at 0 -0.4445 180)
			(size 0.1524 0.1524)
			(layers "F.Cu" "F.Mask" "F.Paste")
			(net "GND")
			(options
				(clearance outline)
				(anchor circle)
			)
			(primitives
				(gr_poly
					(pts
						(arc
							(start 0.3048 -0.2032)
							(mid 0.275042 -0.275042)
							(end 0.2032 -0.3048)
						)
						(arc
							(start -0.2032 -0.3048)
							(mid -0.275042 -0.275042)
							(end -0.3048 -0.2032)
						)
						(arc
							(start -0.3048 0.2032)
							(mid -0.275042 0.275042)
							(end -0.2032 0.3048)
						)
						(arc
							(start 0.2032 0.3048)
							(mid 0.275042 0.275042)
							(end 0.3048 0.2032)
						)
					)
					(width 0)
					(fill yes)
				)
			)
		)
		(pad "2" smd custom
			(at 0 0.4445 180)
			(size 0.1524 0.1524)
			(layers "F.Cu" "F.Mask" "F.Paste")
			(net "XTAL_IN_I210_R")
			(options
				(clearance outline)
				(anchor circle)
			)
			(primitives
				(gr_poly
					(pts
						(arc
							(start 0.3048 -0.2032)
							(mid 0.275042 -0.275042)
							(end 0.2032 -0.3048)
						)
						(arc
							(start -0.2032 -0.3048)
							(mid -0.275042 -0.275042)
							(end -0.3048 -0.2032)
						)
						(arc
							(start -0.3048 0.2032)
							(mid -0.275042 0.275042)
							(end -0.2032 0.3048)
						)
						(arc
							(start 0.2032 0.3048)
							(mid 0.275042 0.275042)
							(end 0.3048 0.2032)
						)
					)
					(width 0)
					(fill yes)
				)
			)
		)
	)
	(footprint ""
		(layer "F.Cu")
		(at 156.898594 -33.421574 180)
		(property "Reference" "R637"
			(at 0 0 180)
			(layer "F.SilkS")
			(hide yes)
			(effects
				(font
					(size 1.27 1.27)
				)
			)
		)
		(property "Value" "0R2J-2-GP"
			(at 0.064008 -3.993896 180)
			(unlocked yes)
			(layer "F.Fab")
			(hide yes)
			(effects
				(font
					(size 1.016 1.016)
					(thickness 0.1524)
				)
			)
		)
		(property "Device Type" "R402H16"
			(at 0.064008 -5.517896 180)
			(unlocked yes)
			(layer "F.Fab")
			(hide yes)
			(effects
				(font
					(size 1.016 1.016)
					(thickness 0.1524)
				)
			)
		)
		(duplicate_pad_numbers_are_jumpers no)
		(fp_line
			(start 0.508 -0.9398)
			(end -0.508 -0.9398)
			(stroke
				(width 0.1524)
				(type default)
			)
			(layer "F.SilkS")
		)
		(fp_line
			(start -0.508 -0.9398)
			(end -0.508 0.9398)
			(stroke
				(width 0.1524)
				(type default)
			)
			(layer "F.SilkS")
		)
		(fp_rect
			(start -0.508 0.9398)
			(end 0.508 -0.9398)
			(stroke
				(width 0)
				(type default)
			)
			(fill no)
			(layer "F.CrtYd")
		)
		(fp_rect
			(start -0.508 0.9398)
			(end 0.508 -0.9398)
			(stroke
				(width 0)
				(type default)
			)
			(fill no)
			(layer "F.Fab")
		)
		(pad "1" smd custom
			(at 0 -0.4445 180)
			(size 0.1397 0.1397)
			(layers "F.Cu" "F.Mask" "F.Paste")
			(net "8644_USB_DP3")
			(options
				(clearance outline)
				(anchor circle)
			)
			(primitives
				(gr_poly
					(pts
						(arc
							(start -0.1778 -0.2794)
							(mid -0.249642 -0.249642)
							(end -0.2794 -0.1778)
						)
						(arc
							(start -0.2794 0.1778)
							(mid -0.249642 0.249642)
							(end -0.1778 0.2794)
						)
						(arc
							(start 0.1778 0.2794)
							(mid 0.249642 0.249642)
							(end 0.2794 0.1778)
						)
						(arc
							(start 0.2794 -0.1778)
							(mid 0.249642 -0.249642)
							(end 0.1778 -0.2794)
						)
					)
					(width 0)
					(fill yes)
				)
			)
		)
		(pad "2" smd custom
			(at 0 0.4445 180)
			(size 0.1397 0.1397)
			(layers "F.Cu" "F.Mask" "F.Paste")
			(net "P3V3_STBY")
			(options
				(clearance outline)
				(anchor circle)
			)
			(primitives
				(gr_poly
					(pts
						(arc
							(start -0.1778 -0.2794)
							(mid -0.249642 -0.249642)
							(end -0.2794 -0.1778)
						)
						(arc
							(start -0.2794 0.1778)
							(mid -0.249642 0.249642)
							(end -0.1778 0.2794)
						)
						(arc
							(start 0.1778 0.2794)
							(mid 0.249642 0.249642)
							(end 0.2794 0.1778)
						)
						(arc
							(start 0.2794 -0.1778)
							(mid 0.249642 -0.249642)
							(end 0.1778 -0.2794)
						)
					)
					(width 0)
					(fill yes)
				)
			)
		)
	)
	(footprint ""
		(layer "F.Cu")
		(at 57.15 -132.1054)
		(property "Reference" "R3098"
			(at 0 0 0)
			(layer "F.SilkS")
			(hide yes)
			(effects
				(font
					(size 1.27 1.27)
				)
			)
		)
		(property "Value" "1KR2F-3-GP"
			(at 0.064008 -3.993896 0)
			(unlocked yes)
			(layer "F.Fab")
			(hide yes)
			(effects
				(font
					(size 1.016 1.016)
					(thickness 0.1524)
				)
			)
		)
		(property "Device Type" "R402H16"
			(at 0.064008 -5.517896 0)
			(unlocked yes)
			(layer "F.Fab")
			(hide yes)
			(effects
				(font
					(size 1.016 1.016)
					(thickness 0.1524)
				)
			)
		)
		(duplicate_pad_numbers_are_jumpers no)
		(fp_line
			(start -0.508 -0.9398)
			(end -0.508 0.9398)
			(stroke
				(width 0.1524)
				(type default)
			)
			(layer "F.SilkS")
		)
		(fp_line
			(start 0.508 -0.9398)
			(end -0.508 -0.9398)
			(stroke
				(width 0.1524)
				(type default)
			)
			(layer "F.SilkS")
		)
		(fp_rect
			(start -0.508 0.9398)
			(end 0.508 -0.9398)
			(stroke
				(width 0)
				(type default)
			)
			(fill no)
			(layer "F.CrtYd")
		)
		(fp_rect
			(start -0.508 0.9398)
			(end 0.508 -0.9398)
			(stroke
				(width 0)
				(type default)
			)
			(fill no)
			(layer "F.Fab")
		)
		(pad "1" smd custom
			(at 0 -0.4445)
			(size 0.1397 0.1397)
			(layers "F.Cu" "F.Mask" "F.Paste")
			(net "ADC_P1V53V")
			(options
				(clearance outline)
				(anchor circle)
			)
			(primitives
				(gr_poly
					(pts
						(arc
							(start -0.1778 -0.2794)
							(mid -0.249642 -0.249642)
							(end -0.2794 -0.1778)
						)
						(arc
							(start -0.2794 0.1778)
							(mid -0.249642 0.249642)
							(end -0.1778 0.2794)
						)
						(arc
							(start 0.1778 0.2794)
							(mid 0.249642 0.249642)
							(end 0.2794 0.1778)
						)
						(arc
							(start 0.2794 -0.1778)
							(mid 0.249642 -0.249642)
							(end 0.1778 -0.2794)
						)
					)
					(width 0)
					(fill yes)
				)
			)
		)
		(pad "2" smd custom
			(at 0 0.4445)
			(size 0.1397 0.1397)
			(layers "F.Cu" "F.Mask" "F.Paste")
			(net "GND")
			(options
				(clearance outline)
				(anchor circle)
			)
			(primitives
				(gr_poly
					(pts
						(arc
							(start -0.1778 -0.2794)
							(mid -0.249642 -0.249642)
							(end -0.2794 -0.1778)
						)
						(arc
							(start -0.2794 0.1778)
							(mid -0.249642 0.249642)
							(end -0.1778 0.2794)
						)
						(arc
							(start 0.1778 0.2794)
							(mid 0.249642 0.249642)
							(end 0.2794 0.1778)
						)
						(arc
							(start 0.2794 -0.1778)
							(mid 0.249642 -0.249642)
							(end 0.1778 -0.2794)
						)
					)
					(width 0)
					(fill yes)
				)
			)
		)
	)
	(footprint ""
		(layer "F.Cu")
		(at 31.369 -43.942 -90)
		(property "Reference" "C238"
			(at 0 0 270)
			(layer "F.SilkS")
			(hide yes)
			(effects
				(font
					(size 1.27 1.27)
				)
			)
		)
		(property "Value" "SCD1U16V2JX-1-GP"
			(at 1.1811 -2.7051 270)
			(unlocked yes)
			(layer "F.Fab")
			(hide yes)
			(effects
				(font
					(size 1.016 1.016)
					(thickness 0.1524)
				)
			)
		)
		(property "Device Type" "C402H22"
			(at 1.1811 -4.2291 270)
			(unlocked yes)
			(layer "F.Fab")
			(hide yes)
			(effects
				(font
					(size 1.016 1.016)
					(thickness 0.1524)
				)
			)
		)
		(duplicate_pad_numbers_are_jumpers no)
		(fp_rect
			(start -0.4318 0.9525)
			(end 0.4318 -0.9525)
			(stroke
				(width 0)
				(type default)
			)
			(fill no)
			(layer "F.CrtYd")
		)
		(fp_rect
			(start -0.4318 0.9525)
			(end 0.4318 -0.9525)
			(stroke
				(width 0)
				(type default)
			)
			(fill no)
			(layer "F.Fab")
		)
		(pad "1" smd custom
			(at 0 -0.4445 270)
			(size 0.1524 0.1524)
			(layers "F.Cu" "F.Mask" "F.Paste")
			(net "P5V_USB")
			(options
				(clearance outline)
				(anchor circle)
			)
			(primitives
				(gr_poly
					(pts
						(arc
							(start 0.3048 -0.2032)
							(mid 0.275042 -0.275042)
							(end 0.2032 -0.3048)
						)
						(arc
							(start -0.2032 -0.3048)
							(mid -0.275042 -0.275042)
							(end -0.3048 -0.2032)
						)
						(arc
							(start -0.3048 0.2032)
							(mid -0.275042 0.275042)
							(end -0.2032 0.3048)
						)
						(arc
							(start 0.2032 0.3048)
							(mid 0.275042 0.275042)
							(end 0.3048 0.2032)
						)
					)
					(width 0)
					(fill yes)
				)
			)
		)
		(pad "2" smd custom
			(at 0 0.4445 270)
			(size 0.1524 0.1524)
			(layers "F.Cu" "F.Mask" "F.Paste")
			(net "GND")
			(options
				(clearance outline)
				(anchor circle)
			)
			(primitives
				(gr_poly
					(pts
						(arc
							(start 0.3048 -0.2032)
							(mid 0.275042 -0.275042)
							(end 0.2032 -0.3048)
						)
						(arc
							(start -0.2032 -0.3048)
							(mid -0.275042 -0.275042)
							(end -0.3048 -0.2032)
						)
						(arc
							(start -0.3048 0.2032)
							(mid -0.275042 0.275042)
							(end -0.2032 0.3048)
						)
						(arc
							(start 0.2032 0.3048)
							(mid 0.275042 0.275042)
							(end 0.3048 0.2032)
						)
					)
					(width 0)
					(fill yes)
				)
			)
		)
	)
	(footprint ""
		(layer "F.Cu")
		(at 195.600066 0 90)
		(property "Reference" "LED4"
			(at 0 0 90)
			(layer "F.SilkS")
			(hide yes)
			(effects
				(font
					(size 1.27 1.27)
				)
			)
		)
		(property "Value" "LED-R-126-GP-U2"
			(at -4.444492 -2.4384 90)
			(unlocked yes)
			(layer "F.Fab")
			(hide yes)
			(effects
				(font
					(size 1.016 1.016)
					(thickness 0.1524)
				)
			)
		)
		(property "Device Type" "LED3020-1A2K-1H44"
			(at -4.444492 -3.9624 90)
			(unlocked yes)
			(layer "F.Fab")
			(hide yes)
			(effects
				(font
					(size 1.016 1.016)
					(thickness 0.1524)
				)
			)
		)
		(duplicate_pad_numbers_are_jumpers no)
		(fp_line
			(start 0.9271 -2.1463)
			(end 0.9271 2.1463)
			(stroke
				(width 0.1524)
				(type default)
			)
			(layer "F.SilkS")
		)
		(fp_line
			(start -0.9271 -2.1463)
			(end 0.9271 -2.1463)
			(stroke
				(width 0.1524)
				(type default)
			)
			(layer "F.SilkS")
		)
		(fp_line
			(start -0.9271 -1.16078)
			(end -0.9271 -2.1463)
			(stroke
				(width 0.1524)
				(type default)
			)
			(layer "F.SilkS")
		)
		(fp_line
			(start 1.1176 1.3462)
			(end 1.1176 2.3241)
			(stroke
				(width 0.508)
				(type default)
			)
			(layer "F.SilkS")
		)
		(fp_line
			(start 0.9271 2.1463)
			(end -0.9271 2.1463)
			(stroke
				(width 0.1524)
				(type default)
			)
			(layer "F.SilkS")
		)
		(fp_line
			(start -0.9271 2.1463)
			(end -0.9271 1.160526)
			(stroke
				(width 0.1524)
				(type default)
			)
			(layer "F.SilkS")
		)
		(fp_line
			(start 1.1176 2.3241)
			(end -1.1176 2.3241)
			(stroke
				(width 0.508)
				(type default)
			)
			(layer "F.SilkS")
		)
		(fp_line
			(start -1.1176 2.3241)
			(end -1.1176 1.397)
			(stroke
				(width 0.508)
				(type default)
			)
			(layer "F.SilkS")
		)
		(fp_arc
			(start -0.9271 1.160526)
			(mid -1.701058 -0.000049)
			(end -0.9271 -1.16078)
			(stroke
				(width 0.1524)
				(type default)
			)
			(layer "F.SilkS")
		)
		(fp_poly
			(pts
				(xy -0.5461 1.4986)
				(arc
					(start -0.5461 0.997966)
					(mid -1.447396 -0.000013)
					(end -0.5461 -0.99822)
				)
				(xy -0.5461 -1.4986) (xy 0.5461 -1.4986) (xy 0.5461 1.4986)
			)
			(stroke
				(width 0)
				(type default)
			)
			(fill no)
			(layer "F.CrtYd")
		)
		(fp_poly
			(pts
				(xy -1.1811 2.2225)
				(arc
					(start -1.1811 1.319276)
					(mid -1.955222 -0.000062)
					(end -1.1811 -1.31953)
				)
				(xy -1.1811 -2.2225) (xy 1.1811 -2.2225) (xy 1.1811 -0.00635) (xy 0.5461 -0.00635) (xy 0.5461 -1.4986)
				(xy -0.5461 -1.4986)
				(arc
					(start -0.5461 -0.99822)
					(mid -1.447649 0)
					(end -0.5461 0.99822)
				)
				(xy -0.5461 1.4986) (xy 0.5461 1.4986) (xy 0.5461 0.00635) (xy 1.1811 0.00635) (xy 1.1811 2.2225)
			)
			(stroke
				(width 0)
				(type default)
			)
			(fill no)
			(layer "F.CrtYd")
		)
		(fp_poly
			(pts
				(xy -1.1811 2.2225)
				(arc
					(start -1.1811 1.319276)
					(mid -1.955222 -0.000062)
					(end -1.1811 -1.31953)
				)
				(xy -1.1811 -2.2225) (xy 1.1811 -2.2225) (xy 1.1811 2.2225)
			)
			(stroke
				(width 0)
				(type default)
			)
			(fill no)
			(layer "F.Fab")
		)
		(pad "1A" smd rect
			(at 0 -1.366774 90)
			(size 1.3462 1.0414)
			(layers "F.Cu" "F.Mask" "F.Paste")
			(net "ENCLO_LED_RED_R")
		)
		(pad "2K" smd rect
			(at 0 1.366774 90)
			(size 1.3462 1.0414)
			(layers "F.Cu" "F.Mask" "F.Paste")
			(net "ENCLO_LED_RED")
		)
	)
	(footprint ""
		(layer "F.Cu")
		(at 331.756512 -172.432218 180)
		(property "Reference" "R574"
			(at 0 0 180)
			(layer "F.SilkS")
			(hide yes)
			(effects
				(font
					(size 1.27 1.27)
				)
			)
		)
		(property "Value" "10KR2F-2-GP"
			(at 0.064008 -3.993896 180)
			(unlocked yes)
			(layer "F.Fab")
			(hide yes)
			(effects
				(font
					(size 1.016 1.016)
					(thickness 0.1524)
				)
			)
		)
		(property "Device Type" "R402H16"
			(at 0.064008 -5.517896 180)
			(unlocked yes)
			(layer "F.Fab")
			(hide yes)
			(effects
				(font
					(size 1.016 1.016)
					(thickness 0.1524)
				)
			)
		)
		(duplicate_pad_numbers_are_jumpers no)
		(fp_line
			(start 0.508 -0.9398)
			(end -0.508 -0.9398)
			(stroke
				(width 0.1524)
				(type default)
			)
			(layer "F.SilkS")
		)
		(fp_line
			(start -0.508 -0.9398)
			(end -0.508 0.9398)
			(stroke
				(width 0.1524)
				(type default)
			)
			(layer "F.SilkS")
		)
		(fp_rect
			(start -0.508 0.9398)
			(end 0.508 -0.9398)
			(stroke
				(width 0)
				(type default)
			)
			(fill no)
			(layer "F.CrtYd")
		)
		(fp_rect
			(start -0.508 0.9398)
			(end 0.508 -0.9398)
			(stroke
				(width 0)
				(type default)
			)
			(fill no)
			(layer "F.Fab")
		)
		(pad "1" smd custom
			(at 0 -0.4445 180)
			(size 0.1397 0.1397)
			(layers "F.Cu" "F.Mask" "F.Paste")
			(net "GND")
			(options
				(clearance outline)
				(anchor circle)
			)
			(primitives
				(gr_poly
					(pts
						(arc
							(start -0.1778 -0.2794)
							(mid -0.249642 -0.249642)
							(end -0.2794 -0.1778)
						)
						(arc
							(start -0.2794 0.1778)
							(mid -0.249642 0.249642)
							(end -0.1778 0.2794)
						)
						(arc
							(start 0.1778 0.2794)
							(mid 0.249642 0.249642)
							(end 0.2794 0.1778)
						)
						(arc
							(start 0.2794 -0.1778)
							(mid 0.249642 -0.249642)
							(end 0.1778 -0.2794)
						)
					)
					(width 0)
					(fill yes)
				)
			)
		)
		(pad "2" smd custom
			(at 0 0.4445 180)
			(size 0.1397 0.1397)
			(layers "F.Cu" "F.Mask" "F.Paste")
			(net "IOEXP4_AD2")
			(options
				(clearance outline)
				(anchor circle)
			)
			(primitives
				(gr_poly
					(pts
						(arc
							(start -0.1778 -0.2794)
							(mid -0.249642 -0.249642)
							(end -0.2794 -0.1778)
						)
						(arc
							(start -0.2794 0.1778)
							(mid -0.249642 0.249642)
							(end -0.1778 0.2794)
						)
						(arc
							(start 0.1778 0.2794)
							(mid 0.249642 0.249642)
							(end 0.2794 0.1778)
						)
						(arc
							(start 0.2794 -0.1778)
							(mid 0.249642 -0.249642)
							(end 0.1778 -0.2794)
						)
					)
					(width 0)
					(fill yes)
				)
			)
		)
	)
	(footprint ""
		(layer "F.Cu")
		(at 56.769 -152.781 90)
		(property "Reference" "TP166"
			(at 0 0 90)
			(layer "F.SilkS")
			(hide yes)
			(effects
				(font
					(size 1.27 1.27)
				)
			)
		)
		(property "Value" "TPAD32-GP"
			(at -0.0508 -1.6764 90)
			(unlocked yes)
			(layer "F.Fab")
			(hide yes)
			(effects
				(font
					(size 1.016 1.016)
					(thickness 0.1524)
				)
			)
		)
		(property "Device Type" "TPAD32"
			(at -0.0508 -3.2004 90)
			(unlocked yes)
			(layer "F.Fab")
			(hide yes)
			(effects
				(font
					(size 1.016 1.016)
					(thickness 0.1524)
				)
			)
		)
		(duplicate_pad_numbers_are_jumpers no)
		(fp_poly
			(pts
				(arc
					(start 0 0.4064)
					(mid 0 -0.4064)
					(end 0 0.4064)
				)
			)
			(stroke
				(width 0)
				(type default)
			)
			(fill no)
			(layer "F.CrtYd")
		)
		(fp_poly
			(pts
				(arc
					(start 0 0.7112)
					(mid 0 -0.7112)
					(end 0 0.7112)
				)
			)
			(stroke
				(width 0)
				(type default)
			)
			(fill no)
			(layer "F.Fab")
		)
		(pad "1" smd circle
			(at 0 0 90)
			(size 0.8128 0.8128)
			(layers "F.Cu" "F.Mask" "F.Paste")
			(net "TEMP_2_ALERT")
		)
	)
	(footprint ""
		(layer "F.Cu")
		(at 310.007 -57.8866)
		(property "Reference" "PG46"
			(at 0 0 0)
			(layer "F.SilkS")
			(hide yes)
			(effects
				(font
					(size 1.27 1.27)
				)
			)
		)
		(property "Value" "GAP-CLOSE-PWR-3-GP"
			(at 0.0254 -6.5786 0)
			(unlocked yes)
			(layer "F.Fab")
			(hide yes)
			(effects
				(font
					(size 1.016 1.016)
					(thickness 0.1524)
				)
			)
		)
		(property "Device Type" "GAP-CLOSE-PWR-3"
			(at 0.0254 -8.255 0)
			(unlocked yes)
			(layer "F.Fab")
			(hide yes)
			(effects
				(font
					(size 1.016 1.016)
					(thickness 0.1524)
				)
			)
		)
		(duplicate_pad_numbers_are_jumpers no)
		(fp_rect
			(start -0.7112 0.4572)
			(end 0.7112 -0.4572)
			(stroke
				(width 0)
				(type default)
			)
			(fill no)
			(layer "F.CrtYd")
		)
		(fp_poly
			(pts
				(xy -0.7112 -0.4572) (xy 0.7112 -0.4572) (xy 0.7112 0.4572) (xy -0.7112 0.4572)
			)
			(stroke
				(width 0)
				(type default)
			)
			(fill no)
			(layer "F.Fab")
		)
		(pad "1" smd rect
			(at -0.3048 0)
			(size 0.6604 0.762)
			(layers "F.Cu" "F.Mask" "F.Paste")
			(net "DUT_VDD")
		)
		(pad "2" smd rect
			(at 0.3048 0)
			(size 0.6604 0.762)
			(layers "F.Cu" "F.Mask" "F.Paste")
			(net "P0V9_E")
		)
	)
	(footprint ""
		(layer "F.Cu")
		(at 38.260528 -114.77117 180)
		(property "Reference" "R286"
			(at 0 0 180)
			(layer "F.SilkS")
			(hide yes)
			(effects
				(font
					(size 1.27 1.27)
				)
			)
		)
		(property "Value" "0R2J-2-GP"
			(at 0.064008 -3.993896 180)
			(unlocked yes)
			(layer "F.Fab")
			(hide yes)
			(effects
				(font
					(size 1.016 1.016)
					(thickness 0.1524)
				)
			)
		)
		(property "Device Type" "R402H16"
			(at 0.064008 -5.517896 180)
			(unlocked yes)
			(layer "F.Fab")
			(hide yes)
			(effects
				(font
					(size 1.016 1.016)
					(thickness 0.1524)
				)
			)
		)
		(duplicate_pad_numbers_are_jumpers no)
		(fp_line
			(start 0.508 -0.9398)
			(end -0.508 -0.9398)
			(stroke
				(width 0.1524)
				(type default)
			)
			(layer "F.SilkS")
		)
		(fp_line
			(start -0.508 -0.9398)
			(end -0.508 0.9398)
			(stroke
				(width 0.1524)
				(type default)
			)
			(layer "F.SilkS")
		)
		(fp_rect
			(start -0.508 0.9398)
			(end 0.508 -0.9398)
			(stroke
				(width 0)
				(type default)
			)
			(fill no)
			(layer "F.CrtYd")
		)
		(fp_rect
			(start -0.508 0.9398)
			(end 0.508 -0.9398)
			(stroke
				(width 0)
				(type default)
			)
			(fill no)
			(layer "F.Fab")
		)
		(pad "1" smd custom
			(at 0 -0.4445 180)
			(size 0.1397 0.1397)
			(layers "F.Cu" "F.Mask" "F.Paste")
			(net "RMII_BMC_CRS_DV")
			(options
				(clearance outline)
				(anchor circle)
			)
			(primitives
				(gr_poly
					(pts
						(arc
							(start -0.1778 -0.2794)
							(mid -0.249642 -0.249642)
							(end -0.2794 -0.1778)
						)
						(arc
							(start -0.2794 0.1778)
							(mid -0.249642 0.249642)
							(end -0.1778 0.2794)
						)
						(arc
							(start 0.1778 0.2794)
							(mid 0.249642 0.249642)
							(end 0.2794 0.1778)
						)
						(arc
							(start 0.2794 -0.1778)
							(mid 0.249642 -0.249642)
							(end 0.1778 -0.2794)
						)
					)
					(width 0)
					(fill yes)
				)
			)
		)
		(pad "2" smd custom
			(at 0 0.4445 180)
			(size 0.1397 0.1397)
			(layers "F.Cu" "F.Mask" "F.Paste")
			(net "RMII0_BMC_C_CRS_DV")
			(options
				(clearance outline)
				(anchor circle)
			)
			(primitives
				(gr_poly
					(pts
						(arc
							(start -0.1778 -0.2794)
							(mid -0.249642 -0.249642)
							(end -0.2794 -0.1778)
						)
						(arc
							(start -0.2794 0.1778)
							(mid -0.249642 0.249642)
							(end -0.1778 0.2794)
						)
						(arc
							(start 0.1778 0.2794)
							(mid 0.249642 0.249642)
							(end 0.2794 0.1778)
						)
						(arc
							(start 0.2794 -0.1778)
							(mid 0.249642 -0.249642)
							(end 0.1778 -0.2794)
						)
					)
					(width 0)
					(fill yes)
				)
			)
		)
	)
	(footprint ""
		(layer "F.Cu")
		(at 7.9248 -180.5686 180)
		(property "Reference" "R2099"
			(at 0 0 180)
			(layer "F.SilkS")
			(hide yes)
			(effects
				(font
					(size 1.27 1.27)
				)
			)
		)
		(property "Value" "39K2R2F-L-GP"
			(at 0.064008 -3.993896 180)
			(unlocked yes)
			(layer "F.Fab")
			(hide yes)
			(effects
				(font
					(size 1.016 1.016)
					(thickness 0.1524)
				)
			)
		)
		(property "Device Type" "R402H16"
			(at 0.064008 -5.517896 180)
			(unlocked yes)
			(layer "F.Fab")
			(hide yes)
			(effects
				(font
					(size 1.016 1.016)
					(thickness 0.1524)
				)
			)
		)
		(duplicate_pad_numbers_are_jumpers no)
		(fp_line
			(start 0.508 -0.9398)
			(end -0.508 -0.9398)
			(stroke
				(width 0.1524)
				(type default)
			)
			(layer "F.SilkS")
		)
		(fp_line
			(start -0.508 -0.9398)
			(end -0.508 0.9398)
			(stroke
				(width 0.1524)
				(type default)
			)
			(layer "F.SilkS")
		)
		(fp_rect
			(start -0.508 0.9398)
			(end 0.508 -0.9398)
			(stroke
				(width 0)
				(type default)
			)
			(fill no)
			(layer "F.CrtYd")
		)
		(fp_rect
			(start -0.508 0.9398)
			(end 0.508 -0.9398)
			(stroke
				(width 0)
				(type default)
			)
			(fill no)
			(layer "F.Fab")
		)
		(pad "1" smd custom
			(at 0 -0.4445 180)
			(size 0.1397 0.1397)
			(layers "F.Cu" "F.Mask" "F.Paste")
			(net "P12V")
			(options
				(clearance outline)
				(anchor circle)
			)
			(primitives
				(gr_poly
					(pts
						(arc
							(start -0.1778 -0.2794)
							(mid -0.249642 -0.249642)
							(end -0.2794 -0.1778)
						)
						(arc
							(start -0.2794 0.1778)
							(mid -0.249642 0.249642)
							(end -0.1778 0.2794)
						)
						(arc
							(start 0.1778 0.2794)
							(mid 0.249642 0.249642)
							(end 0.2794 0.1778)
						)
						(arc
							(start 0.2794 -0.1778)
							(mid 0.249642 -0.249642)
							(end 0.1778 -0.2794)
						)
					)
					(width 0)
					(fill yes)
				)
			)
		)
		(pad "2" smd custom
			(at 0 0.4445 180)
			(size 0.1397 0.1397)
			(layers "F.Cu" "F.Mask" "F.Paste")
			(net "MB0_P12V_PWRGOOD")
			(options
				(clearance outline)
				(anchor circle)
			)
			(primitives
				(gr_poly
					(pts
						(arc
							(start -0.1778 -0.2794)
							(mid -0.249642 -0.249642)
							(end -0.2794 -0.1778)
						)
						(arc
							(start -0.2794 0.1778)
							(mid -0.249642 0.249642)
							(end -0.1778 0.2794)
						)
						(arc
							(start 0.1778 0.2794)
							(mid 0.249642 0.249642)
							(end 0.2794 0.1778)
						)
						(arc
							(start 0.2794 -0.1778)
							(mid 0.249642 -0.249642)
							(end 0.1778 -0.2794)
						)
					)
					(width 0)
					(fill yes)
				)
			)
		)
	)
	(footprint ""
		(layer "F.Cu")
		(at 145.796 -89.535 180)
		(property "Reference" "PC88"
			(at 0 0 180)
			(layer "F.SilkS")
			(hide yes)
			(effects
				(font
					(size 1.27 1.27)
				)
			)
		)
		(property "Value" "SC22U6D3V5MX-5-GP"
			(at -0.0762 -6.1214 180)
			(unlocked yes)
			(layer "F.Fab")
			(hide yes)
			(effects
				(font
					(size 1.016 1.016)
					(thickness 0.1524)
				)
			)
		)
		(property "Device Type" "C805H56"
			(at -0.0762 -8.1534 180)
			(unlocked yes)
			(layer "F.Fab")
			(hide yes)
			(effects
				(font
					(size 1.016 1.016)
					(thickness 0.1524)
				)
			)
		)
		(duplicate_pad_numbers_are_jumpers no)
		(fp_line
			(start 0.635 0)
			(end -0.635 0)
			(stroke
				(width 0.508)
				(type default)
			)
			(layer "F.SilkS")
		)
		(fp_rect
			(start -0.9652 1.778)
			(end 0.9652 -1.778)
			(stroke
				(width 0)
				(type default)
			)
			(fill no)
			(layer "F.CrtYd")
		)
		(fp_poly
			(pts
				(xy -0.9652 -1.778) (xy 0.9652 -1.778) (xy 0.9652 1.778) (xy -0.9652 1.778)
			)
			(stroke
				(width 0)
				(type default)
			)
			(fill no)
			(layer "F.Fab")
		)
		(pad "1" smd rect
			(at 0 -0.9652 180)
			(size 1.397 1.143)
			(layers "F.Cu" "F.Mask" "F.Paste")
			(net "P1V8_PWR")
		)
		(pad "2" smd rect
			(at 0 0.9652 180)
			(size 1.397 1.143)
			(layers "F.Cu" "F.Mask" "F.Paste")
			(net "GND")
		)
	)
	(footprint ""
		(layer "F.Cu")
		(at 202.0062 -4.0894 180)
		(property "Reference" "JP10"
			(at 0 0 180)
			(layer "F.SilkS")
			(hide yes)
			(effects
				(font
					(size 1.27 1.27)
				)
			)
		)
		(property "Value" "PIN-CON3-S-GP"
			(at -5.588 -5.3086 180)
			(unlocked yes)
			(layer "F.Fab")
			(hide yes)
			(effects
				(font
					(size 1.016 1.016)
					(thickness 0.1524)
				)
			)
		)
		(property "Device Type" "21S-91-03GB01"
			(at -5.588 -6.8326 180)
			(unlocked yes)
			(layer "F.Fab")
			(hide yes)
			(effects
				(font
					(size 1.016 1.016)
					(thickness 0.1524)
				)
			)
		)
		(duplicate_pad_numbers_are_jumpers no)
		(fp_line
			(start 3.8862 1.4986)
			(end 3.8862 -1.4986)
			(stroke
				(width 0.1524)
				(type default)
			)
			(layer "F.SilkS")
		)
		(fp_line
			(start 3.8862 -1.4986)
			(end -3.8862 -1.4986)
			(stroke
				(width 0.1524)
				(type default)
			)
			(layer "F.SilkS")
		)
		(fp_line
			(start -3.8862 1.4986)
			(end 3.8862 1.4986)
			(stroke
				(width 0.1524)
				(type default)
			)
			(layer "F.SilkS")
		)
		(fp_line
			(start -3.8862 -1.4986)
			(end -3.8862 1.4986)
			(stroke
				(width 0.1524)
				(type default)
			)
			(layer "F.SilkS")
		)
		(fp_line
			(start -4.0132 -0.3556)
			(end -4.0132 -1.6256)
			(stroke
				(width 0.4064)
				(type default)
			)
			(layer "F.SilkS")
		)
		(fp_line
			(start -4.0132 -1.6256)
			(end -2.7432 -1.6256)
			(stroke
				(width 0.4064)
				(type default)
			)
			(layer "F.SilkS")
		)
		(fp_circle
			(center 2.54 0)
			(end 1.4732 0)
			(stroke
				(width 0.3048)
				(type default)
			)
			(fill no)
			(layer "F.SilkS")
		)
		(fp_circle
			(center 0 0)
			(end -1.0668 0)
			(stroke
				(width 0.3048)
				(type default)
			)
			(fill no)
			(layer "F.SilkS")
		)
		(fp_circle
			(center -2.54 0)
			(end -3.6068 0)
			(stroke
				(width 0.3048)
				(type default)
			)
			(fill no)
			(layer "F.SilkS")
		)
		(fp_rect
			(start -3.6322 1.2446)
			(end 3.6322 -1.2446)
			(stroke
				(width 0)
				(type default)
			)
			(fill no)
			(layer "F.CrtYd")
		)
		(fp_poly
			(pts
				(xy 4.1402 -1.2446) (xy -3.6322 -1.2446) (xy -3.6322 1.2446) (xy 3.6322 1.2446) (xy 3.6322 -1.2319)
				(xy 4.1402 -1.2319) (xy 4.1402 1.7526) (xy -4.1402 1.7526) (xy -4.1402 -1.7526) (xy 4.1402 -1.7526)
			)
			(stroke
				(width 0)
				(type default)
			)
			(fill no)
			(layer "F.CrtYd")
		)
		(fp_rect
			(start -4.1402 1.7526)
			(end 4.1402 -1.7526)
			(stroke
				(width 0)
				(type default)
			)
			(fill no)
			(layer "F.Fab")
		)
		(pad "1" thru_hole circle
			(at -2.54 0 180)
			(size 1.4224 1.4224)
			(drill 1.016)
			(layers "*.Cu" "*.Mask")
			(remove_unused_layers no)
			(net "BOOT_RECOVERY_1")
			(clearance 0.1524)
			(thermal_gap 0.1524)
		)
		(pad "2" thru_hole circle
			(at 0 0 180)
			(size 1.4224 1.4224)
			(drill 1.016)
			(layers "*.Cu" "*.Mask")
			(remove_unused_layers no)
			(net "BOOT_RECOVERY#_R")
			(clearance 0.1524)
			(thermal_gap 0.1524)
		)
		(pad "3" thru_hole circle
			(at 2.54 0 180)
			(size 1.4224 1.4224)
			(drill 1.016)
			(layers "*.Cu" "*.Mask")
			(remove_unused_layers no)
			(net "BOOT_RECOVERY_0")
			(clearance 0.1524)
			(thermal_gap 0.1524)
		)
	)
	(footprint ""
		(layer "F.Cu")
		(at 148.463 -33.528)
		(property "Reference" "C392"
			(at 0 0 0)
			(layer "F.SilkS")
			(hide yes)
			(effects
				(font
					(size 1.27 1.27)
				)
			)
		)
		(property "Value" "SCD22U10V2KX-1GP"
			(at 1.1811 -2.7051 0)
			(unlocked yes)
			(layer "F.Fab")
			(hide yes)
			(effects
				(font
					(size 1.016 1.016)
					(thickness 0.1524)
				)
			)
		)
		(property "Device Type" "C402H22"
			(at 1.1811 -4.2291 0)
			(unlocked yes)
			(layer "F.Fab")
			(hide yes)
			(effects
				(font
					(size 1.016 1.016)
					(thickness 0.1524)
				)
			)
		)
		(duplicate_pad_numbers_are_jumpers no)
		(fp_rect
			(start -0.4318 0.9525)
			(end 0.4318 -0.9525)
			(stroke
				(width 0)
				(type default)
			)
			(fill no)
			(layer "F.CrtYd")
		)
		(fp_rect
			(start -0.4318 0.9525)
			(end 0.4318 -0.9525)
			(stroke
				(width 0)
				(type default)
			)
			(fill no)
			(layer "F.Fab")
		)
		(pad "1" smd custom
			(at 0 -0.4445)
			(size 0.1524 0.1524)
			(layers "F.Cu" "F.Mask" "F.Paste")
			(net "PCIE_TX_CAP_P86")
			(options
				(clearance outline)
				(anchor circle)
			)
			(primitives
				(gr_poly
					(pts
						(arc
							(start 0.3048 -0.2032)
							(mid 0.275042 -0.275042)
							(end 0.2032 -0.3048)
						)
						(arc
							(start -0.2032 -0.3048)
							(mid -0.275042 -0.275042)
							(end -0.3048 -0.2032)
						)
						(arc
							(start -0.3048 0.2032)
							(mid -0.275042 0.275042)
							(end -0.2032 0.3048)
						)
						(arc
							(start 0.2032 0.3048)
							(mid 0.275042 0.275042)
							(end 0.3048 0.2032)
						)
					)
					(width 0)
					(fill yes)
				)
			)
		)
		(pad "2" smd custom
			(at 0 0.4445)
			(size 0.1524 0.1524)
			(layers "F.Cu" "F.Mask" "F.Paste")
			(net "PCIE_TX_P86")
			(options
				(clearance outline)
				(anchor circle)
			)
			(primitives
				(gr_poly
					(pts
						(arc
							(start 0.3048 -0.2032)
							(mid 0.275042 -0.275042)
							(end 0.2032 -0.3048)
						)
						(arc
							(start -0.2032 -0.3048)
							(mid -0.275042 -0.275042)
							(end -0.3048 -0.2032)
						)
						(arc
							(start -0.3048 0.2032)
							(mid -0.275042 0.275042)
							(end -0.2032 0.3048)
						)
						(arc
							(start 0.2032 0.3048)
							(mid 0.275042 0.275042)
							(end 0.3048 0.2032)
						)
					)
					(width 0)
					(fill yes)
				)
			)
		)
	)
	(footprint ""
		(layer "F.Cu")
		(at 273.939 -13.589 90)
		(property "Reference" "C2"
			(at 0 0 90)
			(layer "F.SilkS")
			(hide yes)
			(effects
				(font
					(size 1.27 1.27)
				)
			)
		)
		(property "Value" "SCD22U10V2KX-1GP"
			(at 1.1811 -2.7051 90)
			(unlocked yes)
			(layer "F.Fab")
			(hide yes)
			(effects
				(font
					(size 1.016 1.016)
					(thickness 0.1524)
				)
			)
		)
		(property "Device Type" "C402H22"
			(at 1.1811 -4.2291 90)
			(unlocked yes)
			(layer "F.Fab")
			(hide yes)
			(effects
				(font
					(size 1.016 1.016)
					(thickness 0.1524)
				)
			)
		)
		(duplicate_pad_numbers_are_jumpers no)
		(fp_rect
			(start -0.4318 0.9525)
			(end 0.4318 -0.9525)
			(stroke
				(width 0)
				(type default)
			)
			(fill no)
			(layer "F.CrtYd")
		)
		(fp_rect
			(start -0.4318 0.9525)
			(end 0.4318 -0.9525)
			(stroke
				(width 0)
				(type default)
			)
			(fill no)
			(layer "F.Fab")
		)
		(pad "1" smd custom
			(at 0 -0.4445 90)
			(size 0.1524 0.1524)
			(layers "F.Cu" "F.Mask" "F.Paste")
			(net "PCIE_TX_CAP_P0")
			(options
				(clearance outline)
				(anchor circle)
			)
			(primitives
				(gr_poly
					(pts
						(arc
							(start 0.3048 -0.2032)
							(mid 0.275042 -0.275042)
							(end 0.2032 -0.3048)
						)
						(arc
							(start -0.2032 -0.3048)
							(mid -0.275042 -0.275042)
							(end -0.3048 -0.2032)
						)
						(arc
							(start -0.3048 0.2032)
							(mid -0.275042 0.275042)
							(end -0.2032 0.3048)
						)
						(arc
							(start 0.2032 0.3048)
							(mid 0.275042 0.275042)
							(end 0.3048 0.2032)
						)
					)
					(width 0)
					(fill yes)
				)
			)
		)
		(pad "2" smd custom
			(at 0 0.4445 90)
			(size 0.1524 0.1524)
			(layers "F.Cu" "F.Mask" "F.Paste")
			(net "PCIE_TX_P0")
			(options
				(clearance outline)
				(anchor circle)
			)
			(primitives
				(gr_poly
					(pts
						(arc
							(start 0.3048 -0.2032)
							(mid 0.275042 -0.275042)
							(end 0.2032 -0.3048)
						)
						(arc
							(start -0.2032 -0.3048)
							(mid -0.275042 -0.275042)
							(end -0.3048 -0.2032)
						)
						(arc
							(start -0.3048 0.2032)
							(mid -0.275042 0.275042)
							(end -0.2032 0.3048)
						)
						(arc
							(start 0.2032 0.3048)
							(mid 0.275042 0.275042)
							(end 0.3048 0.2032)
						)
					)
					(width 0)
					(fill yes)
				)
			)
		)
	)
	(footprint ""
		(layer "F.Cu")
		(at 219.329 -10.16 -90)
		(property "Reference" "R657"
			(at 0 0 270)
			(layer "F.SilkS")
			(hide yes)
			(effects
				(font
					(size 1.27 1.27)
				)
			)
		)
		(property "Value" "100KR2F-L1-GP"
			(at 0.064008 -3.993896 270)
			(unlocked yes)
			(layer "F.Fab")
			(hide yes)
			(effects
				(font
					(size 1.016 1.016)
					(thickness 0.1524)
				)
			)
		)
		(property "Device Type" "R402H16"
			(at 0.064008 -5.517896 270)
			(unlocked yes)
			(layer "F.Fab")
			(hide yes)
			(effects
				(font
					(size 1.016 1.016)
					(thickness 0.1524)
				)
			)
		)
		(duplicate_pad_numbers_are_jumpers no)
		(fp_line
			(start -0.508 -0.9398)
			(end -0.508 0.9398)
			(stroke
				(width 0.1524)
				(type default)
			)
			(layer "F.SilkS")
		)
		(fp_line
			(start 0.508 -0.9398)
			(end -0.508 -0.9398)
			(stroke
				(width 0.1524)
				(type default)
			)
			(layer "F.SilkS")
		)
		(fp_rect
			(start -0.508 0.9398)
			(end 0.508 -0.9398)
			(stroke
				(width 0)
				(type default)
			)
			(fill no)
			(layer "F.CrtYd")
		)
		(fp_rect
			(start -0.508 0.9398)
			(end 0.508 -0.9398)
			(stroke
				(width 0)
				(type default)
			)
			(fill no)
			(layer "F.Fab")
		)
		(pad "1" smd custom
			(at 0 -0.4445 270)
			(size 0.1397 0.1397)
			(layers "F.Cu" "F.Mask" "F.Paste")
			(net "EEPROM_A1")
			(options
				(clearance outline)
				(anchor circle)
			)
			(primitives
				(gr_poly
					(pts
						(arc
							(start -0.1778 -0.2794)
							(mid -0.249642 -0.249642)
							(end -0.2794 -0.1778)
						)
						(arc
							(start -0.2794 0.1778)
							(mid -0.249642 0.249642)
							(end -0.1778 0.2794)
						)
						(arc
							(start 0.1778 0.2794)
							(mid 0.249642 0.249642)
							(end 0.2794 0.1778)
						)
						(arc
							(start 0.2794 -0.1778)
							(mid 0.249642 -0.249642)
							(end 0.1778 -0.2794)
						)
					)
					(width 0)
					(fill yes)
				)
			)
		)
		(pad "2" smd custom
			(at 0 0.4445 270)
			(size 0.1397 0.1397)
			(layers "F.Cu" "F.Mask" "F.Paste")
			(net "GND")
			(options
				(clearance outline)
				(anchor circle)
			)
			(primitives
				(gr_poly
					(pts
						(arc
							(start -0.1778 -0.2794)
							(mid -0.249642 -0.249642)
							(end -0.2794 -0.1778)
						)
						(arc
							(start -0.2794 0.1778)
							(mid -0.249642 0.249642)
							(end -0.1778 0.2794)
						)
						(arc
							(start 0.1778 0.2794)
							(mid 0.249642 0.249642)
							(end 0.2794 0.1778)
						)
						(arc
							(start 0.2794 -0.1778)
							(mid 0.249642 -0.249642)
							(end 0.1778 -0.2794)
						)
					)
					(width 0)
					(fill yes)
				)
			)
		)
	)
	(footprint ""
		(layer "F.Cu")
		(at 217.781124 -203.047092)
		(property "Reference" "R7918"
			(at 0 0 0)
			(layer "F.SilkS")
			(hide yes)
			(effects
				(font
					(size 1.27 1.27)
				)
			)
		)
		(property "Value" "0R2J-2-GP"
			(at 0.064008 -3.993896 0)
			(unlocked yes)
			(layer "F.Fab")
			(hide yes)
			(effects
				(font
					(size 1.016 1.016)
					(thickness 0.1524)
				)
			)
		)
		(property "Device Type" "R402H16"
			(at 0.064008 -5.517896 0)
			(unlocked yes)
			(layer "F.Fab")
			(hide yes)
			(effects
				(font
					(size 1.016 1.016)
					(thickness 0.1524)
				)
			)
		)
		(duplicate_pad_numbers_are_jumpers no)
		(fp_line
			(start -0.508 -0.9398)
			(end -0.508 0.9398)
			(stroke
				(width 0.1524)
				(type default)
			)
			(layer "F.SilkS")
		)
		(fp_line
			(start 0.508 -0.9398)
			(end -0.508 -0.9398)
			(stroke
				(width 0.1524)
				(type default)
			)
			(layer "F.SilkS")
		)
		(fp_rect
			(start -0.508 0.9398)
			(end 0.508 -0.9398)
			(stroke
				(width 0)
				(type default)
			)
			(fill no)
			(layer "F.CrtYd")
		)
		(fp_rect
			(start -0.508 0.9398)
			(end 0.508 -0.9398)
			(stroke
				(width 0)
				(type default)
			)
			(fill no)
			(layer "F.Fab")
		)
		(pad "1" smd custom
			(at 0 -0.4445)
			(size 0.1397 0.1397)
			(layers "F.Cu" "F.Mask" "F.Paste")
			(net "TWI_SDA1")
			(options
				(clearance outline)
				(anchor circle)
			)
			(primitives
				(gr_poly
					(pts
						(arc
							(start -0.1778 -0.2794)
							(mid -0.249642 -0.249642)
							(end -0.2794 -0.1778)
						)
						(arc
							(start -0.2794 0.1778)
							(mid -0.249642 0.249642)
							(end -0.1778 0.2794)
						)
						(arc
							(start 0.1778 0.2794)
							(mid 0.249642 0.249642)
							(end 0.2794 0.1778)
						)
						(arc
							(start 0.2794 -0.1778)
							(mid 0.249642 -0.249642)
							(end 0.1778 -0.2794)
						)
					)
					(width 0)
					(fill yes)
				)
			)
		)
		(pad "2" smd custom
			(at 0 0.4445)
			(size 0.1397 0.1397)
			(layers "F.Cu" "F.Mask" "F.Paste")
			(net "I2C_GPIO_SDA_3")
			(options
				(clearance outline)
				(anchor circle)
			)
			(primitives
				(gr_poly
					(pts
						(arc
							(start -0.1778 -0.2794)
							(mid -0.249642 -0.249642)
							(end -0.2794 -0.1778)
						)
						(arc
							(start -0.2794 0.1778)
							(mid -0.249642 0.249642)
							(end -0.1778 0.2794)
						)
						(arc
							(start 0.1778 0.2794)
							(mid 0.249642 0.249642)
							(end 0.2794 0.1778)
						)
						(arc
							(start 0.2794 -0.1778)
							(mid 0.249642 -0.249642)
							(end 0.1778 -0.2794)
						)
					)
					(width 0)
					(fill yes)
				)
			)
		)
	)
	(footprint ""
		(layer "F.Cu")
		(at 310.007 -58.6486)
		(property "Reference" "PG47"
			(at 0 0 0)
			(layer "F.SilkS")
			(hide yes)
			(effects
				(font
					(size 1.27 1.27)
				)
			)
		)
		(property "Value" "GAP-CLOSE-PWR-3-GP"
			(at 0.0254 -6.5786 0)
			(unlocked yes)
			(layer "F.Fab")
			(hide yes)
			(effects
				(font
					(size 1.016 1.016)
					(thickness 0.1524)
				)
			)
		)
		(property "Device Type" "GAP-CLOSE-PWR-3"
			(at 0.0254 -8.255 0)
			(unlocked yes)
			(layer "F.Fab")
			(hide yes)
			(effects
				(font
					(size 1.016 1.016)
					(thickness 0.1524)
				)
			)
		)
		(duplicate_pad_numbers_are_jumpers no)
		(fp_rect
			(start -0.7112 0.4572)
			(end 0.7112 -0.4572)
			(stroke
				(width 0)
				(type default)
			)
			(fill no)
			(layer "F.CrtYd")
		)
		(fp_poly
			(pts
				(xy -0.7112 -0.4572) (xy 0.7112 -0.4572) (xy 0.7112 0.4572) (xy -0.7112 0.4572)
			)
			(stroke
				(width 0)
				(type default)
			)
			(fill no)
			(layer "F.Fab")
		)
		(pad "1" smd rect
			(at -0.3048 0)
			(size 0.6604 0.762)
			(layers "F.Cu" "F.Mask" "F.Paste")
			(net "DUT_VDD")
		)
		(pad "2" smd rect
			(at 0.3048 0)
			(size 0.6604 0.762)
			(layers "F.Cu" "F.Mask" "F.Paste")
			(net "P0V9_E")
		)
	)
	(footprint ""
		(layer "F.Cu")
		(at 36.829492 -106.757724 -90)
		(property "Reference" "R417"
			(at 0 0 270)
			(layer "F.SilkS")
			(hide yes)
			(effects
				(font
					(size 1.27 1.27)
				)
			)
		)
		(property "Value" "10KR2F-2-GP"
			(at 0.064008 -3.993896 270)
			(unlocked yes)
			(layer "F.Fab")
			(hide yes)
			(effects
				(font
					(size 1.016 1.016)
					(thickness 0.1524)
				)
			)
		)
		(property "Device Type" "R402H16"
			(at 0.064008 -5.517896 270)
			(unlocked yes)
			(layer "F.Fab")
			(hide yes)
			(effects
				(font
					(size 1.016 1.016)
					(thickness 0.1524)
				)
			)
		)
		(duplicate_pad_numbers_are_jumpers no)
		(fp_line
			(start -0.508 -0.9398)
			(end -0.508 0.9398)
			(stroke
				(width 0.1524)
				(type default)
			)
			(layer "F.SilkS")
		)
		(fp_line
			(start 0.508 -0.9398)
			(end -0.508 -0.9398)
			(stroke
				(width 0.1524)
				(type default)
			)
			(layer "F.SilkS")
		)
		(fp_rect
			(start -0.508 0.9398)
			(end 0.508 -0.9398)
			(stroke
				(width 0)
				(type default)
			)
			(fill no)
			(layer "F.CrtYd")
		)
		(fp_rect
			(start -0.508 0.9398)
			(end 0.508 -0.9398)
			(stroke
				(width 0)
				(type default)
			)
			(fill no)
			(layer "F.Fab")
		)
		(pad "1" smd custom
			(at 0 -0.4445 270)
			(size 0.1397 0.1397)
			(layers "F.Cu" "F.Mask" "F.Paste")
			(net "GND")
			(options
				(clearance outline)
				(anchor circle)
			)
			(primitives
				(gr_poly
					(pts
						(arc
							(start -0.1778 -0.2794)
							(mid -0.249642 -0.249642)
							(end -0.2794 -0.1778)
						)
						(arc
							(start -0.2794 0.1778)
							(mid -0.249642 0.249642)
							(end -0.1778 0.2794)
						)
						(arc
							(start 0.1778 0.2794)
							(mid 0.249642 0.249642)
							(end 0.2794 0.1778)
						)
						(arc
							(start 0.2794 -0.1778)
							(mid 0.249642 -0.249642)
							(end 0.1778 -0.2794)
						)
					)
					(width 0)
					(fill yes)
				)
			)
		)
		(pad "2" smd custom
			(at 0 0.4445 270)
			(size 0.1397 0.1397)
			(layers "F.Cu" "F.Mask" "F.Paste")
			(net "RMII0_PHY_BMC_RXCTL0")
			(options
				(clearance outline)
				(anchor circle)
			)
			(primitives
				(gr_poly
					(pts
						(arc
							(start -0.1778 -0.2794)
							(mid -0.249642 -0.249642)
							(end -0.2794 -0.1778)
						)
						(arc
							(start -0.2794 0.1778)
							(mid -0.249642 0.249642)
							(end -0.1778 0.2794)
						)
						(arc
							(start 0.1778 0.2794)
							(mid 0.249642 0.249642)
							(end 0.2794 0.1778)
						)
						(arc
							(start 0.2794 -0.1778)
							(mid 0.249642 -0.249642)
							(end 0.1778 -0.2794)
						)
					)
					(width 0)
					(fill yes)
				)
			)
		)
	)
	(footprint ""
		(layer "F.Cu")
		(at 183.09336 -14.76756)
		(property "Reference" "R211"
			(at 0 0 0)
			(layer "F.SilkS")
			(hide yes)
			(effects
				(font
					(size 1.27 1.27)
				)
			)
		)
		(property "Value" "4K7R2F-GP"
			(at 0.064008 -3.993896 0)
			(unlocked yes)
			(layer "F.Fab")
			(hide yes)
			(effects
				(font
					(size 1.016 1.016)
					(thickness 0.1524)
				)
			)
		)
		(property "Device Type" "R402H16"
			(at 0.064008 -5.517896 0)
			(unlocked yes)
			(layer "F.Fab")
			(hide yes)
			(effects
				(font
					(size 1.016 1.016)
					(thickness 0.1524)
				)
			)
		)
		(duplicate_pad_numbers_are_jumpers no)
		(fp_line
			(start -0.508 -0.9398)
			(end -0.508 0.9398)
			(stroke
				(width 0.1524)
				(type default)
			)
			(layer "F.SilkS")
		)
		(fp_line
			(start 0.508 -0.9398)
			(end -0.508 -0.9398)
			(stroke
				(width 0.1524)
				(type default)
			)
			(layer "F.SilkS")
		)
		(fp_rect
			(start -0.508 0.9398)
			(end 0.508 -0.9398)
			(stroke
				(width 0)
				(type default)
			)
			(fill no)
			(layer "F.CrtYd")
		)
		(fp_rect
			(start -0.508 0.9398)
			(end 0.508 -0.9398)
			(stroke
				(width 0)
				(type default)
			)
			(fill no)
			(layer "F.Fab")
		)
		(pad "1" smd custom
			(at 0 -0.4445)
			(size 0.1397 0.1397)
			(layers "F.Cu" "F.Mask" "F.Paste")
			(net "CLK_P_4_R")
			(options
				(clearance outline)
				(anchor circle)
			)
			(primitives
				(gr_poly
					(pts
						(arc
							(start -0.1778 -0.2794)
							(mid -0.249642 -0.249642)
							(end -0.2794 -0.1778)
						)
						(arc
							(start -0.2794 0.1778)
							(mid -0.249642 0.249642)
							(end -0.1778 0.2794)
						)
						(arc
							(start 0.1778 0.2794)
							(mid 0.249642 0.249642)
							(end 0.2794 0.1778)
						)
						(arc
							(start 0.2794 -0.1778)
							(mid 0.249642 -0.249642)
							(end 0.1778 -0.2794)
						)
					)
					(width 0)
					(fill yes)
				)
			)
		)
		(pad "2" smd custom
			(at 0 0.4445)
			(size 0.1397 0.1397)
			(layers "F.Cu" "F.Mask" "F.Paste")
			(net "GND")
			(options
				(clearance outline)
				(anchor circle)
			)
			(primitives
				(gr_poly
					(pts
						(arc
							(start -0.1778 -0.2794)
							(mid -0.249642 -0.249642)
							(end -0.2794 -0.1778)
						)
						(arc
							(start -0.2794 0.1778)
							(mid -0.249642 0.249642)
							(end -0.1778 0.2794)
						)
						(arc
							(start 0.1778 0.2794)
							(mid 0.249642 0.249642)
							(end 0.2794 0.1778)
						)
						(arc
							(start 0.2794 -0.1778)
							(mid 0.249642 -0.249642)
							(end 0.1778 -0.2794)
						)
					)
					(width 0)
					(fill yes)
				)
			)
		)
	)
	(footprint ""
		(layer "F.Cu")
		(at 14.8082 -83.6168)
		(property "Reference" "R403"
			(at 0 0 0)
			(layer "F.SilkS")
			(hide yes)
			(effects
				(font
					(size 1.27 1.27)
				)
			)
		)
		(property "Value" "3K3R2F-2-GP"
			(at 0.064008 -3.993896 0)
			(unlocked yes)
			(layer "F.Fab")
			(hide yes)
			(effects
				(font
					(size 1.016 1.016)
					(thickness 0.1524)
				)
			)
		)
		(property "Device Type" "R402H16"
			(at 0.064008 -5.517896 0)
			(unlocked yes)
			(layer "F.Fab")
			(hide yes)
			(effects
				(font
					(size 1.016 1.016)
					(thickness 0.1524)
				)
			)
		)
		(duplicate_pad_numbers_are_jumpers no)
		(fp_line
			(start -0.508 -0.9398)
			(end -0.508 0.9398)
			(stroke
				(width 0.1524)
				(type default)
			)
			(layer "F.SilkS")
		)
		(fp_line
			(start 0.508 -0.9398)
			(end -0.508 -0.9398)
			(stroke
				(width 0.1524)
				(type default)
			)
			(layer "F.SilkS")
		)
		(fp_rect
			(start -0.508 0.9398)
			(end 0.508 -0.9398)
			(stroke
				(width 0)
				(type default)
			)
			(fill no)
			(layer "F.CrtYd")
		)
		(fp_rect
			(start -0.508 0.9398)
			(end 0.508 -0.9398)
			(stroke
				(width 0)
				(type default)
			)
			(fill no)
			(layer "F.Fab")
		)
		(pad "1" smd custom
			(at 0 -0.4445)
			(size 0.1397 0.1397)
			(layers "F.Cu" "F.Mask" "F.Paste")
			(net "P3V3_STBY")
			(options
				(clearance outline)
				(anchor circle)
			)
			(primitives
				(gr_poly
					(pts
						(arc
							(start -0.1778 -0.2794)
							(mid -0.249642 -0.249642)
							(end -0.2794 -0.1778)
						)
						(arc
							(start -0.2794 0.1778)
							(mid -0.249642 0.249642)
							(end -0.1778 0.2794)
						)
						(arc
							(start 0.1778 0.2794)
							(mid 0.249642 0.249642)
							(end 0.2794 0.1778)
						)
						(arc
							(start 0.2794 -0.1778)
							(mid 0.249642 -0.249642)
							(end 0.1778 -0.2794)
						)
					)
					(width 0)
					(fill yes)
				)
			)
		)
		(pad "2" smd custom
			(at 0 0.4445)
			(size 0.1397 0.1397)
			(layers "F.Cu" "F.Mask" "F.Paste")
			(net "NIC_JTDI")
			(options
				(clearance outline)
				(anchor circle)
			)
			(primitives
				(gr_poly
					(pts
						(arc
							(start -0.1778 -0.2794)
							(mid -0.249642 -0.249642)
							(end -0.2794 -0.1778)
						)
						(arc
							(start -0.2794 0.1778)
							(mid -0.249642 0.249642)
							(end -0.1778 0.2794)
						)
						(arc
							(start 0.1778 0.2794)
							(mid 0.249642 0.249642)
							(end 0.2794 0.1778)
						)
						(arc
							(start 0.2794 -0.1778)
							(mid 0.249642 -0.249642)
							(end 0.1778 -0.2794)
						)
					)
					(width 0)
					(fill yes)
				)
			)
		)
	)
	(footprint ""
		(layer "F.Cu")
		(at 134.342124 -208.889092 180)
		(property "Reference" "R7940"
			(at 0 0 180)
			(layer "F.SilkS")
			(hide yes)
			(effects
				(font
					(size 1.27 1.27)
				)
			)
		)
		(property "Value" "0R2J-2-GP"
			(at 0.064008 -3.993896 180)
			(unlocked yes)
			(layer "F.Fab")
			(hide yes)
			(effects
				(font
					(size 1.016 1.016)
					(thickness 0.1524)
				)
			)
		)
		(property "Device Type" "R402H16"
			(at 0.064008 -5.517896 180)
			(unlocked yes)
			(layer "F.Fab")
			(hide yes)
			(effects
				(font
					(size 1.016 1.016)
					(thickness 0.1524)
				)
			)
		)
		(duplicate_pad_numbers_are_jumpers no)
		(fp_line
			(start 0.508 -0.9398)
			(end -0.508 -0.9398)
			(stroke
				(width 0.1524)
				(type default)
			)
			(layer "F.SilkS")
		)
		(fp_line
			(start -0.508 -0.9398)
			(end -0.508 0.9398)
			(stroke
				(width 0.1524)
				(type default)
			)
			(layer "F.SilkS")
		)
		(fp_rect
			(start -0.508 0.9398)
			(end 0.508 -0.9398)
			(stroke
				(width 0)
				(type default)
			)
			(fill no)
			(layer "F.CrtYd")
		)
		(fp_rect
			(start -0.508 0.9398)
			(end 0.508 -0.9398)
			(stroke
				(width 0)
				(type default)
			)
			(fill no)
			(layer "F.Fab")
		)
		(pad "1" smd custom
			(at 0 -0.4445 180)
			(size 0.1397 0.1397)
			(layers "F.Cu" "F.Mask" "F.Paste")
			(net "SSD_ATNLED#6")
			(options
				(clearance outline)
				(anchor circle)
			)
			(primitives
				(gr_poly
					(pts
						(arc
							(start -0.1778 -0.2794)
							(mid -0.249642 -0.249642)
							(end -0.2794 -0.1778)
						)
						(arc
							(start -0.2794 0.1778)
							(mid -0.249642 0.249642)
							(end -0.1778 0.2794)
						)
						(arc
							(start 0.1778 0.2794)
							(mid 0.249642 0.249642)
							(end 0.2794 0.1778)
						)
						(arc
							(start 0.2794 -0.1778)
							(mid 0.249642 -0.249642)
							(end 0.1778 -0.2794)
						)
					)
					(width 0)
					(fill yes)
				)
			)
		)
		(pad "2" smd custom
			(at 0 0.4445 180)
			(size 0.1397 0.1397)
			(layers "F.Cu" "F.Mask" "F.Paste")
			(net "SSD_ATNLED#6_R")
			(options
				(clearance outline)
				(anchor circle)
			)
			(primitives
				(gr_poly
					(pts
						(arc
							(start -0.1778 -0.2794)
							(mid -0.249642 -0.249642)
							(end -0.2794 -0.1778)
						)
						(arc
							(start -0.2794 0.1778)
							(mid -0.249642 0.249642)
							(end -0.1778 0.2794)
						)
						(arc
							(start 0.1778 0.2794)
							(mid 0.249642 0.249642)
							(end 0.2794 0.1778)
						)
						(arc
							(start 0.2794 -0.1778)
							(mid 0.249642 -0.249642)
							(end 0.1778 -0.2794)
						)
					)
					(width 0)
					(fill yes)
				)
			)
		)
	)
	(footprint ""
		(layer "F.Cu")
		(at 182.62727 -3.800856 -90)
		(property "Reference" "R716"
			(at 0 0 270)
			(layer "F.SilkS")
			(hide yes)
			(effects
				(font
					(size 1.27 1.27)
				)
			)
		)
		(property "Value" "0R2J-2-GP"
			(at 0.064008 -3.993896 270)
			(unlocked yes)
			(layer "F.Fab")
			(hide yes)
			(effects
				(font
					(size 1.016 1.016)
					(thickness 0.1524)
				)
			)
		)
		(property "Device Type" "R402H16"
			(at 0.064008 -5.517896 270)
			(unlocked yes)
			(layer "F.Fab")
			(hide yes)
			(effects
				(font
					(size 1.016 1.016)
					(thickness 0.1524)
				)
			)
		)
		(duplicate_pad_numbers_are_jumpers no)
		(fp_line
			(start -0.508 -0.9398)
			(end -0.508 0.9398)
			(stroke
				(width 0.1524)
				(type default)
			)
			(layer "F.SilkS")
		)
		(fp_line
			(start 0.508 -0.9398)
			(end -0.508 -0.9398)
			(stroke
				(width 0.1524)
				(type default)
			)
			(layer "F.SilkS")
		)
		(fp_rect
			(start -0.508 0.9398)
			(end 0.508 -0.9398)
			(stroke
				(width 0)
				(type default)
			)
			(fill no)
			(layer "F.CrtYd")
		)
		(fp_rect
			(start -0.508 0.9398)
			(end 0.508 -0.9398)
			(stroke
				(width 0)
				(type default)
			)
			(fill no)
			(layer "F.Fab")
		)
		(pad "1" smd custom
			(at 0 -0.4445 270)
			(size 0.1397 0.1397)
			(layers "F.Cu" "F.Mask" "F.Paste")
			(net "HOST3_RST_N_C")
			(options
				(clearance outline)
				(anchor circle)
			)
			(primitives
				(gr_poly
					(pts
						(arc
							(start -0.1778 -0.2794)
							(mid -0.249642 -0.249642)
							(end -0.2794 -0.1778)
						)
						(arc
							(start -0.2794 0.1778)
							(mid -0.249642 0.249642)
							(end -0.1778 0.2794)
						)
						(arc
							(start 0.1778 0.2794)
							(mid 0.249642 0.249642)
							(end 0.2794 0.1778)
						)
						(arc
							(start 0.2794 -0.1778)
							(mid 0.249642 -0.249642)
							(end 0.1778 -0.2794)
						)
					)
					(width 0)
					(fill yes)
				)
			)
		)
		(pad "2" smd custom
			(at 0 0.4445 270)
			(size 0.1397 0.1397)
			(layers "F.Cu" "F.Mask" "F.Paste")
			(net "P3V3_STBY")
			(options
				(clearance outline)
				(anchor circle)
			)
			(primitives
				(gr_poly
					(pts
						(arc
							(start -0.1778 -0.2794)
							(mid -0.249642 -0.249642)
							(end -0.2794 -0.1778)
						)
						(arc
							(start -0.2794 0.1778)
							(mid -0.249642 0.249642)
							(end -0.1778 0.2794)
						)
						(arc
							(start 0.1778 0.2794)
							(mid 0.249642 0.249642)
							(end 0.2794 0.1778)
						)
						(arc
							(start 0.2794 -0.1778)
							(mid 0.249642 -0.249642)
							(end 0.1778 -0.2794)
						)
					)
					(width 0)
					(fill yes)
				)
			)
		)
	)
	(footprint ""
		(layer "F.Cu")
		(at 223.877124 -190.601092)
		(property "Reference" "R7929"
			(at 0 0 0)
			(layer "F.SilkS")
			(hide yes)
			(effects
				(font
					(size 1.27 1.27)
				)
			)
		)
		(property "Value" "0R2J-2-GP"
			(at 0.064008 -3.993896 0)
			(unlocked yes)
			(layer "F.Fab")
			(hide yes)
			(effects
				(font
					(size 1.016 1.016)
					(thickness 0.1524)
				)
			)
		)
		(property "Device Type" "R402H16"
			(at 0.064008 -5.517896 0)
			(unlocked yes)
			(layer "F.Fab")
			(hide yes)
			(effects
				(font
					(size 1.016 1.016)
					(thickness 0.1524)
				)
			)
		)
		(duplicate_pad_numbers_are_jumpers no)
		(fp_line
			(start -0.508 -0.9398)
			(end -0.508 0.9398)
			(stroke
				(width 0.1524)
				(type default)
			)
			(layer "F.SilkS")
		)
		(fp_line
			(start 0.508 -0.9398)
			(end -0.508 -0.9398)
			(stroke
				(width 0.1524)
				(type default)
			)
			(layer "F.SilkS")
		)
		(fp_rect
			(start -0.508 0.9398)
			(end 0.508 -0.9398)
			(stroke
				(width 0)
				(type default)
			)
			(fill no)
			(layer "F.CrtYd")
		)
		(fp_rect
			(start -0.508 0.9398)
			(end 0.508 -0.9398)
			(stroke
				(width 0)
				(type default)
			)
			(fill no)
			(layer "F.Fab")
		)
		(pad "1" smd custom
			(at 0 -0.4445)
			(size 0.1397 0.1397)
			(layers "F.Cu" "F.Mask" "F.Paste")
			(net "SSD_PRSNT#8")
			(options
				(clearance outline)
				(anchor circle)
			)
			(primitives
				(gr_poly
					(pts
						(arc
							(start -0.1778 -0.2794)
							(mid -0.249642 -0.249642)
							(end -0.2794 -0.1778)
						)
						(arc
							(start -0.2794 0.1778)
							(mid -0.249642 0.249642)
							(end -0.1778 0.2794)
						)
						(arc
							(start 0.1778 0.2794)
							(mid 0.249642 0.249642)
							(end 0.2794 0.1778)
						)
						(arc
							(start 0.2794 -0.1778)
							(mid 0.249642 -0.249642)
							(end 0.1778 -0.2794)
						)
					)
					(width 0)
					(fill yes)
				)
			)
		)
		(pad "2" smd custom
			(at 0 0.4445)
			(size 0.1397 0.1397)
			(layers "F.Cu" "F.Mask" "F.Paste")
			(net "SSD_PRSNT#8_R")
			(options
				(clearance outline)
				(anchor circle)
			)
			(primitives
				(gr_poly
					(pts
						(arc
							(start -0.1778 -0.2794)
							(mid -0.249642 -0.249642)
							(end -0.2794 -0.1778)
						)
						(arc
							(start -0.2794 0.1778)
							(mid -0.249642 0.249642)
							(end -0.1778 0.2794)
						)
						(arc
							(start 0.1778 0.2794)
							(mid 0.249642 0.249642)
							(end 0.2794 0.1778)
						)
						(arc
							(start 0.2794 -0.1778)
							(mid 0.249642 -0.249642)
							(end 0.1778 -0.2794)
						)
					)
					(width 0)
					(fill yes)
				)
			)
		)
	)
	(footprint ""
		(layer "F.Cu")
		(at 141.798802 -34.34588)
		(property "Reference" "R302"
			(at 0 0 0)
			(layer "F.SilkS")
			(hide yes)
			(effects
				(font
					(size 1.27 1.27)
				)
			)
		)
		(property "Value" "0R2J-2-GP"
			(at 0.064008 -3.993896 0)
			(unlocked yes)
			(layer "F.Fab")
			(hide yes)
			(effects
				(font
					(size 1.016 1.016)
					(thickness 0.1524)
				)
			)
		)
		(property "Device Type" "R402H16"
			(at 0.064008 -5.517896 0)
			(unlocked yes)
			(layer "F.Fab")
			(hide yes)
			(effects
				(font
					(size 1.016 1.016)
					(thickness 0.1524)
				)
			)
		)
		(duplicate_pad_numbers_are_jumpers no)
		(fp_line
			(start -0.508 -0.9398)
			(end -0.508 0.9398)
			(stroke
				(width 0.1524)
				(type default)
			)
			(layer "F.SilkS")
		)
		(fp_line
			(start 0.508 -0.9398)
			(end -0.508 -0.9398)
			(stroke
				(width 0.1524)
				(type default)
			)
			(layer "F.SilkS")
		)
		(fp_rect
			(start -0.508 0.9398)
			(end 0.508 -0.9398)
			(stroke
				(width 0)
				(type default)
			)
			(fill no)
			(layer "F.CrtYd")
		)
		(fp_rect
			(start -0.508 0.9398)
			(end 0.508 -0.9398)
			(stroke
				(width 0)
				(type default)
			)
			(fill no)
			(layer "F.Fab")
		)
		(pad "1" smd custom
			(at 0 -0.4445)
			(size 0.1397 0.1397)
			(layers "F.Cu" "F.Mask" "F.Paste")
			(net "CLK_P_2_R")
			(options
				(clearance outline)
				(anchor circle)
			)
			(primitives
				(gr_poly
					(pts
						(arc
							(start -0.1778 -0.2794)
							(mid -0.249642 -0.249642)
							(end -0.2794 -0.1778)
						)
						(arc
							(start -0.2794 0.1778)
							(mid -0.249642 0.249642)
							(end -0.1778 0.2794)
						)
						(arc
							(start 0.1778 0.2794)
							(mid 0.249642 0.249642)
							(end 0.2794 0.1778)
						)
						(arc
							(start 0.2794 -0.1778)
							(mid 0.249642 -0.249642)
							(end 0.1778 -0.2794)
						)
					)
					(width 0)
					(fill yes)
				)
			)
		)
		(pad "2" smd custom
			(at 0 0.4445)
			(size 0.1397 0.1397)
			(layers "F.Cu" "F.Mask" "F.Paste")
			(net "CLK_P_2")
			(options
				(clearance outline)
				(anchor circle)
			)
			(primitives
				(gr_poly
					(pts
						(arc
							(start -0.1778 -0.2794)
							(mid -0.249642 -0.249642)
							(end -0.2794 -0.1778)
						)
						(arc
							(start -0.2794 0.1778)
							(mid -0.249642 0.249642)
							(end -0.1778 0.2794)
						)
						(arc
							(start 0.1778 0.2794)
							(mid 0.249642 0.249642)
							(end 0.2794 0.1778)
						)
						(arc
							(start 0.2794 -0.1778)
							(mid 0.249642 -0.249642)
							(end 0.1778 -0.2794)
						)
					)
					(width 0)
					(fill yes)
				)
			)
		)
	)
	(footprint ""
		(layer "F.Cu")
		(at 133.326124 -208.889092 180)
		(property "Reference" "R7956"
			(at 0 0 180)
			(layer "F.SilkS")
			(hide yes)
			(effects
				(font
					(size 1.27 1.27)
				)
			)
		)
		(property "Value" "0R2J-2-GP"
			(at 0.064008 -3.993896 180)
			(unlocked yes)
			(layer "F.Fab")
			(hide yes)
			(effects
				(font
					(size 1.016 1.016)
					(thickness 0.1524)
				)
			)
		)
		(property "Device Type" "R402H16"
			(at 0.064008 -5.517896 180)
			(unlocked yes)
			(layer "F.Fab")
			(hide yes)
			(effects
				(font
					(size 1.016 1.016)
					(thickness 0.1524)
				)
			)
		)
		(duplicate_pad_numbers_are_jumpers no)
		(fp_line
			(start 0.508 -0.9398)
			(end -0.508 -0.9398)
			(stroke
				(width 0.1524)
				(type default)
			)
			(layer "F.SilkS")
		)
		(fp_line
			(start -0.508 -0.9398)
			(end -0.508 0.9398)
			(stroke
				(width 0.1524)
				(type default)
			)
			(layer "F.SilkS")
		)
		(fp_rect
			(start -0.508 0.9398)
			(end 0.508 -0.9398)
			(stroke
				(width 0)
				(type default)
			)
			(fill no)
			(layer "F.CrtYd")
		)
		(fp_rect
			(start -0.508 0.9398)
			(end 0.508 -0.9398)
			(stroke
				(width 0)
				(type default)
			)
			(fill no)
			(layer "F.Fab")
		)
		(pad "1" smd custom
			(at 0 -0.4445 180)
			(size 0.1397 0.1397)
			(layers "F.Cu" "F.Mask" "F.Paste")
			(net "SSD_PWREN6")
			(options
				(clearance outline)
				(anchor circle)
			)
			(primitives
				(gr_poly
					(pts
						(arc
							(start -0.1778 -0.2794)
							(mid -0.249642 -0.249642)
							(end -0.2794 -0.1778)
						)
						(arc
							(start -0.2794 0.1778)
							(mid -0.249642 0.249642)
							(end -0.1778 0.2794)
						)
						(arc
							(start 0.1778 0.2794)
							(mid 0.249642 0.249642)
							(end 0.2794 0.1778)
						)
						(arc
							(start 0.2794 -0.1778)
							(mid 0.249642 -0.249642)
							(end 0.1778 -0.2794)
						)
					)
					(width 0)
					(fill yes)
				)
			)
		)
		(pad "2" smd custom
			(at 0 0.4445 180)
			(size 0.1397 0.1397)
			(layers "F.Cu" "F.Mask" "F.Paste")
			(net "SSD_PWREN6_R")
			(options
				(clearance outline)
				(anchor circle)
			)
			(primitives
				(gr_poly
					(pts
						(arc
							(start -0.1778 -0.2794)
							(mid -0.249642 -0.249642)
							(end -0.2794 -0.1778)
						)
						(arc
							(start -0.2794 0.1778)
							(mid -0.249642 0.249642)
							(end -0.1778 0.2794)
						)
						(arc
							(start 0.1778 0.2794)
							(mid 0.249642 0.249642)
							(end 0.2794 0.1778)
						)
						(arc
							(start 0.2794 -0.1778)
							(mid 0.249642 -0.249642)
							(end 0.1778 -0.2794)
						)
					)
					(width 0)
					(fill yes)
				)
			)
		)
	)
	(footprint ""
		(layer "F.Cu")
		(at 164.084 -33.528)
		(property "Reference" "C397"
			(at 0 0 0)
			(layer "F.SilkS")
			(hide yes)
			(effects
				(font
					(size 1.27 1.27)
				)
			)
		)
		(property "Value" "SCD22U10V2KX-1GP"
			(at 1.1811 -2.7051 0)
			(unlocked yes)
			(layer "F.Fab")
			(hide yes)
			(effects
				(font
					(size 1.016 1.016)
					(thickness 0.1524)
				)
			)
		)
		(property "Device Type" "C402H22"
			(at 1.1811 -4.2291 0)
			(unlocked yes)
			(layer "F.Fab")
			(hide yes)
			(effects
				(font
					(size 1.016 1.016)
					(thickness 0.1524)
				)
			)
		)
		(duplicate_pad_numbers_are_jumpers no)
		(fp_rect
			(start -0.4318 0.9525)
			(end 0.4318 -0.9525)
			(stroke
				(width 0)
				(type default)
			)
			(fill no)
			(layer "F.CrtYd")
		)
		(fp_rect
			(start -0.4318 0.9525)
			(end 0.4318 -0.9525)
			(stroke
				(width 0)
				(type default)
			)
			(fill no)
			(layer "F.Fab")
		)
		(pad "1" smd custom
			(at 0 -0.4445)
			(size 0.1524 0.1524)
			(layers "F.Cu" "F.Mask" "F.Paste")
			(net "PCIE_TX_CAP_N88")
			(options
				(clearance outline)
				(anchor circle)
			)
			(primitives
				(gr_poly
					(pts
						(arc
							(start 0.3048 -0.2032)
							(mid 0.275042 -0.275042)
							(end 0.2032 -0.3048)
						)
						(arc
							(start -0.2032 -0.3048)
							(mid -0.275042 -0.275042)
							(end -0.3048 -0.2032)
						)
						(arc
							(start -0.3048 0.2032)
							(mid -0.275042 0.275042)
							(end -0.2032 0.3048)
						)
						(arc
							(start 0.2032 0.3048)
							(mid 0.275042 0.275042)
							(end 0.3048 0.2032)
						)
					)
					(width 0)
					(fill yes)
				)
			)
		)
		(pad "2" smd custom
			(at 0 0.4445)
			(size 0.1524 0.1524)
			(layers "F.Cu" "F.Mask" "F.Paste")
			(net "PCIE_TX_N88")
			(options
				(clearance outline)
				(anchor circle)
			)
			(primitives
				(gr_poly
					(pts
						(arc
							(start 0.3048 -0.2032)
							(mid 0.275042 -0.275042)
							(end 0.2032 -0.3048)
						)
						(arc
							(start -0.2032 -0.3048)
							(mid -0.275042 -0.275042)
							(end -0.3048 -0.2032)
						)
						(arc
							(start -0.3048 0.2032)
							(mid -0.275042 0.275042)
							(end -0.2032 0.3048)
						)
						(arc
							(start 0.2032 0.3048)
							(mid 0.275042 0.275042)
							(end 0.3048 0.2032)
						)
					)
					(width 0)
					(fill yes)
				)
			)
		)
	)
	(footprint ""
		(layer "F.Cu")
		(at 56.134 -133.985 180)
		(property "Reference" "C8085"
			(at 0 0 180)
			(layer "F.SilkS")
			(hide yes)
			(effects
				(font
					(size 1.27 1.27)
				)
			)
		)
		(property "Value" "SCD1U25V2KX-2-GP"
			(at 1.1811 -2.7051 180)
			(unlocked yes)
			(layer "F.Fab")
			(hide yes)
			(effects
				(font
					(size 1.016 1.016)
					(thickness 0.1524)
				)
			)
		)
		(property "Device Type" "C402H22"
			(at 1.1811 -4.2291 180)
			(unlocked yes)
			(layer "F.Fab")
			(hide yes)
			(effects
				(font
					(size 1.016 1.016)
					(thickness 0.1524)
				)
			)
		)
		(duplicate_pad_numbers_are_jumpers no)
		(fp_rect
			(start -0.4318 0.9525)
			(end 0.4318 -0.9525)
			(stroke
				(width 0)
				(type default)
			)
			(fill no)
			(layer "F.CrtYd")
		)
		(fp_rect
			(start -0.4318 0.9525)
			(end 0.4318 -0.9525)
			(stroke
				(width 0)
				(type default)
			)
			(fill no)
			(layer "F.Fab")
		)
		(pad "1" smd custom
			(at 0 -0.4445 180)
			(size 0.1524 0.1524)
			(layers "F.Cu" "F.Mask" "F.Paste")
			(net "ADC_P1V8_STBY")
			(options
				(clearance outline)
				(anchor circle)
			)
			(primitives
				(gr_poly
					(pts
						(arc
							(start 0.3048 -0.2032)
							(mid 0.275042 -0.275042)
							(end 0.2032 -0.3048)
						)
						(arc
							(start -0.2032 -0.3048)
							(mid -0.275042 -0.275042)
							(end -0.3048 -0.2032)
						)
						(arc
							(start -0.3048 0.2032)
							(mid -0.275042 0.275042)
							(end -0.2032 0.3048)
						)
						(arc
							(start 0.2032 0.3048)
							(mid 0.275042 0.275042)
							(end 0.3048 0.2032)
						)
					)
					(width 0)
					(fill yes)
				)
			)
		)
		(pad "2" smd custom
			(at 0 0.4445 180)
			(size 0.1524 0.1524)
			(layers "F.Cu" "F.Mask" "F.Paste")
			(net "GND")
			(options
				(clearance outline)
				(anchor circle)
			)
			(primitives
				(gr_poly
					(pts
						(arc
							(start 0.3048 -0.2032)
							(mid 0.275042 -0.275042)
							(end 0.2032 -0.3048)
						)
						(arc
							(start -0.2032 -0.3048)
							(mid -0.275042 -0.275042)
							(end -0.3048 -0.2032)
						)
						(arc
							(start -0.3048 0.2032)
							(mid -0.275042 0.275042)
							(end -0.2032 0.3048)
						)
						(arc
							(start 0.2032 0.3048)
							(mid 0.275042 0.275042)
							(end 0.3048 0.2032)
						)
					)
					(width 0)
					(fill yes)
				)
			)
		)
	)
	(footprint ""
		(layer "F.Cu")
		(at 20.447 -143.383)
		(property "Reference" "C202"
			(at 0 0 0)
			(layer "F.SilkS")
			(hide yes)
			(effects
				(font
					(size 1.27 1.27)
				)
			)
		)
		(property "Value" "SCD1U16V2KX-3GP"
			(at 1.1811 -2.7051 0)
			(unlocked yes)
			(layer "F.Fab")
			(hide yes)
			(effects
				(font
					(size 1.016 1.016)
					(thickness 0.1524)
				)
			)
		)
		(property "Device Type" "C402H22"
			(at 1.1811 -4.2291 0)
			(unlocked yes)
			(layer "F.Fab")
			(hide yes)
			(effects
				(font
					(size 1.016 1.016)
					(thickness 0.1524)
				)
			)
		)
		(duplicate_pad_numbers_are_jumpers no)
		(fp_rect
			(start -0.4318 0.9525)
			(end 0.4318 -0.9525)
			(stroke
				(width 0)
				(type default)
			)
			(fill no)
			(layer "F.CrtYd")
		)
		(fp_rect
			(start -0.4318 0.9525)
			(end 0.4318 -0.9525)
			(stroke
				(width 0)
				(type default)
			)
			(fill no)
			(layer "F.Fab")
		)
		(pad "1" smd custom
			(at 0 -0.4445)
			(size 0.1524 0.1524)
			(layers "F.Cu" "F.Mask" "F.Paste")
			(net "V1PLLAV12")
			(options
				(clearance outline)
				(anchor circle)
			)
			(primitives
				(gr_poly
					(pts
						(arc
							(start 0.3048 -0.2032)
							(mid 0.275042 -0.275042)
							(end 0.2032 -0.3048)
						)
						(arc
							(start -0.2032 -0.3048)
							(mid -0.275042 -0.275042)
							(end -0.3048 -0.2032)
						)
						(arc
							(start -0.3048 0.2032)
							(mid -0.275042 0.275042)
							(end -0.2032 0.3048)
						)
						(arc
							(start 0.2032 0.3048)
							(mid 0.275042 0.275042)
							(end 0.3048 0.2032)
						)
					)
					(width 0)
					(fill yes)
				)
			)
		)
		(pad "2" smd custom
			(at 0 0.4445)
			(size 0.1524 0.1524)
			(layers "F.Cu" "F.Mask" "F.Paste")
			(net "GND")
			(options
				(clearance outline)
				(anchor circle)
			)
			(primitives
				(gr_poly
					(pts
						(arc
							(start 0.3048 -0.2032)
							(mid 0.275042 -0.275042)
							(end 0.2032 -0.3048)
						)
						(arc
							(start -0.2032 -0.3048)
							(mid -0.275042 -0.275042)
							(end -0.3048 -0.2032)
						)
						(arc
							(start -0.3048 0.2032)
							(mid -0.275042 0.275042)
							(end -0.2032 0.3048)
						)
						(arc
							(start 0.2032 0.3048)
							(mid 0.275042 0.275042)
							(end 0.3048 0.2032)
						)
					)
					(width 0)
					(fill yes)
				)
			)
		)
	)
	(footprint ""
		(layer "F.Cu")
		(at 50.292 -199.39 90)
		(property "Reference" "R886"
			(at 0 0 90)
			(layer "F.SilkS")
			(hide yes)
			(effects
				(font
					(size 1.27 1.27)
				)
			)
		)
		(property "Value" "4K7R2J-2-GP"
			(at 0.064008 -3.993896 90)
			(unlocked yes)
			(layer "F.Fab")
			(hide yes)
			(effects
				(font
					(size 1.016 1.016)
					(thickness 0.1524)
				)
			)
		)
		(property "Device Type" "R402H16"
			(at 0.064008 -5.517896 90)
			(unlocked yes)
			(layer "F.Fab")
			(hide yes)
			(effects
				(font
					(size 1.016 1.016)
					(thickness 0.1524)
				)
			)
		)
		(duplicate_pad_numbers_are_jumpers no)
		(fp_line
			(start 0.508 -0.9398)
			(end -0.508 -0.9398)
			(stroke
				(width 0.1524)
				(type default)
			)
			(layer "F.SilkS")
		)
		(fp_line
			(start -0.508 -0.9398)
			(end -0.508 0.9398)
			(stroke
				(width 0.1524)
				(type default)
			)
			(layer "F.SilkS")
		)
		(fp_rect
			(start -0.508 0.9398)
			(end 0.508 -0.9398)
			(stroke
				(width 0)
				(type default)
			)
			(fill no)
			(layer "F.CrtYd")
		)
		(fp_rect
			(start -0.508 0.9398)
			(end 0.508 -0.9398)
			(stroke
				(width 0)
				(type default)
			)
			(fill no)
			(layer "F.Fab")
		)
		(pad "1" smd custom
			(at 0 -0.4445 90)
			(size 0.1397 0.1397)
			(layers "F.Cu" "F.Mask" "F.Paste")
			(net "P3V3_STBY")
			(options
				(clearance outline)
				(anchor circle)
			)
			(primitives
				(gr_poly
					(pts
						(arc
							(start -0.1778 -0.2794)
							(mid -0.249642 -0.249642)
							(end -0.2794 -0.1778)
						)
						(arc
							(start -0.2794 0.1778)
							(mid -0.249642 0.249642)
							(end -0.1778 0.2794)
						)
						(arc
							(start 0.1778 0.2794)
							(mid 0.249642 0.249642)
							(end 0.2794 0.1778)
						)
						(arc
							(start 0.2794 -0.1778)
							(mid 0.249642 -0.249642)
							(end 0.1778 -0.2794)
						)
					)
					(width 0)
					(fill yes)
				)
			)
		)
		(pad "2" smd custom
			(at 0 0.4445 90)
			(size 0.1397 0.1397)
			(layers "F.Cu" "F.Mask" "F.Paste")
			(net "BUF_I2C7_B_DPB_SDA_R")
			(options
				(clearance outline)
				(anchor circle)
			)
			(primitives
				(gr_poly
					(pts
						(arc
							(start -0.1778 -0.2794)
							(mid -0.249642 -0.249642)
							(end -0.2794 -0.1778)
						)
						(arc
							(start -0.2794 0.1778)
							(mid -0.249642 0.249642)
							(end -0.1778 0.2794)
						)
						(arc
							(start 0.1778 0.2794)
							(mid 0.249642 0.249642)
							(end 0.2794 0.1778)
						)
						(arc
							(start 0.2794 -0.1778)
							(mid 0.249642 -0.249642)
							(end 0.1778 -0.2794)
						)
					)
					(width 0)
					(fill yes)
				)
			)
		)
	)
	(footprint ""
		(layer "F.Cu")
		(at 181.61 -21.59 -90)
		(property "Reference" "C405"
			(at 0 0 270)
			(layer "F.SilkS")
			(hide yes)
			(effects
				(font
					(size 1.27 1.27)
				)
			)
		)
		(property "Value" "SCD22U10V2KX-1GP"
			(at 1.1811 -2.7051 270)
			(unlocked yes)
			(layer "F.Fab")
			(hide yes)
			(effects
				(font
					(size 1.016 1.016)
					(thickness 0.1524)
				)
			)
		)
		(property "Device Type" "C402H22"
			(at 1.1811 -4.2291 270)
			(unlocked yes)
			(layer "F.Fab")
			(hide yes)
			(effects
				(font
					(size 1.016 1.016)
					(thickness 0.1524)
				)
			)
		)
		(duplicate_pad_numbers_are_jumpers no)
		(fp_rect
			(start -0.4318 0.9525)
			(end 0.4318 -0.9525)
			(stroke
				(width 0)
				(type default)
			)
			(fill no)
			(layer "F.CrtYd")
		)
		(fp_rect
			(start -0.4318 0.9525)
			(end 0.4318 -0.9525)
			(stroke
				(width 0)
				(type default)
			)
			(fill no)
			(layer "F.Fab")
		)
		(pad "1" smd custom
			(at 0 -0.4445 270)
			(size 0.1524 0.1524)
			(layers "F.Cu" "F.Mask" "F.Paste")
			(net "PCIE_TX_CAP_N92")
			(options
				(clearance outline)
				(anchor circle)
			)
			(primitives
				(gr_poly
					(pts
						(arc
							(start 0.3048 -0.2032)
							(mid 0.275042 -0.275042)
							(end 0.2032 -0.3048)
						)
						(arc
							(start -0.2032 -0.3048)
							(mid -0.275042 -0.275042)
							(end -0.3048 -0.2032)
						)
						(arc
							(start -0.3048 0.2032)
							(mid -0.275042 0.275042)
							(end -0.2032 0.3048)
						)
						(arc
							(start 0.2032 0.3048)
							(mid 0.275042 0.275042)
							(end 0.3048 0.2032)
						)
					)
					(width 0)
					(fill yes)
				)
			)
		)
		(pad "2" smd custom
			(at 0 0.4445 270)
			(size 0.1524 0.1524)
			(layers "F.Cu" "F.Mask" "F.Paste")
			(net "PCIE_TX_N92")
			(options
				(clearance outline)
				(anchor circle)
			)
			(primitives
				(gr_poly
					(pts
						(arc
							(start 0.3048 -0.2032)
							(mid 0.275042 -0.275042)
							(end 0.2032 -0.3048)
						)
						(arc
							(start -0.2032 -0.3048)
							(mid -0.275042 -0.275042)
							(end -0.3048 -0.2032)
						)
						(arc
							(start -0.3048 0.2032)
							(mid -0.275042 0.275042)
							(end -0.2032 0.3048)
						)
						(arc
							(start 0.2032 0.3048)
							(mid 0.275042 0.275042)
							(end 0.3048 0.2032)
						)
					)
					(width 0)
					(fill yes)
				)
			)
		)
	)
	(footprint ""
		(layer "F.Cu")
		(at 270.302482 -12.403328 90)
		(property "Reference" "R219"
			(at 0 0 90)
			(layer "F.SilkS")
			(hide yes)
			(effects
				(font
					(size 1.27 1.27)
				)
			)
		)
		(property "Value" "4K7R2F-GP"
			(at 0.064008 -3.993896 90)
			(unlocked yes)
			(layer "F.Fab")
			(hide yes)
			(effects
				(font
					(size 1.016 1.016)
					(thickness 0.1524)
				)
			)
		)
		(property "Device Type" "R402H16"
			(at 0.064008 -5.517896 90)
			(unlocked yes)
			(layer "F.Fab")
			(hide yes)
			(effects
				(font
					(size 1.016 1.016)
					(thickness 0.1524)
				)
			)
		)
		(duplicate_pad_numbers_are_jumpers no)
		(fp_line
			(start 0.508 -0.9398)
			(end -0.508 -0.9398)
			(stroke
				(width 0.1524)
				(type default)
			)
			(layer "F.SilkS")
		)
		(fp_line
			(start -0.508 -0.9398)
			(end -0.508 0.9398)
			(stroke
				(width 0.1524)
				(type default)
			)
			(layer "F.SilkS")
		)
		(fp_rect
			(start -0.508 0.9398)
			(end 0.508 -0.9398)
			(stroke
				(width 0)
				(type default)
			)
			(fill no)
			(layer "F.CrtYd")
		)
		(fp_rect
			(start -0.508 0.9398)
			(end 0.508 -0.9398)
			(stroke
				(width 0)
				(type default)
			)
			(fill no)
			(layer "F.Fab")
		)
		(pad "1" smd custom
			(at 0 -0.4445 90)
			(size 0.1397 0.1397)
			(layers "F.Cu" "F.Mask" "F.Paste")
			(net "P3V3_STBY")
			(options
				(clearance outline)
				(anchor circle)
			)
			(primitives
				(gr_poly
					(pts
						(arc
							(start -0.1778 -0.2794)
							(mid -0.249642 -0.249642)
							(end -0.2794 -0.1778)
						)
						(arc
							(start -0.2794 0.1778)
							(mid -0.249642 0.249642)
							(end -0.1778 0.2794)
						)
						(arc
							(start 0.1778 0.2794)
							(mid 0.249642 0.249642)
							(end 0.2794 0.1778)
						)
						(arc
							(start 0.2794 -0.1778)
							(mid 0.249642 -0.249642)
							(end 0.1778 -0.2794)
						)
					)
					(width 0)
					(fill yes)
				)
			)
		)
		(pad "2" smd custom
			(at 0 0.4445 90)
			(size 0.1397 0.1397)
			(layers "F.Cu" "F.Mask" "F.Paste")
			(net "CLK_P_5_R")
			(options
				(clearance outline)
				(anchor circle)
			)
			(primitives
				(gr_poly
					(pts
						(arc
							(start -0.1778 -0.2794)
							(mid -0.249642 -0.249642)
							(end -0.2794 -0.1778)
						)
						(arc
							(start -0.2794 0.1778)
							(mid -0.249642 0.249642)
							(end -0.1778 0.2794)
						)
						(arc
							(start 0.1778 0.2794)
							(mid 0.249642 0.249642)
							(end 0.2794 0.1778)
						)
						(arc
							(start 0.2794 -0.1778)
							(mid 0.249642 -0.249642)
							(end 0.1778 -0.2794)
						)
					)
					(width 0)
					(fill yes)
				)
			)
		)
	)
	(footprint ""
		(layer "F.Cu")
		(at 50.673 -200.914 180)
		(property "Reference" "R890"
			(at 0 0 180)
			(layer "F.SilkS")
			(hide yes)
			(effects
				(font
					(size 1.27 1.27)
				)
			)
		)
		(property "Value" "0R2J-2-GP"
			(at 0.064008 -3.993896 180)
			(unlocked yes)
			(layer "F.Fab")
			(hide yes)
			(effects
				(font
					(size 1.016 1.016)
					(thickness 0.1524)
				)
			)
		)
		(property "Device Type" "R402H16"
			(at 0.064008 -5.517896 180)
			(unlocked yes)
			(layer "F.Fab")
			(hide yes)
			(effects
				(font
					(size 1.016 1.016)
					(thickness 0.1524)
				)
			)
		)
		(duplicate_pad_numbers_are_jumpers no)
		(fp_line
			(start 0.508 -0.9398)
			(end -0.508 -0.9398)
			(stroke
				(width 0.1524)
				(type default)
			)
			(layer "F.SilkS")
		)
		(fp_line
			(start -0.508 -0.9398)
			(end -0.508 0.9398)
			(stroke
				(width 0.1524)
				(type default)
			)
			(layer "F.SilkS")
		)
		(fp_rect
			(start -0.508 0.9398)
			(end 0.508 -0.9398)
			(stroke
				(width 0)
				(type default)
			)
			(fill no)
			(layer "F.CrtYd")
		)
		(fp_rect
			(start -0.508 0.9398)
			(end 0.508 -0.9398)
			(stroke
				(width 0)
				(type default)
			)
			(fill no)
			(layer "F.Fab")
		)
		(pad "1" smd custom
			(at 0 -0.4445 180)
			(size 0.1397 0.1397)
			(layers "F.Cu" "F.Mask" "F.Paste")
			(net "BUF_I2C7_B_DPB_SDA_R")
			(options
				(clearance outline)
				(anchor circle)
			)
			(primitives
				(gr_poly
					(pts
						(arc
							(start -0.1778 -0.2794)
							(mid -0.249642 -0.249642)
							(end -0.2794 -0.1778)
						)
						(arc
							(start -0.2794 0.1778)
							(mid -0.249642 0.249642)
							(end -0.1778 0.2794)
						)
						(arc
							(start 0.1778 0.2794)
							(mid 0.249642 0.249642)
							(end 0.2794 0.1778)
						)
						(arc
							(start 0.2794 -0.1778)
							(mid 0.249642 -0.249642)
							(end 0.1778 -0.2794)
						)
					)
					(width 0)
					(fill yes)
				)
			)
		)
		(pad "2" smd custom
			(at 0 0.4445 180)
			(size 0.1397 0.1397)
			(layers "F.Cu" "F.Mask" "F.Paste")
			(net "BUF_I2C7_B_DPB_SDA")
			(options
				(clearance outline)
				(anchor circle)
			)
			(primitives
				(gr_poly
					(pts
						(arc
							(start -0.1778 -0.2794)
							(mid -0.249642 -0.249642)
							(end -0.2794 -0.1778)
						)
						(arc
							(start -0.2794 0.1778)
							(mid -0.249642 0.249642)
							(end -0.1778 0.2794)
						)
						(arc
							(start 0.1778 0.2794)
							(mid 0.249642 0.249642)
							(end 0.2794 0.1778)
						)
						(arc
							(start 0.2794 -0.1778)
							(mid 0.249642 -0.249642)
							(end 0.1778 -0.2794)
						)
					)
					(width 0)
					(fill yes)
				)
			)
		)
	)
	(footprint ""
		(layer "F.Cu")
		(at 223.393 -23.241 180)
		(property "Reference" "R3724"
			(at 0 0 180)
			(layer "F.SilkS")
			(hide yes)
			(effects
				(font
					(size 1.27 1.27)
				)
			)
		)
		(property "Value" "4K7R2F-GP"
			(at 0.064008 -3.993896 180)
			(unlocked yes)
			(layer "F.Fab")
			(hide yes)
			(effects
				(font
					(size 1.016 1.016)
					(thickness 0.1524)
				)
			)
		)
		(property "Device Type" "R402H16"
			(at 0.064008 -5.517896 180)
			(unlocked yes)
			(layer "F.Fab")
			(hide yes)
			(effects
				(font
					(size 1.016 1.016)
					(thickness 0.1524)
				)
			)
		)
		(duplicate_pad_numbers_are_jumpers no)
		(fp_line
			(start 0.508 -0.9398)
			(end -0.508 -0.9398)
			(stroke
				(width 0.1524)
				(type default)
			)
			(layer "F.SilkS")
		)
		(fp_line
			(start -0.508 -0.9398)
			(end -0.508 0.9398)
			(stroke
				(width 0.1524)
				(type default)
			)
			(layer "F.SilkS")
		)
		(fp_rect
			(start -0.508 0.9398)
			(end 0.508 -0.9398)
			(stroke
				(width 0)
				(type default)
			)
			(fill no)
			(layer "F.CrtYd")
		)
		(fp_rect
			(start -0.508 0.9398)
			(end 0.508 -0.9398)
			(stroke
				(width 0)
				(type default)
			)
			(fill no)
			(layer "F.Fab")
		)
		(pad "1" smd custom
			(at 0 -0.4445 180)
			(size 0.1397 0.1397)
			(layers "F.Cu" "F.Mask" "F.Paste")
			(net "HOST7_RST_N_LS")
			(options
				(clearance outline)
				(anchor circle)
			)
			(primitives
				(gr_poly
					(pts
						(arc
							(start -0.1778 -0.2794)
							(mid -0.249642 -0.249642)
							(end -0.2794 -0.1778)
						)
						(arc
							(start -0.2794 0.1778)
							(mid -0.249642 0.249642)
							(end -0.1778 0.2794)
						)
						(arc
							(start 0.1778 0.2794)
							(mid 0.249642 0.249642)
							(end 0.2794 0.1778)
						)
						(arc
							(start 0.2794 -0.1778)
							(mid 0.249642 -0.249642)
							(end 0.1778 -0.2794)
						)
					)
					(width 0)
					(fill yes)
				)
			)
		)
		(pad "2" smd custom
			(at 0 0.4445 180)
			(size 0.1397 0.1397)
			(layers "F.Cu" "F.Mask" "F.Paste")
			(net "GND")
			(options
				(clearance outline)
				(anchor circle)
			)
			(primitives
				(gr_poly
					(pts
						(arc
							(start -0.1778 -0.2794)
							(mid -0.249642 -0.249642)
							(end -0.2794 -0.1778)
						)
						(arc
							(start -0.2794 0.1778)
							(mid -0.249642 0.249642)
							(end -0.1778 0.2794)
						)
						(arc
							(start 0.1778 0.2794)
							(mid 0.249642 0.249642)
							(end 0.2794 0.1778)
						)
						(arc
							(start 0.2794 -0.1778)
							(mid 0.249642 -0.249642)
							(end 0.1778 -0.2794)
						)
					)
					(width 0)
					(fill yes)
				)
			)
		)
	)
	(footprint ""
		(layer "F.Cu")
		(at 339.108034 -34.572194 180)
		(property "Reference" "R627"
			(at 0 0 180)
			(layer "F.SilkS")
			(hide yes)
			(effects
				(font
					(size 1.27 1.27)
				)
			)
		)
		(property "Value" "0R2J-2-GP"
			(at 0.064008 -3.993896 180)
			(unlocked yes)
			(layer "F.Fab")
			(hide yes)
			(effects
				(font
					(size 1.016 1.016)
					(thickness 0.1524)
				)
			)
		)
		(property "Device Type" "R402H16"
			(at 0.064008 -5.517896 180)
			(unlocked yes)
			(layer "F.Fab")
			(hide yes)
			(effects
				(font
					(size 1.016 1.016)
					(thickness 0.1524)
				)
			)
		)
		(duplicate_pad_numbers_are_jumpers no)
		(fp_line
			(start 0.508 -0.9398)
			(end -0.508 -0.9398)
			(stroke
				(width 0.1524)
				(type default)
			)
			(layer "F.SilkS")
		)
		(fp_line
			(start -0.508 -0.9398)
			(end -0.508 0.9398)
			(stroke
				(width 0.1524)
				(type default)
			)
			(layer "F.SilkS")
		)
		(fp_rect
			(start -0.508 0.9398)
			(end 0.508 -0.9398)
			(stroke
				(width 0)
				(type default)
			)
			(fill no)
			(layer "F.CrtYd")
		)
		(fp_rect
			(start -0.508 0.9398)
			(end 0.508 -0.9398)
			(stroke
				(width 0)
				(type default)
			)
			(fill no)
			(layer "F.Fab")
		)
		(pad "1" smd custom
			(at 0 -0.4445 180)
			(size 0.1397 0.1397)
			(layers "F.Cu" "F.Mask" "F.Paste")
			(net "UPLINK8_R")
			(options
				(clearance outline)
				(anchor circle)
			)
			(primitives
				(gr_poly
					(pts
						(arc
							(start -0.1778 -0.2794)
							(mid -0.249642 -0.249642)
							(end -0.2794 -0.1778)
						)
						(arc
							(start -0.2794 0.1778)
							(mid -0.249642 0.249642)
							(end -0.1778 0.2794)
						)
						(arc
							(start 0.1778 0.2794)
							(mid 0.249642 0.249642)
							(end 0.2794 0.1778)
						)
						(arc
							(start 0.2794 -0.1778)
							(mid 0.249642 -0.249642)
							(end 0.1778 -0.2794)
						)
					)
					(width 0)
					(fill yes)
				)
			)
		)
		(pad "2" smd custom
			(at 0 0.4445 180)
			(size 0.1397 0.1397)
			(layers "F.Cu" "F.Mask" "F.Paste")
			(net "UPLINK8")
			(options
				(clearance outline)
				(anchor circle)
			)
			(primitives
				(gr_poly
					(pts
						(arc
							(start -0.1778 -0.2794)
							(mid -0.249642 -0.249642)
							(end -0.2794 -0.1778)
						)
						(arc
							(start -0.2794 0.1778)
							(mid -0.249642 0.249642)
							(end -0.1778 0.2794)
						)
						(arc
							(start 0.1778 0.2794)
							(mid 0.249642 0.249642)
							(end 0.2794 0.1778)
						)
						(arc
							(start 0.2794 -0.1778)
							(mid 0.249642 -0.249642)
							(end 0.1778 -0.2794)
						)
					)
					(width 0)
					(fill yes)
				)
			)
		)
	)
	(footprint ""
		(layer "F.Cu")
		(at 75.180952 -149.52091 90)
		(property "Reference" "R199"
			(at 0 0 90)
			(layer "F.SilkS")
			(hide yes)
			(effects
				(font
					(size 1.27 1.27)
				)
			)
		)
		(property "Value" "8K2R2J-3-GP"
			(at 0.064008 -3.993896 90)
			(unlocked yes)
			(layer "F.Fab")
			(hide yes)
			(effects
				(font
					(size 1.016 1.016)
					(thickness 0.1524)
				)
			)
		)
		(property "Device Type" "R402H16"
			(at 0.064008 -5.517896 90)
			(unlocked yes)
			(layer "F.Fab")
			(hide yes)
			(effects
				(font
					(size 1.016 1.016)
					(thickness 0.1524)
				)
			)
		)
		(duplicate_pad_numbers_are_jumpers no)
		(fp_line
			(start 0.508 -0.9398)
			(end -0.508 -0.9398)
			(stroke
				(width 0.1524)
				(type default)
			)
			(layer "F.SilkS")
		)
		(fp_line
			(start -0.508 -0.9398)
			(end -0.508 0.9398)
			(stroke
				(width 0.1524)
				(type default)
			)
			(layer "F.SilkS")
		)
		(fp_rect
			(start -0.508 0.9398)
			(end 0.508 -0.9398)
			(stroke
				(width 0)
				(type default)
			)
			(fill no)
			(layer "F.CrtYd")
		)
		(fp_rect
			(start -0.508 0.9398)
			(end 0.508 -0.9398)
			(stroke
				(width 0)
				(type default)
			)
			(fill no)
			(layer "F.Fab")
		)
		(pad "1" smd custom
			(at 0 -0.4445 90)
			(size 0.1397 0.1397)
			(layers "F.Cu" "F.Mask" "F.Paste")
			(net "EEPROM_A2_R")
			(options
				(clearance outline)
				(anchor circle)
			)
			(primitives
				(gr_poly
					(pts
						(arc
							(start -0.1778 -0.2794)
							(mid -0.249642 -0.249642)
							(end -0.2794 -0.1778)
						)
						(arc
							(start -0.2794 0.1778)
							(mid -0.249642 0.249642)
							(end -0.1778 0.2794)
						)
						(arc
							(start 0.1778 0.2794)
							(mid 0.249642 0.249642)
							(end 0.2794 0.1778)
						)
						(arc
							(start 0.2794 -0.1778)
							(mid 0.249642 -0.249642)
							(end 0.1778 -0.2794)
						)
					)
					(width 0)
					(fill yes)
				)
			)
		)
		(pad "2" smd custom
			(at 0 0.4445 90)
			(size 0.1397 0.1397)
			(layers "F.Cu" "F.Mask" "F.Paste")
			(net "GND")
			(options
				(clearance outline)
				(anchor circle)
			)
			(primitives
				(gr_poly
					(pts
						(arc
							(start -0.1778 -0.2794)
							(mid -0.249642 -0.249642)
							(end -0.2794 -0.1778)
						)
						(arc
							(start -0.2794 0.1778)
							(mid -0.249642 0.249642)
							(end -0.1778 0.2794)
						)
						(arc
							(start 0.1778 0.2794)
							(mid 0.249642 0.249642)
							(end 0.2794 0.1778)
						)
						(arc
							(start 0.2794 -0.1778)
							(mid 0.249642 -0.249642)
							(end 0.1778 -0.2794)
						)
					)
					(width 0)
					(fill yes)
				)
			)
		)
	)
	(footprint ""
		(layer "F.Cu")
		(at 238.5314 -17.1196 90)
		(property "Reference" "Q22"
			(at 0 0 90)
			(layer "F.SilkS")
			(hide yes)
			(effects
				(font
					(size 1.27 1.27)
				)
			)
		)
		(property "Value" "2N7002K-1-GP"
			(at 0.127 -8.9662 90)
			(unlocked yes)
			(layer "F.Fab")
			(hide yes)
			(effects
				(font
					(size 1.016 1.016)
					(thickness 0.1524)
				)
			)
		)
		(property "Device Type" "SOT23DGS2D4H44"
			(at 0.127 -10.4902 90)
			(unlocked yes)
			(layer "F.Fab")
			(hide yes)
			(effects
				(font
					(size 1.016 1.016)
					(thickness 0.1524)
				)
			)
		)
		(duplicate_pad_numbers_are_jumpers no)
		(fp_line
			(start 1.651 -1.778)
			(end -1.651 -1.778)
			(stroke
				(width 0.1524)
				(type default)
			)
			(layer "F.SilkS")
		)
		(fp_line
			(start -1.651 -1.778)
			(end -1.651 1.778)
			(stroke
				(width 0.1524)
				(type default)
			)
			(layer "F.SilkS")
		)
		(fp_line
			(start 1.651 1.778)
			(end 1.651 -1.778)
			(stroke
				(width 0.1524)
				(type default)
			)
			(layer "F.SilkS")
		)
		(fp_line
			(start -1.651 1.778)
			(end 1.651 1.778)
			(stroke
				(width 0.1524)
				(type default)
			)
			(layer "F.SilkS")
		)
		(fp_poly
			(pts
				(xy -1.778 1.8796) (xy -1.778 -1.8796) (xy 1.778 -1.8796) (xy 1.778 1.8796)
			)
			(stroke
				(width 0)
				(type default)
			)
			(fill no)
			(layer "F.CrtYd")
		)
		(fp_poly
			(pts
				(xy -1.778 1.8796) (xy -1.778 -1.8796) (xy 1.778 -1.8796) (xy 1.778 1.8796)
			)
			(stroke
				(width 0)
				(type default)
			)
			(fill no)
			(layer "F.Fab")
		)
		(pad "D" smd custom
			(at 0 -0.9525 90)
			(size 0.1905 0.1905)
			(layers "F.Cu" "F.Mask" "F.Paste")
			(net "Q22_D")
			(options
				(clearance outline)
				(anchor circle)
			)
			(primitives
				(gr_poly
					(pts
						(arc
							(start -0.1778 0.5715)
							(mid -0.321484 0.511984)
							(end -0.381 0.3683)
						)
						(arc
							(start -0.381 -0.3683)
							(mid -0.321484 -0.511984)
							(end -0.1778 -0.5715)
						)
						(arc
							(start 0.1778 -0.5715)
							(mid 0.321484 -0.511984)
							(end 0.381 -0.3683)
						)
						(arc
							(start 0.381 0.3683)
							(mid 0.321484 0.511984)
							(end 0.1778 0.5715)
						)
					)
					(width 0)
					(fill yes)
				)
			)
		)
		(pad "G" smd custom
			(at -0.98425 0.9525 90)
			(size 0.1905 0.1905)
			(layers "F.Cu" "F.Mask" "F.Paste")
			(net "Q22_G")
			(options
				(clearance outline)
				(anchor circle)
			)
			(primitives
				(gr_poly
					(pts
						(arc
							(start -0.1778 0.5715)
							(mid -0.321484 0.511984)
							(end -0.381 0.3683)
						)
						(arc
							(start -0.381 -0.3683)
							(mid -0.321484 -0.511984)
							(end -0.1778 -0.5715)
						)
						(arc
							(start 0.1778 -0.5715)
							(mid 0.321484 -0.511984)
							(end 0.381 -0.3683)
						)
						(arc
							(start 0.381 0.3683)
							(mid 0.321484 0.511984)
							(end 0.1778 0.5715)
						)
					)
					(width 0)
					(fill yes)
				)
			)
		)
		(pad "S" smd custom
			(at 0.98425 0.9525 90)
			(size 0.1905 0.1905)
			(layers "F.Cu" "F.Mask" "F.Paste")
			(net "GND")
			(options
				(clearance outline)
				(anchor circle)
			)
			(primitives
				(gr_poly
					(pts
						(arc
							(start -0.1778 0.5715)
							(mid -0.321484 0.511984)
							(end -0.381 0.3683)
						)
						(arc
							(start -0.381 -0.3683)
							(mid -0.321484 -0.511984)
							(end -0.1778 -0.5715)
						)
						(arc
							(start 0.1778 -0.5715)
							(mid 0.321484 -0.511984)
							(end 0.381 -0.3683)
						)
						(arc
							(start 0.381 0.3683)
							(mid 0.321484 0.511984)
							(end 0.1778 0.5715)
						)
					)
					(width 0)
					(fill yes)
				)
			)
		)
	)
	(footprint ""
		(layer "F.Cu")
		(at 160.528 -83.5914 90)
		(property "Reference" "TP78"
			(at 0 0 90)
			(layer "F.SilkS")
			(hide yes)
			(effects
				(font
					(size 1.27 1.27)
				)
			)
		)
		(property "Value" "TPAD28-2-GP"
			(at -0.0127 -1.6637 90)
			(unlocked yes)
			(layer "F.Fab")
			(hide yes)
			(effects
				(font
					(size 1.016 1.016)
					(thickness 0.1524)
				)
			)
		)
		(property "Device Type" "TPAD28"
			(at -0.0127 -3.1877 90)
			(unlocked yes)
			(layer "F.Fab")
			(hide yes)
			(effects
				(font
					(size 1.016 1.016)
					(thickness 0.1524)
				)
			)
		)
		(duplicate_pad_numbers_are_jumpers no)
		(fp_poly
			(pts
				(arc
					(start 0 0.3556)
					(mid 0 -0.3556)
					(end 0 0.3556)
				)
			)
			(stroke
				(width 0)
				(type default)
			)
			(fill no)
			(layer "F.CrtYd")
		)
		(fp_poly
			(pts
				(arc
					(start 0 0.6096)
					(mid 0 -0.6096)
					(end 0 0.6096)
				)
			)
			(stroke
				(width 0)
				(type default)
			)
			(fill no)
			(layer "F.Fab")
		)
		(pad "1" smd circle
			(at 0 0 90)
			(size 0.7112 0.7112)
			(layers "F.Cu" "F.Mask" "F.Paste")
			(net "PCIE_CLKGEN2_OE0")
		)
	)
	(footprint ""
		(layer "F.Cu")
		(at 71.755 -125.349 180)
		(property "Reference" "R426"
			(at 0 0 180)
			(layer "F.SilkS")
			(hide yes)
			(effects
				(font
					(size 1.27 1.27)
				)
			)
		)
		(property "Value" "10KR2F-2-GP"
			(at 0.064008 -3.993896 180)
			(unlocked yes)
			(layer "F.Fab")
			(hide yes)
			(effects
				(font
					(size 1.016 1.016)
					(thickness 0.1524)
				)
			)
		)
		(property "Device Type" "R402H16"
			(at 0.064008 -5.517896 180)
			(unlocked yes)
			(layer "F.Fab")
			(hide yes)
			(effects
				(font
					(size 1.016 1.016)
					(thickness 0.1524)
				)
			)
		)
		(duplicate_pad_numbers_are_jumpers no)
		(fp_line
			(start 0.508 -0.9398)
			(end -0.508 -0.9398)
			(stroke
				(width 0.1524)
				(type default)
			)
			(layer "F.SilkS")
		)
		(fp_line
			(start -0.508 -0.9398)
			(end -0.508 0.9398)
			(stroke
				(width 0.1524)
				(type default)
			)
			(layer "F.SilkS")
		)
		(fp_rect
			(start -0.508 0.9398)
			(end 0.508 -0.9398)
			(stroke
				(width 0)
				(type default)
			)
			(fill no)
			(layer "F.CrtYd")
		)
		(fp_rect
			(start -0.508 0.9398)
			(end 0.508 -0.9398)
			(stroke
				(width 0)
				(type default)
			)
			(fill no)
			(layer "F.Fab")
		)
		(pad "1" smd custom
			(at 0 -0.4445 180)
			(size 0.1397 0.1397)
			(layers "F.Cu" "F.Mask" "F.Paste")
			(net "P3V3_STBY")
			(options
				(clearance outline)
				(anchor circle)
			)
			(primitives
				(gr_poly
					(pts
						(arc
							(start -0.1778 -0.2794)
							(mid -0.249642 -0.249642)
							(end -0.2794 -0.1778)
						)
						(arc
							(start -0.2794 0.1778)
							(mid -0.249642 0.249642)
							(end -0.1778 0.2794)
						)
						(arc
							(start 0.1778 0.2794)
							(mid 0.249642 0.249642)
							(end 0.2794 0.1778)
						)
						(arc
							(start 0.2794 -0.1778)
							(mid 0.249642 -0.249642)
							(end 0.1778 -0.2794)
						)
					)
					(width 0)
					(fill yes)
				)
			)
		)
		(pad "2" smd custom
			(at 0 0.4445 180)
			(size 0.1397 0.1397)
			(layers "F.Cu" "F.Mask" "F.Paste")
			(net "MBP_UART_TX")
			(options
				(clearance outline)
				(anchor circle)
			)
			(primitives
				(gr_poly
					(pts
						(arc
							(start -0.1778 -0.2794)
							(mid -0.249642 -0.249642)
							(end -0.2794 -0.1778)
						)
						(arc
							(start -0.2794 0.1778)
							(mid -0.249642 0.249642)
							(end -0.1778 0.2794)
						)
						(arc
							(start 0.1778 0.2794)
							(mid 0.249642 0.249642)
							(end 0.2794 0.1778)
						)
						(arc
							(start 0.2794 -0.1778)
							(mid 0.249642 -0.249642)
							(end 0.1778 -0.2794)
						)
					)
					(width 0)
					(fill yes)
				)
			)
		)
	)
	(footprint ""
		(layer "F.Cu")
		(at 151.19223 -212.420454 180)
		(property "Reference" "C252"
			(at 0 0 180)
			(layer "F.SilkS")
			(hide yes)
			(effects
				(font
					(size 1.27 1.27)
				)
			)
		)
		(property "Value" "SCD22U10V2KX-1GP"
			(at 1.1811 -2.7051 180)
			(unlocked yes)
			(layer "F.Fab")
			(hide yes)
			(effects
				(font
					(size 1.016 1.016)
					(thickness 0.1524)
				)
			)
		)
		(property "Device Type" "C402H22"
			(at 1.1811 -4.2291 180)
			(unlocked yes)
			(layer "F.Fab")
			(hide yes)
			(effects
				(font
					(size 1.016 1.016)
					(thickness 0.1524)
				)
			)
		)
		(duplicate_pad_numbers_are_jumpers no)
		(fp_rect
			(start -0.4318 0.9525)
			(end 0.4318 -0.9525)
			(stroke
				(width 0)
				(type default)
			)
			(fill no)
			(layer "F.CrtYd")
		)
		(fp_rect
			(start -0.4318 0.9525)
			(end 0.4318 -0.9525)
			(stroke
				(width 0)
				(type default)
			)
			(fill no)
			(layer "F.Fab")
		)
		(pad "1" smd custom
			(at 0 -0.4445 180)
			(size 0.1524 0.1524)
			(layers "F.Cu" "F.Mask" "F.Paste")
			(net "PCIE_TX_CAP_P55")
			(options
				(clearance outline)
				(anchor circle)
			)
			(primitives
				(gr_poly
					(pts
						(arc
							(start 0.3048 -0.2032)
							(mid 0.275042 -0.275042)
							(end 0.2032 -0.3048)
						)
						(arc
							(start -0.2032 -0.3048)
							(mid -0.275042 -0.275042)
							(end -0.3048 -0.2032)
						)
						(arc
							(start -0.3048 0.2032)
							(mid -0.275042 0.275042)
							(end -0.2032 0.3048)
						)
						(arc
							(start 0.2032 0.3048)
							(mid 0.275042 0.275042)
							(end 0.3048 0.2032)
						)
					)
					(width 0)
					(fill yes)
				)
			)
		)
		(pad "2" smd custom
			(at 0 0.4445 180)
			(size 0.1524 0.1524)
			(layers "F.Cu" "F.Mask" "F.Paste")
			(net "PCIE_TX_P55")
			(options
				(clearance outline)
				(anchor circle)
			)
			(primitives
				(gr_poly
					(pts
						(arc
							(start 0.3048 -0.2032)
							(mid 0.275042 -0.275042)
							(end 0.2032 -0.3048)
						)
						(arc
							(start -0.2032 -0.3048)
							(mid -0.275042 -0.275042)
							(end -0.3048 -0.2032)
						)
						(arc
							(start -0.3048 0.2032)
							(mid -0.275042 0.275042)
							(end -0.2032 0.3048)
						)
						(arc
							(start 0.2032 0.3048)
							(mid 0.275042 0.275042)
							(end 0.3048 0.2032)
						)
					)
					(width 0)
					(fill yes)
				)
			)
		)
	)
	(footprint ""
		(layer "F.Cu")
		(at 26.888948 -109.32668 -90)
		(property "Reference" "C286"
			(at 0 0 270)
			(layer "F.SilkS")
			(hide yes)
			(effects
				(font
					(size 1.27 1.27)
				)
			)
		)
		(property "Value" "SCD01U16V2KX-3GP"
			(at 1.1811 -2.7051 270)
			(unlocked yes)
			(layer "F.Fab")
			(hide yes)
			(effects
				(font
					(size 1.016 1.016)
					(thickness 0.1524)
				)
			)
		)
		(property "Device Type" "C402H22"
			(at 1.1811 -4.2291 270)
			(unlocked yes)
			(layer "F.Fab")
			(hide yes)
			(effects
				(font
					(size 1.016 1.016)
					(thickness 0.1524)
				)
			)
		)
		(duplicate_pad_numbers_are_jumpers no)
		(fp_rect
			(start -0.4318 0.9525)
			(end 0.4318 -0.9525)
			(stroke
				(width 0)
				(type default)
			)
			(fill no)
			(layer "F.CrtYd")
		)
		(fp_rect
			(start -0.4318 0.9525)
			(end 0.4318 -0.9525)
			(stroke
				(width 0)
				(type default)
			)
			(fill no)
			(layer "F.Fab")
		)
		(pad "1" smd custom
			(at 0 -0.4445 270)
			(size 0.1524 0.1524)
			(layers "F.Cu" "F.Mask" "F.Paste")
			(net "PCIE_REFCLK_S5_P")
			(options
				(clearance outline)
				(anchor circle)
			)
			(primitives
				(gr_poly
					(pts
						(arc
							(start 0.3048 -0.2032)
							(mid 0.275042 -0.275042)
							(end 0.2032 -0.3048)
						)
						(arc
							(start -0.2032 -0.3048)
							(mid -0.275042 -0.275042)
							(end -0.3048 -0.2032)
						)
						(arc
							(start -0.3048 0.2032)
							(mid -0.275042 0.275042)
							(end -0.2032 0.3048)
						)
						(arc
							(start 0.2032 0.3048)
							(mid 0.275042 0.275042)
							(end 0.3048 0.2032)
						)
					)
					(width 0)
					(fill yes)
				)
			)
		)
		(pad "2" smd custom
			(at 0 0.4445 270)
			(size 0.1524 0.1524)
			(layers "F.Cu" "F.Mask" "F.Paste")
			(net "BMC_REFCLK_P")
			(options
				(clearance outline)
				(anchor circle)
			)
			(primitives
				(gr_poly
					(pts
						(arc
							(start 0.3048 -0.2032)
							(mid 0.275042 -0.275042)
							(end 0.2032 -0.3048)
						)
						(arc
							(start -0.2032 -0.3048)
							(mid -0.275042 -0.275042)
							(end -0.3048 -0.2032)
						)
						(arc
							(start -0.3048 0.2032)
							(mid -0.275042 0.275042)
							(end -0.2032 0.3048)
						)
						(arc
							(start 0.2032 0.3048)
							(mid 0.275042 0.275042)
							(end 0.3048 0.2032)
						)
					)
					(width 0)
					(fill yes)
				)
			)
		)
	)
	(footprint ""
		(layer "F.Cu")
		(at 122.8598 -93.4212 90)
		(property "Reference" "C246"
			(at 0 0 90)
			(layer "F.SilkS")
			(hide yes)
			(effects
				(font
					(size 1.27 1.27)
				)
			)
		)
		(property "Value" "SC220P50V3JN-GP"
			(at 0 -2.8194 90)
			(unlocked yes)
			(layer "F.Fab")
			(hide yes)
			(effects
				(font
					(size 1.016 1.016)
					(thickness 0.1524)
				)
			)
		)
		(property "Device Type" "C603H36"
			(at 0 -4.3434 90)
			(unlocked yes)
			(layer "F.Fab")
			(hide yes)
			(effects
				(font
					(size 1.016 1.016)
					(thickness 0.1524)
				)
			)
		)
		(duplicate_pad_numbers_are_jumpers no)
		(fp_line
			(start 0.508 0)
			(end -0.508 0)
			(stroke
				(width 0.2032)
				(type default)
			)
			(layer "F.SilkS")
		)
		(fp_rect
			(start -0.5842 1.3335)
			(end 0.5842 -1.3335)
			(stroke
				(width 0)
				(type default)
			)
			(fill no)
			(layer "F.CrtYd")
		)
		(fp_rect
			(start -0.5842 1.3335)
			(end 0.5842 -1.3335)
			(stroke
				(width 0)
				(type default)
			)
			(fill no)
			(layer "F.Fab")
		)
		(pad "1" smd custom
			(at 0 -0.762 90)
			(size 0.2159 0.2159)
			(layers "F.Cu" "F.Mask" "F.Paste")
			(net "BMC_I2C10_8536_SCL_R")
			(options
				(clearance outline)
				(anchor circle)
			)
			(primitives
				(gr_poly
					(pts
						(arc
							(start -0.3302 -0.4318)
							(mid -0.402042 -0.402042)
							(end -0.4318 -0.3302)
						)
						(arc
							(start -0.4318 0.3302)
							(mid -0.402042 0.402042)
							(end -0.3302 0.4318)
						)
						(arc
							(start 0.3302 0.4318)
							(mid 0.402042 0.402042)
							(end 0.4318 0.3302)
						)
						(arc
							(start 0.4318 -0.3302)
							(mid 0.402042 -0.402042)
							(end 0.3302 -0.4318)
						)
					)
					(width 0)
					(fill yes)
				)
			)
		)
		(pad "2" smd custom
			(at 0 0.762 90)
			(size 0.2159 0.2159)
			(layers "F.Cu" "F.Mask" "F.Paste")
			(net "GND")
			(options
				(clearance outline)
				(anchor circle)
			)
			(primitives
				(gr_poly
					(pts
						(arc
							(start -0.3302 -0.4318)
							(mid -0.402042 -0.402042)
							(end -0.4318 -0.3302)
						)
						(arc
							(start -0.4318 0.3302)
							(mid -0.402042 0.402042)
							(end -0.3302 0.4318)
						)
						(arc
							(start 0.3302 0.4318)
							(mid 0.402042 0.402042)
							(end 0.4318 0.3302)
						)
						(arc
							(start 0.4318 -0.3302)
							(mid 0.402042 -0.402042)
							(end 0.3302 -0.4318)
						)
					)
					(width 0)
					(fill yes)
				)
			)
		)
	)
	(footprint ""
		(layer "F.Cu")
		(at 62.3062 -153.5176 180)
		(property "Reference" "PG11"
			(at 0 0 180)
			(layer "F.SilkS")
			(hide yes)
			(effects
				(font
					(size 1.27 1.27)
				)
			)
		)
		(property "Value" "GAP-CLOSE-PWR-3-GP"
			(at 0.0254 -6.5786 180)
			(unlocked yes)
			(layer "F.Fab")
			(hide yes)
			(effects
				(font
					(size 1.016 1.016)
					(thickness 0.1524)
				)
			)
		)
		(property "Device Type" "GAP-CLOSE-PWR-3"
			(at 0.0254 -8.255 180)
			(unlocked yes)
			(layer "F.Fab")
			(hide yes)
			(effects
				(font
					(size 1.016 1.016)
					(thickness 0.1524)
				)
			)
		)
		(duplicate_pad_numbers_are_jumpers no)
		(fp_rect
			(start -0.7112 0.4572)
			(end 0.7112 -0.4572)
			(stroke
				(width 0)
				(type default)
			)
			(fill no)
			(layer "F.CrtYd")
		)
		(fp_poly
			(pts
				(xy -0.7112 -0.4572) (xy 0.7112 -0.4572) (xy 0.7112 0.4572) (xy -0.7112 0.4572)
			)
			(stroke
				(width 0)
				(type default)
			)
			(fill no)
			(layer "F.Fab")
		)
		(pad "1" smd rect
			(at -0.3048 0 180)
			(size 0.6604 0.762)
			(layers "F.Cu" "F.Mask" "F.Paste")
			(net "P1V53_PWR")
		)
		(pad "2" smd rect
			(at 0.3048 0 180)
			(size 0.6604 0.762)
			(layers "F.Cu" "F.Mask" "F.Paste")
			(net "P1V53_STBY")
		)
	)
	(footprint ""
		(layer "F.Cu")
		(at 319.670176 -33.507426)
		(property "Reference" "C47"
			(at 0 0 0)
			(layer "F.SilkS")
			(hide yes)
			(effects
				(font
					(size 1.27 1.27)
				)
			)
		)
		(property "Value" "SCD22U10V2KX-1GP"
			(at 1.1811 -2.7051 0)
			(unlocked yes)
			(layer "F.Fab")
			(hide yes)
			(effects
				(font
					(size 1.016 1.016)
					(thickness 0.1524)
				)
			)
		)
		(property "Device Type" "C402H22"
			(at 1.1811 -4.2291 0)
			(unlocked yes)
			(layer "F.Fab")
			(hide yes)
			(effects
				(font
					(size 1.016 1.016)
					(thickness 0.1524)
				)
			)
		)
		(duplicate_pad_numbers_are_jumpers no)
		(fp_rect
			(start -0.4318 0.9525)
			(end 0.4318 -0.9525)
			(stroke
				(width 0)
				(type default)
			)
			(fill no)
			(layer "F.CrtYd")
		)
		(fp_rect
			(start -0.4318 0.9525)
			(end 0.4318 -0.9525)
			(stroke
				(width 0)
				(type default)
			)
			(fill no)
			(layer "F.Fab")
		)
		(pad "1" smd custom
			(at 0 -0.4445)
			(size 0.1524 0.1524)
			(layers "F.Cu" "F.Mask" "F.Paste")
			(net "PCIE_TX_CAP_P12")
			(options
				(clearance outline)
				(anchor circle)
			)
			(primitives
				(gr_poly
					(pts
						(arc
							(start 0.3048 -0.2032)
							(mid 0.275042 -0.275042)
							(end 0.2032 -0.3048)
						)
						(arc
							(start -0.2032 -0.3048)
							(mid -0.275042 -0.275042)
							(end -0.3048 -0.2032)
						)
						(arc
							(start -0.3048 0.2032)
							(mid -0.275042 0.275042)
							(end -0.2032 0.3048)
						)
						(arc
							(start 0.2032 0.3048)
							(mid 0.275042 0.275042)
							(end 0.3048 0.2032)
						)
					)
					(width 0)
					(fill yes)
				)
			)
		)
		(pad "2" smd custom
			(at 0 0.4445)
			(size 0.1524 0.1524)
			(layers "F.Cu" "F.Mask" "F.Paste")
			(net "PCIE_TX_P12")
			(options
				(clearance outline)
				(anchor circle)
			)
			(primitives
				(gr_poly
					(pts
						(arc
							(start 0.3048 -0.2032)
							(mid 0.275042 -0.275042)
							(end 0.2032 -0.3048)
						)
						(arc
							(start -0.2032 -0.3048)
							(mid -0.275042 -0.275042)
							(end -0.3048 -0.2032)
						)
						(arc
							(start -0.3048 0.2032)
							(mid -0.275042 0.275042)
							(end -0.2032 0.3048)
						)
						(arc
							(start 0.2032 0.3048)
							(mid 0.275042 0.275042)
							(end 0.3048 0.2032)
						)
					)
					(width 0)
					(fill yes)
				)
			)
		)
	)
	(footprint ""
		(layer "F.Cu")
		(at 147.0152 -83.7946 -90)
		(property "Reference" "PG70"
			(at 0 0 270)
			(layer "F.SilkS")
			(hide yes)
			(effects
				(font
					(size 1.27 1.27)
				)
			)
		)
		(property "Value" "GAP-CLOSE-PWR-3-GP"
			(at 0.0254 -6.5786 270)
			(unlocked yes)
			(layer "F.Fab")
			(hide yes)
			(effects
				(font
					(size 1.016 1.016)
					(thickness 0.1524)
				)
			)
		)
		(property "Device Type" "GAP-CLOSE-PWR-3"
			(at 0.0254 -8.255 270)
			(unlocked yes)
			(layer "F.Fab")
			(hide yes)
			(effects
				(font
					(size 1.016 1.016)
					(thickness 0.1524)
				)
			)
		)
		(duplicate_pad_numbers_are_jumpers no)
		(fp_rect
			(start -0.7112 0.4572)
			(end 0.7112 -0.4572)
			(stroke
				(width 0)
				(type default)
			)
			(fill no)
			(layer "F.CrtYd")
		)
		(fp_poly
			(pts
				(xy -0.7112 -0.4572) (xy 0.7112 -0.4572) (xy 0.7112 0.4572) (xy -0.7112 0.4572)
			)
			(stroke
				(width 0)
				(type default)
			)
			(fill no)
			(layer "F.Fab")
		)
		(pad "1" smd rect
			(at -0.3048 0 270)
			(size 0.6604 0.762)
			(layers "F.Cu" "F.Mask" "F.Paste")
			(net "P1V8_PWR")
		)
		(pad "2" smd rect
			(at 0.3048 0 270)
			(size 0.6604 0.762)
			(layers "F.Cu" "F.Mask" "F.Paste")
			(net "DUT_VDDO")
		)
	)
	(footprint ""
		(layer "F.Cu")
		(at 13.569188 -90.452956 180)
		(property "Reference" "R476"
			(at 0 0 180)
			(layer "F.SilkS")
			(hide yes)
			(effects
				(font
					(size 1.27 1.27)
				)
			)
		)
		(property "Value" "10KR2F-2-GP"
			(at 0.064008 -3.993896 180)
			(unlocked yes)
			(layer "F.Fab")
			(hide yes)
			(effects
				(font
					(size 1.016 1.016)
					(thickness 0.1524)
				)
			)
		)
		(property "Device Type" "R402H16"
			(at 0.064008 -5.517896 180)
			(unlocked yes)
			(layer "F.Fab")
			(hide yes)
			(effects
				(font
					(size 1.016 1.016)
					(thickness 0.1524)
				)
			)
		)
		(duplicate_pad_numbers_are_jumpers no)
		(fp_line
			(start 0.508 -0.9398)
			(end -0.508 -0.9398)
			(stroke
				(width 0.1524)
				(type default)
			)
			(layer "F.SilkS")
		)
		(fp_line
			(start -0.508 -0.9398)
			(end -0.508 0.9398)
			(stroke
				(width 0.1524)
				(type default)
			)
			(layer "F.SilkS")
		)
		(fp_rect
			(start -0.508 0.9398)
			(end 0.508 -0.9398)
			(stroke
				(width 0)
				(type default)
			)
			(fill no)
			(layer "F.CrtYd")
		)
		(fp_rect
			(start -0.508 0.9398)
			(end 0.508 -0.9398)
			(stroke
				(width 0)
				(type default)
			)
			(fill no)
			(layer "F.Fab")
		)
		(pad "1" smd custom
			(at 0 -0.4445 180)
			(size 0.1397 0.1397)
			(layers "F.Cu" "F.Mask" "F.Paste")
			(net "GND")
			(options
				(clearance outline)
				(anchor circle)
			)
			(primitives
				(gr_poly
					(pts
						(arc
							(start -0.1778 -0.2794)
							(mid -0.249642 -0.249642)
							(end -0.2794 -0.1778)
						)
						(arc
							(start -0.2794 0.1778)
							(mid -0.249642 0.249642)
							(end -0.1778 0.2794)
						)
						(arc
							(start 0.1778 0.2794)
							(mid 0.249642 0.249642)
							(end 0.2794 0.1778)
						)
						(arc
							(start 0.2794 -0.1778)
							(mid 0.249642 -0.249642)
							(end 0.1778 -0.2794)
						)
					)
					(width 0)
					(fill yes)
				)
			)
		)
		(pad "2" smd custom
			(at 0 0.4445 180)
			(size 0.1397 0.1397)
			(layers "F.Cu" "F.Mask" "F.Paste")
			(net "CLK_50M_RMII_PHY")
			(options
				(clearance outline)
				(anchor circle)
			)
			(primitives
				(gr_poly
					(pts
						(arc
							(start -0.1778 -0.2794)
							(mid -0.249642 -0.249642)
							(end -0.2794 -0.1778)
						)
						(arc
							(start -0.2794 0.1778)
							(mid -0.249642 0.249642)
							(end -0.1778 0.2794)
						)
						(arc
							(start 0.1778 0.2794)
							(mid 0.249642 0.249642)
							(end 0.2794 0.1778)
						)
						(arc
							(start 0.2794 -0.1778)
							(mid 0.249642 -0.249642)
							(end 0.1778 -0.2794)
						)
					)
					(width 0)
					(fill yes)
				)
			)
		)
	)
	(footprint ""
		(layer "F.Cu")
		(at 43.6118 -192.8876)
		(property "Reference" "R868"
			(at 0 0 0)
			(layer "F.SilkS")
			(hide yes)
			(effects
				(font
					(size 1.27 1.27)
				)
			)
		)
		(property "Value" "0R2J-2-GP"
			(at 0.064008 -3.993896 0)
			(unlocked yes)
			(layer "F.Fab")
			(hide yes)
			(effects
				(font
					(size 1.016 1.016)
					(thickness 0.1524)
				)
			)
		)
		(property "Device Type" "R402H16"
			(at 0.064008 -5.517896 0)
			(unlocked yes)
			(layer "F.Fab")
			(hide yes)
			(effects
				(font
					(size 1.016 1.016)
					(thickness 0.1524)
				)
			)
		)
		(duplicate_pad_numbers_are_jumpers no)
		(fp_line
			(start -0.508 -0.9398)
			(end -0.508 0.9398)
			(stroke
				(width 0.1524)
				(type default)
			)
			(layer "F.SilkS")
		)
		(fp_line
			(start 0.508 -0.9398)
			(end -0.508 -0.9398)
			(stroke
				(width 0.1524)
				(type default)
			)
			(layer "F.SilkS")
		)
		(fp_rect
			(start -0.508 0.9398)
			(end 0.508 -0.9398)
			(stroke
				(width 0)
				(type default)
			)
			(fill no)
			(layer "F.CrtYd")
		)
		(fp_rect
			(start -0.508 0.9398)
			(end 0.508 -0.9398)
			(stroke
				(width 0)
				(type default)
			)
			(fill no)
			(layer "F.Fab")
		)
		(pad "1" smd custom
			(at 0 -0.4445)
			(size 0.1397 0.1397)
			(layers "F.Cu" "F.Mask" "F.Paste")
			(net "BUF_I2C9_CLKBUF2_SCL")
			(options
				(clearance outline)
				(anchor circle)
			)
			(primitives
				(gr_poly
					(pts
						(arc
							(start -0.1778 -0.2794)
							(mid -0.249642 -0.249642)
							(end -0.2794 -0.1778)
						)
						(arc
							(start -0.2794 0.1778)
							(mid -0.249642 0.249642)
							(end -0.1778 0.2794)
						)
						(arc
							(start 0.1778 0.2794)
							(mid 0.249642 0.249642)
							(end 0.2794 0.1778)
						)
						(arc
							(start 0.2794 -0.1778)
							(mid 0.249642 -0.249642)
							(end 0.1778 -0.2794)
						)
					)
					(width 0)
					(fill yes)
				)
			)
		)
		(pad "2" smd custom
			(at 0 0.4445)
			(size 0.1397 0.1397)
			(layers "F.Cu" "F.Mask" "F.Paste")
			(net "BUF_I2C9_CLKBUF2_SCL_R")
			(options
				(clearance outline)
				(anchor circle)
			)
			(primitives
				(gr_poly
					(pts
						(arc
							(start -0.1778 -0.2794)
							(mid -0.249642 -0.249642)
							(end -0.2794 -0.1778)
						)
						(arc
							(start -0.2794 0.1778)
							(mid -0.249642 0.249642)
							(end -0.1778 0.2794)
						)
						(arc
							(start 0.1778 0.2794)
							(mid 0.249642 0.249642)
							(end 0.2794 0.1778)
						)
						(arc
							(start 0.2794 -0.1778)
							(mid 0.249642 -0.249642)
							(end 0.1778 -0.2794)
						)
					)
					(width 0)
					(fill yes)
				)
			)
		)
	)
	(footprint ""
		(layer "F.Cu")
		(at 265.028172 -8.627364)
		(property "Reference" "C375"
			(at 0 0 0)
			(layer "F.SilkS")
			(hide yes)
			(effects
				(font
					(size 1.27 1.27)
				)
			)
		)
		(property "Value" "SCD1U25V2KX-2-GP"
			(at 1.1811 -2.7051 0)
			(unlocked yes)
			(layer "F.Fab")
			(hide yes)
			(effects
				(font
					(size 1.016 1.016)
					(thickness 0.1524)
				)
			)
		)
		(property "Device Type" "C402H22"
			(at 1.1811 -4.2291 0)
			(unlocked yes)
			(layer "F.Fab")
			(hide yes)
			(effects
				(font
					(size 1.016 1.016)
					(thickness 0.1524)
				)
			)
		)
		(duplicate_pad_numbers_are_jumpers no)
		(fp_rect
			(start -0.4318 0.9525)
			(end 0.4318 -0.9525)
			(stroke
				(width 0)
				(type default)
			)
			(fill no)
			(layer "F.CrtYd")
		)
		(fp_rect
			(start -0.4318 0.9525)
			(end 0.4318 -0.9525)
			(stroke
				(width 0)
				(type default)
			)
			(fill no)
			(layer "F.Fab")
		)
		(pad "1" smd custom
			(at 0 -0.4445)
			(size 0.1524 0.1524)
			(layers "F.Cu" "F.Mask" "F.Paste")
			(net "P3V3_STBY")
			(options
				(clearance outline)
				(anchor circle)
			)
			(primitives
				(gr_poly
					(pts
						(arc
							(start 0.3048 -0.2032)
							(mid 0.275042 -0.275042)
							(end 0.2032 -0.3048)
						)
						(arc
							(start -0.2032 -0.3048)
							(mid -0.275042 -0.275042)
							(end -0.3048 -0.2032)
						)
						(arc
							(start -0.3048 0.2032)
							(mid -0.275042 0.275042)
							(end -0.2032 0.3048)
						)
						(arc
							(start 0.2032 0.3048)
							(mid 0.275042 0.275042)
							(end 0.3048 0.2032)
						)
					)
					(width 0)
					(fill yes)
				)
			)
		)
		(pad "2" smd custom
			(at 0 0.4445)
			(size 0.1524 0.1524)
			(layers "F.Cu" "F.Mask" "F.Paste")
			(net "GND")
			(options
				(clearance outline)
				(anchor circle)
			)
			(primitives
				(gr_poly
					(pts
						(arc
							(start 0.3048 -0.2032)
							(mid 0.275042 -0.275042)
							(end 0.2032 -0.3048)
						)
						(arc
							(start -0.2032 -0.3048)
							(mid -0.275042 -0.275042)
							(end -0.3048 -0.2032)
						)
						(arc
							(start -0.3048 0.2032)
							(mid -0.275042 0.275042)
							(end -0.2032 0.3048)
						)
						(arc
							(start 0.2032 0.3048)
							(mid 0.275042 0.275042)
							(end 0.3048 0.2032)
						)
					)
					(width 0)
					(fill yes)
				)
			)
		)
	)
	(footprint ""
		(layer "F.Cu")
		(at 180.9242 -71.628 180)
		(property "Reference" "C554"
			(at 0 0 180)
			(layer "F.SilkS")
			(hide yes)
			(effects
				(font
					(size 1.27 1.27)
				)
			)
		)
		(property "Value" "SC4D7U16V5KX-1-GP"
			(at -0.0762 -6.1214 180)
			(unlocked yes)
			(layer "F.Fab")
			(hide yes)
			(effects
				(font
					(size 1.016 1.016)
					(thickness 0.1524)
				)
			)
		)
		(property "Device Type" "C805H56"
			(at -0.0762 -8.1534 180)
			(unlocked yes)
			(layer "F.Fab")
			(hide yes)
			(effects
				(font
					(size 1.016 1.016)
					(thickness 0.1524)
				)
			)
		)
		(duplicate_pad_numbers_are_jumpers no)
		(fp_line
			(start 0.635 0)
			(end -0.635 0)
			(stroke
				(width 0.508)
				(type default)
			)
			(layer "F.SilkS")
		)
		(fp_rect
			(start -0.9652 1.778)
			(end 0.9652 -1.778)
			(stroke
				(width 0)
				(type default)
			)
			(fill no)
			(layer "F.CrtYd")
		)
		(fp_poly
			(pts
				(xy -0.9652 -1.778) (xy 0.9652 -1.778) (xy 0.9652 1.778) (xy -0.9652 1.778)
			)
			(stroke
				(width 0)
				(type default)
			)
			(fill no)
			(layer "F.Fab")
		)
		(pad "1" smd rect
			(at 0 -0.9652 180)
			(size 1.397 1.143)
			(layers "F.Cu" "F.Mask" "F.Paste")
			(net "DUT_AVD_PCIE")
		)
		(pad "2" smd rect
			(at 0 0.9652 180)
			(size 1.397 1.143)
			(layers "F.Cu" "F.Mask" "F.Paste")
			(net "GND")
		)
	)
	(footprint ""
		(layer "F.Cu")
		(at 78.843124 -183.235092)
		(property "Reference" "R7973"
			(at 0 0 0)
			(layer "F.SilkS")
			(hide yes)
			(effects
				(font
					(size 1.27 1.27)
				)
			)
		)
		(property "Value" "0R2J-2-GP"
			(at 0.064008 -3.993896 0)
			(unlocked yes)
			(layer "F.Fab")
			(hide yes)
			(effects
				(font
					(size 1.016 1.016)
					(thickness 0.1524)
				)
			)
		)
		(property "Device Type" "R402H16"
			(at 0.064008 -5.517896 0)
			(unlocked yes)
			(layer "F.Fab")
			(hide yes)
			(effects
				(font
					(size 1.016 1.016)
					(thickness 0.1524)
				)
			)
		)
		(duplicate_pad_numbers_are_jumpers no)
		(fp_line
			(start -0.508 -0.9398)
			(end -0.508 0.9398)
			(stroke
				(width 0.1524)
				(type default)
			)
			(layer "F.SilkS")
		)
		(fp_line
			(start 0.508 -0.9398)
			(end -0.508 -0.9398)
			(stroke
				(width 0.1524)
				(type default)
			)
			(layer "F.SilkS")
		)
		(fp_rect
			(start -0.508 0.9398)
			(end 0.508 -0.9398)
			(stroke
				(width 0)
				(type default)
			)
			(fill no)
			(layer "F.CrtYd")
		)
		(fp_rect
			(start -0.508 0.9398)
			(end 0.508 -0.9398)
			(stroke
				(width 0)
				(type default)
			)
			(fill no)
			(layer "F.Fab")
		)
		(pad "1" smd custom
			(at 0 -0.4445)
			(size 0.1397 0.1397)
			(layers "F.Cu" "F.Mask" "F.Paste")
			(net "SSD_PERST#5")
			(options
				(clearance outline)
				(anchor circle)
			)
			(primitives
				(gr_poly
					(pts
						(arc
							(start -0.1778 -0.2794)
							(mid -0.249642 -0.249642)
							(end -0.2794 -0.1778)
						)
						(arc
							(start -0.2794 0.1778)
							(mid -0.249642 0.249642)
							(end -0.1778 0.2794)
						)
						(arc
							(start 0.1778 0.2794)
							(mid 0.249642 0.249642)
							(end 0.2794 0.1778)
						)
						(arc
							(start 0.2794 -0.1778)
							(mid 0.249642 -0.249642)
							(end 0.1778 -0.2794)
						)
					)
					(width 0)
					(fill yes)
				)
			)
		)
		(pad "2" smd custom
			(at 0 0.4445)
			(size 0.1397 0.1397)
			(layers "F.Cu" "F.Mask" "F.Paste")
			(net "SSD_PERST#5_R")
			(options
				(clearance outline)
				(anchor circle)
			)
			(primitives
				(gr_poly
					(pts
						(arc
							(start -0.1778 -0.2794)
							(mid -0.249642 -0.249642)
							(end -0.2794 -0.1778)
						)
						(arc
							(start -0.2794 0.1778)
							(mid -0.249642 0.249642)
							(end -0.1778 0.2794)
						)
						(arc
							(start 0.1778 0.2794)
							(mid 0.249642 0.249642)
							(end 0.2794 0.1778)
						)
						(arc
							(start 0.2794 -0.1778)
							(mid 0.249642 -0.249642)
							(end 0.1778 -0.2794)
						)
					)
					(width 0)
					(fill yes)
				)
			)
		)
	)
	(footprint ""
		(layer "F.Cu")
		(at 192.9384 -25.0952 90)
		(property "Reference" "R836"
			(at 0 0 90)
			(layer "F.SilkS")
			(hide yes)
			(effects
				(font
					(size 1.27 1.27)
				)
			)
		)
		(property "Value" "4K7R2F-GP"
			(at 0.064008 -3.993896 90)
			(unlocked yes)
			(layer "F.Fab")
			(hide yes)
			(effects
				(font
					(size 1.016 1.016)
					(thickness 0.1524)
				)
			)
		)
		(property "Device Type" "R402H16"
			(at 0.064008 -5.517896 90)
			(unlocked yes)
			(layer "F.Fab")
			(hide yes)
			(effects
				(font
					(size 1.016 1.016)
					(thickness 0.1524)
				)
			)
		)
		(duplicate_pad_numbers_are_jumpers no)
		(fp_line
			(start 0.508 -0.9398)
			(end -0.508 -0.9398)
			(stroke
				(width 0.1524)
				(type default)
			)
			(layer "F.SilkS")
		)
		(fp_line
			(start -0.508 -0.9398)
			(end -0.508 0.9398)
			(stroke
				(width 0.1524)
				(type default)
			)
			(layer "F.SilkS")
		)
		(fp_rect
			(start -0.508 0.9398)
			(end 0.508 -0.9398)
			(stroke
				(width 0)
				(type default)
			)
			(fill no)
			(layer "F.CrtYd")
		)
		(fp_rect
			(start -0.508 0.9398)
			(end 0.508 -0.9398)
			(stroke
				(width 0)
				(type default)
			)
			(fill no)
			(layer "F.Fab")
		)
		(pad "1" smd custom
			(at 0 -0.4445 90)
			(size 0.1397 0.1397)
			(layers "F.Cu" "F.Mask" "F.Paste")
			(net "GND")
			(options
				(clearance outline)
				(anchor circle)
			)
			(primitives
				(gr_poly
					(pts
						(arc
							(start -0.1778 -0.2794)
							(mid -0.249642 -0.249642)
							(end -0.2794 -0.1778)
						)
						(arc
							(start -0.2794 0.1778)
							(mid -0.249642 0.249642)
							(end -0.1778 0.2794)
						)
						(arc
							(start 0.1778 0.2794)
							(mid 0.249642 0.249642)
							(end 0.2794 0.1778)
						)
						(arc
							(start 0.2794 -0.1778)
							(mid 0.249642 -0.249642)
							(end 0.1778 -0.2794)
						)
					)
					(width 0)
					(fill yes)
				)
			)
		)
		(pad "2" smd custom
			(at 0 0.4445 90)
			(size 0.1397 0.1397)
			(layers "F.Cu" "F.Mask" "F.Paste")
			(net "U56_A1")
			(options
				(clearance outline)
				(anchor circle)
			)
			(primitives
				(gr_poly
					(pts
						(arc
							(start -0.1778 -0.2794)
							(mid -0.249642 -0.249642)
							(end -0.2794 -0.1778)
						)
						(arc
							(start -0.2794 0.1778)
							(mid -0.249642 0.249642)
							(end -0.1778 0.2794)
						)
						(arc
							(start 0.1778 0.2794)
							(mid 0.249642 0.249642)
							(end 0.2794 0.1778)
						)
						(arc
							(start 0.2794 -0.1778)
							(mid 0.249642 -0.249642)
							(end 0.1778 -0.2794)
						)
					)
					(width 0)
					(fill yes)
				)
			)
		)
	)
	(footprint ""
		(layer "F.Cu")
		(at 346.456 -51.689 90)
		(property "Reference" "PC217"
			(at 0 0 90)
			(layer "F.SilkS")
			(hide yes)
			(effects
				(font
					(size 1.27 1.27)
				)
			)
		)
		(property "Value" "SC22U25V6KX-GP-U"
			(at -2.860802 -5.279644 90)
			(unlocked yes)
			(layer "F.Fab")
			(hide yes)
			(effects
				(font
					(size 1.016 1.016)
					(thickness 0.1524)
				)
			)
		)
		(property "Device Type" "C1206-TO0D3H75"
			(at -2.860802 -6.803644 90)
			(unlocked yes)
			(layer "F.Fab")
			(hide yes)
			(effects
				(font
					(size 1.016 1.016)
					(thickness 0.1524)
				)
			)
		)
		(duplicate_pad_numbers_are_jumpers no)
		(fp_line
			(start 1.3081 -2.3749)
			(end 1.3081 2.3749)
			(stroke
				(width 0.1524)
				(type default)
			)
			(layer "F.SilkS")
		)
		(fp_line
			(start -1.3081 -2.3749)
			(end 1.3081 -2.3749)
			(stroke
				(width 0.1524)
				(type default)
			)
			(layer "F.SilkS")
		)
		(fp_line
			(start 1.3081 2.3749)
			(end -1.3081 2.3749)
			(stroke
				(width 0.1524)
				(type default)
			)
			(layer "F.SilkS")
		)
		(fp_line
			(start -1.3081 2.3749)
			(end -1.3081 -2.3749)
			(stroke
				(width 0.1524)
				(type default)
			)
			(layer "F.SilkS")
		)
		(fp_rect
			(start -0.8001 1.6002)
			(end 0.8001 -1.6002)
			(stroke
				(width 0)
				(type default)
			)
			(fill no)
			(layer "F.CrtYd")
		)
		(fp_poly
			(pts
				(xy -1.5621 2.4511) (xy -1.5621 1.6002) (xy 0.8001 1.6002) (xy 0.8001 -1.6002) (xy -0.8001 -1.6002)
				(xy -0.8001 1.5875) (xy -1.5621 1.5875) (xy -1.5621 -2.4511) (xy 1.5621 -2.4511) (xy 1.5621 2.4511)
			)
			(stroke
				(width 0)
				(type default)
			)
			(fill no)
			(layer "F.CrtYd")
		)
		(fp_rect
			(start -1.5621 2.4511)
			(end 1.5621 -2.4511)
			(stroke
				(width 0)
				(type default)
			)
			(fill no)
			(layer "F.Fab")
		)
		(pad "1" smd rect
			(at 0 -1.392936 90)
			(size 2.1082 1.4478)
			(layers "F.Cu" "F.Mask" "F.Paste")
			(net "P0V9_E_VIN")
		)
		(pad "2" smd rect
			(at 0 1.392936 90)
			(size 2.1082 1.4478)
			(layers "F.Cu" "F.Mask" "F.Paste")
			(net "GND")
		)
	)
	(footprint ""
		(layer "F.Cu")
		(at 208.4578 -16.2306 90)
		(property "Reference" "Q6"
			(at 0 0 90)
			(layer "F.SilkS")
			(hide yes)
			(effects
				(font
					(size 1.27 1.27)
				)
			)
		)
		(property "Value" "2N7002K-1-GP"
			(at 0.127 -8.9662 90)
			(unlocked yes)
			(layer "F.Fab")
			(hide yes)
			(effects
				(font
					(size 1.016 1.016)
					(thickness 0.1524)
				)
			)
		)
		(property "Device Type" "SOT23DGS2D4H44"
			(at 0.127 -10.4902 90)
			(unlocked yes)
			(layer "F.Fab")
			(hide yes)
			(effects
				(font
					(size 1.016 1.016)
					(thickness 0.1524)
				)
			)
		)
		(duplicate_pad_numbers_are_jumpers no)
		(fp_line
			(start 1.651 -1.778)
			(end -1.651 -1.778)
			(stroke
				(width 0.1524)
				(type default)
			)
			(layer "F.SilkS")
		)
		(fp_line
			(start -1.651 -1.778)
			(end -1.651 1.778)
			(stroke
				(width 0.1524)
				(type default)
			)
			(layer "F.SilkS")
		)
		(fp_line
			(start 1.651 1.778)
			(end 1.651 -1.778)
			(stroke
				(width 0.1524)
				(type default)
			)
			(layer "F.SilkS")
		)
		(fp_line
			(start -1.651 1.778)
			(end 1.651 1.778)
			(stroke
				(width 0.1524)
				(type default)
			)
			(layer "F.SilkS")
		)
		(fp_poly
			(pts
				(xy -1.778 1.8796) (xy -1.778 -1.8796) (xy 1.778 -1.8796) (xy 1.778 1.8796)
			)
			(stroke
				(width 0)
				(type default)
			)
			(fill no)
			(layer "F.CrtYd")
		)
		(fp_poly
			(pts
				(xy -1.778 1.8796) (xy -1.778 -1.8796) (xy 1.778 -1.8796) (xy 1.778 1.8796)
			)
			(stroke
				(width 0)
				(type default)
			)
			(fill no)
			(layer "F.Fab")
		)
		(pad "D" smd custom
			(at 0 -0.9525 90)
			(size 0.1905 0.1905)
			(layers "F.Cu" "F.Mask" "F.Paste")
			(net "LED_PWR_N_ON")
			(options
				(clearance outline)
				(anchor circle)
			)
			(primitives
				(gr_poly
					(pts
						(arc
							(start -0.1778 0.5715)
							(mid -0.321484 0.511984)
							(end -0.381 0.3683)
						)
						(arc
							(start -0.381 -0.3683)
							(mid -0.321484 -0.511984)
							(end -0.1778 -0.5715)
						)
						(arc
							(start 0.1778 -0.5715)
							(mid 0.321484 -0.511984)
							(end 0.381 -0.3683)
						)
						(arc
							(start 0.381 0.3683)
							(mid 0.321484 0.511984)
							(end 0.1778 0.5715)
						)
					)
					(width 0)
					(fill yes)
				)
			)
		)
		(pad "G" smd custom
			(at -0.98425 0.9525 90)
			(size 0.1905 0.1905)
			(layers "F.Cu" "F.Mask" "F.Paste")
			(net "BMC_ID_LED_R")
			(options
				(clearance outline)
				(anchor circle)
			)
			(primitives
				(gr_poly
					(pts
						(arc
							(start -0.1778 0.5715)
							(mid -0.321484 0.511984)
							(end -0.381 0.3683)
						)
						(arc
							(start -0.381 -0.3683)
							(mid -0.321484 -0.511984)
							(end -0.1778 -0.5715)
						)
						(arc
							(start 0.1778 -0.5715)
							(mid 0.321484 -0.511984)
							(end 0.381 -0.3683)
						)
						(arc
							(start 0.381 0.3683)
							(mid 0.321484 0.511984)
							(end 0.1778 0.5715)
						)
					)
					(width 0)
					(fill yes)
				)
			)
		)
		(pad "S" smd custom
			(at 0.98425 0.9525 90)
			(size 0.1905 0.1905)
			(layers "F.Cu" "F.Mask" "F.Paste")
			(net "GND")
			(options
				(clearance outline)
				(anchor circle)
			)
			(primitives
				(gr_poly
					(pts
						(arc
							(start -0.1778 0.5715)
							(mid -0.321484 0.511984)
							(end -0.381 0.3683)
						)
						(arc
							(start -0.381 -0.3683)
							(mid -0.321484 -0.511984)
							(end -0.1778 -0.5715)
						)
						(arc
							(start 0.1778 -0.5715)
							(mid 0.321484 -0.511984)
							(end 0.381 -0.3683)
						)
						(arc
							(start 0.381 0.3683)
							(mid 0.321484 0.511984)
							(end 0.1778 0.5715)
						)
					)
					(width 0)
					(fill yes)
				)
			)
		)
	)
	(footprint ""
		(layer "F.Cu")
		(at 220.345 -5.588 180)
		(property "Reference" "R454"
			(at 0 0 180)
			(layer "F.SilkS")
			(hide yes)
			(effects
				(font
					(size 1.27 1.27)
				)
			)
		)
		(property "Value" "0R2J-2-GP"
			(at 0.064008 -3.993896 180)
			(unlocked yes)
			(layer "F.Fab")
			(hide yes)
			(effects
				(font
					(size 1.016 1.016)
					(thickness 0.1524)
				)
			)
		)
		(property "Device Type" "R402H16"
			(at 0.064008 -5.517896 180)
			(unlocked yes)
			(layer "F.Fab")
			(hide yes)
			(effects
				(font
					(size 1.016 1.016)
					(thickness 0.1524)
				)
			)
		)
		(duplicate_pad_numbers_are_jumpers no)
		(fp_line
			(start 0.508 -0.9398)
			(end -0.508 -0.9398)
			(stroke
				(width 0.1524)
				(type default)
			)
			(layer "F.SilkS")
		)
		(fp_line
			(start -0.508 -0.9398)
			(end -0.508 0.9398)
			(stroke
				(width 0.1524)
				(type default)
			)
			(layer "F.SilkS")
		)
		(fp_rect
			(start -0.508 0.9398)
			(end 0.508 -0.9398)
			(stroke
				(width 0)
				(type default)
			)
			(fill no)
			(layer "F.CrtYd")
		)
		(fp_rect
			(start -0.508 0.9398)
			(end 0.508 -0.9398)
			(stroke
				(width 0)
				(type default)
			)
			(fill no)
			(layer "F.Fab")
		)
		(pad "1" smd custom
			(at 0 -0.4445 180)
			(size 0.1397 0.1397)
			(layers "F.Cu" "F.Mask" "F.Paste")
			(net "BMC_UART_SWITCH_1")
			(options
				(clearance outline)
				(anchor circle)
			)
			(primitives
				(gr_poly
					(pts
						(arc
							(start -0.1778 -0.2794)
							(mid -0.249642 -0.249642)
							(end -0.2794 -0.1778)
						)
						(arc
							(start -0.2794 0.1778)
							(mid -0.249642 0.249642)
							(end -0.1778 0.2794)
						)
						(arc
							(start 0.1778 0.2794)
							(mid 0.249642 0.249642)
							(end 0.2794 0.1778)
						)
						(arc
							(start 0.2794 -0.1778)
							(mid 0.249642 -0.249642)
							(end 0.1778 -0.2794)
						)
					)
					(width 0)
					(fill yes)
				)
			)
		)
		(pad "2" smd custom
			(at 0 0.4445 180)
			(size 0.1397 0.1397)
			(layers "F.Cu" "F.Mask" "F.Paste")
			(net "BMC_CONSOLE_LED0_R")
			(options
				(clearance outline)
				(anchor circle)
			)
			(primitives
				(gr_poly
					(pts
						(arc
							(start -0.1778 -0.2794)
							(mid -0.249642 -0.249642)
							(end -0.2794 -0.1778)
						)
						(arc
							(start -0.2794 0.1778)
							(mid -0.249642 0.249642)
							(end -0.1778 0.2794)
						)
						(arc
							(start 0.1778 0.2794)
							(mid 0.249642 0.249642)
							(end 0.2794 0.1778)
						)
						(arc
							(start 0.2794 -0.1778)
							(mid 0.249642 -0.249642)
							(end 0.1778 -0.2794)
						)
					)
					(width 0)
					(fill yes)
				)
			)
		)
	)
	(footprint ""
		(layer "F.Cu")
		(at 85.70214 -74.71664 180)
		(property "Reference" "R423"
			(at 0 0 180)
			(layer "F.SilkS")
			(hide yes)
			(effects
				(font
					(size 1.27 1.27)
				)
			)
		)
		(property "Value" "2K2R2J-2-GP"
			(at 0.064008 -3.993896 180)
			(unlocked yes)
			(layer "F.Fab")
			(hide yes)
			(effects
				(font
					(size 1.016 1.016)
					(thickness 0.1524)
				)
			)
		)
		(property "Device Type" "R402H16"
			(at 0.064008 -5.517896 180)
			(unlocked yes)
			(layer "F.Fab")
			(hide yes)
			(effects
				(font
					(size 1.016 1.016)
					(thickness 0.1524)
				)
			)
		)
		(duplicate_pad_numbers_are_jumpers no)
		(fp_line
			(start 0.508 -0.9398)
			(end -0.508 -0.9398)
			(stroke
				(width 0.1524)
				(type default)
			)
			(layer "F.SilkS")
		)
		(fp_line
			(start -0.508 -0.9398)
			(end -0.508 0.9398)
			(stroke
				(width 0.1524)
				(type default)
			)
			(layer "F.SilkS")
		)
		(fp_rect
			(start -0.508 0.9398)
			(end 0.508 -0.9398)
			(stroke
				(width 0)
				(type default)
			)
			(fill no)
			(layer "F.CrtYd")
		)
		(fp_rect
			(start -0.508 0.9398)
			(end 0.508 -0.9398)
			(stroke
				(width 0)
				(type default)
			)
			(fill no)
			(layer "F.Fab")
		)
		(pad "1" smd custom
			(at 0 -0.4445 180)
			(size 0.1397 0.1397)
			(layers "F.Cu" "F.Mask" "F.Paste")
			(net "SEC_SPI_HOLD_N")
			(options
				(clearance outline)
				(anchor circle)
			)
			(primitives
				(gr_poly
					(pts
						(arc
							(start -0.1778 -0.2794)
							(mid -0.249642 -0.249642)
							(end -0.2794 -0.1778)
						)
						(arc
							(start -0.2794 0.1778)
							(mid -0.249642 0.249642)
							(end -0.1778 0.2794)
						)
						(arc
							(start 0.1778 0.2794)
							(mid 0.249642 0.249642)
							(end 0.2794 0.1778)
						)
						(arc
							(start 0.2794 -0.1778)
							(mid 0.249642 -0.249642)
							(end 0.1778 -0.2794)
						)
					)
					(width 0)
					(fill yes)
				)
			)
		)
		(pad "2" smd custom
			(at 0 0.4445 180)
			(size 0.1397 0.1397)
			(layers "F.Cu" "F.Mask" "F.Paste")
			(net "P3V3_STBY")
			(options
				(clearance outline)
				(anchor circle)
			)
			(primitives
				(gr_poly
					(pts
						(arc
							(start -0.1778 -0.2794)
							(mid -0.249642 -0.249642)
							(end -0.2794 -0.1778)
						)
						(arc
							(start -0.2794 0.1778)
							(mid -0.249642 0.249642)
							(end -0.1778 0.2794)
						)
						(arc
							(start 0.1778 0.2794)
							(mid 0.249642 0.249642)
							(end 0.2794 0.1778)
						)
						(arc
							(start 0.2794 -0.1778)
							(mid 0.249642 -0.249642)
							(end 0.1778 -0.2794)
						)
					)
					(width 0)
					(fill yes)
				)
			)
		)
	)
	(footprint ""
		(layer "F.Cu")
		(at 192.9384 -26.1366 -90)
		(property "Reference" "R824"
			(at 0 0 270)
			(layer "F.SilkS")
			(hide yes)
			(effects
				(font
					(size 1.27 1.27)
				)
			)
		)
		(property "Value" "4K7R2F-GP"
			(at 0.064008 -3.993896 270)
			(unlocked yes)
			(layer "F.Fab")
			(hide yes)
			(effects
				(font
					(size 1.016 1.016)
					(thickness 0.1524)
				)
			)
		)
		(property "Device Type" "R402H16"
			(at 0.064008 -5.517896 270)
			(unlocked yes)
			(layer "F.Fab")
			(hide yes)
			(effects
				(font
					(size 1.016 1.016)
					(thickness 0.1524)
				)
			)
		)
		(duplicate_pad_numbers_are_jumpers no)
		(fp_line
			(start -0.508 -0.9398)
			(end -0.508 0.9398)
			(stroke
				(width 0.1524)
				(type default)
			)
			(layer "F.SilkS")
		)
		(fp_line
			(start 0.508 -0.9398)
			(end -0.508 -0.9398)
			(stroke
				(width 0.1524)
				(type default)
			)
			(layer "F.SilkS")
		)
		(fp_rect
			(start -0.508 0.9398)
			(end 0.508 -0.9398)
			(stroke
				(width 0)
				(type default)
			)
			(fill no)
			(layer "F.CrtYd")
		)
		(fp_rect
			(start -0.508 0.9398)
			(end 0.508 -0.9398)
			(stroke
				(width 0)
				(type default)
			)
			(fill no)
			(layer "F.Fab")
		)
		(pad "1" smd custom
			(at 0 -0.4445 270)
			(size 0.1397 0.1397)
			(layers "F.Cu" "F.Mask" "F.Paste")
			(net "U56_A1")
			(options
				(clearance outline)
				(anchor circle)
			)
			(primitives
				(gr_poly
					(pts
						(arc
							(start -0.1778 -0.2794)
							(mid -0.249642 -0.249642)
							(end -0.2794 -0.1778)
						)
						(arc
							(start -0.2794 0.1778)
							(mid -0.249642 0.249642)
							(end -0.1778 0.2794)
						)
						(arc
							(start 0.1778 0.2794)
							(mid 0.249642 0.249642)
							(end 0.2794 0.1778)
						)
						(arc
							(start 0.2794 -0.1778)
							(mid 0.249642 -0.249642)
							(end 0.1778 -0.2794)
						)
					)
					(width 0)
					(fill yes)
				)
			)
		)
		(pad "2" smd custom
			(at 0 0.4445 270)
			(size 0.1397 0.1397)
			(layers "F.Cu" "F.Mask" "F.Paste")
			(net "P3V3_STBY")
			(options
				(clearance outline)
				(anchor circle)
			)
			(primitives
				(gr_poly
					(pts
						(arc
							(start -0.1778 -0.2794)
							(mid -0.249642 -0.249642)
							(end -0.2794 -0.1778)
						)
						(arc
							(start -0.2794 0.1778)
							(mid -0.249642 0.249642)
							(end -0.1778 0.2794)
						)
						(arc
							(start 0.1778 0.2794)
							(mid 0.249642 0.249642)
							(end 0.2794 0.1778)
						)
						(arc
							(start 0.2794 -0.1778)
							(mid 0.249642 -0.249642)
							(end 0.1778 -0.2794)
						)
					)
					(width 0)
					(fill yes)
				)
			)
		)
	)
	(footprint ""
		(layer "F.Cu")
		(at 26.887932 -108.459016 -90)
		(property "Reference" "C287"
			(at 0 0 270)
			(layer "F.SilkS")
			(hide yes)
			(effects
				(font
					(size 1.27 1.27)
				)
			)
		)
		(property "Value" "SCD01U16V2KX-3GP"
			(at 1.1811 -2.7051 270)
			(unlocked yes)
			(layer "F.Fab")
			(hide yes)
			(effects
				(font
					(size 1.016 1.016)
					(thickness 0.1524)
				)
			)
		)
		(property "Device Type" "C402H22"
			(at 1.1811 -4.2291 270)
			(unlocked yes)
			(layer "F.Fab")
			(hide yes)
			(effects
				(font
					(size 1.016 1.016)
					(thickness 0.1524)
				)
			)
		)
		(duplicate_pad_numbers_are_jumpers no)
		(fp_rect
			(start -0.4318 0.9525)
			(end 0.4318 -0.9525)
			(stroke
				(width 0)
				(type default)
			)
			(fill no)
			(layer "F.CrtYd")
		)
		(fp_rect
			(start -0.4318 0.9525)
			(end 0.4318 -0.9525)
			(stroke
				(width 0)
				(type default)
			)
			(fill no)
			(layer "F.Fab")
		)
		(pad "1" smd custom
			(at 0 -0.4445 270)
			(size 0.1524 0.1524)
			(layers "F.Cu" "F.Mask" "F.Paste")
			(net "PCIE_REFCLK_S5_N")
			(options
				(clearance outline)
				(anchor circle)
			)
			(primitives
				(gr_poly
					(pts
						(arc
							(start 0.3048 -0.2032)
							(mid 0.275042 -0.275042)
							(end 0.2032 -0.3048)
						)
						(arc
							(start -0.2032 -0.3048)
							(mid -0.275042 -0.275042)
							(end -0.3048 -0.2032)
						)
						(arc
							(start -0.3048 0.2032)
							(mid -0.275042 0.275042)
							(end -0.2032 0.3048)
						)
						(arc
							(start 0.2032 0.3048)
							(mid 0.275042 0.275042)
							(end 0.3048 0.2032)
						)
					)
					(width 0)
					(fill yes)
				)
			)
		)
		(pad "2" smd custom
			(at 0 0.4445 270)
			(size 0.1524 0.1524)
			(layers "F.Cu" "F.Mask" "F.Paste")
			(net "BMC_REFCLK_N")
			(options
				(clearance outline)
				(anchor circle)
			)
			(primitives
				(gr_poly
					(pts
						(arc
							(start 0.3048 -0.2032)
							(mid 0.275042 -0.275042)
							(end 0.2032 -0.3048)
						)
						(arc
							(start -0.2032 -0.3048)
							(mid -0.275042 -0.275042)
							(end -0.3048 -0.2032)
						)
						(arc
							(start -0.3048 0.2032)
							(mid -0.275042 0.275042)
							(end -0.2032 0.3048)
						)
						(arc
							(start 0.2032 0.3048)
							(mid 0.275042 0.275042)
							(end 0.3048 0.2032)
						)
					)
					(width 0)
					(fill yes)
				)
			)
		)
	)
	(footprint ""
		(layer "F.Cu")
		(at 145.808192 -212.420454 180)
		(property "Reference" "C314"
			(at 0 0 180)
			(layer "F.SilkS")
			(hide yes)
			(effects
				(font
					(size 1.27 1.27)
				)
			)
		)
		(property "Value" "SCD22U10V2KX-1GP"
			(at 1.1811 -2.7051 180)
			(unlocked yes)
			(layer "F.Fab")
			(hide yes)
			(effects
				(font
					(size 1.016 1.016)
					(thickness 0.1524)
				)
			)
		)
		(property "Device Type" "C402H22"
			(at 1.1811 -4.2291 180)
			(unlocked yes)
			(layer "F.Fab")
			(hide yes)
			(effects
				(font
					(size 1.016 1.016)
					(thickness 0.1524)
				)
			)
		)
		(duplicate_pad_numbers_are_jumpers no)
		(fp_rect
			(start -0.4318 0.9525)
			(end 0.4318 -0.9525)
			(stroke
				(width 0)
				(type default)
			)
			(fill no)
			(layer "F.CrtYd")
		)
		(fp_rect
			(start -0.4318 0.9525)
			(end 0.4318 -0.9525)
			(stroke
				(width 0)
				(type default)
			)
			(fill no)
			(layer "F.Fab")
		)
		(pad "1" smd custom
			(at 0 -0.4445 180)
			(size 0.1524 0.1524)
			(layers "F.Cu" "F.Mask" "F.Paste")
			(net "PCIE_TX_CAP_N57")
			(options
				(clearance outline)
				(anchor circle)
			)
			(primitives
				(gr_poly
					(pts
						(arc
							(start 0.3048 -0.2032)
							(mid 0.275042 -0.275042)
							(end 0.2032 -0.3048)
						)
						(arc
							(start -0.2032 -0.3048)
							(mid -0.275042 -0.275042)
							(end -0.3048 -0.2032)
						)
						(arc
							(start -0.3048 0.2032)
							(mid -0.275042 0.275042)
							(end -0.2032 0.3048)
						)
						(arc
							(start 0.2032 0.3048)
							(mid 0.275042 0.275042)
							(end 0.3048 0.2032)
						)
					)
					(width 0)
					(fill yes)
				)
			)
		)
		(pad "2" smd custom
			(at 0 0.4445 180)
			(size 0.1524 0.1524)
			(layers "F.Cu" "F.Mask" "F.Paste")
			(net "PCIE_TX_N57")
			(options
				(clearance outline)
				(anchor circle)
			)
			(primitives
				(gr_poly
					(pts
						(arc
							(start 0.3048 -0.2032)
							(mid 0.275042 -0.275042)
							(end 0.2032 -0.3048)
						)
						(arc
							(start -0.2032 -0.3048)
							(mid -0.275042 -0.275042)
							(end -0.3048 -0.2032)
						)
						(arc
							(start -0.3048 0.2032)
							(mid -0.275042 0.275042)
							(end -0.2032 0.3048)
						)
						(arc
							(start 0.2032 0.3048)
							(mid 0.275042 0.275042)
							(end 0.3048 0.2032)
						)
					)
					(width 0)
					(fill yes)
				)
			)
		)
	)
	(footprint ""
		(layer "F.Cu")
		(at 122.8598 -98.7552 90)
		(property "Reference" "C245"
			(at 0 0 90)
			(layer "F.SilkS")
			(hide yes)
			(effects
				(font
					(size 1.27 1.27)
				)
			)
		)
		(property "Value" "SC220P50V3JN-GP"
			(at 0 -2.8194 90)
			(unlocked yes)
			(layer "F.Fab")
			(hide yes)
			(effects
				(font
					(size 1.016 1.016)
					(thickness 0.1524)
				)
			)
		)
		(property "Device Type" "C603H36"
			(at 0 -4.3434 90)
			(unlocked yes)
			(layer "F.Fab")
			(hide yes)
			(effects
				(font
					(size 1.016 1.016)
					(thickness 0.1524)
				)
			)
		)
		(duplicate_pad_numbers_are_jumpers no)
		(fp_line
			(start 0.508 0)
			(end -0.508 0)
			(stroke
				(width 0.2032)
				(type default)
			)
			(layer "F.SilkS")
		)
		(fp_rect
			(start -0.5842 1.3335)
			(end 0.5842 -1.3335)
			(stroke
				(width 0)
				(type default)
			)
			(fill no)
			(layer "F.CrtYd")
		)
		(fp_rect
			(start -0.5842 1.3335)
			(end 0.5842 -1.3335)
			(stroke
				(width 0)
				(type default)
			)
			(fill no)
			(layer "F.Fab")
		)
		(pad "1" smd custom
			(at 0 -0.762 90)
			(size 0.2159 0.2159)
			(layers "F.Cu" "F.Mask" "F.Paste")
			(net "BUF_I2C_SCL_2_R")
			(options
				(clearance outline)
				(anchor circle)
			)
			(primitives
				(gr_poly
					(pts
						(arc
							(start -0.3302 -0.4318)
							(mid -0.402042 -0.402042)
							(end -0.4318 -0.3302)
						)
						(arc
							(start -0.4318 0.3302)
							(mid -0.402042 0.402042)
							(end -0.3302 0.4318)
						)
						(arc
							(start 0.3302 0.4318)
							(mid 0.402042 0.402042)
							(end 0.4318 0.3302)
						)
						(arc
							(start 0.4318 -0.3302)
							(mid 0.402042 -0.402042)
							(end 0.3302 -0.4318)
						)
					)
					(width 0)
					(fill yes)
				)
			)
		)
		(pad "2" smd custom
			(at 0 0.762 90)
			(size 0.2159 0.2159)
			(layers "F.Cu" "F.Mask" "F.Paste")
			(net "GND")
			(options
				(clearance outline)
				(anchor circle)
			)
			(primitives
				(gr_poly
					(pts
						(arc
							(start -0.3302 -0.4318)
							(mid -0.402042 -0.402042)
							(end -0.4318 -0.3302)
						)
						(arc
							(start -0.4318 0.3302)
							(mid -0.402042 0.402042)
							(end -0.3302 0.4318)
						)
						(arc
							(start 0.3302 0.4318)
							(mid 0.402042 0.402042)
							(end 0.4318 0.3302)
						)
						(arc
							(start 0.4318 -0.3302)
							(mid 0.402042 -0.402042)
							(end 0.3302 -0.4318)
						)
					)
					(width 0)
					(fill yes)
				)
			)
		)
	)
	(footprint ""
		(layer "F.Cu")
		(at 41.783 -197.231 180)
		(property "Reference" "R884"
			(at 0 0 180)
			(layer "F.SilkS")
			(hide yes)
			(effects
				(font
					(size 1.27 1.27)
				)
			)
		)
		(property "Value" "0R2J-2-GP"
			(at 0.064008 -3.993896 180)
			(unlocked yes)
			(layer "F.Fab")
			(hide yes)
			(effects
				(font
					(size 1.016 1.016)
					(thickness 0.1524)
				)
			)
		)
		(property "Device Type" "R402H16"
			(at 0.064008 -5.517896 180)
			(unlocked yes)
			(layer "F.Fab")
			(hide yes)
			(effects
				(font
					(size 1.016 1.016)
					(thickness 0.1524)
				)
			)
		)
		(duplicate_pad_numbers_are_jumpers no)
		(fp_line
			(start 0.508 -0.9398)
			(end -0.508 -0.9398)
			(stroke
				(width 0.1524)
				(type default)
			)
			(layer "F.SilkS")
		)
		(fp_line
			(start -0.508 -0.9398)
			(end -0.508 0.9398)
			(stroke
				(width 0.1524)
				(type default)
			)
			(layer "F.SilkS")
		)
		(fp_rect
			(start -0.508 0.9398)
			(end 0.508 -0.9398)
			(stroke
				(width 0)
				(type default)
			)
			(fill no)
			(layer "F.CrtYd")
		)
		(fp_rect
			(start -0.508 0.9398)
			(end 0.508 -0.9398)
			(stroke
				(width 0)
				(type default)
			)
			(fill no)
			(layer "F.Fab")
		)
		(pad "1" smd custom
			(at 0 -0.4445 180)
			(size 0.1397 0.1397)
			(layers "F.Cu" "F.Mask" "F.Paste")
			(net "BMC_I2C6_C_FCB_SCL")
			(options
				(clearance outline)
				(anchor circle)
			)
			(primitives
				(gr_poly
					(pts
						(arc
							(start -0.1778 -0.2794)
							(mid -0.249642 -0.249642)
							(end -0.2794 -0.1778)
						)
						(arc
							(start -0.2794 0.1778)
							(mid -0.249642 0.249642)
							(end -0.1778 0.2794)
						)
						(arc
							(start 0.1778 0.2794)
							(mid 0.249642 0.249642)
							(end 0.2794 0.1778)
						)
						(arc
							(start 0.2794 -0.1778)
							(mid 0.249642 -0.249642)
							(end 0.1778 -0.2794)
						)
					)
					(width 0)
					(fill yes)
				)
			)
		)
		(pad "2" smd custom
			(at 0 0.4445 180)
			(size 0.1397 0.1397)
			(layers "F.Cu" "F.Mask" "F.Paste")
			(net "BMC_I2C6_C_FCB_SCL_R")
			(options
				(clearance outline)
				(anchor circle)
			)
			(primitives
				(gr_poly
					(pts
						(arc
							(start -0.1778 -0.2794)
							(mid -0.249642 -0.249642)
							(end -0.2794 -0.1778)
						)
						(arc
							(start -0.2794 0.1778)
							(mid -0.249642 0.249642)
							(end -0.1778 0.2794)
						)
						(arc
							(start 0.1778 0.2794)
							(mid 0.249642 0.249642)
							(end 0.2794 0.1778)
						)
						(arc
							(start 0.2794 -0.1778)
							(mid 0.249642 -0.249642)
							(end 0.1778 -0.2794)
						)
					)
					(width 0)
					(fill yes)
				)
			)
		)
	)
	(footprint ""
		(layer "F.Cu")
		(at 184.12206 -14.76502 180)
		(property "Reference" "R252"
			(at 0 0 180)
			(layer "F.SilkS")
			(hide yes)
			(effects
				(font
					(size 1.27 1.27)
				)
			)
		)
		(property "Value" "4K7R2F-GP"
			(at 0.064008 -3.993896 180)
			(unlocked yes)
			(layer "F.Fab")
			(hide yes)
			(effects
				(font
					(size 1.016 1.016)
					(thickness 0.1524)
				)
			)
		)
		(property "Device Type" "R402H16"
			(at 0.064008 -5.517896 180)
			(unlocked yes)
			(layer "F.Fab")
			(hide yes)
			(effects
				(font
					(size 1.016 1.016)
					(thickness 0.1524)
				)
			)
		)
		(duplicate_pad_numbers_are_jumpers no)
		(fp_line
			(start 0.508 -0.9398)
			(end -0.508 -0.9398)
			(stroke
				(width 0.1524)
				(type default)
			)
			(layer "F.SilkS")
		)
		(fp_line
			(start -0.508 -0.9398)
			(end -0.508 0.9398)
			(stroke
				(width 0.1524)
				(type default)
			)
			(layer "F.SilkS")
		)
		(fp_rect
			(start -0.508 0.9398)
			(end 0.508 -0.9398)
			(stroke
				(width 0)
				(type default)
			)
			(fill no)
			(layer "F.CrtYd")
		)
		(fp_rect
			(start -0.508 0.9398)
			(end 0.508 -0.9398)
			(stroke
				(width 0)
				(type default)
			)
			(fill no)
			(layer "F.Fab")
		)
		(pad "1" smd custom
			(at 0 -0.4445 180)
			(size 0.1397 0.1397)
			(layers "F.Cu" "F.Mask" "F.Paste")
			(net "P3V3_STBY")
			(options
				(clearance outline)
				(anchor circle)
			)
			(primitives
				(gr_poly
					(pts
						(arc
							(start -0.1778 -0.2794)
							(mid -0.249642 -0.249642)
							(end -0.2794 -0.1778)
						)
						(arc
							(start -0.2794 0.1778)
							(mid -0.249642 0.249642)
							(end -0.1778 0.2794)
						)
						(arc
							(start 0.1778 0.2794)
							(mid 0.249642 0.249642)
							(end 0.2794 0.1778)
						)
						(arc
							(start 0.2794 -0.1778)
							(mid 0.249642 -0.249642)
							(end 0.1778 -0.2794)
						)
					)
					(width 0)
					(fill yes)
				)
			)
		)
		(pad "2" smd custom
			(at 0 0.4445 180)
			(size 0.1397 0.1397)
			(layers "F.Cu" "F.Mask" "F.Paste")
			(net "CLK_P_4_R")
			(options
				(clearance outline)
				(anchor circle)
			)
			(primitives
				(gr_poly
					(pts
						(arc
							(start -0.1778 -0.2794)
							(mid -0.249642 -0.249642)
							(end -0.2794 -0.1778)
						)
						(arc
							(start -0.2794 0.1778)
							(mid -0.249642 0.249642)
							(end -0.1778 0.2794)
						)
						(arc
							(start 0.1778 0.2794)
							(mid 0.249642 0.249642)
							(end 0.2794 0.1778)
						)
						(arc
							(start 0.2794 -0.1778)
							(mid 0.249642 -0.249642)
							(end 0.1778 -0.2794)
						)
					)
					(width 0)
					(fill yes)
				)
			)
		)
	)
	(footprint ""
		(layer "F.Cu")
		(at 157.826202 -56.288432 -90)
		(property "Reference" "PC203"
			(at 0 0 270)
			(layer "F.SilkS")
			(hide yes)
			(effects
				(font
					(size 1.27 1.27)
				)
			)
		)
		(property "Value" "SC1KP50V2KX-1GP"
			(at 1.1811 -2.7051 270)
			(unlocked yes)
			(layer "F.Fab")
			(hide yes)
			(effects
				(font
					(size 1.016 1.016)
					(thickness 0.1524)
				)
			)
		)
		(property "Device Type" "C402H22"
			(at 1.1811 -4.2291 270)
			(unlocked yes)
			(layer "F.Fab")
			(hide yes)
			(effects
				(font
					(size 1.016 1.016)
					(thickness 0.1524)
				)
			)
		)
		(duplicate_pad_numbers_are_jumpers no)
		(fp_rect
			(start -0.4318 0.9525)
			(end 0.4318 -0.9525)
			(stroke
				(width 0)
				(type default)
			)
			(fill no)
			(layer "F.CrtYd")
		)
		(fp_rect
			(start -0.4318 0.9525)
			(end 0.4318 -0.9525)
			(stroke
				(width 0)
				(type default)
			)
			(fill no)
			(layer "F.Fab")
		)
		(pad "1" smd custom
			(at 0 -0.4445 270)
			(size 0.1524 0.1524)
			(layers "F.Cu" "F.Mask" "F.Paste")
			(net "P0V9_SW_R")
			(options
				(clearance outline)
				(anchor circle)
			)
			(primitives
				(gr_poly
					(pts
						(arc
							(start 0.3048 -0.2032)
							(mid 0.275042 -0.275042)
							(end 0.2032 -0.3048)
						)
						(arc
							(start -0.2032 -0.3048)
							(mid -0.275042 -0.275042)
							(end -0.3048 -0.2032)
						)
						(arc
							(start -0.3048 0.2032)
							(mid -0.275042 0.275042)
							(end -0.2032 0.3048)
						)
						(arc
							(start 0.2032 0.3048)
							(mid 0.275042 0.275042)
							(end 0.3048 0.2032)
						)
					)
					(width 0)
					(fill yes)
				)
			)
		)
		(pad "2" smd custom
			(at 0 0.4445 270)
			(size 0.1524 0.1524)
			(layers "F.Cu" "F.Mask" "F.Paste")
			(net "P0V9_VFB")
			(options
				(clearance outline)
				(anchor circle)
			)
			(primitives
				(gr_poly
					(pts
						(arc
							(start 0.3048 -0.2032)
							(mid 0.275042 -0.275042)
							(end 0.2032 -0.3048)
						)
						(arc
							(start -0.2032 -0.3048)
							(mid -0.275042 -0.275042)
							(end -0.3048 -0.2032)
						)
						(arc
							(start -0.3048 0.2032)
							(mid -0.275042 0.275042)
							(end -0.2032 0.3048)
						)
						(arc
							(start 0.2032 0.3048)
							(mid 0.275042 0.275042)
							(end 0.3048 0.2032)
						)
					)
					(width 0)
					(fill yes)
				)
			)
		)
	)
	(footprint ""
		(layer "F.Cu")
		(at 311.263792 -33.555686)
		(property "Reference" "C20"
			(at 0 0 0)
			(layer "F.SilkS")
			(hide yes)
			(effects
				(font
					(size 1.27 1.27)
				)
			)
		)
		(property "Value" "SCD22U10V2KX-1GP"
			(at 1.1811 -2.7051 0)
			(unlocked yes)
			(layer "F.Fab")
			(hide yes)
			(effects
				(font
					(size 1.016 1.016)
					(thickness 0.1524)
				)
			)
		)
		(property "Device Type" "C402H22"
			(at 1.1811 -4.2291 0)
			(unlocked yes)
			(layer "F.Fab")
			(hide yes)
			(effects
				(font
					(size 1.016 1.016)
					(thickness 0.1524)
				)
			)
		)
		(duplicate_pad_numbers_are_jumpers no)
		(fp_rect
			(start -0.4318 0.9525)
			(end 0.4318 -0.9525)
			(stroke
				(width 0)
				(type default)
			)
			(fill no)
			(layer "F.CrtYd")
		)
		(fp_rect
			(start -0.4318 0.9525)
			(end 0.4318 -0.9525)
			(stroke
				(width 0)
				(type default)
			)
			(fill no)
			(layer "F.Fab")
		)
		(pad "1" smd custom
			(at 0 -0.4445)
			(size 0.1524 0.1524)
			(layers "F.Cu" "F.Mask" "F.Paste")
			(net "PCIE_TX_CAP_N9")
			(options
				(clearance outline)
				(anchor circle)
			)
			(primitives
				(gr_poly
					(pts
						(arc
							(start 0.3048 -0.2032)
							(mid 0.275042 -0.275042)
							(end 0.2032 -0.3048)
						)
						(arc
							(start -0.2032 -0.3048)
							(mid -0.275042 -0.275042)
							(end -0.3048 -0.2032)
						)
						(arc
							(start -0.3048 0.2032)
							(mid -0.275042 0.275042)
							(end -0.2032 0.3048)
						)
						(arc
							(start 0.2032 0.3048)
							(mid 0.275042 0.275042)
							(end 0.3048 0.2032)
						)
					)
					(width 0)
					(fill yes)
				)
			)
		)
		(pad "2" smd custom
			(at 0 0.4445)
			(size 0.1524 0.1524)
			(layers "F.Cu" "F.Mask" "F.Paste")
			(net "PCIE_TX_N9")
			(options
				(clearance outline)
				(anchor circle)
			)
			(primitives
				(gr_poly
					(pts
						(arc
							(start 0.3048 -0.2032)
							(mid 0.275042 -0.275042)
							(end 0.2032 -0.3048)
						)
						(arc
							(start -0.2032 -0.3048)
							(mid -0.275042 -0.275042)
							(end -0.3048 -0.2032)
						)
						(arc
							(start -0.3048 0.2032)
							(mid -0.275042 0.275042)
							(end -0.2032 0.3048)
						)
						(arc
							(start 0.2032 0.3048)
							(mid 0.275042 0.275042)
							(end 0.3048 0.2032)
						)
					)
					(width 0)
					(fill yes)
				)
			)
		)
	)
	(footprint ""
		(layer "F.Cu")
		(at 179.9844 -61.595)
		(property "Reference" "C559"
			(at 0 0 0)
			(layer "F.SilkS")
			(hide yes)
			(effects
				(font
					(size 1.27 1.27)
				)
			)
		)
		(property "Value" "SC4D7U16V5KX-1-GP"
			(at -0.0762 -6.1214 0)
			(unlocked yes)
			(layer "F.Fab")
			(hide yes)
			(effects
				(font
					(size 1.016 1.016)
					(thickness 0.1524)
				)
			)
		)
		(property "Device Type" "C805H56"
			(at -0.0762 -8.1534 0)
			(unlocked yes)
			(layer "F.Fab")
			(hide yes)
			(effects
				(font
					(size 1.016 1.016)
					(thickness 0.1524)
				)
			)
		)
		(duplicate_pad_numbers_are_jumpers no)
		(fp_line
			(start 0.635 0)
			(end -0.635 0)
			(stroke
				(width 0.508)
				(type default)
			)
			(layer "F.SilkS")
		)
		(fp_rect
			(start -0.9652 1.778)
			(end 0.9652 -1.778)
			(stroke
				(width 0)
				(type default)
			)
			(fill no)
			(layer "F.CrtYd")
		)
		(fp_poly
			(pts
				(xy -0.9652 -1.778) (xy 0.9652 -1.778) (xy 0.9652 1.778) (xy -0.9652 1.778)
			)
			(stroke
				(width 0)
				(type default)
			)
			(fill no)
			(layer "F.Fab")
		)
		(pad "1" smd rect
			(at 0 -0.9652)
			(size 1.397 1.143)
			(layers "F.Cu" "F.Mask" "F.Paste")
			(net "DUT_AVD_PCIE")
		)
		(pad "2" smd rect
			(at 0 0.9652)
			(size 1.397 1.143)
			(layers "F.Cu" "F.Mask" "F.Paste")
			(net "GND")
		)
	)
	(footprint ""
		(layer "F.Cu")
		(at 166.497 -90.8304 90)
		(property "Reference" "R92"
			(at 0 0 90)
			(layer "F.SilkS")
			(hide yes)
			(effects
				(font
					(size 1.27 1.27)
				)
			)
		)
		(property "Value" "1R3F-GP"
			(at -0.0254 -2.5146 90)
			(unlocked yes)
			(layer "F.Fab")
			(hide yes)
			(effects
				(font
					(size 1.016 1.016)
					(thickness 0.1524)
				)
			)
		)
		(property "Device Type" "R603H22"
			(at -0.0254 -4.0386 90)
			(unlocked yes)
			(layer "F.Fab")
			(hide yes)
			(effects
				(font
					(size 1.016 1.016)
					(thickness 0.1524)
				)
			)
		)
		(duplicate_pad_numbers_are_jumpers no)
		(fp_line
			(start 0.2032 0)
			(end 0.4826 0)
			(stroke
				(width 0.2032)
				(type default)
			)
			(layer "F.SilkS")
		)
		(fp_line
			(start -0.4826 0)
			(end -0.2032 0)
			(stroke
				(width 0.2032)
				(type default)
			)
			(layer "F.SilkS")
		)
		(fp_rect
			(start -0.5842 1.3335)
			(end 0.5842 -1.3335)
			(stroke
				(width 0)
				(type default)
			)
			(fill no)
			(layer "F.CrtYd")
		)
		(fp_rect
			(start -0.5842 1.3335)
			(end 0.5842 -1.3335)
			(stroke
				(width 0)
				(type default)
			)
			(fill no)
			(layer "F.Fab")
		)
		(pad "1" smd custom
			(at 0 -0.762 90)
			(size 0.2159 0.2159)
			(layers "F.Cu" "F.Mask" "F.Paste")
			(net "P1V8_CLKGEN_A")
			(options
				(clearance outline)
				(anchor circle)
			)
			(primitives
				(gr_poly
					(pts
						(arc
							(start -0.3302 -0.4318)
							(mid -0.402042 -0.402042)
							(end -0.4318 -0.3302)
						)
						(arc
							(start -0.4318 0.3302)
							(mid -0.402042 0.402042)
							(end -0.3302 0.4318)
						)
						(arc
							(start 0.3302 0.4318)
							(mid 0.402042 0.402042)
							(end 0.4318 0.3302)
						)
						(arc
							(start 0.4318 -0.3302)
							(mid 0.402042 -0.402042)
							(end 0.3302 -0.4318)
						)
					)
					(width 0)
					(fill yes)
				)
			)
		)
		(pad "2" smd custom
			(at 0 0.762 90)
			(size 0.2159 0.2159)
			(layers "F.Cu" "F.Mask" "F.Paste")
			(net "P1V8_CLKGEN")
			(options
				(clearance outline)
				(anchor circle)
			)
			(primitives
				(gr_poly
					(pts
						(arc
							(start -0.3302 -0.4318)
							(mid -0.402042 -0.402042)
							(end -0.4318 -0.3302)
						)
						(arc
							(start -0.4318 0.3302)
							(mid -0.402042 0.402042)
							(end -0.3302 0.4318)
						)
						(arc
							(start 0.3302 0.4318)
							(mid 0.402042 0.402042)
							(end 0.4318 0.3302)
						)
						(arc
							(start 0.4318 -0.3302)
							(mid 0.402042 -0.402042)
							(end 0.3302 -0.4318)
						)
					)
					(width 0)
					(fill yes)
				)
			)
		)
	)
	(footprint ""
		(layer "F.Cu")
		(at 239.720374 -6.444996 90)
		(property "Reference" "C319"
			(at 0 0 90)
			(layer "F.SilkS")
			(hide yes)
			(effects
				(font
					(size 1.27 1.27)
				)
			)
		)
		(property "Value" "SCD1U16V2KX-3GP"
			(at 1.1811 -2.7051 90)
			(unlocked yes)
			(layer "F.Fab")
			(hide yes)
			(effects
				(font
					(size 1.016 1.016)
					(thickness 0.1524)
				)
			)
		)
		(property "Device Type" "C402H22"
			(at 1.1811 -4.2291 90)
			(unlocked yes)
			(layer "F.Fab")
			(hide yes)
			(effects
				(font
					(size 1.016 1.016)
					(thickness 0.1524)
				)
			)
		)
		(duplicate_pad_numbers_are_jumpers no)
		(fp_rect
			(start -0.4318 0.9525)
			(end 0.4318 -0.9525)
			(stroke
				(width 0)
				(type default)
			)
			(fill no)
			(layer "F.CrtYd")
		)
		(fp_rect
			(start -0.4318 0.9525)
			(end 0.4318 -0.9525)
			(stroke
				(width 0)
				(type default)
			)
			(fill no)
			(layer "F.Fab")
		)
		(pad "1" smd custom
			(at 0 -0.4445 90)
			(size 0.1524 0.1524)
			(layers "F.Cu" "F.Mask" "F.Paste")
			(net "UART_COUNT")
			(options
				(clearance outline)
				(anchor circle)
			)
			(primitives
				(gr_poly
					(pts
						(arc
							(start 0.3048 -0.2032)
							(mid 0.275042 -0.275042)
							(end 0.2032 -0.3048)
						)
						(arc
							(start -0.2032 -0.3048)
							(mid -0.275042 -0.275042)
							(end -0.3048 -0.2032)
						)
						(arc
							(start -0.3048 0.2032)
							(mid -0.275042 0.275042)
							(end -0.2032 0.3048)
						)
						(arc
							(start 0.2032 0.3048)
							(mid 0.275042 0.275042)
							(end 0.3048 0.2032)
						)
					)
					(width 0)
					(fill yes)
				)
			)
		)
		(pad "2" smd custom
			(at 0 0.4445 90)
			(size 0.1524 0.1524)
			(layers "F.Cu" "F.Mask" "F.Paste")
			(net "GND")
			(options
				(clearance outline)
				(anchor circle)
			)
			(primitives
				(gr_poly
					(pts
						(arc
							(start 0.3048 -0.2032)
							(mid 0.275042 -0.275042)
							(end 0.2032 -0.3048)
						)
						(arc
							(start -0.2032 -0.3048)
							(mid -0.275042 -0.275042)
							(end -0.3048 -0.2032)
						)
						(arc
							(start -0.3048 0.2032)
							(mid -0.275042 0.275042)
							(end -0.2032 0.3048)
						)
						(arc
							(start 0.2032 0.3048)
							(mid 0.275042 0.275042)
							(end 0.3048 0.2032)
						)
					)
					(width 0)
					(fill yes)
				)
			)
		)
	)
	(footprint ""
		(layer "F.Cu")
		(at 18.415 -130.683 -90)
		(property "Reference" "R353"
			(at 0 0 270)
			(layer "F.SilkS")
			(hide yes)
			(effects
				(font
					(size 1.27 1.27)
				)
			)
		)
		(property "Value" "3K3R2F-2-GP"
			(at 0.064008 -3.993896 270)
			(unlocked yes)
			(layer "F.Fab")
			(hide yes)
			(effects
				(font
					(size 1.016 1.016)
					(thickness 0.1524)
				)
			)
		)
		(property "Device Type" "R402H16"
			(at 0.064008 -5.517896 270)
			(unlocked yes)
			(layer "F.Fab")
			(hide yes)
			(effects
				(font
					(size 1.016 1.016)
					(thickness 0.1524)
				)
			)
		)
		(duplicate_pad_numbers_are_jumpers no)
		(fp_line
			(start -0.508 -0.9398)
			(end -0.508 0.9398)
			(stroke
				(width 0.1524)
				(type default)
			)
			(layer "F.SilkS")
		)
		(fp_line
			(start 0.508 -0.9398)
			(end -0.508 -0.9398)
			(stroke
				(width 0.1524)
				(type default)
			)
			(layer "F.SilkS")
		)
		(fp_rect
			(start -0.508 0.9398)
			(end 0.508 -0.9398)
			(stroke
				(width 0)
				(type default)
			)
			(fill no)
			(layer "F.CrtYd")
		)
		(fp_rect
			(start -0.508 0.9398)
			(end 0.508 -0.9398)
			(stroke
				(width 0)
				(type default)
			)
			(fill no)
			(layer "F.Fab")
		)
		(pad "1" smd custom
			(at 0 -0.4445 270)
			(size 0.1397 0.1397)
			(layers "F.Cu" "F.Mask" "F.Paste")
			(net "P3V3_STBY")
			(options
				(clearance outline)
				(anchor circle)
			)
			(primitives
				(gr_poly
					(pts
						(arc
							(start -0.1778 -0.2794)
							(mid -0.249642 -0.249642)
							(end -0.2794 -0.1778)
						)
						(arc
							(start -0.2794 0.1778)
							(mid -0.249642 0.249642)
							(end -0.1778 0.2794)
						)
						(arc
							(start 0.1778 0.2794)
							(mid 0.249642 0.249642)
							(end 0.2794 0.1778)
						)
						(arc
							(start 0.2794 -0.1778)
							(mid 0.249642 -0.249642)
							(end 0.1778 -0.2794)
						)
					)
					(width 0)
					(fill yes)
				)
			)
		)
		(pad "2" smd custom
			(at 0 0.4445 270)
			(size 0.1397 0.1397)
			(layers "F.Cu" "F.Mask" "F.Paste")
			(net "ROMA19")
			(options
				(clearance outline)
				(anchor circle)
			)
			(primitives
				(gr_poly
					(pts
						(arc
							(start -0.1778 -0.2794)
							(mid -0.249642 -0.249642)
							(end -0.2794 -0.1778)
						)
						(arc
							(start -0.2794 0.1778)
							(mid -0.249642 0.249642)
							(end -0.1778 0.2794)
						)
						(arc
							(start 0.1778 0.2794)
							(mid 0.249642 0.249642)
							(end 0.2794 0.1778)
						)
						(arc
							(start 0.2794 -0.1778)
							(mid 0.249642 -0.249642)
							(end 0.1778 -0.2794)
						)
					)
					(width 0)
					(fill yes)
				)
			)
		)
	)
	(footprint ""
		(layer "F.Cu")
		(at 240.599976 -47.999904 -90)
		(property "Reference" "U1"
			(at 0 0 270)
			(layer "F.SilkS")
			(hide yes)
			(effects
				(font
					(size 1.27 1.27)
				)
			)
		)
		(property "Value" "PM8546A-FEIP-GP"
			(at -25.785064 -6.40334 270)
			(unlocked yes)
			(layer "F.Fab")
			(hide yes)
			(effects
				(font
					(size 1.016 1.016)
					(thickness 0.1524)
				)
			)
		)
		(property "Device Type" "BGA1311C37D5H134"
			(at -25.785064 -7.92734 270)
			(unlocked yes)
			(layer "F.Fab")
			(hide yes)
			(effects
				(font
					(size 1.016 1.016)
					(thickness 0.1524)
				)
			)
		)
		(duplicate_pad_numbers_are_jumpers no)
		(fp_line
			(start -18.280126 18.750026)
			(end -16.969994 18.750026)
			(stroke
				(width 0.1524)
				(type default)
			)
			(layer "F.SilkS")
		)
		(fp_line
			(start 16.030194 18.750026)
			(end -16.030194 18.750026)
			(stroke
				(width 0.1524)
				(type default)
			)
			(layer "F.SilkS")
		)
		(fp_line
			(start 18.280126 18.750026)
			(end 16.969994 18.750026)
			(stroke
				(width 0.1524)
				(type default)
			)
			(layer "F.SilkS")
		)
		(fp_line
			(start -18.750026 18.280126)
			(end -18.750026 16.969994)
			(stroke
				(width 0.1524)
				(type default)
			)
			(layer "F.SilkS")
		)
		(fp_line
			(start 18.750026 18.280126)
			(end 18.750026 16.969994)
			(stroke
				(width 0.1524)
				(type default)
			)
			(layer "F.SilkS")
		)
		(fp_line
			(start -18.750026 -16.030194)
			(end -18.750026 16.030194)
			(stroke
				(width 0.1524)
				(type default)
			)
			(layer "F.SilkS")
		)
		(fp_line
			(start 18.750026 -16.030194)
			(end 18.750026 16.030194)
			(stroke
				(width 0.1524)
				(type default)
			)
			(layer "F.SilkS")
		)
		(fp_line
			(start -18.750026 -18.280126)
			(end -18.750026 -16.969994)
			(stroke
				(width 0.1524)
				(type default)
			)
			(layer "F.SilkS")
		)
		(fp_line
			(start 18.750026 -18.280126)
			(end 18.750026 -16.969994)
			(stroke
				(width 0.1524)
				(type default)
			)
			(layer "F.SilkS")
		)
		(fp_line
			(start -18.280126 -18.750026)
			(end -16.969994 -18.750026)
			(stroke
				(width 0.1524)
				(type default)
			)
			(layer "F.SilkS")
		)
		(fp_line
			(start 16.030194 -18.750026)
			(end -16.030194 -18.750026)
			(stroke
				(width 0.1524)
				(type default)
			)
			(layer "F.SilkS")
		)
		(fp_line
			(start 18.280126 -18.750026)
			(end 16.969994 -18.750026)
			(stroke
				(width 0.1524)
				(type default)
			)
			(layer "F.SilkS")
		)
		(fp_circle
			(center -16.500094 18.851626)
			(end -16.500094 18.483326)
			(stroke
				(width 0.1524)
				(type default)
			)
			(fill no)
			(layer "F.SilkS")
		)
		(fp_circle
			(center 16.500094 18.851626)
			(end 16.500094 18.483326)
			(stroke
				(width 0.1524)
				(type default)
			)
			(fill no)
			(layer "F.SilkS")
		)
		(fp_circle
			(center -18.750026 18.750026)
			(end -18.750026 18.280126)
			(stroke
				(width 0.1524)
				(type default)
			)
			(fill no)
			(layer "F.SilkS")
		)
		(fp_circle
			(center 18.750026 18.750026)
			(end 18.750026 18.280126)
			(stroke
				(width 0.1524)
				(type default)
			)
			(fill no)
			(layer "F.SilkS")
		)
		(fp_circle
			(center -18.851626 16.500094)
			(end -18.851626 16.131794)
			(stroke
				(width 0.1524)
				(type default)
			)
			(fill no)
			(layer "F.SilkS")
		)
		(fp_circle
			(center 18.851626 16.500094)
			(end 18.851626 16.131794)
			(stroke
				(width 0.1524)
				(type default)
			)
			(fill no)
			(layer "F.SilkS")
		)
		(fp_circle
			(center -18.851626 -16.500094)
			(end -18.851626 -16.868394)
			(stroke
				(width 0.1524)
				(type default)
			)
			(fill no)
			(layer "F.SilkS")
		)
		(fp_circle
			(center 18.851626 -16.500094)
			(end 18.851626 -16.868394)
			(stroke
				(width 0.1524)
				(type default)
			)
			(fill no)
			(layer "F.SilkS")
		)
		(fp_circle
			(center -18.750026 -18.750026)
			(end -18.750026 -19.219926)
			(stroke
				(width 0.1524)
				(type default)
			)
			(fill no)
			(layer "F.SilkS")
		)
		(fp_circle
			(center 18.750026 -18.750026)
			(end 18.750026 -19.219926)
			(stroke
				(width 0.1524)
				(type default)
			)
			(fill no)
			(layer "F.SilkS")
		)
		(fp_circle
			(center -16.500094 -18.851626)
			(end -16.500094 -19.219926)
			(stroke
				(width 0.1524)
				(type default)
			)
			(fill no)
			(layer "F.SilkS")
		)
		(fp_circle
			(center 16.500094 -18.851626)
			(end 16.500094 -19.219926)
			(stroke
				(width 0.1524)
				(type default)
			)
			(fill no)
			(layer "F.SilkS")
		)
		(fp_poly
			(pts
				(xy -19.181826 -19.181826) (xy -19.181826 -20.705826) (xy -20.705826 -19.181826)
			)
			(stroke
				(width 0)
				(type default)
			)
			(fill yes)
			(layer "F.SilkS")
		)
		(fp_rect
			(start -18.750026 18.750026)
			(end 18.750026 -18.750026)
			(stroke
				(width 0)
				(type default)
			)
			(fill no)
			(layer "F.CrtYd")
		)
		(fp_poly
			(pts
				(xy 19.750024 -18.750026) (xy -18.750026 -18.750026) (xy -18.750026 18.750026) (xy 18.750026 18.750026)
				(xy 18.750026 -18.737326) (xy 19.750024 -18.737326) (xy 19.750024 19.750024) (xy -19.750024 19.750024)
				(xy -19.750024 -19.750024) (xy 19.750024 -19.750024)
			)
			(stroke
				(width 0)
				(type default)
			)
			(fill no)
			(layer "F.CrtYd")
		)
		(fp_rect
			(start -20.750022 20.750022)
			(end 20.750022 -20.750022)
			(stroke
				(width 0)
				(type default)
			)
			(fill no)
			(layer "F.Fab")
		)
		(pad "A2" smd circle
			(at -16.999966 -17.999964 270)
			(size 0.508 0.508)
			(layers "F.Cu" "F.Mask" "F.Paste")
			(net "GND")
		)
		(pad "A3" smd circle
			(at -15.999968 -17.999964 270)
			(size 0.508 0.508)
			(layers "F.Cu" "F.Mask" "F.Paste")
			(net "GND")
		)
		(pad "A4" smd circle
			(at -14.99997 -17.999964 270)
			(size 0.4572 0.4572)
			(layers "F.Cu" "F.Mask" "F.Paste")
			(net "GND")
		)
		(pad "A5" smd circle
			(at -13.999972 -17.999964 270)
			(size 0.4572 0.4572)
			(layers "F.Cu" "F.Mask" "F.Paste")
			(net "GND")
		)
		(pad "A6" smd circle
			(at -12.999974 -17.999964 270)
			(size 0.4572 0.4572)
			(layers "F.Cu" "F.Mask" "F.Paste")
			(net "GND")
		)
		(pad "A7" smd circle
			(at -11.999976 -17.999964 270)
			(size 0.4572 0.4572)
			(layers "F.Cu" "F.Mask" "F.Paste")
			(net "GND")
		)
		(pad "A9" smd circle
			(at -9.99998 -17.999964 270)
			(size 0.4572 0.4572)
			(layers "F.Cu" "F.Mask" "F.Paste")
			(net "PCIE_TX_CAP_N30")
		)
		(pad "A11" smd circle
			(at -7.999984 -17.999964 270)
			(size 0.4572 0.4572)
			(layers "F.Cu" "F.Mask" "F.Paste")
			(net "PCIE_TX_CAP_N28")
		)
		(pad "A13" smd circle
			(at -5.999988 -17.999964 270)
			(size 0.4572 0.4572)
			(layers "F.Cu" "F.Mask" "F.Paste")
			(net "PCIE_TX_CAP_N26")
		)
		(pad "A15" smd circle
			(at -3.999992 -17.999964 270)
			(size 0.4572 0.4572)
			(layers "F.Cu" "F.Mask" "F.Paste")
			(net "PCIE_TX_CAP_N24")
		)
		(pad "A16" smd circle
			(at -2.999994 -17.999964 270)
			(size 0.4572 0.4572)
			(layers "F.Cu" "F.Mask" "F.Paste")
			(net "GND")
		)
		(pad "A18" smd circle
			(at -0.999998 -17.999964 270)
			(size 0.4572 0.4572)
			(layers "F.Cu" "F.Mask" "F.Paste")
			(net "PCIE_TX_CAP_N22")
		)
		(pad "A20" smd circle
			(at 0.999998 -17.999964 270)
			(size 0.4572 0.4572)
			(layers "F.Cu" "F.Mask" "F.Paste")
			(net "PCIE_TX_CAP_N20")
		)
		(pad "A22" smd circle
			(at 2.999994 -17.999964 270)
			(size 0.4572 0.4572)
			(layers "F.Cu" "F.Mask" "F.Paste")
			(net "PCIE_TX_CAP_N18")
		)
		(pad "A24" smd circle
			(at 4.99999 -17.999964 270)
			(size 0.4572 0.4572)
			(layers "F.Cu" "F.Mask" "F.Paste")
			(net "PCIE_TX_CAP_N16")
		)
		(pad "A25" smd circle
			(at 5.999988 -17.999964 270)
			(size 0.4572 0.4572)
			(layers "F.Cu" "F.Mask" "F.Paste")
			(net "GND")
		)
		(pad "A27" smd circle
			(at 7.999984 -17.999964 270)
			(size 0.4572 0.4572)
			(layers "F.Cu" "F.Mask" "F.Paste")
			(net "PCIE_TX_CAP_N14")
		)
		(pad "A29" smd circle
			(at 9.99998 -17.999964 270)
			(size 0.4572 0.4572)
			(layers "F.Cu" "F.Mask" "F.Paste")
			(net "PCIE_TX_CAP_N12")
		)
		(pad "A31" smd circle
			(at 11.999976 -17.999964 270)
			(size 0.4572 0.4572)
			(layers "F.Cu" "F.Mask" "F.Paste")
			(net "PCIE_TX_CAP_N10")
		)
		(pad "A33" smd circle
			(at 13.999972 -17.999964 270)
			(size 0.4572 0.4572)
			(layers "F.Cu" "F.Mask" "F.Paste")
			(net "PCIE_TX_CAP_N8")
		)
		(pad "A34" smd circle
			(at 14.99997 -17.999964 270)
			(size 0.4572 0.4572)
			(layers "F.Cu" "F.Mask" "F.Paste")
			(net "GND")
		)
		(pad "A35" smd circle
			(at 15.999968 -17.999964 270)
			(size 0.508 0.508)
			(layers "F.Cu" "F.Mask" "F.Paste")
			(net "PCIE_TX_CAP_P7")
		)
		(pad "A36" smd circle
			(at 16.999966 -17.999964 270)
			(size 0.508 0.508)
			(layers "F.Cu" "F.Mask" "F.Paste")
			(net "PCIE_TX_CAP_N7")
		)
		(pad "AA1" smd circle
			(at -17.999964 1.999996 270)
			(size 0.4572 0.4572)
			(layers "F.Cu" "F.Mask" "F.Paste")
			(net "PCIE_TX_CAP_N49")
		)
		(pad "AA2" smd circle
			(at -16.999966 1.999996 270)
			(size 0.4572 0.4572)
			(layers "F.Cu" "F.Mask" "F.Paste")
			(net "PCIE_TX_CAP_P49")
		)
		(pad "AA3" smd circle
			(at -15.999968 1.999996 270)
			(size 0.4572 0.4572)
			(layers "F.Cu" "F.Mask" "F.Paste")
			(net "GND")
		)
		(pad "AA4" smd circle
			(at -14.99997 1.999996 270)
			(size 0.4572 0.4572)
			(layers "F.Cu" "F.Mask" "F.Paste")
			(net "PCIE_RX_N49")
		)
		(pad "AA5" smd circle
			(at -13.999972 1.999996 270)
			(size 0.4572 0.4572)
			(layers "F.Cu" "F.Mask" "F.Paste")
			(net "PCIE_RX_P49")
		)
		(pad "AA6" smd circle
			(at -12.999974 1.999996 270)
			(size 0.4572 0.4572)
			(layers "F.Cu" "F.Mask" "F.Paste")
			(net "GND")
		)
		(pad "AA7" smd circle
			(at -11.999976 1.999996 270)
			(size 0.4572 0.4572)
			(layers "F.Cu" "F.Mask" "F.Paste")
			(net "DUT_AVD_TX")
		)
		(pad "AA8" smd circle
			(at -10.999978 1.999996 270)
			(size 0.4572 0.4572)
			(layers "F.Cu" "F.Mask" "F.Paste")
			(net "GND")
		)
		(pad "AA9" smd circle
			(at -9.99998 1.999996 270)
			(size 0.4572 0.4572)
			(layers "F.Cu" "F.Mask" "F.Paste")
			(net "DUT_AVD_TX")
		)
		(pad "AA10" smd circle
			(at -8.999982 1.999996 270)
			(size 0.4572 0.4572)
			(layers "F.Cu" "F.Mask" "F.Paste")
			(net "GND")
		)
		(pad "AA11" smd circle
			(at -7.999984 1.999996 270)
			(size 0.4572 0.4572)
			(layers "F.Cu" "F.Mask" "F.Paste")
			(net "DUT_AVD_TX")
		)
		(pad "AA12" smd circle
			(at -6.999986 1.999996 270)
			(size 0.4572 0.4572)
			(layers "F.Cu" "F.Mask" "F.Paste")
			(net "GND")
		)
		(pad "AA13" smd circle
			(at -5.999988 1.999996 270)
			(size 0.4572 0.4572)
			(layers "F.Cu" "F.Mask" "F.Paste")
			(net "GND")
		)
		(pad "AA14" smd circle
			(at -4.99999 1.999996 270)
			(size 0.4572 0.4572)
			(layers "F.Cu" "F.Mask" "F.Paste")
			(net "DUT_VDD")
		)
		(pad "AA15" smd circle
			(at -3.999992 1.999996 270)
			(size 0.4572 0.4572)
			(layers "F.Cu" "F.Mask" "F.Paste")
			(net "GND")
		)
		(pad "AA16" smd circle
			(at -2.999994 1.999996 270)
			(size 0.4572 0.4572)
			(layers "F.Cu" "F.Mask" "F.Paste")
			(net "DUT_VDD")
		)
		(pad "AA17" smd circle
			(at -1.999996 1.999996 270)
			(size 0.4572 0.4572)
			(layers "F.Cu" "F.Mask" "F.Paste")
			(net "GND")
		)
		(pad "AA18" smd circle
			(at -0.999998 1.999996 270)
			(size 0.4572 0.4572)
			(layers "F.Cu" "F.Mask" "F.Paste")
			(net "DUT_VDD")
		)
		(pad "AA19" smd circle
			(at 0 1.999996 270)
			(size 0.4572 0.4572)
			(layers "F.Cu" "F.Mask" "F.Paste")
			(net "GND")
		)
		(pad "AA20" smd circle
			(at 0.999998 1.999996 270)
			(size 0.4572 0.4572)
			(layers "F.Cu" "F.Mask" "F.Paste")
			(net "DUT_VDD")
		)
		(pad "AA21" smd circle
			(at 1.999996 1.999996 270)
			(size 0.4572 0.4572)
			(layers "F.Cu" "F.Mask" "F.Paste")
			(net "GND")
		)
		(pad "AA22" smd circle
			(at 2.999994 1.999996 270)
			(size 0.4572 0.4572)
			(layers "F.Cu" "F.Mask" "F.Paste")
			(net "DUT_VDD")
		)
		(pad "AA23" smd circle
			(at 3.999992 1.999996 270)
			(size 0.4572 0.4572)
			(layers "F.Cu" "F.Mask" "F.Paste")
			(net "GND")
		)
		(pad "AA24" smd circle
			(at 4.99999 1.999996 270)
			(size 0.4572 0.4572)
			(layers "F.Cu" "F.Mask" "F.Paste")
			(net "DUT_VDD")
		)
		(pad "AA25" smd circle
			(at 5.999988 1.999996 270)
			(size 0.4572 0.4572)
			(layers "F.Cu" "F.Mask" "F.Paste")
			(net "GND")
		)
		(pad "AA26" smd circle
			(at 6.999986 1.999996 270)
			(size 0.4572 0.4572)
			(layers "F.Cu" "F.Mask" "F.Paste")
			(net "DUT_VDDO")
		)
		(pad "AA27" smd circle
			(at 7.999984 1.999996 270)
			(size 0.4572 0.4572)
			(layers "F.Cu" "F.Mask" "F.Paste")
			(net "BOOTSTRAP_R_10")
		)
		(pad "AA28" smd circle
			(at 8.999982 1.999996 270)
			(size 0.4572 0.4572)
			(layers "F.Cu" "F.Mask" "F.Paste")
			(net "GND")
		)
		(pad "AA29" smd circle
			(at 9.99998 1.999996 270)
			(size 0.4572 0.4572)
			(layers "F.Cu" "F.Mask" "F.Paste")
			(net "PCIE_REFCLK_H2_P")
		)
		(pad "AA30" smd circle
			(at 10.999978 1.999996 270)
			(size 0.4572 0.4572)
			(layers "F.Cu" "F.Mask" "F.Paste")
			(net "PCIE_REFCLK_H2_N")
		)
		(pad "AA31" smd circle
			(at 11.999976 1.999996 270)
			(size 0.4572 0.4572)
			(layers "F.Cu" "F.Mask" "F.Paste")
			(net "DUT_VDDO_REF")
		)
		(pad "AA32" smd circle
			(at 12.999974 1.999996 270)
			(size 0.4572 0.4572)
			(layers "F.Cu" "F.Mask" "F.Paste")
			(net "PCIE_REFCLK_S3_P")
		)
		(pad "AA33" smd circle
			(at 13.999972 1.999996 270)
			(size 0.4572 0.4572)
			(layers "F.Cu" "F.Mask" "F.Paste")
			(net "PCIE_REFCLK_S3_N")
		)
		(pad "AA34" smd circle
			(at 14.99997 1.999996 270)
			(size 0.4572 0.4572)
			(layers "F.Cu" "F.Mask" "F.Paste")
			(net "DUT_VDDO_REF")
		)
		(pad "AA35" smd circle
			(at 15.999968 1.999996 270)
			(size 0.4572 0.4572)
			(layers "F.Cu" "F.Mask" "F.Paste")
			(net "GND")
		)
		(pad "AA36" smd circle
			(at 16.999966 1.999996 270)
			(size 0.4572 0.4572)
			(layers "F.Cu" "F.Mask" "F.Paste")
			(net "PCIE_RX_P95")
		)
		(pad "AA37" smd circle
			(at 17.999964 1.999996 270)
			(size 0.4572 0.4572)
			(layers "F.Cu" "F.Mask" "F.Paste")
			(net "PCIE_RX_N95")
		)
		(pad "AB2" smd circle
			(at -16.999966 2.999994 270)
			(size 0.4572 0.4572)
			(layers "F.Cu" "F.Mask" "F.Paste")
			(net "PCIE_TX_CAP_N50")
		)
		(pad "AB3" smd circle
			(at -15.999968 2.999994 270)
			(size 0.4572 0.4572)
			(layers "F.Cu" "F.Mask" "F.Paste")
			(net "PCIE_TX_CAP_P50")
		)
		(pad "AB4" smd circle
			(at -14.99997 2.999994 270)
			(size 0.4572 0.4572)
			(layers "F.Cu" "F.Mask" "F.Paste")
			(net "GND")
		)
		(pad "AB5" smd circle
			(at -13.999972 2.999994 270)
			(size 0.4572 0.4572)
			(layers "F.Cu" "F.Mask" "F.Paste")
			(net "PCIE_RX_N50")
		)
		(pad "AB6" smd circle
			(at -12.999974 2.999994 270)
			(size 0.4572 0.4572)
			(layers "F.Cu" "F.Mask" "F.Paste")
			(net "PCIE_RX_P50")
		)
		(pad "AB7" smd circle
			(at -11.999976 2.999994 270)
			(size 0.4572 0.4572)
			(layers "F.Cu" "F.Mask" "F.Paste")
			(net "GND")
		)
		(pad "AB8" smd circle
			(at -10.999978 2.999994 270)
			(size 0.4572 0.4572)
			(layers "F.Cu" "F.Mask" "F.Paste")
			(net "DUT_AVD_TX")
		)
		(pad "AB9" smd circle
			(at -9.99998 2.999994 270)
			(size 0.4572 0.4572)
			(layers "F.Cu" "F.Mask" "F.Paste")
			(net "GND")
		)
		(pad "AB10" smd circle
			(at -8.999982 2.999994 270)
			(size 0.4572 0.4572)
			(layers "F.Cu" "F.Mask" "F.Paste")
			(net "DUT_AVD_TX")
		)
		(pad "AB11" smd circle
			(at -7.999984 2.999994 270)
			(size 0.4572 0.4572)
			(layers "F.Cu" "F.Mask" "F.Paste")
			(net "GND")
		)
		(pad "AB12" smd circle
			(at -6.999986 2.999994 270)
			(size 0.4572 0.4572)
			(layers "F.Cu" "F.Mask" "F.Paste")
			(net "GND")
		)
		(pad "AB13" smd circle
			(at -5.999988 2.999994 270)
			(size 0.4572 0.4572)
			(layers "F.Cu" "F.Mask" "F.Paste")
			(net "DUT_VDD")
		)
		(pad "AB14" smd circle
			(at -4.99999 2.999994 270)
			(size 0.4572 0.4572)
			(layers "F.Cu" "F.Mask" "F.Paste")
			(net "GND")
		)
		(pad "AB15" smd circle
			(at -3.999992 2.999994 270)
			(size 0.4572 0.4572)
			(layers "F.Cu" "F.Mask" "F.Paste")
			(net "DUT_VDD")
		)
		(pad "AB16" smd circle
			(at -2.999994 2.999994 270)
			(size 0.4572 0.4572)
			(layers "F.Cu" "F.Mask" "F.Paste")
			(net "GND")
		)
		(pad "AB17" smd circle
			(at -1.999996 2.999994 270)
			(size 0.4572 0.4572)
			(layers "F.Cu" "F.Mask" "F.Paste")
			(net "DUT_VDD")
		)
		(pad "AB18" smd circle
			(at -0.999998 2.999994 270)
			(size 0.4572 0.4572)
			(layers "F.Cu" "F.Mask" "F.Paste")
			(net "GND")
		)
		(pad "AB19" smd circle
			(at 0 2.999994 270)
			(size 0.4572 0.4572)
			(layers "F.Cu" "F.Mask" "F.Paste")
			(net "DUT_VDD")
		)
		(pad "AB20" smd circle
			(at 0.999998 2.999994 270)
			(size 0.4572 0.4572)
			(layers "F.Cu" "F.Mask" "F.Paste")
			(net "GND")
		)
		(pad "AB21" smd circle
			(at 1.999996 2.999994 270)
			(size 0.4572 0.4572)
			(layers "F.Cu" "F.Mask" "F.Paste")
			(net "DUT_VDD")
		)
		(pad "AB22" smd circle
			(at 2.999994 2.999994 270)
			(size 0.4572 0.4572)
			(layers "F.Cu" "F.Mask" "F.Paste")
			(net "GND")
		)
		(pad "AB23" smd circle
			(at 3.999992 2.999994 270)
			(size 0.4572 0.4572)
			(layers "F.Cu" "F.Mask" "F.Paste")
			(net "DUT_VDD")
		)
		(pad "AB24" smd circle
			(at 4.99999 2.999994 270)
			(size 0.4572 0.4572)
			(layers "F.Cu" "F.Mask" "F.Paste")
			(net "GND")
		)
		(pad "AB25" smd circle
			(at 5.999988 2.999994 270)
			(size 0.4572 0.4572)
			(layers "F.Cu" "F.Mask" "F.Paste")
			(net "DUT_VDD")
		)
		(pad "AB26" smd circle
			(at 6.999986 2.999994 270)
			(size 0.4572 0.4572)
			(layers "F.Cu" "F.Mask" "F.Paste")
			(net "GND")
		)
		(pad "AB27" smd circle
			(at 7.999984 2.999994 270)
			(size 0.4572 0.4572)
			(layers "F.Cu" "F.Mask" "F.Paste")
			(net "LBI_ADDR_1_R")
		)
		(pad "AB28" smd circle
			(at 8.999982 2.999994 270)
			(size 0.4572 0.4572)
			(layers "F.Cu" "F.Mask" "F.Paste")
			(net "LBI_ADDR_0_R")
		)
		(pad "AB29" smd circle
			(at 9.99998 2.999994 270)
			(size 0.4572 0.4572)
			(layers "F.Cu" "F.Mask" "F.Paste")
			(net "PCIE_REFCLK_H1_P")
		)
		(pad "AB30" smd circle
			(at 10.999978 2.999994 270)
			(size 0.4572 0.4572)
			(layers "F.Cu" "F.Mask" "F.Paste")
			(net "PCIE_REFCLK_H1_N")
		)
		(pad "AB31" smd circle
			(at 11.999976 2.999994 270)
			(size 0.4572 0.4572)
			(layers "F.Cu" "F.Mask" "F.Paste")
			(net "GND")
		)
		(pad "AB32" smd circle
			(at 12.999974 2.999994 270)
			(size 0.4572 0.4572)
			(layers "F.Cu" "F.Mask" "F.Paste")
			(net "PCIE_REFCLK_S2_P")
		)
		(pad "AB33" smd circle
			(at 13.999972 2.999994 270)
			(size 0.4572 0.4572)
			(layers "F.Cu" "F.Mask" "F.Paste")
			(net "PCIE_REFCLK_S2_N")
		)
		(pad "AB34" smd circle
			(at 14.99997 2.999994 270)
			(size 0.4572 0.4572)
			(layers "F.Cu" "F.Mask" "F.Paste")
			(net "GND")
		)
		(pad "AB35" smd circle
			(at 15.999968 2.999994 270)
			(size 0.4572 0.4572)
			(layers "F.Cu" "F.Mask" "F.Paste")
			(net "PCIE_RX_P94")
		)
		(pad "AB36" smd circle
			(at 16.999966 2.999994 270)
			(size 0.4572 0.4572)
			(layers "F.Cu" "F.Mask" "F.Paste")
			(net "PCIE_RX_N94")
		)
		(pad "AC1" smd circle
			(at -17.999964 3.999992 270)
			(size 0.4572 0.4572)
			(layers "F.Cu" "F.Mask" "F.Paste")
			(net "PCIE_TX_CAP_N51")
		)
		(pad "AC2" smd circle
			(at -16.999966 3.999992 270)
			(size 0.4572 0.4572)
			(layers "F.Cu" "F.Mask" "F.Paste")
			(net "PCIE_TX_CAP_P51")
		)
		(pad "AC3" smd circle
			(at -15.999968 3.999992 270)
			(size 0.4572 0.4572)
			(layers "F.Cu" "F.Mask" "F.Paste")
			(net "GND")
		)
		(pad "AC4" smd circle
			(at -14.99997 3.999992 270)
			(size 0.4572 0.4572)
			(layers "F.Cu" "F.Mask" "F.Paste")
			(net "PCIE_RX_N51")
		)
		(pad "AC5" smd circle
			(at -13.999972 3.999992 270)
			(size 0.4572 0.4572)
			(layers "F.Cu" "F.Mask" "F.Paste")
			(net "PCIE_RX_P51")
		)
		(pad "AC6" smd circle
			(at -12.999974 3.999992 270)
			(size 0.4572 0.4572)
			(layers "F.Cu" "F.Mask" "F.Paste")
			(net "GND")
		)
		(pad "AC7" smd circle
			(at -11.999976 3.999992 270)
			(size 0.4572 0.4572)
			(layers "F.Cu" "F.Mask" "F.Paste")
			(net "DUT_AVD_TX")
		)
		(pad "AC8" smd circle
			(at -10.999978 3.999992 270)
			(size 0.4572 0.4572)
			(layers "F.Cu" "F.Mask" "F.Paste")
			(net "GND")
		)
		(pad "AC9" smd circle
			(at -9.99998 3.999992 270)
			(size 0.4572 0.4572)
			(layers "F.Cu" "F.Mask" "F.Paste")
			(net "DUT_AVD_TX")
		)
		(pad "AC10" smd circle
			(at -8.999982 3.999992 270)
			(size 0.4572 0.4572)
			(layers "F.Cu" "F.Mask" "F.Paste")
			(net "GND")
		)
		(pad "AC11" smd circle
			(at -7.999984 3.999992 270)
			(size 0.4572 0.4572)
			(layers "F.Cu" "F.Mask" "F.Paste")
			(net "DUT_AVD_TX")
		)
		(pad "AC12" smd circle
			(at -6.999986 3.999992 270)
			(size 0.4572 0.4572)
			(layers "F.Cu" "F.Mask" "F.Paste")
			(net "GND")
		)
		(pad "AC13" smd circle
			(at -5.999988 3.999992 270)
			(size 0.4572 0.4572)
			(layers "F.Cu" "F.Mask" "F.Paste")
			(net "GND")
		)
		(pad "AC14" smd circle
			(at -4.99999 3.999992 270)
			(size 0.4572 0.4572)
			(layers "F.Cu" "F.Mask" "F.Paste")
			(net "DUT_VDD")
		)
		(pad "AC15" smd circle
			(at -3.999992 3.999992 270)
			(size 0.4572 0.4572)
			(layers "F.Cu" "F.Mask" "F.Paste")
			(net "GND")
		)
		(pad "AC16" smd circle
			(at -2.999994 3.999992 270)
			(size 0.4572 0.4572)
			(layers "F.Cu" "F.Mask" "F.Paste")
			(net "DUT_VDD")
		)
		(pad "AC17" smd circle
			(at -1.999996 3.999992 270)
			(size 0.4572 0.4572)
			(layers "F.Cu" "F.Mask" "F.Paste")
			(net "GND")
		)
		(pad "AC18" smd circle
			(at -0.999998 3.999992 270)
			(size 0.4572 0.4572)
			(layers "F.Cu" "F.Mask" "F.Paste")
			(net "DUT_VDD")
		)
		(pad "AC19" smd circle
			(at 0 3.999992 270)
			(size 0.4572 0.4572)
			(layers "F.Cu" "F.Mask" "F.Paste")
			(net "GND")
		)
		(pad "AC20" smd circle
			(at 0.999998 3.999992 270)
			(size 0.4572 0.4572)
			(layers "F.Cu" "F.Mask" "F.Paste")
			(net "DUT_VDD")
		)
		(pad "AC21" smd circle
			(at 1.999996 3.999992 270)
			(size 0.4572 0.4572)
			(layers "F.Cu" "F.Mask" "F.Paste")
			(net "GND")
		)
		(pad "AC22" smd circle
			(at 2.999994 3.999992 270)
			(size 0.4572 0.4572)
			(layers "F.Cu" "F.Mask" "F.Paste")
			(net "DUT_VDD")
		)
		(pad "AC23" smd circle
			(at 3.999992 3.999992 270)
			(size 0.4572 0.4572)
			(layers "F.Cu" "F.Mask" "F.Paste")
			(net "GND")
		)
		(pad "AC24" smd circle
			(at 4.99999 3.999992 270)
			(size 0.4572 0.4572)
			(layers "F.Cu" "F.Mask" "F.Paste")
			(net "DUT_VDD")
		)
		(pad "AC25" smd circle
			(at 5.999988 3.999992 270)
			(size 0.4572 0.4572)
			(layers "F.Cu" "F.Mask" "F.Paste")
			(net "GND")
		)
		(pad "AC26" smd circle
			(at 6.999986 3.999992 270)
			(size 0.4572 0.4572)
			(layers "F.Cu" "F.Mask" "F.Paste")
			(net "DUT_AVD_PCIE")
		)
		(pad "AC27" smd circle
			(at 7.999984 3.999992 270)
			(size 0.4572 0.4572)
			(layers "F.Cu" "F.Mask" "F.Paste")
			(net "LBI_ADDR_4_R")
		)
		(pad "AC28" smd circle
			(at 8.999982 3.999992 270)
			(size 0.4572 0.4572)
			(layers "F.Cu" "F.Mask" "F.Paste")
			(net "LBI_ADDR_3_R")
		)
		(pad "AC29" smd circle
			(at 9.99998 3.999992 270)
			(size 0.4572 0.4572)
			(layers "F.Cu" "F.Mask" "F.Paste")
			(net "PCIE_REFCLK_H3_P")
		)
		(pad "AC30" smd circle
			(at 10.999978 3.999992 270)
			(size 0.4572 0.4572)
			(layers "F.Cu" "F.Mask" "F.Paste")
			(net "PCIE_REFCLK_H3_N")
		)
		(pad "AC31" smd circle
			(at 11.999976 3.999992 270)
			(size 0.4572 0.4572)
			(layers "F.Cu" "F.Mask" "F.Paste")
			(net "LBI_ADDR_2_R")
		)
		(pad "AC32" smd circle
			(at 12.999974 3.999992 270)
			(size 0.4572 0.4572)
			(layers "F.Cu" "F.Mask" "F.Paste")
			(net "PCIE_REFCLK_S4_P")
		)
		(pad "AC33" smd circle
			(at 13.999972 3.999992 270)
			(size 0.4572 0.4572)
			(layers "F.Cu" "F.Mask" "F.Paste")
			(net "PCIE_REFCLK_S4_N")
		)
		(pad "AC34" smd circle
			(at 14.99997 3.999992 270)
			(size 0.4572 0.4572)
			(layers "F.Cu" "F.Mask" "F.Paste")
			(net "DUT_VDDO")
		)
		(pad "AC35" smd circle
			(at 15.999968 3.999992 270)
			(size 0.4572 0.4572)
			(layers "F.Cu" "F.Mask" "F.Paste")
			(net "GND")
		)
		(pad "AC36" smd circle
			(at 16.999966 3.999992 270)
			(size 0.4572 0.4572)
			(layers "F.Cu" "F.Mask" "F.Paste")
			(net "PCIE_RX_P93")
		)
		(pad "AC37" smd circle
			(at 17.999964 3.999992 270)
			(size 0.4572 0.4572)
			(layers "F.Cu" "F.Mask" "F.Paste")
			(net "PCIE_RX_N93")
		)
		(pad "AD2" smd circle
			(at -16.999966 4.99999 270)
			(size 0.4572 0.4572)
			(layers "F.Cu" "F.Mask" "F.Paste")
			(net "PCIE_TX_CAP_N52")
		)
		(pad "AD3" smd circle
			(at -15.999968 4.99999 270)
			(size 0.4572 0.4572)
			(layers "F.Cu" "F.Mask" "F.Paste")
			(net "PCIE_TX_CAP_P52")
		)
		(pad "AD4" smd circle
			(at -14.99997 4.99999 270)
			(size 0.4572 0.4572)
			(layers "F.Cu" "F.Mask" "F.Paste")
			(net "GND")
		)
		(pad "AD5" smd circle
			(at -13.999972 4.99999 270)
			(size 0.4572 0.4572)
			(layers "F.Cu" "F.Mask" "F.Paste")
			(net "PCIE_RX_N52")
		)
		(pad "AD6" smd circle
			(at -12.999974 4.99999 270)
			(size 0.4572 0.4572)
			(layers "F.Cu" "F.Mask" "F.Paste")
			(net "PCIE_RX_P52")
		)
		(pad "AD7" smd circle
			(at -11.999976 4.99999 270)
			(size 0.4572 0.4572)
			(layers "F.Cu" "F.Mask" "F.Paste")
			(net "GND")
		)
		(pad "AD8" smd circle
			(at -10.999978 4.99999 270)
			(size 0.4572 0.4572)
			(layers "F.Cu" "F.Mask" "F.Paste")
			(net "DUT_AVD_TX")
		)
		(pad "AD9" smd circle
			(at -9.99998 4.99999 270)
			(size 0.4572 0.4572)
			(layers "F.Cu" "F.Mask" "F.Paste")
			(net "GND")
		)
		(pad "AD10" smd circle
			(at -8.999982 4.99999 270)
			(size 0.4572 0.4572)
			(layers "F.Cu" "F.Mask" "F.Paste")
			(net "DUT_AVD_TX")
		)
		(pad "AD11" smd circle
			(at -7.999984 4.99999 270)
			(size 0.4572 0.4572)
			(layers "F.Cu" "F.Mask" "F.Paste")
			(net "GND")
		)
		(pad "AD12" smd circle
			(at -6.999986 4.99999 270)
			(size 0.4572 0.4572)
			(layers "F.Cu" "F.Mask" "F.Paste")
			(net "GND")
		)
		(pad "AD13" smd circle
			(at -5.999988 4.99999 270)
			(size 0.4572 0.4572)
			(layers "F.Cu" "F.Mask" "F.Paste")
			(net "DUT_VDD")
		)
		(pad "AD14" smd circle
			(at -4.99999 4.99999 270)
			(size 0.4572 0.4572)
			(layers "F.Cu" "F.Mask" "F.Paste")
			(net "GND")
		)
		(pad "AD15" smd circle
			(at -3.999992 4.99999 270)
			(size 0.4572 0.4572)
			(layers "F.Cu" "F.Mask" "F.Paste")
			(net "DUT_VDD")
		)
		(pad "AD16" smd circle
			(at -2.999994 4.99999 270)
			(size 0.4572 0.4572)
			(layers "F.Cu" "F.Mask" "F.Paste")
			(net "GND")
		)
		(pad "AD17" smd circle
			(at -1.999996 4.99999 270)
			(size 0.4572 0.4572)
			(layers "F.Cu" "F.Mask" "F.Paste")
			(net "DUT_VDD")
		)
		(pad "AD18" smd circle
			(at -0.999998 4.99999 270)
			(size 0.4572 0.4572)
			(layers "F.Cu" "F.Mask" "F.Paste")
			(net "GND")
		)
		(pad "AD19" smd circle
			(at 0 4.99999 270)
			(size 0.4572 0.4572)
			(layers "F.Cu" "F.Mask" "F.Paste")
			(net "DUT_VDD")
		)
		(pad "AD20" smd circle
			(at 0.999998 4.99999 270)
			(size 0.4572 0.4572)
			(layers "F.Cu" "F.Mask" "F.Paste")
			(net "GND")
		)
		(pad "AD21" smd circle
			(at 1.999996 4.99999 270)
			(size 0.4572 0.4572)
			(layers "F.Cu" "F.Mask" "F.Paste")
			(net "DUT_VDD")
		)
		(pad "AD22" smd circle
			(at 2.999994 4.99999 270)
			(size 0.4572 0.4572)
			(layers "F.Cu" "F.Mask" "F.Paste")
			(net "GND")
		)
		(pad "AD23" smd circle
			(at 3.999992 4.99999 270)
			(size 0.4572 0.4572)
			(layers "F.Cu" "F.Mask" "F.Paste")
			(net "DUT_VDD")
		)
		(pad "AD24" smd circle
			(at 4.99999 4.99999 270)
			(size 0.4572 0.4572)
			(layers "F.Cu" "F.Mask" "F.Paste")
			(net "GND")
		)
		(pad "AD25" smd circle
			(at 5.999988 4.99999 270)
			(size 0.4572 0.4572)
			(layers "F.Cu" "F.Mask" "F.Paste")
			(net "DUT_VDD")
		)
		(pad "AD26" smd circle
			(at 6.999986 4.99999 270)
			(size 0.4572 0.4572)
			(layers "F.Cu" "F.Mask" "F.Paste")
			(net "GND")
		)
		(pad "AD27" smd circle
			(at 7.999984 4.99999 270)
			(size 0.4572 0.4572)
			(layers "F.Cu" "F.Mask" "F.Paste")
			(net "LBI_ADDR_8")
		)
		(pad "AD28" smd circle
			(at 8.999982 4.99999 270)
			(size 0.4572 0.4572)
			(layers "F.Cu" "F.Mask" "F.Paste")
			(net "DUT_VDDO")
		)
		(pad "AD29" smd circle
			(at 9.99998 4.99999 270)
			(size 0.4572 0.4572)
			(layers "F.Cu" "F.Mask" "F.Paste")
			(net "LBI_ADDR_7_R")
		)
		(pad "AD30" smd circle
			(at 10.999978 4.99999 270)
			(size 0.4572 0.4572)
			(layers "F.Cu" "F.Mask" "F.Paste")
			(net "LBI_ADDR_6_R")
		)
		(pad "AD31" smd circle
			(at 11.999976 4.99999 270)
			(size 0.4572 0.4572)
			(layers "F.Cu" "F.Mask" "F.Paste")
			(net "LBI_ADDR_5_R")
		)
		(pad "AD32" smd circle
			(at 12.999974 4.99999 270)
			(size 0.4572 0.4572)
			(layers "F.Cu" "F.Mask" "F.Paste")
			(net "PCIE_REFCLK_S5_P")
		)
		(pad "AD33" smd circle
			(at 13.999972 4.99999 270)
			(size 0.4572 0.4572)
			(layers "F.Cu" "F.Mask" "F.Paste")
			(net "PCIE_REFCLK_S5_N")
		)
		(pad "AD34" smd circle
			(at 14.99997 4.99999 270)
			(size 0.4572 0.4572)
			(layers "F.Cu" "F.Mask" "F.Paste")
			(net "GND")
		)
		(pad "AD35" smd circle
			(at 15.999968 4.99999 270)
			(size 0.4572 0.4572)
			(layers "F.Cu" "F.Mask" "F.Paste")
			(net "PCIE_RX_P92")
		)
		(pad "AD36" smd circle
			(at 16.999966 4.99999 270)
			(size 0.4572 0.4572)
			(layers "F.Cu" "F.Mask" "F.Paste")
			(net "PCIE_RX_N92")
		)
		(pad "AE1" smd circle
			(at -17.999964 5.999988 270)
			(size 0.4572 0.4572)
			(layers "F.Cu" "F.Mask" "F.Paste")
			(net "PCIE_TX_CAP_N53")
		)
		(pad "AE2" smd circle
			(at -16.999966 5.999988 270)
			(size 0.4572 0.4572)
			(layers "F.Cu" "F.Mask" "F.Paste")
			(net "PCIE_TX_CAP_P53")
		)
		(pad "AE3" smd circle
			(at -15.999968 5.999988 270)
			(size 0.4572 0.4572)
			(layers "F.Cu" "F.Mask" "F.Paste")
			(net "GND")
		)
		(pad "AE4" smd circle
			(at -14.99997 5.999988 270)
			(size 0.4572 0.4572)
			(layers "F.Cu" "F.Mask" "F.Paste")
			(net "PCIE_RX_N53")
		)
		(pad "AE5" smd circle
			(at -13.999972 5.999988 270)
			(size 0.4572 0.4572)
			(layers "F.Cu" "F.Mask" "F.Paste")
			(net "PCIE_RX_P53")
		)
		(pad "AE6" smd circle
			(at -12.999974 5.999988 270)
			(size 0.4572 0.4572)
			(layers "F.Cu" "F.Mask" "F.Paste")
			(net "GND")
		)
		(pad "AE7" smd circle
			(at -11.999976 5.999988 270)
			(size 0.4572 0.4572)
			(layers "F.Cu" "F.Mask" "F.Paste")
			(net "DUT_AVD_PCIE")
		)
		(pad "AE8" smd circle
			(at -10.999978 5.999988 270)
			(size 0.4572 0.4572)
			(layers "F.Cu" "F.Mask" "F.Paste")
			(net "GND")
		)
		(pad "AE9" smd circle
			(at -9.99998 5.999988 270)
			(size 0.4572 0.4572)
			(layers "F.Cu" "F.Mask" "F.Paste")
			(net "GND")
		)
		(pad "AE10" smd circle
			(at -8.999982 5.999988 270)
			(size 0.4572 0.4572)
			(layers "F.Cu" "F.Mask" "F.Paste")
			(net "GND")
		)
		(pad "AE11" smd circle
			(at -7.999984 5.999988 270)
			(size 0.4572 0.4572)
			(layers "F.Cu" "F.Mask" "F.Paste")
			(net "GND")
		)
		(pad "AE12" smd circle
			(at -6.999986 5.999988 270)
			(size 0.4572 0.4572)
			(layers "F.Cu" "F.Mask" "F.Paste")
			(net "GND")
		)
		(pad "AE13" smd circle
			(at -5.999988 5.999988 270)
			(size 0.4572 0.4572)
			(layers "F.Cu" "F.Mask" "F.Paste")
			(net "GND")
		)
		(pad "AE14" smd circle
			(at -4.99999 5.999988 270)
			(size 0.4572 0.4572)
			(layers "F.Cu" "F.Mask" "F.Paste")
			(net "DUT_VDD")
		)
		(pad "AE15" smd circle
			(at -3.999992 5.999988 270)
			(size 0.4572 0.4572)
			(layers "F.Cu" "F.Mask" "F.Paste")
			(net "GND")
		)
		(pad "AE16" smd circle
			(at -2.999994 5.999988 270)
			(size 0.4572 0.4572)
			(layers "F.Cu" "F.Mask" "F.Paste")
			(net "DUT_VDD")
		)
		(pad "AE17" smd circle
			(at -1.999996 5.999988 270)
			(size 0.4572 0.4572)
			(layers "F.Cu" "F.Mask" "F.Paste")
			(net "GND")
		)
		(pad "AE18" smd circle
			(at -0.999998 5.999988 270)
			(size 0.4572 0.4572)
			(layers "F.Cu" "F.Mask" "F.Paste")
			(net "DUT_VDD")
		)
		(pad "AE19" smd circle
			(at 0 5.999988 270)
			(size 0.4572 0.4572)
			(layers "F.Cu" "F.Mask" "F.Paste")
			(net "GND")
		)
		(pad "AE20" smd circle
			(at 0.999998 5.999988 270)
			(size 0.4572 0.4572)
			(layers "F.Cu" "F.Mask" "F.Paste")
			(net "DUT_VDD")
		)
		(pad "AE21" smd circle
			(at 1.999996 5.999988 270)
			(size 0.4572 0.4572)
			(layers "F.Cu" "F.Mask" "F.Paste")
			(net "GND")
		)
		(pad "AE22" smd circle
			(at 2.999994 5.999988 270)
			(size 0.4572 0.4572)
			(layers "F.Cu" "F.Mask" "F.Paste")
			(net "DUT_VDD")
		)
		(pad "AE23" smd circle
			(at 3.999992 5.999988 270)
			(size 0.4572 0.4572)
			(layers "F.Cu" "F.Mask" "F.Paste")
			(net "GND")
		)
		(pad "AE24" smd circle
			(at 4.99999 5.999988 270)
			(size 0.4572 0.4572)
			(layers "F.Cu" "F.Mask" "F.Paste")
			(net "DUT_VDD")
		)
		(pad "AE25" smd circle
			(at 5.999988 5.999988 270)
			(size 0.4572 0.4572)
			(layers "F.Cu" "F.Mask" "F.Paste")
			(net "GND")
		)
		(pad "AE26" smd circle
			(at 6.999986 5.999988 270)
			(size 0.4572 0.4572)
			(layers "F.Cu" "F.Mask" "F.Paste")
			(net "DUT_VDD")
		)
		(pad "AE27" smd circle
			(at 7.999984 5.999988 270)
			(size 0.4572 0.4572)
			(layers "F.Cu" "F.Mask" "F.Paste")
			(net "RMII_TX_EN")
		)
		(pad "AE28" smd circle
			(at 8.999982 5.999988 270)
			(size 0.4572 0.4572)
			(layers "F.Cu" "F.Mask" "F.Paste")
			(net "LBI_ADDR_12_R")
		)
		(pad "AE29" smd circle
			(at 9.99998 5.999988 270)
			(size 0.4572 0.4572)
			(layers "F.Cu" "F.Mask" "F.Paste")
			(net "GND")
		)
		(pad "AE30" smd circle
			(at 10.999978 5.999988 270)
			(size 0.4572 0.4572)
			(layers "F.Cu" "F.Mask" "F.Paste")
			(net "Net_325")
		)
		(pad "AE31" smd circle
			(at 11.999976 5.999988 270)
			(size 0.4572 0.4572)
			(layers "F.Cu" "F.Mask" "F.Paste")
			(net "LBI_ADDR_10")
		)
		(pad "AE32" smd circle
			(at 12.999974 5.999988 270)
			(size 0.4572 0.4572)
			(layers "F.Cu" "F.Mask" "F.Paste")
			(net "GND")
		)
		(pad "AE33" smd circle
			(at 13.999972 5.999988 270)
			(size 0.4572 0.4572)
			(layers "F.Cu" "F.Mask" "F.Paste")
			(net "LBI_ADDR_9")
		)
		(pad "AE34" smd circle
			(at 14.99997 5.999988 270)
			(size 0.4572 0.4572)
			(layers "F.Cu" "F.Mask" "F.Paste")
			(net "DUT_VDDO")
		)
		(pad "AE35" smd circle
			(at 15.999968 5.999988 270)
			(size 0.4572 0.4572)
			(layers "F.Cu" "F.Mask" "F.Paste")
			(net "GND")
		)
		(pad "AE36" smd circle
			(at 16.999966 5.999988 270)
			(size 0.4572 0.4572)
			(layers "F.Cu" "F.Mask" "F.Paste")
			(net "PCIE_RX_P91")
		)
		(pad "AE37" smd circle
			(at 17.999964 5.999988 270)
			(size 0.4572 0.4572)
			(layers "F.Cu" "F.Mask" "F.Paste")
			(net "PCIE_RX_N91")
		)
		(pad "AF2" smd circle
			(at -16.999966 6.999986 270)
			(size 0.4572 0.4572)
			(layers "F.Cu" "F.Mask" "F.Paste")
			(net "PCIE_TX_CAP_N54")
		)
		(pad "AF3" smd circle
			(at -15.999968 6.999986 270)
			(size 0.4572 0.4572)
			(layers "F.Cu" "F.Mask" "F.Paste")
			(net "PCIE_TX_CAP_P54")
		)
		(pad "AF4" smd circle
			(at -14.99997 6.999986 270)
			(size 0.4572 0.4572)
			(layers "F.Cu" "F.Mask" "F.Paste")
			(net "GND")
		)
		(pad "AF5" smd circle
			(at -13.999972 6.999986 270)
			(size 0.4572 0.4572)
			(layers "F.Cu" "F.Mask" "F.Paste")
			(net "PCIE_RX_N54")
		)
		(pad "AF6" smd circle
			(at -12.999974 6.999986 270)
			(size 0.4572 0.4572)
			(layers "F.Cu" "F.Mask" "F.Paste")
			(net "PCIE_RX_P54")
		)
		(pad "AF7" smd circle
			(at -11.999976 6.999986 270)
			(size 0.4572 0.4572)
			(layers "F.Cu" "F.Mask" "F.Paste")
			(net "DUT_AVD_PCIE")
		)
		(pad "AF8" smd circle
			(at -10.999978 6.999986 270)
			(size 0.4572 0.4572)
			(layers "F.Cu" "F.Mask" "F.Paste")
			(net "GND")
		)
		(pad "AF9" smd circle
			(at -9.99998 6.999986 270)
			(size 0.4572 0.4572)
			(layers "F.Cu" "F.Mask" "F.Paste")
			(net "GND")
		)
		(pad "AF10" smd circle
			(at -8.999982 6.999986 270)
			(size 0.4572 0.4572)
			(layers "F.Cu" "F.Mask" "F.Paste")
			(net "GND")
		)
		(pad "AF11" smd circle
			(at -7.999984 6.999986 270)
			(size 0.4572 0.4572)
			(layers "F.Cu" "F.Mask" "F.Paste")
			(net "GND")
		)
		(pad "AF12" smd circle
			(at -6.999986 6.999986 270)
			(size 0.4572 0.4572)
			(layers "F.Cu" "F.Mask" "F.Paste")
			(net "GND")
		)
		(pad "AF13" smd circle
			(at -5.999988 6.999986 270)
			(size 0.4572 0.4572)
			(layers "F.Cu" "F.Mask" "F.Paste")
			(net "DUT_AVD_PCIE")
		)
		(pad "AF14" smd circle
			(at -4.99999 6.999986 270)
			(size 0.4572 0.4572)
			(layers "F.Cu" "F.Mask" "F.Paste")
			(net "GND")
		)
		(pad "AF15" smd circle
			(at -3.999992 6.999986 270)
			(size 0.4572 0.4572)
			(layers "F.Cu" "F.Mask" "F.Paste")
			(net "DUT_VDD")
		)
		(pad "AF16" smd circle
			(at -2.999994 6.999986 270)
			(size 0.4572 0.4572)
			(layers "F.Cu" "F.Mask" "F.Paste")
			(net "GND")
		)
		(pad "AF17" smd circle
			(at -1.999996 6.999986 270)
			(size 0.4572 0.4572)
			(layers "F.Cu" "F.Mask" "F.Paste")
			(net "DUT_VDD")
		)
		(pad "AF18" smd circle
			(at -0.999998 6.999986 270)
			(size 0.4572 0.4572)
			(layers "F.Cu" "F.Mask" "F.Paste")
			(net "GND")
		)
		(pad "AF19" smd circle
			(at 0 6.999986 270)
			(size 0.4572 0.4572)
			(layers "F.Cu" "F.Mask" "F.Paste")
			(net "DUT_VDD")
		)
		(pad "AF20" smd circle
			(at 0.999998 6.999986 270)
			(size 0.4572 0.4572)
			(layers "F.Cu" "F.Mask" "F.Paste")
			(net "GND")
		)
		(pad "AF21" smd circle
			(at 1.999996 6.999986 270)
			(size 0.4572 0.4572)
			(layers "F.Cu" "F.Mask" "F.Paste")
			(net "DUT_AVD_PCIE")
		)
		(pad "AF22" smd circle
			(at 2.999994 6.999986 270)
			(size 0.4572 0.4572)
			(layers "F.Cu" "F.Mask" "F.Paste")
			(net "GND")
		)
		(pad "AF23" smd circle
			(at 3.999992 6.999986 270)
			(size 0.4572 0.4572)
			(layers "F.Cu" "F.Mask" "F.Paste")
			(net "DUT_VDD")
		)
		(pad "AF24" smd circle
			(at 4.99999 6.999986 270)
			(size 0.4572 0.4572)
			(layers "F.Cu" "F.Mask" "F.Paste")
			(net "GND")
		)
		(pad "AF25" smd circle
			(at 5.999988 6.999986 270)
			(size 0.4572 0.4572)
			(layers "F.Cu" "F.Mask" "F.Paste")
			(net "DUT_VDD")
		)
		(pad "AF26" smd circle
			(at 6.999986 6.999986 270)
			(size 0.4572 0.4572)
			(layers "F.Cu" "F.Mask" "F.Paste")
			(net "EJTAG_TCK_R")
		)
		(pad "AF27" smd circle
			(at 7.999984 6.999986 270)
			(size 0.4572 0.4572)
			(layers "F.Cu" "F.Mask" "F.Paste")
			(net "RMII_CRS_DV")
		)
		(pad "AF28" smd circle
			(at 8.999982 6.999986 270)
			(size 0.4572 0.4572)
			(layers "F.Cu" "F.Mask" "F.Paste")
			(net "RMII_REF_CLK")
		)
		(pad "AF29" smd circle
			(at 9.99998 6.999986 270)
			(size 0.4572 0.4572)
			(layers "F.Cu" "F.Mask" "F.Paste")
			(net "RMII_RXD_1")
		)
		(pad "AF30" smd circle
			(at 10.999978 6.999986 270)
			(size 0.4572 0.4572)
			(layers "F.Cu" "F.Mask" "F.Paste")
			(net "RMII_RXD_0")
		)
		(pad "AF31" smd circle
			(at 11.999976 6.999986 270)
			(size 0.4572 0.4572)
			(layers "F.Cu" "F.Mask" "F.Paste")
			(net "RMII_RX_ER")
		)
		(pad "AF32" smd circle
			(at 12.999974 6.999986 270)
			(size 0.4572 0.4572)
			(layers "F.Cu" "F.Mask" "F.Paste")
			(net "RMII_TXD_1")
		)
		(pad "AF33" smd circle
			(at 13.999972 6.999986 270)
			(size 0.4572 0.4572)
			(layers "F.Cu" "F.Mask" "F.Paste")
			(net "RMII_TXD_0")
		)
		(pad "AF34" smd circle
			(at 14.99997 6.999986 270)
			(size 0.4572 0.4572)
			(layers "F.Cu" "F.Mask" "F.Paste")
			(net "GND")
		)
		(pad "AF35" smd circle
			(at 15.999968 6.999986 270)
			(size 0.4572 0.4572)
			(layers "F.Cu" "F.Mask" "F.Paste")
			(net "PCIE_RX_P90")
		)
		(pad "AF36" smd circle
			(at 16.999966 6.999986 270)
			(size 0.4572 0.4572)
			(layers "F.Cu" "F.Mask" "F.Paste")
			(net "PCIE_RX_N90")
		)
		(pad "AG1" smd circle
			(at -17.999964 7.999984 270)
			(size 0.4572 0.4572)
			(layers "F.Cu" "F.Mask" "F.Paste")
			(net "PCIE_TX_CAP_N55")
		)
		(pad "AG2" smd circle
			(at -16.999966 7.999984 270)
			(size 0.4572 0.4572)
			(layers "F.Cu" "F.Mask" "F.Paste")
			(net "PCIE_TX_CAP_P55")
		)
		(pad "AG3" smd circle
			(at -15.999968 7.999984 270)
			(size 0.4572 0.4572)
			(layers "F.Cu" "F.Mask" "F.Paste")
			(net "GND")
		)
		(pad "AG4" smd circle
			(at -14.99997 7.999984 270)
			(size 0.4572 0.4572)
			(layers "F.Cu" "F.Mask" "F.Paste")
			(net "PCIE_RX_N55")
		)
		(pad "AG5" smd circle
			(at -13.999972 7.999984 270)
			(size 0.4572 0.4572)
			(layers "F.Cu" "F.Mask" "F.Paste")
			(net "PCIE_RX_P55")
		)
		(pad "AG6" smd circle
			(at -12.999974 7.999984 270)
			(size 0.4572 0.4572)
			(layers "F.Cu" "F.Mask" "F.Paste")
			(net "GND")
		)
		(pad "AG7" smd circle
			(at -11.999976 7.999984 270)
			(size 0.4572 0.4572)
			(layers "F.Cu" "F.Mask" "F.Paste")
			(net "DUT_AVD_PCIE")
		)
		(pad "AG8" smd circle
			(at -10.999978 7.999984 270)
			(size 0.4572 0.4572)
			(layers "F.Cu" "F.Mask" "F.Paste")
			(net "GND")
		)
		(pad "AG9" smd circle
			(at -9.99998 7.999984 270)
			(size 0.4572 0.4572)
			(layers "F.Cu" "F.Mask" "F.Paste")
			(net "GND")
		)
		(pad "AG10" smd circle
			(at -8.999982 7.999984 270)
			(size 0.4572 0.4572)
			(layers "F.Cu" "F.Mask" "F.Paste")
			(net "GND")
		)
		(pad "AG11" smd circle
			(at -7.999984 7.999984 270)
			(size 0.4572 0.4572)
			(layers "F.Cu" "F.Mask" "F.Paste")
			(net "GND")
		)
		(pad "AG12" smd circle
			(at -6.999986 7.999984 270)
			(size 0.4572 0.4572)
			(layers "F.Cu" "F.Mask" "F.Paste")
			(net "GND")
		)
		(pad "AG13" smd circle
			(at -5.999988 7.999984 270)
			(size 0.4572 0.4572)
			(layers "F.Cu" "F.Mask" "F.Paste")
			(net "DUT_AVD_PCIE_Q")
		)
		(pad "AG14" smd circle
			(at -4.99999 7.999984 270)
			(size 0.4572 0.4572)
			(layers "F.Cu" "F.Mask" "F.Paste")
			(net "GND")
		)
		(pad "AG15" smd circle
			(at -3.999992 7.999984 270)
			(size 0.4572 0.4572)
			(layers "F.Cu" "F.Mask" "F.Paste")
			(net "GND")
		)
		(pad "AG16" smd circle
			(at -2.999994 7.999984 270)
			(size 0.4572 0.4572)
			(layers "F.Cu" "F.Mask" "F.Paste")
			(net "GND")
		)
		(pad "AG17" smd circle
			(at -1.999996 7.999984 270)
			(size 0.4572 0.4572)
			(layers "F.Cu" "F.Mask" "F.Paste")
			(net "GND")
		)
		(pad "AG18" smd circle
			(at -0.999998 7.999984 270)
			(size 0.4572 0.4572)
			(layers "F.Cu" "F.Mask" "F.Paste")
			(net "GND")
		)
		(pad "AG19" smd circle
			(at 0 7.999984 270)
			(size 0.4572 0.4572)
			(layers "F.Cu" "F.Mask" "F.Paste")
			(net "GND")
		)
		(pad "AG20" smd circle
			(at 0.999998 7.999984 270)
			(size 0.4572 0.4572)
			(layers "F.Cu" "F.Mask" "F.Paste")
			(net "DUT_AVD_PCIE_Q")
		)
		(pad "AG21" smd circle
			(at 1.999996 7.999984 270)
			(size 0.4572 0.4572)
			(layers "F.Cu" "F.Mask" "F.Paste")
			(net "GND")
		)
		(pad "AG22" smd circle
			(at 2.999994 7.999984 270)
			(size 0.4572 0.4572)
			(layers "F.Cu" "F.Mask" "F.Paste")
			(net "GND")
		)
		(pad "AG23" smd circle
			(at 3.999992 7.999984 270)
			(size 0.4572 0.4572)
			(layers "F.Cu" "F.Mask" "F.Paste")
			(net "GND")
		)
		(pad "AG24" smd circle
			(at 4.99999 7.999984 270)
			(size 0.4572 0.4572)
			(layers "F.Cu" "F.Mask" "F.Paste")
			(net "GND")
		)
		(pad "AG25" smd circle
			(at 5.999988 7.999984 270)
			(size 0.4572 0.4572)
			(layers "F.Cu" "F.Mask" "F.Paste")
			(net "GND")
		)
		(pad "AG26" smd circle
			(at 6.999986 7.999984 270)
			(size 0.4572 0.4572)
			(layers "F.Cu" "F.Mask" "F.Paste")
			(net "DUT_TDI_R")
		)
		(pad "AG27" smd circle
			(at 7.999984 7.999984 270)
			(size 0.4572 0.4572)
			(layers "F.Cu" "F.Mask" "F.Paste")
			(net "EJTAG_TMS_R")
		)
		(pad "AG28" smd circle
			(at 8.999982 7.999984 270)
			(size 0.4572 0.4572)
			(layers "F.Cu" "F.Mask" "F.Paste")
			(net "EJTAG_TRSTB_R")
		)
		(pad "AG29" smd circle
			(at 9.99998 7.999984 270)
			(size 0.4572 0.4572)
			(layers "F.Cu" "F.Mask" "F.Paste")
			(net "EJTAG_RSTB")
		)
		(pad "AG30" smd circle
			(at 10.999978 7.999984 270)
			(size 0.4572 0.4572)
			(layers "F.Cu" "F.Mask" "F.Paste")
			(net "DUT_TAP_SEL_R")
		)
		(pad "AG31" smd circle
			(at 11.999976 7.999984 270)
			(size 0.4572 0.4572)
			(layers "F.Cu" "F.Mask" "F.Paste")
			(net "DUT_VDDO")
		)
		(pad "AG32" smd circle
			(at 12.999974 7.999984 270)
			(size 0.4572 0.4572)
			(layers "F.Cu" "F.Mask" "F.Paste")
			(net "PM8536_RST#")
		)
		(pad "AG33" smd circle
			(at 13.999972 7.999984 270)
			(size 0.4572 0.4572)
			(layers "F.Cu" "F.Mask" "F.Paste")
			(net "DUT_TDO_R")
		)
		(pad "AG34" smd circle
			(at 14.99997 7.999984 270)
			(size 0.4572 0.4572)
			(layers "F.Cu" "F.Mask" "F.Paste")
			(net "DUT_VDDO")
		)
		(pad "AG35" smd circle
			(at 15.999968 7.999984 270)
			(size 0.4572 0.4572)
			(layers "F.Cu" "F.Mask" "F.Paste")
			(net "GND")
		)
		(pad "AG36" smd circle
			(at 16.999966 7.999984 270)
			(size 0.4572 0.4572)
			(layers "F.Cu" "F.Mask" "F.Paste")
			(net "PCIE_RX_P89")
		)
		(pad "AG37" smd circle
			(at 17.999964 7.999984 270)
			(size 0.4572 0.4572)
			(layers "F.Cu" "F.Mask" "F.Paste")
			(net "PCIE_RX_N89")
		)
		(pad "AH1" smd circle
			(at -17.999964 8.999982 270)
			(size 0.4572 0.4572)
			(layers "F.Cu" "F.Mask" "F.Paste")
			(net "GND")
		)
		(pad "AH2" smd circle
			(at -16.999966 8.999982 270)
			(size 0.4572 0.4572)
			(layers "F.Cu" "F.Mask" "F.Paste")
			(net "GND")
		)
		(pad "AH3" smd circle
			(at -15.999968 8.999982 270)
			(size 0.4572 0.4572)
			(layers "F.Cu" "F.Mask" "F.Paste")
			(net "GND")
		)
		(pad "AH4" smd circle
			(at -14.99997 8.999982 270)
			(size 0.4572 0.4572)
			(layers "F.Cu" "F.Mask" "F.Paste")
			(net "GND")
		)
		(pad "AH5" smd circle
			(at -13.999972 8.999982 270)
			(size 0.4572 0.4572)
			(layers "F.Cu" "F.Mask" "F.Paste")
			(net "GND")
		)
		(pad "AH6" smd circle
			(at -12.999974 8.999982 270)
			(size 0.4572 0.4572)
			(layers "F.Cu" "F.Mask" "F.Paste")
			(net "GND")
		)
		(pad "AH7" smd circle
			(at -11.999976 8.999982 270)
			(size 0.4572 0.4572)
			(layers "F.Cu" "F.Mask" "F.Paste")
			(net "DUT_AVD_PCIE")
		)
		(pad "AH8" smd circle
			(at -10.999978 8.999982 270)
			(size 0.4572 0.4572)
			(layers "F.Cu" "F.Mask" "F.Paste")
			(net "GND")
		)
		(pad "AH9" smd circle
			(at -9.99998 8.999982 270)
			(size 0.4572 0.4572)
			(layers "F.Cu" "F.Mask" "F.Paste")
			(net "GND")
		)
		(pad "AH10" smd circle
			(at -8.999982 8.999982 270)
			(size 0.4572 0.4572)
			(layers "F.Cu" "F.Mask" "F.Paste")
			(net "GND")
		)
		(pad "AH11" smd circle
			(at -7.999984 8.999982 270)
			(size 0.4572 0.4572)
			(layers "F.Cu" "F.Mask" "F.Paste")
			(net "GND")
		)
		(pad "AH12" smd circle
			(at -6.999986 8.999982 270)
			(size 0.4572 0.4572)
			(layers "F.Cu" "F.Mask" "F.Paste")
			(net "GND")
		)
		(pad "AH13" smd circle
			(at -5.999988 8.999982 270)
			(size 0.4572 0.4572)
			(layers "F.Cu" "F.Mask" "F.Paste")
			(net "GND")
		)
		(pad "AH14" smd circle
			(at -4.99999 8.999982 270)
			(size 0.4572 0.4572)
			(layers "F.Cu" "F.Mask" "F.Paste")
			(net "GND")
		)
		(pad "AH15" smd circle
			(at -3.999992 8.999982 270)
			(size 0.4572 0.4572)
			(layers "F.Cu" "F.Mask" "F.Paste")
			(net "GND")
		)
		(pad "AH16" smd circle
			(at -2.999994 8.999982 270)
			(size 0.4572 0.4572)
			(layers "F.Cu" "F.Mask" "F.Paste")
			(net "GND")
		)
		(pad "AH17" smd circle
			(at -1.999996 8.999982 270)
			(size 0.4572 0.4572)
			(layers "F.Cu" "F.Mask" "F.Paste")
			(net "GND")
		)
		(pad "AH18" smd circle
			(at -0.999998 8.999982 270)
			(size 0.4572 0.4572)
			(layers "F.Cu" "F.Mask" "F.Paste")
			(net "GND")
		)
		(pad "AH19" smd circle
			(at 0 8.999982 270)
			(size 0.4572 0.4572)
			(layers "F.Cu" "F.Mask" "F.Paste")
			(net "GND")
		)
		(pad "AH20" smd circle
			(at 0.999998 8.999982 270)
			(size 0.4572 0.4572)
			(layers "F.Cu" "F.Mask" "F.Paste")
			(net "GND")
		)
		(pad "AH21" smd circle
			(at 1.999996 8.999982 270)
			(size 0.4572 0.4572)
			(layers "F.Cu" "F.Mask" "F.Paste")
			(net "GND")
		)
		(pad "AH22" smd circle
			(at 2.999994 8.999982 270)
			(size 0.4572 0.4572)
			(layers "F.Cu" "F.Mask" "F.Paste")
			(net "GND")
		)
		(pad "AH23" smd circle
			(at 3.999992 8.999982 270)
			(size 0.4572 0.4572)
			(layers "F.Cu" "F.Mask" "F.Paste")
			(net "GND")
		)
		(pad "AH24" smd circle
			(at 4.99999 8.999982 270)
			(size 0.4572 0.4572)
			(layers "F.Cu" "F.Mask" "F.Paste")
			(net "GND")
		)
		(pad "AH25" smd circle
			(at 5.999988 8.999982 270)
			(size 0.4572 0.4572)
			(layers "F.Cu" "F.Mask" "F.Paste")
			(net "GND")
		)
		(pad "AH26" smd circle
			(at 6.999986 8.999982 270)
			(size 0.4572 0.4572)
			(layers "F.Cu" "F.Mask" "F.Paste")
			(net "LINK")
		)
		(pad "AH27" smd circle
			(at 7.999984 8.999982 270)
			(size 0.4572 0.4572)
			(layers "F.Cu" "F.Mask" "F.Paste")
			(net "MDIO")
		)
		(pad "AH28" smd circle
			(at 8.999982 8.999982 270)
			(size 0.4572 0.4572)
			(layers "F.Cu" "F.Mask" "F.Paste")
			(net "Net_2106")
		)
		(pad "AH29" smd circle
			(at 9.99998 8.999982 270)
			(size 0.4572 0.4572)
			(layers "F.Cu" "F.Mask" "F.Paste")
			(net "GND")
		)
		(pad "AH30" smd circle
			(at 10.999978 8.999982 270)
			(size 0.4572 0.4572)
			(layers "F.Cu" "F.Mask" "F.Paste")
			(net "MDC")
		)
		(pad "AH31" smd circle
			(at 11.999976 8.999982 270)
			(size 0.4572 0.4572)
			(layers "F.Cu" "F.Mask" "F.Paste")
			(net "VSS_571")
		)
		(pad "AH32" smd circle
			(at 12.999974 8.999982 270)
			(size 0.4572 0.4572)
			(layers "F.Cu" "F.Mask" "F.Paste")
			(net "GND")
		)
		(pad "AH33" smd circle
			(at 13.999972 8.999982 270)
			(size 0.4572 0.4572)
			(layers "F.Cu" "F.Mask" "F.Paste")
			(net "BOOT_RECOVERY#")
		)
		(pad "AH34" smd circle
			(at 14.99997 8.999982 270)
			(size 0.4572 0.4572)
			(layers "F.Cu" "F.Mask" "F.Paste")
			(net "GND")
		)
		(pad "AH35" smd circle
			(at 15.999968 8.999982 270)
			(size 0.4572 0.4572)
			(layers "F.Cu" "F.Mask" "F.Paste")
			(net "PCIE_RX_P88")
		)
		(pad "AH36" smd circle
			(at 16.999966 8.999982 270)
			(size 0.4572 0.4572)
			(layers "F.Cu" "F.Mask" "F.Paste")
			(net "PCIE_RX_N88")
		)
		(pad "AJ2" smd circle
			(at -16.999966 9.99998 270)
			(size 0.4572 0.4572)
			(layers "F.Cu" "F.Mask" "F.Paste")
			(net "PCIE_TX_CAP_N56")
		)
		(pad "AJ3" smd circle
			(at -15.999968 9.99998 270)
			(size 0.4572 0.4572)
			(layers "F.Cu" "F.Mask" "F.Paste")
			(net "PCIE_TX_CAP_P56")
		)
		(pad "AJ4" smd circle
			(at -14.99997 9.99998 270)
			(size 0.4572 0.4572)
			(layers "F.Cu" "F.Mask" "F.Paste")
			(net "GND")
		)
		(pad "AJ5" smd circle
			(at -13.999972 9.99998 270)
			(size 0.4572 0.4572)
			(layers "F.Cu" "F.Mask" "F.Paste")
			(net "PCIE_RX_N56")
		)
		(pad "AJ6" smd circle
			(at -12.999974 9.99998 270)
			(size 0.4572 0.4572)
			(layers "F.Cu" "F.Mask" "F.Paste")
			(net "PCIE_RX_P56")
		)
		(pad "AJ7" smd circle
			(at -11.999976 9.99998 270)
			(size 0.4572 0.4572)
			(layers "F.Cu" "F.Mask" "F.Paste")
			(net "DUT_AVD_PCIE")
		)
		(pad "AJ8" smd circle
			(at -10.999978 9.99998 270)
			(size 0.4572 0.4572)
			(layers "F.Cu" "F.Mask" "F.Paste")
			(net "GND")
		)
		(pad "AJ9" smd circle
			(at -9.99998 9.99998 270)
			(size 0.4572 0.4572)
			(layers "F.Cu" "F.Mask" "F.Paste")
			(net "GND")
		)
		(pad "AJ10" smd circle
			(at -8.999982 9.99998 270)
			(size 0.4572 0.4572)
			(layers "F.Cu" "F.Mask" "F.Paste")
			(net "GND")
		)
		(pad "AJ11" smd circle
			(at -7.999984 9.99998 270)
			(size 0.4572 0.4572)
			(layers "F.Cu" "F.Mask" "F.Paste")
			(net "GND")
		)
		(pad "AJ12" smd circle
			(at -6.999986 9.99998 270)
			(size 0.4572 0.4572)
			(layers "F.Cu" "F.Mask" "F.Paste")
			(net "GND")
		)
		(pad "AJ13" smd circle
			(at -5.999988 9.99998 270)
			(size 0.4572 0.4572)
			(layers "F.Cu" "F.Mask" "F.Paste")
			(net "GND")
		)
		(pad "AJ14" smd circle
			(at -4.99999 9.99998 270)
			(size 0.4572 0.4572)
			(layers "F.Cu" "F.Mask" "F.Paste")
			(net "GND")
		)
		(pad "AJ15" smd circle
			(at -3.999992 9.99998 270)
			(size 0.4572 0.4572)
			(layers "F.Cu" "F.Mask" "F.Paste")
			(net "GND")
		)
		(pad "AJ16" smd circle
			(at -2.999994 9.99998 270)
			(size 0.4572 0.4572)
			(layers "F.Cu" "F.Mask" "F.Paste")
			(net "GND")
		)
		(pad "AJ17" smd circle
			(at -1.999996 9.99998 270)
			(size 0.4572 0.4572)
			(layers "F.Cu" "F.Mask" "F.Paste")
			(net "GND")
		)
		(pad "AJ18" smd circle
			(at -0.999998 9.99998 270)
			(size 0.4572 0.4572)
			(layers "F.Cu" "F.Mask" "F.Paste")
			(net "GND")
		)
		(pad "AJ19" smd circle
			(at 0 9.99998 270)
			(size 0.4572 0.4572)
			(layers "F.Cu" "F.Mask" "F.Paste")
			(net "GND")
		)
		(pad "AJ20" smd circle
			(at 0.999998 9.99998 270)
			(size 0.4572 0.4572)
			(layers "F.Cu" "F.Mask" "F.Paste")
			(net "DUT_AVD_PCIE")
		)
		(pad "AJ21" smd circle
			(at 1.999996 9.99998 270)
			(size 0.4572 0.4572)
			(layers "F.Cu" "F.Mask" "F.Paste")
			(net "GND")
		)
		(pad "AJ22" smd circle
			(at 2.999994 9.99998 270)
			(size 0.4572 0.4572)
			(layers "F.Cu" "F.Mask" "F.Paste")
			(net "GND")
		)
		(pad "AJ23" smd circle
			(at 3.999992 9.99998 270)
			(size 0.4572 0.4572)
			(layers "F.Cu" "F.Mask" "F.Paste")
			(net "GND")
		)
		(pad "AJ24" smd circle
			(at 4.99999 9.99998 270)
			(size 0.4572 0.4572)
			(layers "F.Cu" "F.Mask" "F.Paste")
			(net "GND")
		)
		(pad "AJ25" smd circle
			(at 5.999988 9.99998 270)
			(size 0.4572 0.4572)
			(layers "F.Cu" "F.Mask" "F.Paste")
			(net "DUT_AVD_PCIE")
		)
		(pad "AJ26" smd circle
			(at 6.999986 9.99998 270)
			(size 0.4572 0.4572)
			(layers "F.Cu" "F.Mask" "F.Paste")
			(net "GND")
		)
		(pad "AJ27" smd circle
			(at 7.999984 9.99998 270)
			(size 0.4572 0.4572)
			(layers "F.Cu" "F.Mask" "F.Paste")
			(net "SPI_CSB0_0")
		)
		(pad "AJ28" smd circle
			(at 8.999982 9.99998 270)
			(size 0.4572 0.4572)
			(layers "F.Cu" "F.Mask" "F.Paste")
			(net "SPI_CSB0_1")
		)
		(pad "AJ29" smd circle
			(at 9.99998 9.99998 270)
			(size 0.4572 0.4572)
			(layers "F.Cu" "F.Mask" "F.Paste")
			(net "SPI_DATA0_0")
		)
		(pad "AJ30" smd circle
			(at 10.999978 9.99998 270)
			(size 0.4572 0.4572)
			(layers "F.Cu" "F.Mask" "F.Paste")
			(net "SPI_DATA0_1")
		)
		(pad "AJ31" smd circle
			(at 11.999976 9.99998 270)
			(size 0.4572 0.4572)
			(layers "F.Cu" "F.Mask" "F.Paste")
			(net "SPI_CLK0")
		)
		(pad "AJ32" smd circle
			(at 12.999974 9.99998 270)
			(size 0.4572 0.4572)
			(layers "F.Cu" "F.Mask" "F.Paste")
			(net "SPI_DATA0_2")
		)
		(pad "AJ33" smd circle
			(at 13.999972 9.99998 270)
			(size 0.4572 0.4572)
			(layers "F.Cu" "F.Mask" "F.Paste")
			(net "SPI_DATA0_3")
		)
		(pad "AJ34" smd circle
			(at 14.99997 9.99998 270)
			(size 0.4572 0.4572)
			(layers "F.Cu" "F.Mask" "F.Paste")
			(net "DUT_VDDO")
		)
		(pad "AJ35" smd circle
			(at 15.999968 9.99998 270)
			(size 0.4572 0.4572)
			(layers "F.Cu" "F.Mask" "F.Paste")
			(net "GND")
		)
		(pad "AJ36" smd circle
			(at 16.999966 9.99998 270)
			(size 0.4572 0.4572)
			(layers "F.Cu" "F.Mask" "F.Paste")
			(net "GND")
		)
		(pad "AJ37" smd circle
			(at 17.999964 9.99998 270)
			(size 0.4572 0.4572)
			(layers "F.Cu" "F.Mask" "F.Paste")
			(net "GND")
		)
		(pad "AK1" smd circle
			(at -17.999964 10.999978 270)
			(size 0.4572 0.4572)
			(layers "F.Cu" "F.Mask" "F.Paste")
			(net "PCIE_TX_CAP_N57")
		)
		(pad "AK2" smd circle
			(at -16.999966 10.999978 270)
			(size 0.4572 0.4572)
			(layers "F.Cu" "F.Mask" "F.Paste")
			(net "PCIE_TX_CAP_P57")
		)
		(pad "AK3" smd circle
			(at -15.999968 10.999978 270)
			(size 0.4572 0.4572)
			(layers "F.Cu" "F.Mask" "F.Paste")
			(net "GND")
		)
		(pad "AK4" smd circle
			(at -14.99997 10.999978 270)
			(size 0.4572 0.4572)
			(layers "F.Cu" "F.Mask" "F.Paste")
			(net "PCIE_RX_N57")
		)
		(pad "AK5" smd circle
			(at -13.999972 10.999978 270)
			(size 0.4572 0.4572)
			(layers "F.Cu" "F.Mask" "F.Paste")
			(net "PCIE_RX_P57")
		)
		(pad "AK6" smd circle
			(at -12.999974 10.999978 270)
			(size 0.4572 0.4572)
			(layers "F.Cu" "F.Mask" "F.Paste")
			(net "GND")
		)
		(pad "AK7" smd circle
			(at -11.999976 10.999978 270)
			(size 0.4572 0.4572)
			(layers "F.Cu" "F.Mask" "F.Paste")
			(net "DUT_AVD_PCIE")
		)
		(pad "AK8" smd circle
			(at -10.999978 10.999978 270)
			(size 0.4572 0.4572)
			(layers "F.Cu" "F.Mask" "F.Paste")
			(net "GND")
		)
		(pad "AK9" smd circle
			(at -9.99998 10.999978 270)
			(size 0.4572 0.4572)
			(layers "F.Cu" "F.Mask" "F.Paste")
			(net "GND")
		)
		(pad "AK10" smd circle
			(at -8.999982 10.999978 270)
			(size 0.4572 0.4572)
			(layers "F.Cu" "F.Mask" "F.Paste")
			(net "GND")
		)
		(pad "AK11" smd circle
			(at -7.999984 10.999978 270)
			(size 0.4572 0.4572)
			(layers "F.Cu" "F.Mask" "F.Paste")
			(net "GND")
		)
		(pad "AK12" smd circle
			(at -6.999986 10.999978 270)
			(size 0.4572 0.4572)
			(layers "F.Cu" "F.Mask" "F.Paste")
			(net "GND")
		)
		(pad "AK13" smd circle
			(at -5.999988 10.999978 270)
			(size 0.4572 0.4572)
			(layers "F.Cu" "F.Mask" "F.Paste")
			(net "GND")
		)
		(pad "AK14" smd circle
			(at -4.99999 10.999978 270)
			(size 0.4572 0.4572)
			(layers "F.Cu" "F.Mask" "F.Paste")
			(net "GND")
		)
		(pad "AK15" smd circle
			(at -3.999992 10.999978 270)
			(size 0.4572 0.4572)
			(layers "F.Cu" "F.Mask" "F.Paste")
			(net "GND")
		)
		(pad "AK16" smd circle
			(at -2.999994 10.999978 270)
			(size 0.4572 0.4572)
			(layers "F.Cu" "F.Mask" "F.Paste")
			(net "GND")
		)
		(pad "AK17" smd circle
			(at -1.999996 10.999978 270)
			(size 0.4572 0.4572)
			(layers "F.Cu" "F.Mask" "F.Paste")
			(net "GND")
		)
		(pad "AK18" smd circle
			(at -0.999998 10.999978 270)
			(size 0.4572 0.4572)
			(layers "F.Cu" "F.Mask" "F.Paste")
			(net "GND")
		)
		(pad "AK19" smd circle
			(at 0 10.999978 270)
			(size 0.4572 0.4572)
			(layers "F.Cu" "F.Mask" "F.Paste")
			(net "GND")
		)
		(pad "AK20" smd circle
			(at 0.999998 10.999978 270)
			(size 0.4572 0.4572)
			(layers "F.Cu" "F.Mask" "F.Paste")
			(net "DUT_AVD_PCIE")
		)
		(pad "AK21" smd circle
			(at 1.999996 10.999978 270)
			(size 0.4572 0.4572)
			(layers "F.Cu" "F.Mask" "F.Paste")
			(net "GND")
		)
		(pad "AK22" smd circle
			(at 2.999994 10.999978 270)
			(size 0.4572 0.4572)
			(layers "F.Cu" "F.Mask" "F.Paste")
			(net "GND")
		)
		(pad "AK23" smd circle
			(at 3.999992 10.999978 270)
			(size 0.4572 0.4572)
			(layers "F.Cu" "F.Mask" "F.Paste")
			(net "GND")
		)
		(pad "AK24" smd circle
			(at 4.99999 10.999978 270)
			(size 0.4572 0.4572)
			(layers "F.Cu" "F.Mask" "F.Paste")
			(net "GND")
		)
		(pad "AK25" smd circle
			(at 5.999988 10.999978 270)
			(size 0.4572 0.4572)
			(layers "F.Cu" "F.Mask" "F.Paste")
			(net "DUT_AVD_PCIE")
		)
		(pad "AK26" smd circle
			(at 6.999986 10.999978 270)
			(size 0.4572 0.4572)
			(layers "F.Cu" "F.Mask" "F.Paste")
			(net "GND")
		)
		(pad "AK27" smd circle
			(at 7.999984 10.999978 270)
			(size 0.4572 0.4572)
			(layers "F.Cu" "F.Mask" "F.Paste")
			(net "LBI_DATA_8")
		)
		(pad "AK28" smd circle
			(at 8.999982 10.999978 270)
			(size 0.4572 0.4572)
			(layers "F.Cu" "F.Mask" "F.Paste")
			(net "LBI_DATA_9")
		)
		(pad "AK29" smd circle
			(at 9.99998 10.999978 270)
			(size 0.4572 0.4572)
			(layers "F.Cu" "F.Mask" "F.Paste")
			(net "LBI_DATA10")
		)
		(pad "AK30" smd circle
			(at 10.999978 10.999978 270)
			(size 0.4572 0.4572)
			(layers "F.Cu" "F.Mask" "F.Paste")
			(net "LBI_DATA11_R")
		)
		(pad "AK31" smd circle
			(at 11.999976 10.999978 270)
			(size 0.4572 0.4572)
			(layers "F.Cu" "F.Mask" "F.Paste")
			(net "LBI_DATA12_R")
		)
		(pad "AK32" smd circle
			(at 12.999974 10.999978 270)
			(size 0.4572 0.4572)
			(layers "F.Cu" "F.Mask" "F.Paste")
			(net "LBI_DATA13_R")
		)
		(pad "AK33" smd circle
			(at 13.999972 10.999978 270)
			(size 0.4572 0.4572)
			(layers "F.Cu" "F.Mask" "F.Paste")
			(net "LBI_DATA14_R")
		)
		(pad "AK34" smd circle
			(at 14.99997 10.999978 270)
			(size 0.4572 0.4572)
			(layers "F.Cu" "F.Mask" "F.Paste")
			(net "GND")
		)
		(pad "AK35" smd circle
			(at 15.999968 10.999978 270)
			(size 0.4572 0.4572)
			(layers "F.Cu" "F.Mask" "F.Paste")
			(net "GND")
		)
		(pad "AK36" smd circle
			(at 16.999966 10.999978 270)
			(size 0.4572 0.4572)
			(layers "F.Cu" "F.Mask" "F.Paste")
			(net "PCIE_TX_CAP_P95")
		)
		(pad "AK37" smd circle
			(at 17.999964 10.999978 270)
			(size 0.4572 0.4572)
			(layers "F.Cu" "F.Mask" "F.Paste")
			(net "PCIE_TX_CAP_N95")
		)
		(pad "AL2" smd circle
			(at -16.999966 11.999976 270)
			(size 0.4572 0.4572)
			(layers "F.Cu" "F.Mask" "F.Paste")
			(net "PCIE_TX_CAP_N58")
		)
		(pad "AL3" smd circle
			(at -15.999968 11.999976 270)
			(size 0.4572 0.4572)
			(layers "F.Cu" "F.Mask" "F.Paste")
			(net "PCIE_TX_CAP_P58")
		)
		(pad "AL4" smd circle
			(at -14.99997 11.999976 270)
			(size 0.4572 0.4572)
			(layers "F.Cu" "F.Mask" "F.Paste")
			(net "GND")
		)
		(pad "AL5" smd circle
			(at -13.999972 11.999976 270)
			(size 0.4572 0.4572)
			(layers "F.Cu" "F.Mask" "F.Paste")
			(net "PCIE_RX_N58")
		)
		(pad "AL6" smd circle
			(at -12.999974 11.999976 270)
			(size 0.4572 0.4572)
			(layers "F.Cu" "F.Mask" "F.Paste")
			(net "PCIE_RX_P58")
		)
		(pad "AL7" smd circle
			(at -11.999976 11.999976 270)
			(size 0.4572 0.4572)
			(layers "F.Cu" "F.Mask" "F.Paste")
			(net "DUT_AVD_PCIE")
		)
		(pad "AL8" smd circle
			(at -10.999978 11.999976 270)
			(size 0.4572 0.4572)
			(layers "F.Cu" "F.Mask" "F.Paste")
			(net "DUT_AVD_PCIE")
		)
		(pad "AL9" smd circle
			(at -9.99998 11.999976 270)
			(size 0.4572 0.4572)
			(layers "F.Cu" "F.Mask" "F.Paste")
			(net "DUT_AVD_PCIE")
		)
		(pad "AL10" smd circle
			(at -8.999982 11.999976 270)
			(size 0.4572 0.4572)
			(layers "F.Cu" "F.Mask" "F.Paste")
			(net "DUT_AVD_PCIE")
		)
		(pad "AL11" smd circle
			(at -7.999984 11.999976 270)
			(size 0.4572 0.4572)
			(layers "F.Cu" "F.Mask" "F.Paste")
			(net "DUT_AVD_PCIE")
		)
		(pad "AL12" smd circle
			(at -6.999986 11.999976 270)
			(size 0.4572 0.4572)
			(layers "F.Cu" "F.Mask" "F.Paste")
			(net "DUT_AVD_PCIE")
		)
		(pad "AL13" smd circle
			(at -5.999988 11.999976 270)
			(size 0.4572 0.4572)
			(layers "F.Cu" "F.Mask" "F.Paste")
			(net "DUT_AVD_PCIE")
		)
		(pad "AL14" smd circle
			(at -4.99999 11.999976 270)
			(size 0.4572 0.4572)
			(layers "F.Cu" "F.Mask" "F.Paste")
			(net "DUT_AVD_PCIE")
		)
		(pad "AL15" smd circle
			(at -3.999992 11.999976 270)
			(size 0.4572 0.4572)
			(layers "F.Cu" "F.Mask" "F.Paste")
			(net "GND")
		)
		(pad "AL16" smd circle
			(at -2.999994 11.999976 270)
			(size 0.4572 0.4572)
			(layers "F.Cu" "F.Mask" "F.Paste")
			(net "DUT_AVD_PCIE")
		)
		(pad "AL17" smd circle
			(at -1.999996 11.999976 270)
			(size 0.4572 0.4572)
			(layers "F.Cu" "F.Mask" "F.Paste")
			(net "DUT_AVD_PCIE")
		)
		(pad "AL18" smd circle
			(at -0.999998 11.999976 270)
			(size 0.4572 0.4572)
			(layers "F.Cu" "F.Mask" "F.Paste")
			(net "DUT_AVD_PCIE")
		)
		(pad "AL19" smd circle
			(at 0 11.999976 270)
			(size 0.4572 0.4572)
			(layers "F.Cu" "F.Mask" "F.Paste")
			(net "DUT_AVD_PCIE")
		)
		(pad "AL20" smd circle
			(at 0.999998 11.999976 270)
			(size 0.4572 0.4572)
			(layers "F.Cu" "F.Mask" "F.Paste")
			(net "DUT_AVD_PCIE")
		)
		(pad "AL21" smd circle
			(at 1.999996 11.999976 270)
			(size 0.4572 0.4572)
			(layers "F.Cu" "F.Mask" "F.Paste")
			(net "DUT_AVD_PCIE")
		)
		(pad "AL22" smd circle
			(at 2.999994 11.999976 270)
			(size 0.4572 0.4572)
			(layers "F.Cu" "F.Mask" "F.Paste")
			(net "DUT_AVD_PCIE")
		)
		(pad "AL23" smd circle
			(at 3.999992 11.999976 270)
			(size 0.4572 0.4572)
			(layers "F.Cu" "F.Mask" "F.Paste")
			(net "DUT_AVD_PCIE")
		)
		(pad "AL24" smd circle
			(at 4.99999 11.999976 270)
			(size 0.4572 0.4572)
			(layers "F.Cu" "F.Mask" "F.Paste")
			(net "DUT_AVD_PCIE")
		)
		(pad "AL25" smd circle
			(at 5.999988 11.999976 270)
			(size 0.4572 0.4572)
			(layers "F.Cu" "F.Mask" "F.Paste")
			(net "DUT_AVD_PCIE")
		)
		(pad "AL26" smd circle
			(at 6.999986 11.999976 270)
			(size 0.4572 0.4572)
			(layers "F.Cu" "F.Mask" "F.Paste")
			(net "DUT_AVD_PCIE")
		)
		(pad "AL27" smd circle
			(at 7.999984 11.999976 270)
			(size 0.4572 0.4572)
			(layers "F.Cu" "F.Mask" "F.Paste")
			(net "DUT_AVD_PCIE")
		)
		(pad "AL28" smd circle
			(at 8.999982 11.999976 270)
			(size 0.4572 0.4572)
			(layers "F.Cu" "F.Mask" "F.Paste")
			(net "DUT_AVD_PCIE")
		)
		(pad "AL29" smd circle
			(at 9.99998 11.999976 270)
			(size 0.4572 0.4572)
			(layers "F.Cu" "F.Mask" "F.Paste")
			(net "DUT_AVD_PCIE")
		)
		(pad "AL30" smd circle
			(at 10.999978 11.999976 270)
			(size 0.4572 0.4572)
			(layers "F.Cu" "F.Mask" "F.Paste")
			(net "DUT_AVD_PCIE")
		)
		(pad "AL31" smd circle
			(at 11.999976 11.999976 270)
			(size 0.4572 0.4572)
			(layers "F.Cu" "F.Mask" "F.Paste")
			(net "DUT_AVD_PCIE")
		)
		(pad "AL32" smd circle
			(at 12.999974 11.999976 270)
			(size 0.4572 0.4572)
			(layers "F.Cu" "F.Mask" "F.Paste")
			(net "DUT_AVD_PCIE")
		)
		(pad "AL33" smd circle
			(at 13.999972 11.999976 270)
			(size 0.4572 0.4572)
			(layers "F.Cu" "F.Mask" "F.Paste")
			(net "DUT_AVD_PCIE")
		)
		(pad "AL34" smd circle
			(at 14.99997 11.999976 270)
			(size 0.4572 0.4572)
			(layers "F.Cu" "F.Mask" "F.Paste")
			(net "GND")
		)
		(pad "AL35" smd circle
			(at 15.999968 11.999976 270)
			(size 0.4572 0.4572)
			(layers "F.Cu" "F.Mask" "F.Paste")
			(net "PCIE_TX_CAP_P94")
		)
		(pad "AL36" smd circle
			(at 16.999966 11.999976 270)
			(size 0.4572 0.4572)
			(layers "F.Cu" "F.Mask" "F.Paste")
			(net "PCIE_TX_CAP_N94")
		)
		(pad "AM1" smd circle
			(at -17.999964 12.999974 270)
			(size 0.4572 0.4572)
			(layers "F.Cu" "F.Mask" "F.Paste")
			(net "PCIE_TX_CAP_N59")
		)
		(pad "AM2" smd circle
			(at -16.999966 12.999974 270)
			(size 0.4572 0.4572)
			(layers "F.Cu" "F.Mask" "F.Paste")
			(net "PCIE_TX_CAP_P59")
		)
		(pad "AM3" smd circle
			(at -15.999968 12.999974 270)
			(size 0.4572 0.4572)
			(layers "F.Cu" "F.Mask" "F.Paste")
			(net "GND")
		)
		(pad "AM4" smd circle
			(at -14.99997 12.999974 270)
			(size 0.4572 0.4572)
			(layers "F.Cu" "F.Mask" "F.Paste")
			(net "PCIE_RX_N59")
		)
		(pad "AM5" smd circle
			(at -13.999972 12.999974 270)
			(size 0.4572 0.4572)
			(layers "F.Cu" "F.Mask" "F.Paste")
			(net "PCIE_RX_P59")
		)
		(pad "AM6" smd circle
			(at -12.999974 12.999974 270)
			(size 0.4572 0.4572)
			(layers "F.Cu" "F.Mask" "F.Paste")
			(net "GND")
		)
		(pad "AM7" smd circle
			(at -11.999976 12.999974 270)
			(size 0.4572 0.4572)
			(layers "F.Cu" "F.Mask" "F.Paste")
			(net "DUT_AVD_PCIE")
		)
		(pad "AM8" smd circle
			(at -10.999978 12.999974 270)
			(size 0.4572 0.4572)
			(layers "F.Cu" "F.Mask" "F.Paste")
			(net "PCIE_RX_P64")
		)
		(pad "AM9" smd circle
			(at -9.99998 12.999974 270)
			(size 0.4572 0.4572)
			(layers "F.Cu" "F.Mask" "F.Paste")
			(net "GND")
		)
		(pad "AM10" smd circle
			(at -8.999982 12.999974 270)
			(size 0.4572 0.4572)
			(layers "F.Cu" "F.Mask" "F.Paste")
			(net "PCIE_RX_P66")
		)
		(pad "AM11" smd circle
			(at -7.999984 12.999974 270)
			(size 0.4572 0.4572)
			(layers "F.Cu" "F.Mask" "F.Paste")
			(net "GND")
		)
		(pad "AM12" smd circle
			(at -6.999986 12.999974 270)
			(size 0.4572 0.4572)
			(layers "F.Cu" "F.Mask" "F.Paste")
			(net "PCIE_RX_P68")
		)
		(pad "AM13" smd circle
			(at -5.999988 12.999974 270)
			(size 0.4572 0.4572)
			(layers "F.Cu" "F.Mask" "F.Paste")
			(net "GND")
		)
		(pad "AM14" smd circle
			(at -4.99999 12.999974 270)
			(size 0.4572 0.4572)
			(layers "F.Cu" "F.Mask" "F.Paste")
			(net "PCIE_RX_P70")
		)
		(pad "AM15" smd circle
			(at -3.999992 12.999974 270)
			(size 0.4572 0.4572)
			(layers "F.Cu" "F.Mask" "F.Paste")
			(net "GND")
		)
		(pad "AM16" smd circle
			(at -2.999994 12.999974 270)
			(size 0.4572 0.4572)
			(layers "F.Cu" "F.Mask" "F.Paste")
			(net "DUT_AVD_PCIE")
		)
		(pad "AM17" smd circle
			(at -1.999996 12.999974 270)
			(size 0.4572 0.4572)
			(layers "F.Cu" "F.Mask" "F.Paste")
			(net "PCIE_RX_P72")
		)
		(pad "AM18" smd circle
			(at -0.999998 12.999974 270)
			(size 0.4572 0.4572)
			(layers "F.Cu" "F.Mask" "F.Paste")
			(net "GND")
		)
		(pad "AM19" smd circle
			(at 0 12.999974 270)
			(size 0.4572 0.4572)
			(layers "F.Cu" "F.Mask" "F.Paste")
			(net "PCIE_RX_P74")
		)
		(pad "AM20" smd circle
			(at 0.999998 12.999974 270)
			(size 0.4572 0.4572)
			(layers "F.Cu" "F.Mask" "F.Paste")
			(net "GND")
		)
		(pad "AM21" smd circle
			(at 1.999996 12.999974 270)
			(size 0.4572 0.4572)
			(layers "F.Cu" "F.Mask" "F.Paste")
			(net "PCIE_RX_P76")
		)
		(pad "AM22" smd circle
			(at 2.999994 12.999974 270)
			(size 0.4572 0.4572)
			(layers "F.Cu" "F.Mask" "F.Paste")
			(net "GND")
		)
		(pad "AM23" smd circle
			(at 3.999992 12.999974 270)
			(size 0.4572 0.4572)
			(layers "F.Cu" "F.Mask" "F.Paste")
			(net "PCIE_RX_P78")
		)
		(pad "AM24" smd circle
			(at 4.99999 12.999974 270)
			(size 0.4572 0.4572)
			(layers "F.Cu" "F.Mask" "F.Paste")
			(net "GND")
		)
		(pad "AM25" smd circle
			(at 5.999988 12.999974 270)
			(size 0.4572 0.4572)
			(layers "F.Cu" "F.Mask" "F.Paste")
			(net "DUT_AVD_PCIE")
		)
		(pad "AM26" smd circle
			(at 6.999986 12.999974 270)
			(size 0.4572 0.4572)
			(layers "F.Cu" "F.Mask" "F.Paste")
			(net "PCIE_RX_P80")
		)
		(pad "AM27" smd circle
			(at 7.999984 12.999974 270)
			(size 0.4572 0.4572)
			(layers "F.Cu" "F.Mask" "F.Paste")
			(net "GND")
		)
		(pad "AM28" smd circle
			(at 8.999982 12.999974 270)
			(size 0.4572 0.4572)
			(layers "F.Cu" "F.Mask" "F.Paste")
			(net "PCIE_RX_P82")
		)
		(pad "AM29" smd circle
			(at 9.99998 12.999974 270)
			(size 0.4572 0.4572)
			(layers "F.Cu" "F.Mask" "F.Paste")
			(net "GND")
		)
		(pad "AM30" smd circle
			(at 10.999978 12.999974 270)
			(size 0.4572 0.4572)
			(layers "F.Cu" "F.Mask" "F.Paste")
			(net "PCIE_RX_P84")
		)
		(pad "AM31" smd circle
			(at 11.999976 12.999974 270)
			(size 0.4572 0.4572)
			(layers "F.Cu" "F.Mask" "F.Paste")
			(net "GND")
		)
		(pad "AM32" smd circle
			(at 12.999974 12.999974 270)
			(size 0.4572 0.4572)
			(layers "F.Cu" "F.Mask" "F.Paste")
			(net "PCIE_RX_P86")
		)
		(pad "AM33" smd circle
			(at 13.999972 12.999974 270)
			(size 0.4572 0.4572)
			(layers "F.Cu" "F.Mask" "F.Paste")
			(net "DUT_AVD_PCIE")
		)
		(pad "AM34" smd circle
			(at 14.99997 12.999974 270)
			(size 0.4572 0.4572)
			(layers "F.Cu" "F.Mask" "F.Paste")
			(net "GND")
		)
		(pad "AM35" smd circle
			(at 15.999968 12.999974 270)
			(size 0.4572 0.4572)
			(layers "F.Cu" "F.Mask" "F.Paste")
			(net "GND")
		)
		(pad "AM36" smd circle
			(at 16.999966 12.999974 270)
			(size 0.4572 0.4572)
			(layers "F.Cu" "F.Mask" "F.Paste")
			(net "PCIE_TX_CAP_P93")
		)
		(pad "AM37" smd circle
			(at 17.999964 12.999974 270)
			(size 0.4572 0.4572)
			(layers "F.Cu" "F.Mask" "F.Paste")
			(net "PCIE_TX_CAP_N93")
		)
		(pad "AN2" smd circle
			(at -16.999966 13.999972 270)
			(size 0.4572 0.4572)
			(layers "F.Cu" "F.Mask" "F.Paste")
			(net "PCIE_TX_CAP_N60")
		)
		(pad "AN3" smd circle
			(at -15.999968 13.999972 270)
			(size 0.4572 0.4572)
			(layers "F.Cu" "F.Mask" "F.Paste")
			(net "PCIE_TX_CAP_P60")
		)
		(pad "AN4" smd circle
			(at -14.99997 13.999972 270)
			(size 0.4572 0.4572)
			(layers "F.Cu" "F.Mask" "F.Paste")
			(net "GND")
		)
		(pad "AN5" smd circle
			(at -13.999972 13.999972 270)
			(size 0.4572 0.4572)
			(layers "F.Cu" "F.Mask" "F.Paste")
			(net "PCIE_RX_N60")
		)
		(pad "AN6" smd circle
			(at -12.999974 13.999972 270)
			(size 0.4572 0.4572)
			(layers "F.Cu" "F.Mask" "F.Paste")
			(net "PCIE_RX_P60")
		)
		(pad "AN7" smd circle
			(at -11.999976 13.999972 270)
			(size 0.4572 0.4572)
			(layers "F.Cu" "F.Mask" "F.Paste")
			(net "GND")
		)
		(pad "AN8" smd circle
			(at -10.999978 13.999972 270)
			(size 0.4572 0.4572)
			(layers "F.Cu" "F.Mask" "F.Paste")
			(net "PCIE_RX_N64")
		)
		(pad "AN9" smd circle
			(at -9.99998 13.999972 270)
			(size 0.4572 0.4572)
			(layers "F.Cu" "F.Mask" "F.Paste")
			(net "PCIE_RX_P65")
		)
		(pad "AN10" smd circle
			(at -8.999982 13.999972 270)
			(size 0.4572 0.4572)
			(layers "F.Cu" "F.Mask" "F.Paste")
			(net "PCIE_RX_N66")
		)
		(pad "AN11" smd circle
			(at -7.999984 13.999972 270)
			(size 0.4572 0.4572)
			(layers "F.Cu" "F.Mask" "F.Paste")
			(net "PCIE_RX_P67")
		)
		(pad "AN12" smd circle
			(at -6.999986 13.999972 270)
			(size 0.4572 0.4572)
			(layers "F.Cu" "F.Mask" "F.Paste")
			(net "PCIE_RX_N68")
		)
		(pad "AN13" smd circle
			(at -5.999988 13.999972 270)
			(size 0.4572 0.4572)
			(layers "F.Cu" "F.Mask" "F.Paste")
			(net "PCIE_RX_P69")
		)
		(pad "AN14" smd circle
			(at -4.99999 13.999972 270)
			(size 0.4572 0.4572)
			(layers "F.Cu" "F.Mask" "F.Paste")
			(net "PCIE_RX_N70")
		)
		(pad "AN15" smd circle
			(at -3.999992 13.999972 270)
			(size 0.4572 0.4572)
			(layers "F.Cu" "F.Mask" "F.Paste")
			(net "PCIE_RX_P71")
		)
		(pad "AN16" smd circle
			(at -2.999994 13.999972 270)
			(size 0.4572 0.4572)
			(layers "F.Cu" "F.Mask" "F.Paste")
			(net "GND")
		)
		(pad "AN17" smd circle
			(at -1.999996 13.999972 270)
			(size 0.4572 0.4572)
			(layers "F.Cu" "F.Mask" "F.Paste")
			(net "PCIE_RX_N72")
		)
		(pad "AN18" smd circle
			(at -0.999998 13.999972 270)
			(size 0.4572 0.4572)
			(layers "F.Cu" "F.Mask" "F.Paste")
			(net "PCIE_RX_P73")
		)
		(pad "AN19" smd circle
			(at 0 13.999972 270)
			(size 0.4572 0.4572)
			(layers "F.Cu" "F.Mask" "F.Paste")
			(net "PCIE_RX_N74")
		)
		(pad "AN20" smd circle
			(at 0.999998 13.999972 270)
			(size 0.4572 0.4572)
			(layers "F.Cu" "F.Mask" "F.Paste")
			(net "PCIE_RX_P75")
		)
		(pad "AN21" smd circle
			(at 1.999996 13.999972 270)
			(size 0.4572 0.4572)
			(layers "F.Cu" "F.Mask" "F.Paste")
			(net "PCIE_RX_N76")
		)
		(pad "AN22" smd circle
			(at 2.999994 13.999972 270)
			(size 0.4572 0.4572)
			(layers "F.Cu" "F.Mask" "F.Paste")
			(net "Net_305")
		)
		(pad "AN23" smd circle
			(at 3.999992 13.999972 270)
			(size 0.4572 0.4572)
			(layers "F.Cu" "F.Mask" "F.Paste")
			(net "PCIE_RX_N78")
		)
		(pad "AN24" smd circle
			(at 4.99999 13.999972 270)
			(size 0.4572 0.4572)
			(layers "F.Cu" "F.Mask" "F.Paste")
			(net "Net_306")
		)
		(pad "AN25" smd circle
			(at 5.999988 13.999972 270)
			(size 0.4572 0.4572)
			(layers "F.Cu" "F.Mask" "F.Paste")
			(net "GND")
		)
		(pad "AN26" smd circle
			(at 6.999986 13.999972 270)
			(size 0.4572 0.4572)
			(layers "F.Cu" "F.Mask" "F.Paste")
			(net "PCIE_RX_N80")
		)
		(pad "AN27" smd circle
			(at 7.999984 13.999972 270)
			(size 0.4572 0.4572)
			(layers "F.Cu" "F.Mask" "F.Paste")
			(net "PCIE_RX_P81")
		)
		(pad "AN28" smd circle
			(at 8.999982 13.999972 270)
			(size 0.4572 0.4572)
			(layers "F.Cu" "F.Mask" "F.Paste")
			(net "PCIE_RX_N82")
		)
		(pad "AN29" smd circle
			(at 9.99998 13.999972 270)
			(size 0.4572 0.4572)
			(layers "F.Cu" "F.Mask" "F.Paste")
			(net "PCIE_RX_P83")
		)
		(pad "AN30" smd circle
			(at 10.999978 13.999972 270)
			(size 0.4572 0.4572)
			(layers "F.Cu" "F.Mask" "F.Paste")
			(net "PCIE_RX_N84")
		)
		(pad "AN31" smd circle
			(at 11.999976 13.999972 270)
			(size 0.4572 0.4572)
			(layers "F.Cu" "F.Mask" "F.Paste")
			(net "PCIE_RX_P85")
		)
		(pad "AN32" smd circle
			(at 12.999974 13.999972 270)
			(size 0.4572 0.4572)
			(layers "F.Cu" "F.Mask" "F.Paste")
			(net "PCIE_RX_N86")
		)
		(pad "AN33" smd circle
			(at 13.999972 13.999972 270)
			(size 0.4572 0.4572)
			(layers "F.Cu" "F.Mask" "F.Paste")
			(net "PCIE_RX_P87")
		)
		(pad "AN34" smd circle
			(at 14.99997 13.999972 270)
			(size 0.4572 0.4572)
			(layers "F.Cu" "F.Mask" "F.Paste")
			(net "GND")
		)
		(pad "AN35" smd circle
			(at 15.999968 13.999972 270)
			(size 0.4572 0.4572)
			(layers "F.Cu" "F.Mask" "F.Paste")
			(net "PCIE_TX_CAP_P92")
		)
		(pad "AN36" smd circle
			(at 16.999966 13.999972 270)
			(size 0.4572 0.4572)
			(layers "F.Cu" "F.Mask" "F.Paste")
			(net "PCIE_TX_CAP_N92")
		)
		(pad "AP1" smd circle
			(at -17.999964 14.99997 270)
			(size 0.4572 0.4572)
			(layers "F.Cu" "F.Mask" "F.Paste")
			(net "PCIE_TX_CAP_N61")
		)
		(pad "AP2" smd circle
			(at -16.999966 14.99997 270)
			(size 0.4572 0.4572)
			(layers "F.Cu" "F.Mask" "F.Paste")
			(net "PCIE_TX_CAP_P61")
		)
		(pad "AP3" smd circle
			(at -15.999968 14.99997 270)
			(size 0.4572 0.4572)
			(layers "F.Cu" "F.Mask" "F.Paste")
			(net "GND")
		)
		(pad "AP4" smd circle
			(at -14.99997 14.99997 270)
			(size 0.4572 0.4572)
			(layers "F.Cu" "F.Mask" "F.Paste")
			(net "PCIE_RX_N61")
		)
		(pad "AP5" smd circle
			(at -13.999972 14.99997 270)
			(size 0.4572 0.4572)
			(layers "F.Cu" "F.Mask" "F.Paste")
			(net "PCIE_RX_P61")
		)
		(pad "AP6" smd circle
			(at -12.999974 14.99997 270)
			(size 0.4572 0.4572)
			(layers "F.Cu" "F.Mask" "F.Paste")
			(net "GND")
		)
		(pad "AP7" smd circle
			(at -11.999976 14.99997 270)
			(size 0.4572 0.4572)
			(layers "F.Cu" "F.Mask" "F.Paste")
			(net "GND")
		)
		(pad "AP8" smd circle
			(at -10.999978 14.99997 270)
			(size 0.4572 0.4572)
			(layers "F.Cu" "F.Mask" "F.Paste")
			(net "GND")
		)
		(pad "AP9" smd circle
			(at -9.99998 14.99997 270)
			(size 0.4572 0.4572)
			(layers "F.Cu" "F.Mask" "F.Paste")
			(net "PCIE_RX_N65")
		)
		(pad "AP10" smd circle
			(at -8.999982 14.99997 270)
			(size 0.4572 0.4572)
			(layers "F.Cu" "F.Mask" "F.Paste")
			(net "GND")
		)
		(pad "AP11" smd circle
			(at -7.999984 14.99997 270)
			(size 0.4572 0.4572)
			(layers "F.Cu" "F.Mask" "F.Paste")
			(net "PCIE_RX_N67")
		)
		(pad "AP12" smd circle
			(at -6.999986 14.99997 270)
			(size 0.4572 0.4572)
			(layers "F.Cu" "F.Mask" "F.Paste")
			(net "GND")
		)
		(pad "AP13" smd circle
			(at -5.999988 14.99997 270)
			(size 0.4572 0.4572)
			(layers "F.Cu" "F.Mask" "F.Paste")
			(net "PCIE_RX_N69")
		)
		(pad "AP14" smd circle
			(at -4.99999 14.99997 270)
			(size 0.4572 0.4572)
			(layers "F.Cu" "F.Mask" "F.Paste")
			(net "GND")
		)
		(pad "AP15" smd circle
			(at -3.999992 14.99997 270)
			(size 0.4572 0.4572)
			(layers "F.Cu" "F.Mask" "F.Paste")
			(net "PCIE_RX_N71")
		)
		(pad "AP16" smd circle
			(at -2.999994 14.99997 270)
			(size 0.4572 0.4572)
			(layers "F.Cu" "F.Mask" "F.Paste")
			(net "GND")
		)
		(pad "AP17" smd circle
			(at -1.999996 14.99997 270)
			(size 0.4572 0.4572)
			(layers "F.Cu" "F.Mask" "F.Paste")
			(net "GND")
		)
		(pad "AP18" smd circle
			(at -0.999998 14.99997 270)
			(size 0.4572 0.4572)
			(layers "F.Cu" "F.Mask" "F.Paste")
			(net "PCIE_RX_N73")
		)
		(pad "AP19" smd circle
			(at 0 14.99997 270)
			(size 0.4572 0.4572)
			(layers "F.Cu" "F.Mask" "F.Paste")
			(net "GND")
		)
		(pad "AP20" smd circle
			(at 0.999998 14.99997 270)
			(size 0.4572 0.4572)
			(layers "F.Cu" "F.Mask" "F.Paste")
			(net "PCIE_RX_N75")
		)
		(pad "AP21" smd circle
			(at 1.999996 14.99997 270)
			(size 0.4572 0.4572)
			(layers "F.Cu" "F.Mask" "F.Paste")
			(net "GND")
		)
		(pad "AP22" smd circle
			(at 2.999994 14.99997 270)
			(size 0.4572 0.4572)
			(layers "F.Cu" "F.Mask" "F.Paste")
			(net "Net_303")
		)
		(pad "AP23" smd circle
			(at 3.999992 14.99997 270)
			(size 0.4572 0.4572)
			(layers "F.Cu" "F.Mask" "F.Paste")
			(net "GND")
		)
		(pad "AP24" smd circle
			(at 4.99999 14.99997 270)
			(size 0.4572 0.4572)
			(layers "F.Cu" "F.Mask" "F.Paste")
			(net "Net_304")
		)
		(pad "AP25" smd circle
			(at 5.999988 14.99997 270)
			(size 0.4572 0.4572)
			(layers "F.Cu" "F.Mask" "F.Paste")
			(net "GND")
		)
		(pad "AP26" smd circle
			(at 6.999986 14.99997 270)
			(size 0.4572 0.4572)
			(layers "F.Cu" "F.Mask" "F.Paste")
			(net "GND")
		)
		(pad "AP27" smd circle
			(at 7.999984 14.99997 270)
			(size 0.4572 0.4572)
			(layers "F.Cu" "F.Mask" "F.Paste")
			(net "PCIE_RX_N81")
		)
		(pad "AP28" smd circle
			(at 8.999982 14.99997 270)
			(size 0.4572 0.4572)
			(layers "F.Cu" "F.Mask" "F.Paste")
			(net "GND")
		)
		(pad "AP29" smd circle
			(at 9.99998 14.99997 270)
			(size 0.4572 0.4572)
			(layers "F.Cu" "F.Mask" "F.Paste")
			(net "PCIE_RX_N83")
		)
		(pad "AP30" smd circle
			(at 10.999978 14.99997 270)
			(size 0.4572 0.4572)
			(layers "F.Cu" "F.Mask" "F.Paste")
			(net "GND")
		)
		(pad "AP31" smd circle
			(at 11.999976 14.99997 270)
			(size 0.4572 0.4572)
			(layers "F.Cu" "F.Mask" "F.Paste")
			(net "PCIE_RX_N85")
		)
		(pad "AP32" smd circle
			(at 12.999974 14.99997 270)
			(size 0.4572 0.4572)
			(layers "F.Cu" "F.Mask" "F.Paste")
			(net "GND")
		)
		(pad "AP33" smd circle
			(at 13.999972 14.99997 270)
			(size 0.4572 0.4572)
			(layers "F.Cu" "F.Mask" "F.Paste")
			(net "PCIE_RX_N87")
		)
		(pad "AP34" smd circle
			(at 14.99997 14.99997 270)
			(size 0.4572 0.4572)
			(layers "F.Cu" "F.Mask" "F.Paste")
			(net "GND")
		)
		(pad "AP35" smd circle
			(at 15.999968 14.99997 270)
			(size 0.4572 0.4572)
			(layers "F.Cu" "F.Mask" "F.Paste")
			(net "GND")
		)
		(pad "AP36" smd circle
			(at 16.999966 14.99997 270)
			(size 0.4572 0.4572)
			(layers "F.Cu" "F.Mask" "F.Paste")
			(net "PCIE_TX_CAP_P91")
		)
		(pad "AP37" smd circle
			(at 17.999964 14.99997 270)
			(size 0.4572 0.4572)
			(layers "F.Cu" "F.Mask" "F.Paste")
			(net "PCIE_TX_CAP_N91")
		)
		(pad "AR2" smd circle
			(at -16.999966 15.999968 270)
			(size 0.508 0.508)
			(layers "F.Cu" "F.Mask" "F.Paste")
			(net "PCIE_TX_CAP_N62")
		)
		(pad "AR3" smd circle
			(at -15.999968 15.999968 270)
			(size 0.508 0.508)
			(layers "F.Cu" "F.Mask" "F.Paste")
			(net "PCIE_TX_CAP_P62")
		)
		(pad "AR4" smd circle
			(at -14.99997 15.999968 270)
			(size 0.4572 0.4572)
			(layers "F.Cu" "F.Mask" "F.Paste")
			(net "GND")
		)
		(pad "AR5" smd circle
			(at -13.999972 15.999968 270)
			(size 0.4572 0.4572)
			(layers "F.Cu" "F.Mask" "F.Paste")
			(net "PCIE_RX_N62")
		)
		(pad "AR6" smd circle
			(at -12.999974 15.999968 270)
			(size 0.4572 0.4572)
			(layers "F.Cu" "F.Mask" "F.Paste")
			(net "PCIE_RX_P62")
		)
		(pad "AR7" smd circle
			(at -11.999976 15.999968 270)
			(size 0.4572 0.4572)
			(layers "F.Cu" "F.Mask" "F.Paste")
			(net "GND")
		)
		(pad "AR8" smd circle
			(at -10.999978 15.999968 270)
			(size 0.4572 0.4572)
			(layers "F.Cu" "F.Mask" "F.Paste")
			(net "PCIE_TX_CAP_P64")
		)
		(pad "AR9" smd circle
			(at -9.99998 15.999968 270)
			(size 0.4572 0.4572)
			(layers "F.Cu" "F.Mask" "F.Paste")
			(net "GND")
		)
		(pad "AR10" smd circle
			(at -8.999982 15.999968 270)
			(size 0.4572 0.4572)
			(layers "F.Cu" "F.Mask" "F.Paste")
			(net "PCIE_TX_CAP_P66")
		)
		(pad "AR11" smd circle
			(at -7.999984 15.999968 270)
			(size 0.4572 0.4572)
			(layers "F.Cu" "F.Mask" "F.Paste")
			(net "GND")
		)
		(pad "AR12" smd circle
			(at -6.999986 15.999968 270)
			(size 0.4572 0.4572)
			(layers "F.Cu" "F.Mask" "F.Paste")
			(net "PCIE_TX_CAP_P68")
		)
		(pad "AR13" smd circle
			(at -5.999988 15.999968 270)
			(size 0.4572 0.4572)
			(layers "F.Cu" "F.Mask" "F.Paste")
			(net "GND")
		)
		(pad "AR14" smd circle
			(at -4.99999 15.999968 270)
			(size 0.4572 0.4572)
			(layers "F.Cu" "F.Mask" "F.Paste")
			(net "PCIE_TX_CAP_P70")
		)
		(pad "AR15" smd circle
			(at -3.999992 15.999968 270)
			(size 0.4572 0.4572)
			(layers "F.Cu" "F.Mask" "F.Paste")
			(net "GND")
		)
		(pad "AR16" smd circle
			(at -2.999994 15.999968 270)
			(size 0.4572 0.4572)
			(layers "F.Cu" "F.Mask" "F.Paste")
			(net "GND")
		)
		(pad "AR17" smd circle
			(at -1.999996 15.999968 270)
			(size 0.4572 0.4572)
			(layers "F.Cu" "F.Mask" "F.Paste")
			(net "PCIE_TX_CAP_P72")
		)
		(pad "AR18" smd circle
			(at -0.999998 15.999968 270)
			(size 0.4572 0.4572)
			(layers "F.Cu" "F.Mask" "F.Paste")
			(net "GND")
		)
		(pad "AR19" smd circle
			(at 0 15.999968 270)
			(size 0.4572 0.4572)
			(layers "F.Cu" "F.Mask" "F.Paste")
			(net "PCIE_TX_CAP_P74")
		)
		(pad "AR20" smd circle
			(at 0.999998 15.999968 270)
			(size 0.4572 0.4572)
			(layers "F.Cu" "F.Mask" "F.Paste")
			(net "GND")
		)
		(pad "AR21" smd circle
			(at 1.999996 15.999968 270)
			(size 0.4572 0.4572)
			(layers "F.Cu" "F.Mask" "F.Paste")
			(net "PCIE_TX_CAP_P76")
		)
		(pad "AR22" smd circle
			(at 2.999994 15.999968 270)
			(size 0.4572 0.4572)
			(layers "F.Cu" "F.Mask" "F.Paste")
			(net "GND")
		)
		(pad "AR23" smd circle
			(at 3.999992 15.999968 270)
			(size 0.4572 0.4572)
			(layers "F.Cu" "F.Mask" "F.Paste")
			(net "PCIE_TX_CAP_P78")
		)
		(pad "AR24" smd circle
			(at 4.99999 15.999968 270)
			(size 0.4572 0.4572)
			(layers "F.Cu" "F.Mask" "F.Paste")
			(net "GND")
		)
		(pad "AR25" smd circle
			(at 5.999988 15.999968 270)
			(size 0.4572 0.4572)
			(layers "F.Cu" "F.Mask" "F.Paste")
			(net "GND")
		)
		(pad "AR26" smd circle
			(at 6.999986 15.999968 270)
			(size 0.4572 0.4572)
			(layers "F.Cu" "F.Mask" "F.Paste")
			(net "PCIE_TX_CAP_P80")
		)
		(pad "AR27" smd circle
			(at 7.999984 15.999968 270)
			(size 0.4572 0.4572)
			(layers "F.Cu" "F.Mask" "F.Paste")
			(net "GND")
		)
		(pad "AR28" smd circle
			(at 8.999982 15.999968 270)
			(size 0.4572 0.4572)
			(layers "F.Cu" "F.Mask" "F.Paste")
			(net "PCIE_TX_CAP_P82")
		)
		(pad "AR29" smd circle
			(at 9.99998 15.999968 270)
			(size 0.4572 0.4572)
			(layers "F.Cu" "F.Mask" "F.Paste")
			(net "GND")
		)
		(pad "AR30" smd circle
			(at 10.999978 15.999968 270)
			(size 0.4572 0.4572)
			(layers "F.Cu" "F.Mask" "F.Paste")
			(net "PCIE_TX_CAP_P84")
		)
		(pad "AR31" smd circle
			(at 11.999976 15.999968 270)
			(size 0.4572 0.4572)
			(layers "F.Cu" "F.Mask" "F.Paste")
			(net "GND")
		)
		(pad "AR32" smd circle
			(at 12.999974 15.999968 270)
			(size 0.4572 0.4572)
			(layers "F.Cu" "F.Mask" "F.Paste")
			(net "PCIE_TX_CAP_P86")
		)
		(pad "AR33" smd circle
			(at 13.999972 15.999968 270)
			(size 0.4572 0.4572)
			(layers "F.Cu" "F.Mask" "F.Paste")
			(net "GND")
		)
		(pad "AR34" smd circle
			(at 14.99997 15.999968 270)
			(size 0.4572 0.4572)
			(layers "F.Cu" "F.Mask" "F.Paste")
			(net "GND")
		)
		(pad "AR35" smd circle
			(at 15.999968 15.999968 270)
			(size 0.508 0.508)
			(layers "F.Cu" "F.Mask" "F.Paste")
			(net "PCIE_TX_CAP_P90")
		)
		(pad "AR36" smd circle
			(at 16.999966 15.999968 270)
			(size 0.508 0.508)
			(layers "F.Cu" "F.Mask" "F.Paste")
			(net "PCIE_TX_CAP_N90")
		)
		(pad "AT1" smd circle
			(at -17.999964 16.999966 270)
			(size 0.508 0.508)
			(layers "F.Cu" "F.Mask" "F.Paste")
			(net "PCIE_TX_CAP_N63")
		)
		(pad "AT2" smd circle
			(at -16.999966 16.999966 270)
			(size 0.508 0.508)
			(layers "F.Cu" "F.Mask" "F.Paste")
			(net "PCIE_TX_CAP_P63")
		)
		(pad "AT3" smd circle
			(at -15.999968 16.999966 270)
			(size 0.508 0.508)
			(layers "F.Cu" "F.Mask" "F.Paste")
			(net "GND")
		)
		(pad "AT4" smd circle
			(at -14.99997 16.999966 270)
			(size 0.4572 0.4572)
			(layers "F.Cu" "F.Mask" "F.Paste")
			(net "PCIE_RX_N63")
		)
		(pad "AT5" smd circle
			(at -13.999972 16.999966 270)
			(size 0.4572 0.4572)
			(layers "F.Cu" "F.Mask" "F.Paste")
			(net "PCIE_RX_P63")
		)
		(pad "AT6" smd circle
			(at -12.999974 16.999966 270)
			(size 0.4572 0.4572)
			(layers "F.Cu" "F.Mask" "F.Paste")
			(net "GND")
		)
		(pad "AT7" smd circle
			(at -11.999976 16.999966 270)
			(size 0.4572 0.4572)
			(layers "F.Cu" "F.Mask" "F.Paste")
			(net "GND")
		)
		(pad "AT8" smd circle
			(at -10.999978 16.999966 270)
			(size 0.4572 0.4572)
			(layers "F.Cu" "F.Mask" "F.Paste")
			(net "PCIE_TX_CAP_N64")
		)
		(pad "AT9" smd circle
			(at -9.99998 16.999966 270)
			(size 0.4572 0.4572)
			(layers "F.Cu" "F.Mask" "F.Paste")
			(net "PCIE_TX_CAP_P65")
		)
		(pad "AT10" smd circle
			(at -8.999982 16.999966 270)
			(size 0.4572 0.4572)
			(layers "F.Cu" "F.Mask" "F.Paste")
			(net "PCIE_TX_CAP_N66")
		)
		(pad "AT11" smd circle
			(at -7.999984 16.999966 270)
			(size 0.4572 0.4572)
			(layers "F.Cu" "F.Mask" "F.Paste")
			(net "PCIE_TX_CAP_P67")
		)
		(pad "AT12" smd circle
			(at -6.999986 16.999966 270)
			(size 0.4572 0.4572)
			(layers "F.Cu" "F.Mask" "F.Paste")
			(net "PCIE_TX_CAP_N68")
		)
		(pad "AT13" smd circle
			(at -5.999988 16.999966 270)
			(size 0.4572 0.4572)
			(layers "F.Cu" "F.Mask" "F.Paste")
			(net "PCIE_TX_CAP_P69")
		)
		(pad "AT14" smd circle
			(at -4.99999 16.999966 270)
			(size 0.4572 0.4572)
			(layers "F.Cu" "F.Mask" "F.Paste")
			(net "PCIE_TX_CAP_N70")
		)
		(pad "AT15" smd circle
			(at -3.999992 16.999966 270)
			(size 0.4572 0.4572)
			(layers "F.Cu" "F.Mask" "F.Paste")
			(net "PCIE_TX_CAP_P71")
		)
		(pad "AT16" smd circle
			(at -2.999994 16.999966 270)
			(size 0.4572 0.4572)
			(layers "F.Cu" "F.Mask" "F.Paste")
			(net "GND")
		)
		(pad "AT17" smd circle
			(at -1.999996 16.999966 270)
			(size 0.4572 0.4572)
			(layers "F.Cu" "F.Mask" "F.Paste")
			(net "PCIE_TX_CAP_N72")
		)
		(pad "AT18" smd circle
			(at -0.999998 16.999966 270)
			(size 0.4572 0.4572)
			(layers "F.Cu" "F.Mask" "F.Paste")
			(net "PCIE_TX_CAP_P73")
		)
		(pad "AT19" smd circle
			(at 0 16.999966 270)
			(size 0.4572 0.4572)
			(layers "F.Cu" "F.Mask" "F.Paste")
			(net "PCIE_TX_CAP_N74")
		)
		(pad "AT20" smd circle
			(at 0.999998 16.999966 270)
			(size 0.4572 0.4572)
			(layers "F.Cu" "F.Mask" "F.Paste")
			(net "PCIE_TX_CAP_P75")
		)
		(pad "AT21" smd circle
			(at 1.999996 16.999966 270)
			(size 0.4572 0.4572)
			(layers "F.Cu" "F.Mask" "F.Paste")
			(net "PCIE_TX_CAP_N76")
		)
		(pad "AT22" smd circle
			(at 2.999994 16.999966 270)
			(size 0.4572 0.4572)
			(layers "F.Cu" "F.Mask" "F.Paste")
			(net "Net_309")
		)
		(pad "AT23" smd circle
			(at 3.999992 16.999966 270)
			(size 0.4572 0.4572)
			(layers "F.Cu" "F.Mask" "F.Paste")
			(net "PCIE_TX_CAP_N78")
		)
		(pad "AT24" smd circle
			(at 4.99999 16.999966 270)
			(size 0.4572 0.4572)
			(layers "F.Cu" "F.Mask" "F.Paste")
			(net "Net_310")
		)
		(pad "AT25" smd circle
			(at 5.999988 16.999966 270)
			(size 0.4572 0.4572)
			(layers "F.Cu" "F.Mask" "F.Paste")
			(net "GND")
		)
		(pad "AT26" smd circle
			(at 6.999986 16.999966 270)
			(size 0.4572 0.4572)
			(layers "F.Cu" "F.Mask" "F.Paste")
			(net "PCIE_TX_CAP_N80")
		)
		(pad "AT27" smd circle
			(at 7.999984 16.999966 270)
			(size 0.4572 0.4572)
			(layers "F.Cu" "F.Mask" "F.Paste")
			(net "PCIE_TX_CAP_P81")
		)
		(pad "AT28" smd circle
			(at 8.999982 16.999966 270)
			(size 0.4572 0.4572)
			(layers "F.Cu" "F.Mask" "F.Paste")
			(net "PCIE_TX_CAP_N82")
		)
		(pad "AT29" smd circle
			(at 9.99998 16.999966 270)
			(size 0.4572 0.4572)
			(layers "F.Cu" "F.Mask" "F.Paste")
			(net "PCIE_TX_CAP_P83")
		)
		(pad "AT30" smd circle
			(at 10.999978 16.999966 270)
			(size 0.4572 0.4572)
			(layers "F.Cu" "F.Mask" "F.Paste")
			(net "PCIE_TX_CAP_N84")
		)
		(pad "AT31" smd circle
			(at 11.999976 16.999966 270)
			(size 0.4572 0.4572)
			(layers "F.Cu" "F.Mask" "F.Paste")
			(net "PCIE_TX_CAP_P85")
		)
		(pad "AT32" smd circle
			(at 12.999974 16.999966 270)
			(size 0.4572 0.4572)
			(layers "F.Cu" "F.Mask" "F.Paste")
			(net "PCIE_TX_CAP_N86")
		)
		(pad "AT33" smd circle
			(at 13.999972 16.999966 270)
			(size 0.4572 0.4572)
			(layers "F.Cu" "F.Mask" "F.Paste")
			(net "PCIE_TX_CAP_P87")
		)
		(pad "AT34" smd circle
			(at 14.99997 16.999966 270)
			(size 0.4572 0.4572)
			(layers "F.Cu" "F.Mask" "F.Paste")
			(net "GND")
		)
		(pad "AT35" smd circle
			(at 15.999968 16.999966 270)
			(size 0.508 0.508)
			(layers "F.Cu" "F.Mask" "F.Paste")
			(net "GND")
		)
		(pad "AT36" smd circle
			(at 16.999966 16.999966 270)
			(size 0.508 0.508)
			(layers "F.Cu" "F.Mask" "F.Paste")
			(net "PCIE_TX_CAP_P89")
		)
		(pad "AT37" smd circle
			(at 17.999964 16.999966 270)
			(size 0.508 0.508)
			(layers "F.Cu" "F.Mask" "F.Paste")
			(net "PCIE_TX_CAP_N89")
		)
		(pad "AU2" smd circle
			(at -16.999966 17.999964 270)
			(size 0.508 0.508)
			(layers "F.Cu" "F.Mask" "F.Paste")
			(net "GND")
		)
		(pad "AU3" smd circle
			(at -15.999968 17.999964 270)
			(size 0.508 0.508)
			(layers "F.Cu" "F.Mask" "F.Paste")
			(net "GND")
		)
		(pad "AU4" smd circle
			(at -14.99997 17.999964 270)
			(size 0.4572 0.4572)
			(layers "F.Cu" "F.Mask" "F.Paste")
			(net "GND")
		)
		(pad "AU5" smd circle
			(at -13.999972 17.999964 270)
			(size 0.4572 0.4572)
			(layers "F.Cu" "F.Mask" "F.Paste")
			(net "GND")
		)
		(pad "AU6" smd circle
			(at -12.999974 17.999964 270)
			(size 0.4572 0.4572)
			(layers "F.Cu" "F.Mask" "F.Paste")
			(net "GND")
		)
		(pad "AU7" smd circle
			(at -11.999976 17.999964 270)
			(size 0.4572 0.4572)
			(layers "F.Cu" "F.Mask" "F.Paste")
			(net "GND")
		)
		(pad "AU9" smd circle
			(at -9.99998 17.999964 270)
			(size 0.4572 0.4572)
			(layers "F.Cu" "F.Mask" "F.Paste")
			(net "PCIE_TX_CAP_N65")
		)
		(pad "AU11" smd circle
			(at -7.999984 17.999964 270)
			(size 0.4572 0.4572)
			(layers "F.Cu" "F.Mask" "F.Paste")
			(net "PCIE_TX_CAP_N67")
		)
		(pad "AU13" smd circle
			(at -5.999988 17.999964 270)
			(size 0.4572 0.4572)
			(layers "F.Cu" "F.Mask" "F.Paste")
			(net "PCIE_TX_CAP_N69")
		)
		(pad "AU15" smd circle
			(at -3.999992 17.999964 270)
			(size 0.4572 0.4572)
			(layers "F.Cu" "F.Mask" "F.Paste")
			(net "PCIE_TX_CAP_N71")
		)
		(pad "AU16" smd circle
			(at -2.999994 17.999964 270)
			(size 0.4572 0.4572)
			(layers "F.Cu" "F.Mask" "F.Paste")
			(net "GND")
		)
		(pad "AU18" smd circle
			(at -0.999998 17.999964 270)
			(size 0.4572 0.4572)
			(layers "F.Cu" "F.Mask" "F.Paste")
			(net "PCIE_TX_CAP_N73")
		)
		(pad "AU20" smd circle
			(at 0.999998 17.999964 270)
			(size 0.4572 0.4572)
			(layers "F.Cu" "F.Mask" "F.Paste")
			(net "PCIE_TX_CAP_N75")
		)
		(pad "AU22" smd circle
			(at 2.999994 17.999964 270)
			(size 0.4572 0.4572)
			(layers "F.Cu" "F.Mask" "F.Paste")
			(net "Net_307")
		)
		(pad "AU24" smd circle
			(at 4.99999 17.999964 270)
			(size 0.4572 0.4572)
			(layers "F.Cu" "F.Mask" "F.Paste")
			(net "Net_308")
		)
		(pad "AU25" smd circle
			(at 5.999988 17.999964 270)
			(size 0.4572 0.4572)
			(layers "F.Cu" "F.Mask" "F.Paste")
			(net "GND")
		)
		(pad "AU27" smd circle
			(at 7.999984 17.999964 270)
			(size 0.4572 0.4572)
			(layers "F.Cu" "F.Mask" "F.Paste")
			(net "PCIE_TX_CAP_N81")
		)
		(pad "AU29" smd circle
			(at 9.99998 17.999964 270)
			(size 0.4572 0.4572)
			(layers "F.Cu" "F.Mask" "F.Paste")
			(net "PCIE_TX_CAP_N83")
		)
		(pad "AU31" smd circle
			(at 11.999976 17.999964 270)
			(size 0.4572 0.4572)
			(layers "F.Cu" "F.Mask" "F.Paste")
			(net "PCIE_TX_CAP_N85")
		)
		(pad "AU33" smd circle
			(at 13.999972 17.999964 270)
			(size 0.4572 0.4572)
			(layers "F.Cu" "F.Mask" "F.Paste")
			(net "PCIE_TX_CAP_N87")
		)
		(pad "AU34" smd circle
			(at 14.99997 17.999964 270)
			(size 0.4572 0.4572)
			(layers "F.Cu" "F.Mask" "F.Paste")
			(net "GND")
		)
		(pad "AU35" smd circle
			(at 15.999968 17.999964 270)
			(size 0.508 0.508)
			(layers "F.Cu" "F.Mask" "F.Paste")
			(net "PCIE_TX_CAP_P88")
		)
		(pad "AU36" smd circle
			(at 16.999966 17.999964 270)
			(size 0.508 0.508)
			(layers "F.Cu" "F.Mask" "F.Paste")
			(net "PCIE_TX_CAP_N88")
		)
		(pad "B1" smd circle
			(at -17.999964 -16.999966 270)
			(size 0.508 0.508)
			(layers "F.Cu" "F.Mask" "F.Paste")
			(net "PCIE_TX_CAP_N32")
		)
		(pad "B2" smd circle
			(at -16.999966 -16.999966 270)
			(size 0.508 0.508)
			(layers "F.Cu" "F.Mask" "F.Paste")
			(net "PCIE_TX_CAP_P32")
		)
		(pad "B3" smd circle
			(at -15.999968 -16.999966 270)
			(size 0.508 0.508)
			(layers "F.Cu" "F.Mask" "F.Paste")
			(net "GND")
		)
		(pad "B4" smd circle
			(at -14.99997 -16.999966 270)
			(size 0.4572 0.4572)
			(layers "F.Cu" "F.Mask" "F.Paste")
			(net "PCIE_RX_N32")
		)
		(pad "B5" smd circle
			(at -13.999972 -16.999966 270)
			(size 0.4572 0.4572)
			(layers "F.Cu" "F.Mask" "F.Paste")
			(net "PCIE_RX_P32")
		)
		(pad "B6" smd circle
			(at -12.999974 -16.999966 270)
			(size 0.4572 0.4572)
			(layers "F.Cu" "F.Mask" "F.Paste")
			(net "GND")
		)
		(pad "B7" smd circle
			(at -11.999976 -16.999966 270)
			(size 0.4572 0.4572)
			(layers "F.Cu" "F.Mask" "F.Paste")
			(net "GND")
		)
		(pad "B8" smd circle
			(at -10.999978 -16.999966 270)
			(size 0.4572 0.4572)
			(layers "F.Cu" "F.Mask" "F.Paste")
			(net "PCIE_TX_CAP_N31")
		)
		(pad "B9" smd circle
			(at -9.99998 -16.999966 270)
			(size 0.4572 0.4572)
			(layers "F.Cu" "F.Mask" "F.Paste")
			(net "PCIE_TX_CAP_P30")
		)
		(pad "B10" smd circle
			(at -8.999982 -16.999966 270)
			(size 0.4572 0.4572)
			(layers "F.Cu" "F.Mask" "F.Paste")
			(net "PCIE_TX_CAP_N29")
		)
		(pad "B11" smd circle
			(at -7.999984 -16.999966 270)
			(size 0.4572 0.4572)
			(layers "F.Cu" "F.Mask" "F.Paste")
			(net "PCIE_TX_CAP_P28")
		)
		(pad "B12" smd circle
			(at -6.999986 -16.999966 270)
			(size 0.4572 0.4572)
			(layers "F.Cu" "F.Mask" "F.Paste")
			(net "PCIE_TX_CAP_N27")
		)
		(pad "B13" smd circle
			(at -5.999988 -16.999966 270)
			(size 0.4572 0.4572)
			(layers "F.Cu" "F.Mask" "F.Paste")
			(net "PCIE_TX_CAP_P26")
		)
		(pad "B14" smd circle
			(at -4.99999 -16.999966 270)
			(size 0.4572 0.4572)
			(layers "F.Cu" "F.Mask" "F.Paste")
			(net "PCIE_TX_CAP_N25")
		)
		(pad "B15" smd circle
			(at -3.999992 -16.999966 270)
			(size 0.4572 0.4572)
			(layers "F.Cu" "F.Mask" "F.Paste")
			(net "PCIE_TX_CAP_P24")
		)
		(pad "B16" smd circle
			(at -2.999994 -16.999966 270)
			(size 0.4572 0.4572)
			(layers "F.Cu" "F.Mask" "F.Paste")
			(net "GND")
		)
		(pad "B17" smd circle
			(at -1.999996 -16.999966 270)
			(size 0.4572 0.4572)
			(layers "F.Cu" "F.Mask" "F.Paste")
			(net "PCIE_TX_CAP_N23")
		)
		(pad "B18" smd circle
			(at -0.999998 -16.999966 270)
			(size 0.4572 0.4572)
			(layers "F.Cu" "F.Mask" "F.Paste")
			(net "PCIE_TX_CAP_P22")
		)
		(pad "B19" smd circle
			(at 0 -16.999966 270)
			(size 0.4572 0.4572)
			(layers "F.Cu" "F.Mask" "F.Paste")
			(net "PCIE_TX_CAP_N21")
		)
		(pad "B20" smd circle
			(at 0.999998 -16.999966 270)
			(size 0.4572 0.4572)
			(layers "F.Cu" "F.Mask" "F.Paste")
			(net "PCIE_TX_CAP_P20")
		)
		(pad "B21" smd circle
			(at 1.999996 -16.999966 270)
			(size 0.4572 0.4572)
			(layers "F.Cu" "F.Mask" "F.Paste")
			(net "PCIE_TX_CAP_N19")
		)
		(pad "B22" smd circle
			(at 2.999994 -16.999966 270)
			(size 0.4572 0.4572)
			(layers "F.Cu" "F.Mask" "F.Paste")
			(net "PCIE_TX_CAP_P18")
		)
		(pad "B23" smd circle
			(at 3.999992 -16.999966 270)
			(size 0.4572 0.4572)
			(layers "F.Cu" "F.Mask" "F.Paste")
			(net "PCIE_TX_CAP_N17")
		)
		(pad "B24" smd circle
			(at 4.99999 -16.999966 270)
			(size 0.4572 0.4572)
			(layers "F.Cu" "F.Mask" "F.Paste")
			(net "PCIE_TX_CAP_P16")
		)
		(pad "B25" smd circle
			(at 5.999988 -16.999966 270)
			(size 0.4572 0.4572)
			(layers "F.Cu" "F.Mask" "F.Paste")
			(net "GND")
		)
		(pad "B26" smd circle
			(at 6.999986 -16.999966 270)
			(size 0.4572 0.4572)
			(layers "F.Cu" "F.Mask" "F.Paste")
			(net "PCIE_TX_CAP_N15")
		)
		(pad "B27" smd circle
			(at 7.999984 -16.999966 270)
			(size 0.4572 0.4572)
			(layers "F.Cu" "F.Mask" "F.Paste")
			(net "PCIE_TX_CAP_P14")
		)
		(pad "B28" smd circle
			(at 8.999982 -16.999966 270)
			(size 0.4572 0.4572)
			(layers "F.Cu" "F.Mask" "F.Paste")
			(net "PCIE_TX_CAP_N13")
		)
		(pad "B29" smd circle
			(at 9.99998 -16.999966 270)
			(size 0.4572 0.4572)
			(layers "F.Cu" "F.Mask" "F.Paste")
			(net "PCIE_TX_CAP_P12")
		)
		(pad "B30" smd circle
			(at 10.999978 -16.999966 270)
			(size 0.4572 0.4572)
			(layers "F.Cu" "F.Mask" "F.Paste")
			(net "PCIE_TX_CAP_N11")
		)
		(pad "B31" smd circle
			(at 11.999976 -16.999966 270)
			(size 0.4572 0.4572)
			(layers "F.Cu" "F.Mask" "F.Paste")
			(net "PCIE_TX_CAP_P10")
		)
		(pad "B32" smd circle
			(at 12.999974 -16.999966 270)
			(size 0.4572 0.4572)
			(layers "F.Cu" "F.Mask" "F.Paste")
			(net "PCIE_TX_CAP_N9")
		)
		(pad "B33" smd circle
			(at 13.999972 -16.999966 270)
			(size 0.4572 0.4572)
			(layers "F.Cu" "F.Mask" "F.Paste")
			(net "PCIE_TX_CAP_P8")
		)
		(pad "B34" smd circle
			(at 14.99997 -16.999966 270)
			(size 0.4572 0.4572)
			(layers "F.Cu" "F.Mask" "F.Paste")
			(net "GND")
		)
		(pad "B35" smd circle
			(at 15.999968 -16.999966 270)
			(size 0.508 0.508)
			(layers "F.Cu" "F.Mask" "F.Paste")
			(net "GND")
		)
		(pad "B36" smd circle
			(at 16.999966 -16.999966 270)
			(size 0.508 0.508)
			(layers "F.Cu" "F.Mask" "F.Paste")
			(net "PCIE_TX_CAP_P6")
		)
		(pad "B37" smd circle
			(at 17.999964 -16.999966 270)
			(size 0.508 0.508)
			(layers "F.Cu" "F.Mask" "F.Paste")
			(net "PCIE_TX_CAP_N6")
		)
		(pad "C2" smd circle
			(at -16.999966 -15.999968 270)
			(size 0.508 0.508)
			(layers "F.Cu" "F.Mask" "F.Paste")
			(net "PCIE_TX_CAP_N33")
		)
		(pad "C3" smd circle
			(at -15.999968 -15.999968 270)
			(size 0.508 0.508)
			(layers "F.Cu" "F.Mask" "F.Paste")
			(net "PCIE_TX_CAP_P33")
		)
		(pad "C4" smd circle
			(at -14.99997 -15.999968 270)
			(size 0.4572 0.4572)
			(layers "F.Cu" "F.Mask" "F.Paste")
			(net "GND")
		)
		(pad "C5" smd circle
			(at -13.999972 -15.999968 270)
			(size 0.4572 0.4572)
			(layers "F.Cu" "F.Mask" "F.Paste")
			(net "PCIE_RX_N33")
		)
		(pad "C6" smd circle
			(at -12.999974 -15.999968 270)
			(size 0.4572 0.4572)
			(layers "F.Cu" "F.Mask" "F.Paste")
			(net "PCIE_RX_P33")
		)
		(pad "C7" smd circle
			(at -11.999976 -15.999968 270)
			(size 0.4572 0.4572)
			(layers "F.Cu" "F.Mask" "F.Paste")
			(net "GND")
		)
		(pad "C8" smd circle
			(at -10.999978 -15.999968 270)
			(size 0.4572 0.4572)
			(layers "F.Cu" "F.Mask" "F.Paste")
			(net "PCIE_TX_CAP_P31")
		)
		(pad "C9" smd circle
			(at -9.99998 -15.999968 270)
			(size 0.4572 0.4572)
			(layers "F.Cu" "F.Mask" "F.Paste")
			(net "GND")
		)
		(pad "C10" smd circle
			(at -8.999982 -15.999968 270)
			(size 0.4572 0.4572)
			(layers "F.Cu" "F.Mask" "F.Paste")
			(net "PCIE_TX_CAP_P29")
		)
		(pad "C11" smd circle
			(at -7.999984 -15.999968 270)
			(size 0.4572 0.4572)
			(layers "F.Cu" "F.Mask" "F.Paste")
			(net "GND")
		)
		(pad "C12" smd circle
			(at -6.999986 -15.999968 270)
			(size 0.4572 0.4572)
			(layers "F.Cu" "F.Mask" "F.Paste")
			(net "PCIE_TX_CAP_P27")
		)
		(pad "C13" smd circle
			(at -5.999988 -15.999968 270)
			(size 0.4572 0.4572)
			(layers "F.Cu" "F.Mask" "F.Paste")
			(net "GND")
		)
		(pad "C14" smd circle
			(at -4.99999 -15.999968 270)
			(size 0.4572 0.4572)
			(layers "F.Cu" "F.Mask" "F.Paste")
			(net "PCIE_TX_CAP_P25")
		)
		(pad "C15" smd circle
			(at -3.999992 -15.999968 270)
			(size 0.4572 0.4572)
			(layers "F.Cu" "F.Mask" "F.Paste")
			(net "GND")
		)
		(pad "C16" smd circle
			(at -2.999994 -15.999968 270)
			(size 0.4572 0.4572)
			(layers "F.Cu" "F.Mask" "F.Paste")
			(net "GND")
		)
		(pad "C17" smd circle
			(at -1.999996 -15.999968 270)
			(size 0.4572 0.4572)
			(layers "F.Cu" "F.Mask" "F.Paste")
			(net "PCIE_TX_CAP_P23")
		)
		(pad "C18" smd circle
			(at -0.999998 -15.999968 270)
			(size 0.4572 0.4572)
			(layers "F.Cu" "F.Mask" "F.Paste")
			(net "GND")
		)
		(pad "C19" smd circle
			(at 0 -15.999968 270)
			(size 0.4572 0.4572)
			(layers "F.Cu" "F.Mask" "F.Paste")
			(net "PCIE_TX_CAP_P21")
		)
		(pad "C20" smd circle
			(at 0.999998 -15.999968 270)
			(size 0.4572 0.4572)
			(layers "F.Cu" "F.Mask" "F.Paste")
			(net "GND")
		)
		(pad "C21" smd circle
			(at 1.999996 -15.999968 270)
			(size 0.4572 0.4572)
			(layers "F.Cu" "F.Mask" "F.Paste")
			(net "PCIE_TX_CAP_P19")
		)
		(pad "C22" smd circle
			(at 2.999994 -15.999968 270)
			(size 0.4572 0.4572)
			(layers "F.Cu" "F.Mask" "F.Paste")
			(net "GND")
		)
		(pad "C23" smd circle
			(at 3.999992 -15.999968 270)
			(size 0.4572 0.4572)
			(layers "F.Cu" "F.Mask" "F.Paste")
			(net "PCIE_TX_CAP_P17")
		)
		(pad "C24" smd circle
			(at 4.99999 -15.999968 270)
			(size 0.4572 0.4572)
			(layers "F.Cu" "F.Mask" "F.Paste")
			(net "GND")
		)
		(pad "C25" smd circle
			(at 5.999988 -15.999968 270)
			(size 0.4572 0.4572)
			(layers "F.Cu" "F.Mask" "F.Paste")
			(net "GND")
		)
		(pad "C26" smd circle
			(at 6.999986 -15.999968 270)
			(size 0.4572 0.4572)
			(layers "F.Cu" "F.Mask" "F.Paste")
			(net "PCIE_TX_CAP_P15")
		)
		(pad "C27" smd circle
			(at 7.999984 -15.999968 270)
			(size 0.4572 0.4572)
			(layers "F.Cu" "F.Mask" "F.Paste")
			(net "GND")
		)
		(pad "C28" smd circle
			(at 8.999982 -15.999968 270)
			(size 0.4572 0.4572)
			(layers "F.Cu" "F.Mask" "F.Paste")
			(net "PCIE_TX_CAP_P13")
		)
		(pad "C29" smd circle
			(at 9.99998 -15.999968 270)
			(size 0.4572 0.4572)
			(layers "F.Cu" "F.Mask" "F.Paste")
			(net "GND")
		)
		(pad "C30" smd circle
			(at 10.999978 -15.999968 270)
			(size 0.4572 0.4572)
			(layers "F.Cu" "F.Mask" "F.Paste")
			(net "PCIE_TX_CAP_P11")
		)
		(pad "C31" smd circle
			(at 11.999976 -15.999968 270)
			(size 0.4572 0.4572)
			(layers "F.Cu" "F.Mask" "F.Paste")
			(net "GND")
		)
		(pad "C32" smd circle
			(at 12.999974 -15.999968 270)
			(size 0.4572 0.4572)
			(layers "F.Cu" "F.Mask" "F.Paste")
			(net "PCIE_TX_CAP_P9")
		)
		(pad "C33" smd circle
			(at 13.999972 -15.999968 270)
			(size 0.4572 0.4572)
			(layers "F.Cu" "F.Mask" "F.Paste")
			(net "GND")
		)
		(pad "C34" smd circle
			(at 14.99997 -15.999968 270)
			(size 0.4572 0.4572)
			(layers "F.Cu" "F.Mask" "F.Paste")
			(net "GND")
		)
		(pad "C35" smd circle
			(at 15.999968 -15.999968 270)
			(size 0.508 0.508)
			(layers "F.Cu" "F.Mask" "F.Paste")
			(net "PCIE_TX_CAP_P5")
		)
		(pad "C36" smd circle
			(at 16.999966 -15.999968 270)
			(size 0.508 0.508)
			(layers "F.Cu" "F.Mask" "F.Paste")
			(net "PCIE_TX_CAP_N5")
		)
		(pad "D1" smd circle
			(at -17.999964 -14.99997 270)
			(size 0.4572 0.4572)
			(layers "F.Cu" "F.Mask" "F.Paste")
			(net "PCIE_TX_CAP_N34")
		)
		(pad "D2" smd circle
			(at -16.999966 -14.99997 270)
			(size 0.4572 0.4572)
			(layers "F.Cu" "F.Mask" "F.Paste")
			(net "PCIE_TX_CAP_P34")
		)
		(pad "D3" smd circle
			(at -15.999968 -14.99997 270)
			(size 0.4572 0.4572)
			(layers "F.Cu" "F.Mask" "F.Paste")
			(net "GND")
		)
		(pad "D4" smd circle
			(at -14.99997 -14.99997 270)
			(size 0.4572 0.4572)
			(layers "F.Cu" "F.Mask" "F.Paste")
			(net "PCIE_RX_N34")
		)
		(pad "D5" smd circle
			(at -13.999972 -14.99997 270)
			(size 0.4572 0.4572)
			(layers "F.Cu" "F.Mask" "F.Paste")
			(net "PCIE_RX_P34")
		)
		(pad "D6" smd circle
			(at -12.999974 -14.99997 270)
			(size 0.4572 0.4572)
			(layers "F.Cu" "F.Mask" "F.Paste")
			(net "GND")
		)
		(pad "D7" smd circle
			(at -11.999976 -14.99997 270)
			(size 0.4572 0.4572)
			(layers "F.Cu" "F.Mask" "F.Paste")
			(net "GND")
		)
		(pad "D8" smd circle
			(at -10.999978 -14.99997 270)
			(size 0.4572 0.4572)
			(layers "F.Cu" "F.Mask" "F.Paste")
			(net "GND")
		)
		(pad "D9" smd circle
			(at -9.99998 -14.99997 270)
			(size 0.4572 0.4572)
			(layers "F.Cu" "F.Mask" "F.Paste")
			(net "PCIE_RX_N30")
		)
		(pad "D10" smd circle
			(at -8.999982 -14.99997 270)
			(size 0.4572 0.4572)
			(layers "F.Cu" "F.Mask" "F.Paste")
			(net "GND")
		)
		(pad "D11" smd circle
			(at -7.999984 -14.99997 270)
			(size 0.4572 0.4572)
			(layers "F.Cu" "F.Mask" "F.Paste")
			(net "PCIE_RX_N28")
		)
		(pad "D12" smd circle
			(at -6.999986 -14.99997 270)
			(size 0.4572 0.4572)
			(layers "F.Cu" "F.Mask" "F.Paste")
			(net "GND")
		)
		(pad "D13" smd circle
			(at -5.999988 -14.99997 270)
			(size 0.4572 0.4572)
			(layers "F.Cu" "F.Mask" "F.Paste")
			(net "PCIE_RX_N26")
		)
		(pad "D14" smd circle
			(at -4.99999 -14.99997 270)
			(size 0.4572 0.4572)
			(layers "F.Cu" "F.Mask" "F.Paste")
			(net "GND")
		)
		(pad "D15" smd circle
			(at -3.999992 -14.99997 270)
			(size 0.4572 0.4572)
			(layers "F.Cu" "F.Mask" "F.Paste")
			(net "PCIE_RX_N24")
		)
		(pad "D16" smd circle
			(at -2.999994 -14.99997 270)
			(size 0.4572 0.4572)
			(layers "F.Cu" "F.Mask" "F.Paste")
			(net "GND")
		)
		(pad "D17" smd circle
			(at -1.999996 -14.99997 270)
			(size 0.4572 0.4572)
			(layers "F.Cu" "F.Mask" "F.Paste")
			(net "GND")
		)
		(pad "D18" smd circle
			(at -0.999998 -14.99997 270)
			(size 0.4572 0.4572)
			(layers "F.Cu" "F.Mask" "F.Paste")
			(net "PCIE_RX_N22")
		)
		(pad "D19" smd circle
			(at 0 -14.99997 270)
			(size 0.4572 0.4572)
			(layers "F.Cu" "F.Mask" "F.Paste")
			(net "GND")
		)
		(pad "D20" smd circle
			(at 0.999998 -14.99997 270)
			(size 0.4572 0.4572)
			(layers "F.Cu" "F.Mask" "F.Paste")
			(net "PCIE_RX_N20")
		)
		(pad "D21" smd circle
			(at 1.999996 -14.99997 270)
			(size 0.4572 0.4572)
			(layers "F.Cu" "F.Mask" "F.Paste")
			(net "GND")
		)
		(pad "D22" smd circle
			(at 2.999994 -14.99997 270)
			(size 0.4572 0.4572)
			(layers "F.Cu" "F.Mask" "F.Paste")
			(net "PCIE_RX_N18")
		)
		(pad "D23" smd circle
			(at 3.999992 -14.99997 270)
			(size 0.4572 0.4572)
			(layers "F.Cu" "F.Mask" "F.Paste")
			(net "GND")
		)
		(pad "D24" smd circle
			(at 4.99999 -14.99997 270)
			(size 0.4572 0.4572)
			(layers "F.Cu" "F.Mask" "F.Paste")
			(net "PCIE_RX_N16")
		)
		(pad "D25" smd circle
			(at 5.999988 -14.99997 270)
			(size 0.4572 0.4572)
			(layers "F.Cu" "F.Mask" "F.Paste")
			(net "GND")
		)
		(pad "D26" smd circle
			(at 6.999986 -14.99997 270)
			(size 0.4572 0.4572)
			(layers "F.Cu" "F.Mask" "F.Paste")
			(net "GND")
		)
		(pad "D27" smd circle
			(at 7.999984 -14.99997 270)
			(size 0.4572 0.4572)
			(layers "F.Cu" "F.Mask" "F.Paste")
			(net "PCIE_RX_N14")
		)
		(pad "D28" smd circle
			(at 8.999982 -14.99997 270)
			(size 0.4572 0.4572)
			(layers "F.Cu" "F.Mask" "F.Paste")
			(net "GND")
		)
		(pad "D29" smd circle
			(at 9.99998 -14.99997 270)
			(size 0.4572 0.4572)
			(layers "F.Cu" "F.Mask" "F.Paste")
			(net "PCIE_RX_N12")
		)
		(pad "D30" smd circle
			(at 10.999978 -14.99997 270)
			(size 0.4572 0.4572)
			(layers "F.Cu" "F.Mask" "F.Paste")
			(net "GND")
		)
		(pad "D31" smd circle
			(at 11.999976 -14.99997 270)
			(size 0.4572 0.4572)
			(layers "F.Cu" "F.Mask" "F.Paste")
			(net "PCIE_RX_N10")
		)
		(pad "D32" smd circle
			(at 12.999974 -14.99997 270)
			(size 0.4572 0.4572)
			(layers "F.Cu" "F.Mask" "F.Paste")
			(net "GND")
		)
		(pad "D33" smd circle
			(at 13.999972 -14.99997 270)
			(size 0.4572 0.4572)
			(layers "F.Cu" "F.Mask" "F.Paste")
			(net "PCIE_RX_N8")
		)
		(pad "D34" smd circle
			(at 14.99997 -14.99997 270)
			(size 0.4572 0.4572)
			(layers "F.Cu" "F.Mask" "F.Paste")
			(net "GND")
		)
		(pad "D35" smd circle
			(at 15.999968 -14.99997 270)
			(size 0.4572 0.4572)
			(layers "F.Cu" "F.Mask" "F.Paste")
			(net "GND")
		)
		(pad "D36" smd circle
			(at 16.999966 -14.99997 270)
			(size 0.4572 0.4572)
			(layers "F.Cu" "F.Mask" "F.Paste")
			(net "PCIE_TX_CAP_P4")
		)
		(pad "D37" smd circle
			(at 17.999964 -14.99997 270)
			(size 0.4572 0.4572)
			(layers "F.Cu" "F.Mask" "F.Paste")
			(net "PCIE_TX_CAP_N4")
		)
		(pad "E2" smd circle
			(at -16.999966 -13.999972 270)
			(size 0.4572 0.4572)
			(layers "F.Cu" "F.Mask" "F.Paste")
			(net "PCIE_TX_CAP_N35")
		)
		(pad "E3" smd circle
			(at -15.999968 -13.999972 270)
			(size 0.4572 0.4572)
			(layers "F.Cu" "F.Mask" "F.Paste")
			(net "PCIE_TX_CAP_P35")
		)
		(pad "E4" smd circle
			(at -14.99997 -13.999972 270)
			(size 0.4572 0.4572)
			(layers "F.Cu" "F.Mask" "F.Paste")
			(net "GND")
		)
		(pad "E5" smd circle
			(at -13.999972 -13.999972 270)
			(size 0.4572 0.4572)
			(layers "F.Cu" "F.Mask" "F.Paste")
			(net "PCIE_RX_N35")
		)
		(pad "E6" smd circle
			(at -12.999974 -13.999972 270)
			(size 0.4572 0.4572)
			(layers "F.Cu" "F.Mask" "F.Paste")
			(net "PCIE_RX_P35")
		)
		(pad "E7" smd circle
			(at -11.999976 -13.999972 270)
			(size 0.4572 0.4572)
			(layers "F.Cu" "F.Mask" "F.Paste")
			(net "GND")
		)
		(pad "E8" smd circle
			(at -10.999978 -13.999972 270)
			(size 0.4572 0.4572)
			(layers "F.Cu" "F.Mask" "F.Paste")
			(net "PCIE_RX_N31")
		)
		(pad "E9" smd circle
			(at -9.99998 -13.999972 270)
			(size 0.4572 0.4572)
			(layers "F.Cu" "F.Mask" "F.Paste")
			(net "PCIE_RX_P30")
		)
		(pad "E10" smd circle
			(at -8.999982 -13.999972 270)
			(size 0.4572 0.4572)
			(layers "F.Cu" "F.Mask" "F.Paste")
			(net "PCIE_RX_N29")
		)
		(pad "E11" smd circle
			(at -7.999984 -13.999972 270)
			(size 0.4572 0.4572)
			(layers "F.Cu" "F.Mask" "F.Paste")
			(net "PCIE_RX_P28")
		)
		(pad "E12" smd circle
			(at -6.999986 -13.999972 270)
			(size 0.4572 0.4572)
			(layers "F.Cu" "F.Mask" "F.Paste")
			(net "PCIE_RX_N27")
		)
		(pad "E13" smd circle
			(at -5.999988 -13.999972 270)
			(size 0.4572 0.4572)
			(layers "F.Cu" "F.Mask" "F.Paste")
			(net "PCIE_RX_P26")
		)
		(pad "E14" smd circle
			(at -4.99999 -13.999972 270)
			(size 0.4572 0.4572)
			(layers "F.Cu" "F.Mask" "F.Paste")
			(net "PCIE_RX_N25")
		)
		(pad "E15" smd circle
			(at -3.999992 -13.999972 270)
			(size 0.4572 0.4572)
			(layers "F.Cu" "F.Mask" "F.Paste")
			(net "PCIE_RX_P24")
		)
		(pad "E16" smd circle
			(at -2.999994 -13.999972 270)
			(size 0.4572 0.4572)
			(layers "F.Cu" "F.Mask" "F.Paste")
			(net "GND")
		)
		(pad "E17" smd circle
			(at -1.999996 -13.999972 270)
			(size 0.4572 0.4572)
			(layers "F.Cu" "F.Mask" "F.Paste")
			(net "PCIE_RX_N23")
		)
		(pad "E18" smd circle
			(at -0.999998 -13.999972 270)
			(size 0.4572 0.4572)
			(layers "F.Cu" "F.Mask" "F.Paste")
			(net "PCIE_RX_P22")
		)
		(pad "E19" smd circle
			(at 0 -13.999972 270)
			(size 0.4572 0.4572)
			(layers "F.Cu" "F.Mask" "F.Paste")
			(net "PCIE_RX_N21")
		)
		(pad "E20" smd circle
			(at 0.999998 -13.999972 270)
			(size 0.4572 0.4572)
			(layers "F.Cu" "F.Mask" "F.Paste")
			(net "PCIE_RX_P20")
		)
		(pad "E21" smd circle
			(at 1.999996 -13.999972 270)
			(size 0.4572 0.4572)
			(layers "F.Cu" "F.Mask" "F.Paste")
			(net "PCIE_RX_N19")
		)
		(pad "E22" smd circle
			(at 2.999994 -13.999972 270)
			(size 0.4572 0.4572)
			(layers "F.Cu" "F.Mask" "F.Paste")
			(net "PCIE_RX_P18")
		)
		(pad "E23" smd circle
			(at 3.999992 -13.999972 270)
			(size 0.4572 0.4572)
			(layers "F.Cu" "F.Mask" "F.Paste")
			(net "PCIE_RX_N17")
		)
		(pad "E24" smd circle
			(at 4.99999 -13.999972 270)
			(size 0.4572 0.4572)
			(layers "F.Cu" "F.Mask" "F.Paste")
			(net "PCIE_RX_P16")
		)
		(pad "E25" smd circle
			(at 5.999988 -13.999972 270)
			(size 0.4572 0.4572)
			(layers "F.Cu" "F.Mask" "F.Paste")
			(net "GND")
		)
		(pad "E26" smd circle
			(at 6.999986 -13.999972 270)
			(size 0.4572 0.4572)
			(layers "F.Cu" "F.Mask" "F.Paste")
			(net "PCIE_RX_N15")
		)
		(pad "E27" smd circle
			(at 7.999984 -13.999972 270)
			(size 0.4572 0.4572)
			(layers "F.Cu" "F.Mask" "F.Paste")
			(net "PCIE_RX_P14")
		)
		(pad "E28" smd circle
			(at 8.999982 -13.999972 270)
			(size 0.4572 0.4572)
			(layers "F.Cu" "F.Mask" "F.Paste")
			(net "PCIE_RX_N13")
		)
		(pad "E29" smd circle
			(at 9.99998 -13.999972 270)
			(size 0.4572 0.4572)
			(layers "F.Cu" "F.Mask" "F.Paste")
			(net "PCIE_RX_P12")
		)
		(pad "E30" smd circle
			(at 10.999978 -13.999972 270)
			(size 0.4572 0.4572)
			(layers "F.Cu" "F.Mask" "F.Paste")
			(net "PCIE_RX_N11")
		)
		(pad "E31" smd circle
			(at 11.999976 -13.999972 270)
			(size 0.4572 0.4572)
			(layers "F.Cu" "F.Mask" "F.Paste")
			(net "PCIE_RX_P10")
		)
		(pad "E32" smd circle
			(at 12.999974 -13.999972 270)
			(size 0.4572 0.4572)
			(layers "F.Cu" "F.Mask" "F.Paste")
			(net "PCIE_RX_N9")
		)
		(pad "E33" smd circle
			(at 13.999972 -13.999972 270)
			(size 0.4572 0.4572)
			(layers "F.Cu" "F.Mask" "F.Paste")
			(net "PCIE_RX_P8")
		)
		(pad "E34" smd circle
			(at 14.99997 -13.999972 270)
			(size 0.4572 0.4572)
			(layers "F.Cu" "F.Mask" "F.Paste")
			(net "GND")
		)
		(pad "E35" smd circle
			(at 15.999968 -13.999972 270)
			(size 0.4572 0.4572)
			(layers "F.Cu" "F.Mask" "F.Paste")
			(net "PCIE_TX_CAP_P3")
		)
		(pad "E36" smd circle
			(at 16.999966 -13.999972 270)
			(size 0.4572 0.4572)
			(layers "F.Cu" "F.Mask" "F.Paste")
			(net "PCIE_TX_CAP_N3")
		)
		(pad "F1" smd circle
			(at -17.999964 -12.999974 270)
			(size 0.4572 0.4572)
			(layers "F.Cu" "F.Mask" "F.Paste")
			(net "PCIE_TX_CAP_N36")
		)
		(pad "F2" smd circle
			(at -16.999966 -12.999974 270)
			(size 0.4572 0.4572)
			(layers "F.Cu" "F.Mask" "F.Paste")
			(net "PCIE_TX_CAP_P36")
		)
		(pad "F3" smd circle
			(at -15.999968 -12.999974 270)
			(size 0.4572 0.4572)
			(layers "F.Cu" "F.Mask" "F.Paste")
			(net "GND")
		)
		(pad "F4" smd circle
			(at -14.99997 -12.999974 270)
			(size 0.4572 0.4572)
			(layers "F.Cu" "F.Mask" "F.Paste")
			(net "PCIE_RX_N36")
		)
		(pad "F5" smd circle
			(at -13.999972 -12.999974 270)
			(size 0.4572 0.4572)
			(layers "F.Cu" "F.Mask" "F.Paste")
			(net "PCIE_RX_P36")
		)
		(pad "F6" smd circle
			(at -12.999974 -12.999974 270)
			(size 0.4572 0.4572)
			(layers "F.Cu" "F.Mask" "F.Paste")
			(net "GND")
		)
		(pad "F7" smd circle
			(at -11.999976 -12.999974 270)
			(size 0.4572 0.4572)
			(layers "F.Cu" "F.Mask" "F.Paste")
			(net "DUT_AVD_PCIE")
		)
		(pad "F8" smd circle
			(at -10.999978 -12.999974 270)
			(size 0.4572 0.4572)
			(layers "F.Cu" "F.Mask" "F.Paste")
			(net "PCIE_RX_P31")
		)
		(pad "F9" smd circle
			(at -9.99998 -12.999974 270)
			(size 0.4572 0.4572)
			(layers "F.Cu" "F.Mask" "F.Paste")
			(net "GND")
		)
		(pad "F10" smd circle
			(at -8.999982 -12.999974 270)
			(size 0.4572 0.4572)
			(layers "F.Cu" "F.Mask" "F.Paste")
			(net "PCIE_RX_P29")
		)
		(pad "F11" smd circle
			(at -7.999984 -12.999974 270)
			(size 0.4572 0.4572)
			(layers "F.Cu" "F.Mask" "F.Paste")
			(net "GND")
		)
		(pad "F12" smd circle
			(at -6.999986 -12.999974 270)
			(size 0.4572 0.4572)
			(layers "F.Cu" "F.Mask" "F.Paste")
			(net "PCIE_RX_P27")
		)
		(pad "F13" smd circle
			(at -5.999988 -12.999974 270)
			(size 0.4572 0.4572)
			(layers "F.Cu" "F.Mask" "F.Paste")
			(net "GND")
		)
		(pad "F14" smd circle
			(at -4.99999 -12.999974 270)
			(size 0.4572 0.4572)
			(layers "F.Cu" "F.Mask" "F.Paste")
			(net "PCIE_RX_P25")
		)
		(pad "F15" smd circle
			(at -3.999992 -12.999974 270)
			(size 0.4572 0.4572)
			(layers "F.Cu" "F.Mask" "F.Paste")
			(net "GND")
		)
		(pad "F16" smd circle
			(at -2.999994 -12.999974 270)
			(size 0.4572 0.4572)
			(layers "F.Cu" "F.Mask" "F.Paste")
			(net "DUT_AVD_PCIE")
		)
		(pad "F17" smd circle
			(at -1.999996 -12.999974 270)
			(size 0.4572 0.4572)
			(layers "F.Cu" "F.Mask" "F.Paste")
			(net "PCIE_RX_P23")
		)
		(pad "F18" smd circle
			(at -0.999998 -12.999974 270)
			(size 0.4572 0.4572)
			(layers "F.Cu" "F.Mask" "F.Paste")
			(net "GND")
		)
		(pad "F19" smd circle
			(at 0 -12.999974 270)
			(size 0.4572 0.4572)
			(layers "F.Cu" "F.Mask" "F.Paste")
			(net "PCIE_RX_P21")
		)
		(pad "F20" smd circle
			(at 0.999998 -12.999974 270)
			(size 0.4572 0.4572)
			(layers "F.Cu" "F.Mask" "F.Paste")
			(net "GND")
		)
		(pad "F21" smd circle
			(at 1.999996 -12.999974 270)
			(size 0.4572 0.4572)
			(layers "F.Cu" "F.Mask" "F.Paste")
			(net "PCIE_RX_P19")
		)
		(pad "F22" smd circle
			(at 2.999994 -12.999974 270)
			(size 0.4572 0.4572)
			(layers "F.Cu" "F.Mask" "F.Paste")
			(net "GND")
		)
		(pad "F23" smd circle
			(at 3.999992 -12.999974 270)
			(size 0.4572 0.4572)
			(layers "F.Cu" "F.Mask" "F.Paste")
			(net "PCIE_RX_P17")
		)
		(pad "F24" smd circle
			(at 4.99999 -12.999974 270)
			(size 0.4572 0.4572)
			(layers "F.Cu" "F.Mask" "F.Paste")
			(net "GND")
		)
		(pad "F25" smd circle
			(at 5.999988 -12.999974 270)
			(size 0.4572 0.4572)
			(layers "F.Cu" "F.Mask" "F.Paste")
			(net "DUT_AVD_PCIE")
		)
		(pad "F26" smd circle
			(at 6.999986 -12.999974 270)
			(size 0.4572 0.4572)
			(layers "F.Cu" "F.Mask" "F.Paste")
			(net "PCIE_RX_P15")
		)
		(pad "F27" smd circle
			(at 7.999984 -12.999974 270)
			(size 0.4572 0.4572)
			(layers "F.Cu" "F.Mask" "F.Paste")
			(net "GND")
		)
		(pad "F28" smd circle
			(at 8.999982 -12.999974 270)
			(size 0.4572 0.4572)
			(layers "F.Cu" "F.Mask" "F.Paste")
			(net "PCIE_RX_P13")
		)
		(pad "F29" smd circle
			(at 9.99998 -12.999974 270)
			(size 0.4572 0.4572)
			(layers "F.Cu" "F.Mask" "F.Paste")
			(net "GND")
		)
		(pad "F30" smd circle
			(at 10.999978 -12.999974 270)
			(size 0.4572 0.4572)
			(layers "F.Cu" "F.Mask" "F.Paste")
			(net "PCIE_RX_P11")
		)
		(pad "F31" smd circle
			(at 11.999976 -12.999974 270)
			(size 0.4572 0.4572)
			(layers "F.Cu" "F.Mask" "F.Paste")
			(net "GND")
		)
		(pad "F32" smd circle
			(at 12.999974 -12.999974 270)
			(size 0.4572 0.4572)
			(layers "F.Cu" "F.Mask" "F.Paste")
			(net "PCIE_RX_P9")
		)
		(pad "F33" smd circle
			(at 13.999972 -12.999974 270)
			(size 0.4572 0.4572)
			(layers "F.Cu" "F.Mask" "F.Paste")
			(net "DUT_AVD_PCIE")
		)
		(pad "F34" smd circle
			(at 14.99997 -12.999974 270)
			(size 0.4572 0.4572)
			(layers "F.Cu" "F.Mask" "F.Paste")
			(net "GND")
		)
		(pad "F35" smd circle
			(at 15.999968 -12.999974 270)
			(size 0.4572 0.4572)
			(layers "F.Cu" "F.Mask" "F.Paste")
			(net "GND")
		)
		(pad "F36" smd circle
			(at 16.999966 -12.999974 270)
			(size 0.4572 0.4572)
			(layers "F.Cu" "F.Mask" "F.Paste")
			(net "PCIE_TX_CAP_P2")
		)
		(pad "F37" smd circle
			(at 17.999964 -12.999974 270)
			(size 0.4572 0.4572)
			(layers "F.Cu" "F.Mask" "F.Paste")
			(net "PCIE_TX_CAP_N2")
		)
		(pad "G2" smd circle
			(at -16.999966 -11.999976 270)
			(size 0.4572 0.4572)
			(layers "F.Cu" "F.Mask" "F.Paste")
			(net "PCIE_TX_CAP_N37")
		)
		(pad "G3" smd circle
			(at -15.999968 -11.999976 270)
			(size 0.4572 0.4572)
			(layers "F.Cu" "F.Mask" "F.Paste")
			(net "PCIE_TX_CAP_P37")
		)
		(pad "G4" smd circle
			(at -14.99997 -11.999976 270)
			(size 0.4572 0.4572)
			(layers "F.Cu" "F.Mask" "F.Paste")
			(net "GND")
		)
		(pad "G5" smd circle
			(at -13.999972 -11.999976 270)
			(size 0.4572 0.4572)
			(layers "F.Cu" "F.Mask" "F.Paste")
			(net "PCIE_RX_N37")
		)
		(pad "G6" smd circle
			(at -12.999974 -11.999976 270)
			(size 0.4572 0.4572)
			(layers "F.Cu" "F.Mask" "F.Paste")
			(net "PCIE_RX_P37")
		)
		(pad "G7" smd circle
			(at -11.999976 -11.999976 270)
			(size 0.4572 0.4572)
			(layers "F.Cu" "F.Mask" "F.Paste")
			(net "DUT_AVD_PCIE")
		)
		(pad "G8" smd circle
			(at -10.999978 -11.999976 270)
			(size 0.4572 0.4572)
			(layers "F.Cu" "F.Mask" "F.Paste")
			(net "DUT_AVD_PCIE")
		)
		(pad "G9" smd circle
			(at -9.99998 -11.999976 270)
			(size 0.4572 0.4572)
			(layers "F.Cu" "F.Mask" "F.Paste")
			(net "DUT_AVD_PCIE")
		)
		(pad "G10" smd circle
			(at -8.999982 -11.999976 270)
			(size 0.4572 0.4572)
			(layers "F.Cu" "F.Mask" "F.Paste")
			(net "DUT_AVD_PCIE")
		)
		(pad "G11" smd circle
			(at -7.999984 -11.999976 270)
			(size 0.4572 0.4572)
			(layers "F.Cu" "F.Mask" "F.Paste")
			(net "DUT_AVD_PCIE")
		)
		(pad "G12" smd circle
			(at -6.999986 -11.999976 270)
			(size 0.4572 0.4572)
			(layers "F.Cu" "F.Mask" "F.Paste")
			(net "DUT_AVD_PCIE")
		)
		(pad "G13" smd circle
			(at -5.999988 -11.999976 270)
			(size 0.4572 0.4572)
			(layers "F.Cu" "F.Mask" "F.Paste")
			(net "DUT_AVD_PCIE")
		)
		(pad "G14" smd circle
			(at -4.99999 -11.999976 270)
			(size 0.4572 0.4572)
			(layers "F.Cu" "F.Mask" "F.Paste")
			(net "DUT_AVD_PCIE")
		)
		(pad "G15" smd circle
			(at -3.999992 -11.999976 270)
			(size 0.4572 0.4572)
			(layers "F.Cu" "F.Mask" "F.Paste")
			(net "GND")
		)
		(pad "G16" smd circle
			(at -2.999994 -11.999976 270)
			(size 0.4572 0.4572)
			(layers "F.Cu" "F.Mask" "F.Paste")
			(net "DUT_AVD_PCIE")
		)
		(pad "G17" smd circle
			(at -1.999996 -11.999976 270)
			(size 0.4572 0.4572)
			(layers "F.Cu" "F.Mask" "F.Paste")
			(net "DUT_AVD_PCIE")
		)
		(pad "G18" smd circle
			(at -0.999998 -11.999976 270)
			(size 0.4572 0.4572)
			(layers "F.Cu" "F.Mask" "F.Paste")
			(net "DUT_AVD_PCIE")
		)
		(pad "G19" smd circle
			(at 0 -11.999976 270)
			(size 0.4572 0.4572)
			(layers "F.Cu" "F.Mask" "F.Paste")
			(net "DUT_AVD_PCIE")
		)
		(pad "G20" smd circle
			(at 0.999998 -11.999976 270)
			(size 0.4572 0.4572)
			(layers "F.Cu" "F.Mask" "F.Paste")
			(net "DUT_AVD_PCIE")
		)
		(pad "G21" smd circle
			(at 1.999996 -11.999976 270)
			(size 0.4572 0.4572)
			(layers "F.Cu" "F.Mask" "F.Paste")
			(net "DUT_AVD_PCIE")
		)
		(pad "G22" smd circle
			(at 2.999994 -11.999976 270)
			(size 0.4572 0.4572)
			(layers "F.Cu" "F.Mask" "F.Paste")
			(net "DUT_AVD_PCIE")
		)
		(pad "G23" smd circle
			(at 3.999992 -11.999976 270)
			(size 0.4572 0.4572)
			(layers "F.Cu" "F.Mask" "F.Paste")
			(net "DUT_AVD_PCIE")
		)
		(pad "G24" smd circle
			(at 4.99999 -11.999976 270)
			(size 0.4572 0.4572)
			(layers "F.Cu" "F.Mask" "F.Paste")
			(net "DUT_AVD_PCIE")
		)
		(pad "G25" smd circle
			(at 5.999988 -11.999976 270)
			(size 0.4572 0.4572)
			(layers "F.Cu" "F.Mask" "F.Paste")
			(net "DUT_AVD_PCIE")
		)
		(pad "G26" smd circle
			(at 6.999986 -11.999976 270)
			(size 0.4572 0.4572)
			(layers "F.Cu" "F.Mask" "F.Paste")
			(net "DUT_AVD_PCIE")
		)
		(pad "G27" smd circle
			(at 7.999984 -11.999976 270)
			(size 0.4572 0.4572)
			(layers "F.Cu" "F.Mask" "F.Paste")
			(net "DUT_AVD_PCIE")
		)
		(pad "G28" smd circle
			(at 8.999982 -11.999976 270)
			(size 0.4572 0.4572)
			(layers "F.Cu" "F.Mask" "F.Paste")
			(net "DUT_AVD_PCIE")
		)
		(pad "G29" smd circle
			(at 9.99998 -11.999976 270)
			(size 0.4572 0.4572)
			(layers "F.Cu" "F.Mask" "F.Paste")
			(net "DUT_AVD_PCIE")
		)
		(pad "G30" smd circle
			(at 10.999978 -11.999976 270)
			(size 0.4572 0.4572)
			(layers "F.Cu" "F.Mask" "F.Paste")
			(net "DUT_AVD_PCIE")
		)
		(pad "G31" smd circle
			(at 11.999976 -11.999976 270)
			(size 0.4572 0.4572)
			(layers "F.Cu" "F.Mask" "F.Paste")
			(net "DUT_AVD_PCIE")
		)
		(pad "G32" smd circle
			(at 12.999974 -11.999976 270)
			(size 0.4572 0.4572)
			(layers "F.Cu" "F.Mask" "F.Paste")
			(net "DUT_AVD_PCIE")
		)
		(pad "G33" smd circle
			(at 13.999972 -11.999976 270)
			(size 0.4572 0.4572)
			(layers "F.Cu" "F.Mask" "F.Paste")
			(net "DUT_AVD_PCIE")
		)
		(pad "G34" smd circle
			(at 14.99997 -11.999976 270)
			(size 0.4572 0.4572)
			(layers "F.Cu" "F.Mask" "F.Paste")
			(net "GND")
		)
		(pad "G35" smd circle
			(at 15.999968 -11.999976 270)
			(size 0.4572 0.4572)
			(layers "F.Cu" "F.Mask" "F.Paste")
			(net "PCIE_TX_CAP_P1")
		)
		(pad "G36" smd circle
			(at 16.999966 -11.999976 270)
			(size 0.4572 0.4572)
			(layers "F.Cu" "F.Mask" "F.Paste")
			(net "PCIE_TX_CAP_N1")
		)
		(pad "H1" smd circle
			(at -17.999964 -10.999978 270)
			(size 0.4572 0.4572)
			(layers "F.Cu" "F.Mask" "F.Paste")
			(net "PCIE_TX_CAP_N38")
		)
		(pad "H2" smd circle
			(at -16.999966 -10.999978 270)
			(size 0.4572 0.4572)
			(layers "F.Cu" "F.Mask" "F.Paste")
			(net "PCIE_TX_CAP_P38")
		)
		(pad "H3" smd circle
			(at -15.999968 -10.999978 270)
			(size 0.4572 0.4572)
			(layers "F.Cu" "F.Mask" "F.Paste")
			(net "GND")
		)
		(pad "H4" smd circle
			(at -14.99997 -10.999978 270)
			(size 0.4572 0.4572)
			(layers "F.Cu" "F.Mask" "F.Paste")
			(net "PCIE_RX_N38")
		)
		(pad "H5" smd circle
			(at -13.999972 -10.999978 270)
			(size 0.4572 0.4572)
			(layers "F.Cu" "F.Mask" "F.Paste")
			(net "PCIE_RX_P38")
		)
		(pad "H6" smd circle
			(at -12.999974 -10.999978 270)
			(size 0.4572 0.4572)
			(layers "F.Cu" "F.Mask" "F.Paste")
			(net "GND")
		)
		(pad "H7" smd circle
			(at -11.999976 -10.999978 270)
			(size 0.4572 0.4572)
			(layers "F.Cu" "F.Mask" "F.Paste")
			(net "DUT_AVD_PCIE")
		)
		(pad "H8" smd circle
			(at -10.999978 -10.999978 270)
			(size 0.4572 0.4572)
			(layers "F.Cu" "F.Mask" "F.Paste")
			(net "GND")
		)
		(pad "H9" smd circle
			(at -9.99998 -10.999978 270)
			(size 0.4572 0.4572)
			(layers "F.Cu" "F.Mask" "F.Paste")
			(net "GND")
		)
		(pad "H10" smd circle
			(at -8.999982 -10.999978 270)
			(size 0.4572 0.4572)
			(layers "F.Cu" "F.Mask" "F.Paste")
			(net "GND")
		)
		(pad "H11" smd circle
			(at -7.999984 -10.999978 270)
			(size 0.4572 0.4572)
			(layers "F.Cu" "F.Mask" "F.Paste")
			(net "GND")
		)
		(pad "H12" smd circle
			(at -6.999986 -10.999978 270)
			(size 0.4572 0.4572)
			(layers "F.Cu" "F.Mask" "F.Paste")
			(net "GND")
		)
		(pad "H13" smd circle
			(at -5.999988 -10.999978 270)
			(size 0.4572 0.4572)
			(layers "F.Cu" "F.Mask" "F.Paste")
			(net "GND")
		)
		(pad "H14" smd circle
			(at -4.99999 -10.999978 270)
			(size 0.4572 0.4572)
			(layers "F.Cu" "F.Mask" "F.Paste")
			(net "GND")
		)
		(pad "H15" smd circle
			(at -3.999992 -10.999978 270)
			(size 0.4572 0.4572)
			(layers "F.Cu" "F.Mask" "F.Paste")
			(net "GND")
		)
		(pad "H16" smd circle
			(at -2.999994 -10.999978 270)
			(size 0.4572 0.4572)
			(layers "F.Cu" "F.Mask" "F.Paste")
			(net "GND")
		)
		(pad "H17" smd circle
			(at -1.999996 -10.999978 270)
			(size 0.4572 0.4572)
			(layers "F.Cu" "F.Mask" "F.Paste")
			(net "GND")
		)
		(pad "H18" smd circle
			(at -0.999998 -10.999978 270)
			(size 0.4572 0.4572)
			(layers "F.Cu" "F.Mask" "F.Paste")
			(net "GND")
		)
		(pad "H19" smd circle
			(at 0 -10.999978 270)
			(size 0.4572 0.4572)
			(layers "F.Cu" "F.Mask" "F.Paste")
			(net "GND")
		)
		(pad "H20" smd circle
			(at 0.999998 -10.999978 270)
			(size 0.4572 0.4572)
			(layers "F.Cu" "F.Mask" "F.Paste")
			(net "DUT_AVD_PCIE")
		)
		(pad "H21" smd circle
			(at 1.999996 -10.999978 270)
			(size 0.4572 0.4572)
			(layers "F.Cu" "F.Mask" "F.Paste")
			(net "GND")
		)
		(pad "H22" smd circle
			(at 2.999994 -10.999978 270)
			(size 0.4572 0.4572)
			(layers "F.Cu" "F.Mask" "F.Paste")
			(net "GND")
		)
		(pad "H23" smd circle
			(at 3.999992 -10.999978 270)
			(size 0.4572 0.4572)
			(layers "F.Cu" "F.Mask" "F.Paste")
			(net "GND")
		)
		(pad "H24" smd circle
			(at 4.99999 -10.999978 270)
			(size 0.4572 0.4572)
			(layers "F.Cu" "F.Mask" "F.Paste")
			(net "GND")
		)
		(pad "H25" smd circle
			(at 5.999988 -10.999978 270)
			(size 0.4572 0.4572)
			(layers "F.Cu" "F.Mask" "F.Paste")
			(net "DUT_AVD_PCIE")
		)
		(pad "H26" smd circle
			(at 6.999986 -10.999978 270)
			(size 0.4572 0.4572)
			(layers "F.Cu" "F.Mask" "F.Paste")
			(net "GND")
		)
		(pad "H27" smd circle
			(at 7.999984 -10.999978 270)
			(size 0.4572 0.4572)
			(layers "F.Cu" "F.Mask" "F.Paste")
			(net "Net_2104")
		)
		(pad "H28" smd circle
			(at 8.999982 -10.999978 270)
			(size 0.4572 0.4572)
			(layers "F.Cu" "F.Mask" "F.Paste")
			(net "Net_2103")
		)
		(pad "H29" smd circle
			(at 9.99998 -10.999978 270)
			(size 0.4572 0.4572)
			(layers "F.Cu" "F.Mask" "F.Paste")
			(net "Net_2102")
		)
		(pad "H30" smd circle
			(at 10.999978 -10.999978 270)
			(size 0.4572 0.4572)
			(layers "F.Cu" "F.Mask" "F.Paste")
			(net "Net_2101")
		)
		(pad "H31" smd circle
			(at 11.999976 -10.999978 270)
			(size 0.4572 0.4572)
			(layers "F.Cu" "F.Mask" "F.Paste")
			(net "AVS_ENB_R")
		)
		(pad "H32" smd circle
			(at 12.999974 -10.999978 270)
			(size 0.4572 0.4572)
			(layers "F.Cu" "F.Mask" "F.Paste")
			(net "Net_2099")
		)
		(pad "H33" smd circle
			(at 13.999972 -10.999978 270)
			(size 0.4572 0.4572)
			(layers "F.Cu" "F.Mask" "F.Paste")
			(net "Net_2098")
		)
		(pad "H34" smd circle
			(at 14.99997 -10.999978 270)
			(size 0.4572 0.4572)
			(layers "F.Cu" "F.Mask" "F.Paste")
			(net "GND")
		)
		(pad "H35" smd circle
			(at 15.999968 -10.999978 270)
			(size 0.4572 0.4572)
			(layers "F.Cu" "F.Mask" "F.Paste")
			(net "GND")
		)
		(pad "H36" smd circle
			(at 16.999966 -10.999978 270)
			(size 0.4572 0.4572)
			(layers "F.Cu" "F.Mask" "F.Paste")
			(net "PCIE_TX_CAP_P0")
		)
		(pad "H37" smd circle
			(at 17.999964 -10.999978 270)
			(size 0.4572 0.4572)
			(layers "F.Cu" "F.Mask" "F.Paste")
			(net "PCIE_TX_CAP_N0")
		)
		(pad "J2" smd circle
			(at -16.999966 -9.99998 270)
			(size 0.4572 0.4572)
			(layers "F.Cu" "F.Mask" "F.Paste")
			(net "PCIE_TX_CAP_N39")
		)
		(pad "J3" smd circle
			(at -15.999968 -9.99998 270)
			(size 0.4572 0.4572)
			(layers "F.Cu" "F.Mask" "F.Paste")
			(net "PCIE_TX_CAP_P39")
		)
		(pad "J4" smd circle
			(at -14.99997 -9.99998 270)
			(size 0.4572 0.4572)
			(layers "F.Cu" "F.Mask" "F.Paste")
			(net "GND")
		)
		(pad "J5" smd circle
			(at -13.999972 -9.99998 270)
			(size 0.4572 0.4572)
			(layers "F.Cu" "F.Mask" "F.Paste")
			(net "PCIE_RX_N39")
		)
		(pad "J6" smd circle
			(at -12.999974 -9.99998 270)
			(size 0.4572 0.4572)
			(layers "F.Cu" "F.Mask" "F.Paste")
			(net "PCIE_RX_P39")
		)
		(pad "J7" smd circle
			(at -11.999976 -9.99998 270)
			(size 0.4572 0.4572)
			(layers "F.Cu" "F.Mask" "F.Paste")
			(net "DUT_AVD_PCIE")
		)
		(pad "J8" smd circle
			(at -10.999978 -9.99998 270)
			(size 0.4572 0.4572)
			(layers "F.Cu" "F.Mask" "F.Paste")
			(net "GND")
		)
		(pad "J9" smd circle
			(at -9.99998 -9.99998 270)
			(size 0.4572 0.4572)
			(layers "F.Cu" "F.Mask" "F.Paste")
			(net "GND")
		)
		(pad "J10" smd circle
			(at -8.999982 -9.99998 270)
			(size 0.4572 0.4572)
			(layers "F.Cu" "F.Mask" "F.Paste")
			(net "GND")
		)
		(pad "J11" smd circle
			(at -7.999984 -9.99998 270)
			(size 0.4572 0.4572)
			(layers "F.Cu" "F.Mask" "F.Paste")
			(net "GND")
		)
		(pad "J12" smd circle
			(at -6.999986 -9.99998 270)
			(size 0.4572 0.4572)
			(layers "F.Cu" "F.Mask" "F.Paste")
			(net "GND")
		)
		(pad "J13" smd circle
			(at -5.999988 -9.99998 270)
			(size 0.4572 0.4572)
			(layers "F.Cu" "F.Mask" "F.Paste")
			(net "GND")
		)
		(pad "J14" smd circle
			(at -4.99999 -9.99998 270)
			(size 0.4572 0.4572)
			(layers "F.Cu" "F.Mask" "F.Paste")
			(net "GND")
		)
		(pad "J15" smd circle
			(at -3.999992 -9.99998 270)
			(size 0.4572 0.4572)
			(layers "F.Cu" "F.Mask" "F.Paste")
			(net "GND")
		)
		(pad "J16" smd circle
			(at -2.999994 -9.99998 270)
			(size 0.4572 0.4572)
			(layers "F.Cu" "F.Mask" "F.Paste")
			(net "GND")
		)
		(pad "J17" smd circle
			(at -1.999996 -9.99998 270)
			(size 0.4572 0.4572)
			(layers "F.Cu" "F.Mask" "F.Paste")
			(net "GND")
		)
		(pad "J18" smd circle
			(at -0.999998 -9.99998 270)
			(size 0.4572 0.4572)
			(layers "F.Cu" "F.Mask" "F.Paste")
			(net "GND")
		)
		(pad "J19" smd circle
			(at 0 -9.99998 270)
			(size 0.4572 0.4572)
			(layers "F.Cu" "F.Mask" "F.Paste")
			(net "GND")
		)
		(pad "J20" smd circle
			(at 0.999998 -9.99998 270)
			(size 0.4572 0.4572)
			(layers "F.Cu" "F.Mask" "F.Paste")
			(net "DUT_AVD_PCIE")
		)
		(pad "J21" smd circle
			(at 1.999996 -9.99998 270)
			(size 0.4572 0.4572)
			(layers "F.Cu" "F.Mask" "F.Paste")
			(net "GND")
		)
		(pad "J22" smd circle
			(at 2.999994 -9.99998 270)
			(size 0.4572 0.4572)
			(layers "F.Cu" "F.Mask" "F.Paste")
			(net "GND")
		)
		(pad "J23" smd circle
			(at 3.999992 -9.99998 270)
			(size 0.4572 0.4572)
			(layers "F.Cu" "F.Mask" "F.Paste")
			(net "GND")
		)
		(pad "J24" smd circle
			(at 4.99999 -9.99998 270)
			(size 0.4572 0.4572)
			(layers "F.Cu" "F.Mask" "F.Paste")
			(net "GND")
		)
		(pad "J25" smd circle
			(at 5.999988 -9.99998 270)
			(size 0.4572 0.4572)
			(layers "F.Cu" "F.Mask" "F.Paste")
			(net "DUT_AVD_PCIE")
		)
		(pad "J26" smd circle
			(at 6.999986 -9.99998 270)
			(size 0.4572 0.4572)
			(layers "F.Cu" "F.Mask" "F.Paste")
			(net "GND")
		)
		(pad "J27" smd circle
			(at 7.999984 -9.99998 270)
			(size 0.4572 0.4572)
			(layers "F.Cu" "F.Mask" "F.Paste")
			(net "Net_2100")
		)
		(pad "J28" smd circle
			(at 8.999982 -9.99998 270)
			(size 0.4572 0.4572)
			(layers "F.Cu" "F.Mask" "F.Paste")
			(net "VSS_573")
		)
		(pad "J29" smd circle
			(at 9.99998 -9.99998 270)
			(size 0.4572 0.4572)
			(layers "F.Cu" "F.Mask" "F.Paste")
			(net "THERM_BASE")
		)
		(pad "J30" smd circle
			(at 10.999978 -9.99998 270)
			(size 0.4572 0.4572)
			(layers "F.Cu" "F.Mask" "F.Paste")
			(net "THERM_EMIT")
		)
		(pad "J31" smd circle
			(at 11.999976 -9.99998 270)
			(size 0.4572 0.4572)
			(layers "F.Cu" "F.Mask" "F.Paste")
			(net "TWI_SCL0")
		)
		(pad "J32" smd circle
			(at 12.999974 -9.99998 270)
			(size 0.4572 0.4572)
			(layers "F.Cu" "F.Mask" "F.Paste")
			(net "TWI_SDA0")
		)
		(pad "J33" smd circle
			(at 13.999972 -9.99998 270)
			(size 0.4572 0.4572)
			(layers "F.Cu" "F.Mask" "F.Paste")
			(net "TWI_SRST#0")
		)
		(pad "J34" smd circle
			(at 14.99997 -9.99998 270)
			(size 0.4572 0.4572)
			(layers "F.Cu" "F.Mask" "F.Paste")
			(net "GND")
		)
		(pad "J35" smd circle
			(at 15.999968 -9.99998 270)
			(size 0.4572 0.4572)
			(layers "F.Cu" "F.Mask" "F.Paste")
			(net "GND")
		)
		(pad "J36" smd circle
			(at 16.999966 -9.99998 270)
			(size 0.4572 0.4572)
			(layers "F.Cu" "F.Mask" "F.Paste")
			(net "GND")
		)
		(pad "J37" smd circle
			(at 17.999964 -9.99998 270)
			(size 0.4572 0.4572)
			(layers "F.Cu" "F.Mask" "F.Paste")
			(net "GND")
		)
		(pad "K1" smd circle
			(at -17.999964 -8.999982 270)
			(size 0.4572 0.4572)
			(layers "F.Cu" "F.Mask" "F.Paste")
			(net "GND")
		)
		(pad "K2" smd circle
			(at -16.999966 -8.999982 270)
			(size 0.4572 0.4572)
			(layers "F.Cu" "F.Mask" "F.Paste")
			(net "GND")
		)
		(pad "K3" smd circle
			(at -15.999968 -8.999982 270)
			(size 0.4572 0.4572)
			(layers "F.Cu" "F.Mask" "F.Paste")
			(net "GND")
		)
		(pad "K4" smd circle
			(at -14.99997 -8.999982 270)
			(size 0.4572 0.4572)
			(layers "F.Cu" "F.Mask" "F.Paste")
			(net "GND")
		)
		(pad "K5" smd circle
			(at -13.999972 -8.999982 270)
			(size 0.4572 0.4572)
			(layers "F.Cu" "F.Mask" "F.Paste")
			(net "GND")
		)
		(pad "K6" smd circle
			(at -12.999974 -8.999982 270)
			(size 0.4572 0.4572)
			(layers "F.Cu" "F.Mask" "F.Paste")
			(net "GND")
		)
		(pad "K7" smd circle
			(at -11.999976 -8.999982 270)
			(size 0.4572 0.4572)
			(layers "F.Cu" "F.Mask" "F.Paste")
			(net "DUT_AVD_PCIE")
		)
		(pad "K8" smd circle
			(at -10.999978 -8.999982 270)
			(size 0.4572 0.4572)
			(layers "F.Cu" "F.Mask" "F.Paste")
			(net "GND")
		)
		(pad "K9" smd circle
			(at -9.99998 -8.999982 270)
			(size 0.4572 0.4572)
			(layers "F.Cu" "F.Mask" "F.Paste")
			(net "GND")
		)
		(pad "K10" smd circle
			(at -8.999982 -8.999982 270)
			(size 0.4572 0.4572)
			(layers "F.Cu" "F.Mask" "F.Paste")
			(net "GND")
		)
		(pad "K11" smd circle
			(at -7.999984 -8.999982 270)
			(size 0.4572 0.4572)
			(layers "F.Cu" "F.Mask" "F.Paste")
			(net "GND")
		)
		(pad "K12" smd circle
			(at -6.999986 -8.999982 270)
			(size 0.4572 0.4572)
			(layers "F.Cu" "F.Mask" "F.Paste")
			(net "GND")
		)
		(pad "K13" smd circle
			(at -5.999988 -8.999982 270)
			(size 0.4572 0.4572)
			(layers "F.Cu" "F.Mask" "F.Paste")
			(net "GND")
		)
		(pad "K14" smd circle
			(at -4.99999 -8.999982 270)
			(size 0.4572 0.4572)
			(layers "F.Cu" "F.Mask" "F.Paste")
			(net "GND")
		)
		(pad "K15" smd circle
			(at -3.999992 -8.999982 270)
			(size 0.4572 0.4572)
			(layers "F.Cu" "F.Mask" "F.Paste")
			(net "GND")
		)
		(pad "K16" smd circle
			(at -2.999994 -8.999982 270)
			(size 0.4572 0.4572)
			(layers "F.Cu" "F.Mask" "F.Paste")
			(net "GND")
		)
		(pad "K17" smd circle
			(at -1.999996 -8.999982 270)
			(size 0.4572 0.4572)
			(layers "F.Cu" "F.Mask" "F.Paste")
			(net "GND")
		)
		(pad "K18" smd circle
			(at -0.999998 -8.999982 270)
			(size 0.4572 0.4572)
			(layers "F.Cu" "F.Mask" "F.Paste")
			(net "GND")
		)
		(pad "K19" smd circle
			(at 0 -8.999982 270)
			(size 0.4572 0.4572)
			(layers "F.Cu" "F.Mask" "F.Paste")
			(net "GND")
		)
		(pad "K20" smd circle
			(at 0.999998 -8.999982 270)
			(size 0.4572 0.4572)
			(layers "F.Cu" "F.Mask" "F.Paste")
			(net "GND")
		)
		(pad "K21" smd circle
			(at 1.999996 -8.999982 270)
			(size 0.4572 0.4572)
			(layers "F.Cu" "F.Mask" "F.Paste")
			(net "GND")
		)
		(pad "K22" smd circle
			(at 2.999994 -8.999982 270)
			(size 0.4572 0.4572)
			(layers "F.Cu" "F.Mask" "F.Paste")
			(net "GND")
		)
		(pad "K23" smd circle
			(at 3.999992 -8.999982 270)
			(size 0.4572 0.4572)
			(layers "F.Cu" "F.Mask" "F.Paste")
			(net "GND")
		)
		(pad "K24" smd circle
			(at 4.99999 -8.999982 270)
			(size 0.4572 0.4572)
			(layers "F.Cu" "F.Mask" "F.Paste")
			(net "GND")
		)
		(pad "K25" smd circle
			(at 5.999988 -8.999982 270)
			(size 0.4572 0.4572)
			(layers "F.Cu" "F.Mask" "F.Paste")
			(net "GND")
		)
		(pad "K26" smd circle
			(at 6.999986 -8.999982 270)
			(size 0.4572 0.4572)
			(layers "F.Cu" "F.Mask" "F.Paste")
			(net "Net_2105")
		)
		(pad "K27" smd circle
			(at 7.999984 -8.999982 270)
			(size 0.4572 0.4572)
			(layers "F.Cu" "F.Mask" "F.Paste")
			(net "TWI_SCL1")
		)
		(pad "K28" smd circle
			(at 8.999982 -8.999982 270)
			(size 0.4572 0.4572)
			(layers "F.Cu" "F.Mask" "F.Paste")
			(net "TWI_SCL2")
		)
		(pad "K29" smd circle
			(at 9.99998 -8.999982 270)
			(size 0.4572 0.4572)
			(layers "F.Cu" "F.Mask" "F.Paste")
			(net "GND")
		)
		(pad "K30" smd circle
			(at 10.999978 -8.999982 270)
			(size 0.4572 0.4572)
			(layers "F.Cu" "F.Mask" "F.Paste")
			(net "TWI_SDA1")
		)
		(pad "K31" smd circle
			(at 11.999976 -8.999982 270)
			(size 0.4572 0.4572)
			(layers "F.Cu" "F.Mask" "F.Paste")
			(net "TWI_SRST#1")
		)
		(pad "K32" smd circle
			(at 12.999974 -8.999982 270)
			(size 0.4572 0.4572)
			(layers "F.Cu" "F.Mask" "F.Paste")
			(net "GND")
		)
		(pad "K33" smd circle
			(at 13.999972 -8.999982 270)
			(size 0.4572 0.4572)
			(layers "F.Cu" "F.Mask" "F.Paste")
			(net "TWI_SDA2")
		)
		(pad "K34" smd circle
			(at 14.99997 -8.999982 270)
			(size 0.4572 0.4572)
			(layers "F.Cu" "F.Mask" "F.Paste")
			(net "GND")
		)
		(pad "K35" smd circle
			(at 15.999968 -8.999982 270)
			(size 0.4572 0.4572)
			(layers "F.Cu" "F.Mask" "F.Paste")
			(net "PCIE_RX_P7")
		)
		(pad "K36" smd circle
			(at 16.999966 -8.999982 270)
			(size 0.4572 0.4572)
			(layers "F.Cu" "F.Mask" "F.Paste")
			(net "PCIE_RX_N7")
		)
		(pad "L1" smd circle
			(at -17.999964 -7.999984 270)
			(size 0.4572 0.4572)
			(layers "F.Cu" "F.Mask" "F.Paste")
			(net "PCIE_TX_CAP_N40")
		)
		(pad "L2" smd circle
			(at -16.999966 -7.999984 270)
			(size 0.4572 0.4572)
			(layers "F.Cu" "F.Mask" "F.Paste")
			(net "PCIE_TX_CAP_P40")
		)
		(pad "L3" smd circle
			(at -15.999968 -7.999984 270)
			(size 0.4572 0.4572)
			(layers "F.Cu" "F.Mask" "F.Paste")
			(net "GND")
		)
		(pad "L4" smd circle
			(at -14.99997 -7.999984 270)
			(size 0.4572 0.4572)
			(layers "F.Cu" "F.Mask" "F.Paste")
			(net "PCIE_RX_N40")
		)
		(pad "L5" smd circle
			(at -13.999972 -7.999984 270)
			(size 0.4572 0.4572)
			(layers "F.Cu" "F.Mask" "F.Paste")
			(net "PCIE_RX_P40")
		)
		(pad "L6" smd circle
			(at -12.999974 -7.999984 270)
			(size 0.4572 0.4572)
			(layers "F.Cu" "F.Mask" "F.Paste")
			(net "GND")
		)
		(pad "L7" smd circle
			(at -11.999976 -7.999984 270)
			(size 0.4572 0.4572)
			(layers "F.Cu" "F.Mask" "F.Paste")
			(net "DUT_AVD_PCIE")
		)
		(pad "L8" smd circle
			(at -10.999978 -7.999984 270)
			(size 0.4572 0.4572)
			(layers "F.Cu" "F.Mask" "F.Paste")
			(net "GND")
		)
		(pad "L9" smd circle
			(at -9.99998 -7.999984 270)
			(size 0.4572 0.4572)
			(layers "F.Cu" "F.Mask" "F.Paste")
			(net "GND")
		)
		(pad "L10" smd circle
			(at -8.999982 -7.999984 270)
			(size 0.4572 0.4572)
			(layers "F.Cu" "F.Mask" "F.Paste")
			(net "GND")
		)
		(pad "L11" smd circle
			(at -7.999984 -7.999984 270)
			(size 0.4572 0.4572)
			(layers "F.Cu" "F.Mask" "F.Paste")
			(net "GND")
		)
		(pad "L12" smd circle
			(at -6.999986 -7.999984 270)
			(size 0.4572 0.4572)
			(layers "F.Cu" "F.Mask" "F.Paste")
			(net "GND")
		)
		(pad "L13" smd circle
			(at -5.999988 -7.999984 270)
			(size 0.4572 0.4572)
			(layers "F.Cu" "F.Mask" "F.Paste")
			(net "DUT_AVD_PCIE_Q")
		)
		(pad "L14" smd circle
			(at -4.99999 -7.999984 270)
			(size 0.4572 0.4572)
			(layers "F.Cu" "F.Mask" "F.Paste")
			(net "GND")
		)
		(pad "L15" smd circle
			(at -3.999992 -7.999984 270)
			(size 0.4572 0.4572)
			(layers "F.Cu" "F.Mask" "F.Paste")
			(net "GND")
		)
		(pad "L16" smd circle
			(at -2.999994 -7.999984 270)
			(size 0.4572 0.4572)
			(layers "F.Cu" "F.Mask" "F.Paste")
			(net "GND")
		)
		(pad "L17" smd circle
			(at -1.999996 -7.999984 270)
			(size 0.4572 0.4572)
			(layers "F.Cu" "F.Mask" "F.Paste")
			(net "GND")
		)
		(pad "L18" smd circle
			(at -0.999998 -7.999984 270)
			(size 0.4572 0.4572)
			(layers "F.Cu" "F.Mask" "F.Paste")
			(net "GND")
		)
		(pad "L19" smd circle
			(at 0 -7.999984 270)
			(size 0.4572 0.4572)
			(layers "F.Cu" "F.Mask" "F.Paste")
			(net "GND")
		)
		(pad "L20" smd circle
			(at 0.999998 -7.999984 270)
			(size 0.4572 0.4572)
			(layers "F.Cu" "F.Mask" "F.Paste")
			(net "DUT_AVD_PCIE_Q")
		)
		(pad "L21" smd circle
			(at 1.999996 -7.999984 270)
			(size 0.4572 0.4572)
			(layers "F.Cu" "F.Mask" "F.Paste")
			(net "GND")
		)
		(pad "L22" smd circle
			(at 2.999994 -7.999984 270)
			(size 0.4572 0.4572)
			(layers "F.Cu" "F.Mask" "F.Paste")
			(net "DUT_AVD_PCIE")
		)
		(pad "L23" smd circle
			(at 3.999992 -7.999984 270)
			(size 0.4572 0.4572)
			(layers "F.Cu" "F.Mask" "F.Paste")
			(net "GND")
		)
		(pad "L24" smd circle
			(at 4.99999 -7.999984 270)
			(size 0.4572 0.4572)
			(layers "F.Cu" "F.Mask" "F.Paste")
			(net "GND")
		)
		(pad "L25" smd circle
			(at 5.999988 -7.999984 270)
			(size 0.4572 0.4572)
			(layers "F.Cu" "F.Mask" "F.Paste")
			(net "GND")
		)
		(pad "L26" smd circle
			(at 6.999986 -7.999984 270)
			(size 0.4572 0.4572)
			(layers "F.Cu" "F.Mask" "F.Paste")
			(net "GPIO107_R")
		)
		(pad "L27" smd circle
			(at 7.999984 -7.999984 270)
			(size 0.4572 0.4572)
			(layers "F.Cu" "F.Mask" "F.Paste")
			(net "GPIO108_R")
		)
		(pad "L28" smd circle
			(at 8.999982 -7.999984 270)
			(size 0.4572 0.4572)
			(layers "F.Cu" "F.Mask" "F.Paste")
			(net "TWI_SRST#2")
		)
		(pad "L29" smd circle
			(at 9.99998 -7.999984 270)
			(size 0.4572 0.4572)
			(layers "F.Cu" "F.Mask" "F.Paste")
			(net "TWI_SDA5")
		)
		(pad "L30" smd circle
			(at 10.999978 -7.999984 270)
			(size 0.4572 0.4572)
			(layers "F.Cu" "F.Mask" "F.Paste")
			(net "TWI_SCL5")
		)
		(pad "L31" smd circle
			(at 11.999976 -7.999984 270)
			(size 0.4572 0.4572)
			(layers "F.Cu" "F.Mask" "F.Paste")
			(net "DUT_VDDO")
		)
		(pad "L32" smd circle
			(at 12.999974 -7.999984 270)
			(size 0.4572 0.4572)
			(layers "F.Cu" "F.Mask" "F.Paste")
			(net "GPIO109_R")
		)
		(pad "L33" smd circle
			(at 13.999972 -7.999984 270)
			(size 0.4572 0.4572)
			(layers "F.Cu" "F.Mask" "F.Paste")
			(net "IOEXP_INT#_3")
		)
		(pad "L34" smd circle
			(at 14.99997 -7.999984 270)
			(size 0.4572 0.4572)
			(layers "F.Cu" "F.Mask" "F.Paste")
			(net "DUT_VDDO")
		)
		(pad "L35" smd circle
			(at 15.999968 -7.999984 270)
			(size 0.4572 0.4572)
			(layers "F.Cu" "F.Mask" "F.Paste")
			(net "GND")
		)
		(pad "L36" smd circle
			(at 16.999966 -7.999984 270)
			(size 0.4572 0.4572)
			(layers "F.Cu" "F.Mask" "F.Paste")
			(net "PCIE_RX_P6")
		)
		(pad "L37" smd circle
			(at 17.999964 -7.999984 270)
			(size 0.4572 0.4572)
			(layers "F.Cu" "F.Mask" "F.Paste")
			(net "PCIE_RX_N6")
		)
		(pad "M2" smd circle
			(at -16.999966 -6.999986 270)
			(size 0.4572 0.4572)
			(layers "F.Cu" "F.Mask" "F.Paste")
			(net "PCIE_TX_CAP_N41")
		)
		(pad "M3" smd circle
			(at -15.999968 -6.999986 270)
			(size 0.4572 0.4572)
			(layers "F.Cu" "F.Mask" "F.Paste")
			(net "PCIE_TX_CAP_P41")
		)
		(pad "M4" smd circle
			(at -14.99997 -6.999986 270)
			(size 0.4572 0.4572)
			(layers "F.Cu" "F.Mask" "F.Paste")
			(net "GND")
		)
		(pad "M5" smd circle
			(at -13.999972 -6.999986 270)
			(size 0.4572 0.4572)
			(layers "F.Cu" "F.Mask" "F.Paste")
			(net "PCIE_RX_N41")
		)
		(pad "M6" smd circle
			(at -12.999974 -6.999986 270)
			(size 0.4572 0.4572)
			(layers "F.Cu" "F.Mask" "F.Paste")
			(net "PCIE_RX_P41")
		)
		(pad "M7" smd circle
			(at -11.999976 -6.999986 270)
			(size 0.4572 0.4572)
			(layers "F.Cu" "F.Mask" "F.Paste")
			(net "DUT_AVD_PCIE")
		)
		(pad "M8" smd circle
			(at -10.999978 -6.999986 270)
			(size 0.4572 0.4572)
			(layers "F.Cu" "F.Mask" "F.Paste")
			(net "GND")
		)
		(pad "M9" smd circle
			(at -9.99998 -6.999986 270)
			(size 0.4572 0.4572)
			(layers "F.Cu" "F.Mask" "F.Paste")
			(net "GND")
		)
		(pad "M10" smd circle
			(at -8.999982 -6.999986 270)
			(size 0.4572 0.4572)
			(layers "F.Cu" "F.Mask" "F.Paste")
			(net "GND")
		)
		(pad "M11" smd circle
			(at -7.999984 -6.999986 270)
			(size 0.4572 0.4572)
			(layers "F.Cu" "F.Mask" "F.Paste")
			(net "GND")
		)
		(pad "M12" smd circle
			(at -6.999986 -6.999986 270)
			(size 0.4572 0.4572)
			(layers "F.Cu" "F.Mask" "F.Paste")
			(net "GND")
		)
		(pad "M13" smd circle
			(at -5.999988 -6.999986 270)
			(size 0.4572 0.4572)
			(layers "F.Cu" "F.Mask" "F.Paste")
			(net "DUT_AVD_PCIE")
		)
		(pad "M14" smd circle
			(at -4.99999 -6.999986 270)
			(size 0.4572 0.4572)
			(layers "F.Cu" "F.Mask" "F.Paste")
			(net "GND")
		)
		(pad "M15" smd circle
			(at -3.999992 -6.999986 270)
			(size 0.4572 0.4572)
			(layers "F.Cu" "F.Mask" "F.Paste")
			(net "DUT_VDD")
		)
		(pad "M16" smd circle
			(at -2.999994 -6.999986 270)
			(size 0.4572 0.4572)
			(layers "F.Cu" "F.Mask" "F.Paste")
			(net "GND")
		)
		(pad "M17" smd circle
			(at -1.999996 -6.999986 270)
			(size 0.4572 0.4572)
			(layers "F.Cu" "F.Mask" "F.Paste")
			(net "DUT_VDD")
		)
		(pad "M18" smd circle
			(at -0.999998 -6.999986 270)
			(size 0.4572 0.4572)
			(layers "F.Cu" "F.Mask" "F.Paste")
			(net "GND")
		)
		(pad "M19" smd circle
			(at 0 -6.999986 270)
			(size 0.4572 0.4572)
			(layers "F.Cu" "F.Mask" "F.Paste")
			(net "DUT_VDD")
		)
		(pad "M20" smd circle
			(at 0.999998 -6.999986 270)
			(size 0.4572 0.4572)
			(layers "F.Cu" "F.Mask" "F.Paste")
			(net "GND")
		)
		(pad "M21" smd circle
			(at 1.999996 -6.999986 270)
			(size 0.4572 0.4572)
			(layers "F.Cu" "F.Mask" "F.Paste")
			(net "DUT_AVD_PCIE")
		)
		(pad "M22" smd circle
			(at 2.999994 -6.999986 270)
			(size 0.4572 0.4572)
			(layers "F.Cu" "F.Mask" "F.Paste")
			(net "GND")
		)
		(pad "M23" smd circle
			(at 3.999992 -6.999986 270)
			(size 0.4572 0.4572)
			(layers "F.Cu" "F.Mask" "F.Paste")
			(net "DUT_VDD")
		)
		(pad "M24" smd circle
			(at 4.99999 -6.999986 270)
			(size 0.4572 0.4572)
			(layers "F.Cu" "F.Mask" "F.Paste")
			(net "GND")
		)
		(pad "M25" smd circle
			(at 5.999988 -6.999986 270)
			(size 0.4572 0.4572)
			(layers "F.Cu" "F.Mask" "F.Paste")
			(net "DUT_VDD")
		)
		(pad "M26" smd circle
			(at 6.999986 -6.999986 270)
			(size 0.4572 0.4572)
			(layers "F.Cu" "F.Mask" "F.Paste")
			(net "TWI_SRST#5")
		)
		(pad "M27" smd circle
			(at 7.999984 -6.999986 270)
			(size 0.4572 0.4572)
			(layers "F.Cu" "F.Mask" "F.Paste")
			(net "TWI_SCL6")
		)
		(pad "M28" smd circle
			(at 8.999982 -6.999986 270)
			(size 0.4572 0.4572)
			(layers "F.Cu" "F.Mask" "F.Paste")
			(net "IOEXP_INT#_4")
		)
		(pad "M29" smd circle
			(at 9.99998 -6.999986 270)
			(size 0.4572 0.4572)
			(layers "F.Cu" "F.Mask" "F.Paste")
			(net "IOEXP_PMC1_INT#")
		)
		(pad "M30" smd circle
			(at 10.999978 -6.999986 270)
			(size 0.4572 0.4572)
			(layers "F.Cu" "F.Mask" "F.Paste")
			(net "TWI_SRST#8")
		)
		(pad "M31" smd circle
			(at 11.999976 -6.999986 270)
			(size 0.4572 0.4572)
			(layers "F.Cu" "F.Mask" "F.Paste")
			(net "TWI_SDA6")
		)
		(pad "M32" smd circle
			(at 12.999974 -6.999986 270)
			(size 0.4572 0.4572)
			(layers "F.Cu" "F.Mask" "F.Paste")
			(net "TWI_SRST#6")
		)
		(pad "M33" smd circle
			(at 13.999972 -6.999986 270)
			(size 0.4572 0.4572)
			(layers "F.Cu" "F.Mask" "F.Paste")
			(net "TWI_SDA9")
		)
		(pad "M34" smd circle
			(at 14.99997 -6.999986 270)
			(size 0.4572 0.4572)
			(layers "F.Cu" "F.Mask" "F.Paste")
			(net "GND")
		)
		(pad "M35" smd circle
			(at 15.999968 -6.999986 270)
			(size 0.4572 0.4572)
			(layers "F.Cu" "F.Mask" "F.Paste")
			(net "PCIE_RX_P5")
		)
		(pad "M36" smd circle
			(at 16.999966 -6.999986 270)
			(size 0.4572 0.4572)
			(layers "F.Cu" "F.Mask" "F.Paste")
			(net "PCIE_RX_N5")
		)
		(pad "N1" smd circle
			(at -17.999964 -5.999988 270)
			(size 0.4572 0.4572)
			(layers "F.Cu" "F.Mask" "F.Paste")
			(net "PCIE_TX_CAP_N42")
		)
		(pad "N2" smd circle
			(at -16.999966 -5.999988 270)
			(size 0.4572 0.4572)
			(layers "F.Cu" "F.Mask" "F.Paste")
			(net "PCIE_TX_CAP_P42")
		)
		(pad "N3" smd circle
			(at -15.999968 -5.999988 270)
			(size 0.4572 0.4572)
			(layers "F.Cu" "F.Mask" "F.Paste")
			(net "GND")
		)
		(pad "N4" smd circle
			(at -14.99997 -5.999988 270)
			(size 0.4572 0.4572)
			(layers "F.Cu" "F.Mask" "F.Paste")
			(net "PCIE_RX_N42")
		)
		(pad "N5" smd circle
			(at -13.999972 -5.999988 270)
			(size 0.4572 0.4572)
			(layers "F.Cu" "F.Mask" "F.Paste")
			(net "PCIE_RX_P42")
		)
		(pad "N6" smd circle
			(at -12.999974 -5.999988 270)
			(size 0.4572 0.4572)
			(layers "F.Cu" "F.Mask" "F.Paste")
			(net "GND")
		)
		(pad "N7" smd circle
			(at -11.999976 -5.999988 270)
			(size 0.4572 0.4572)
			(layers "F.Cu" "F.Mask" "F.Paste")
			(net "DUT_AVD_PCIE")
		)
		(pad "N8" smd circle
			(at -10.999978 -5.999988 270)
			(size 0.4572 0.4572)
			(layers "F.Cu" "F.Mask" "F.Paste")
			(net "GND")
		)
		(pad "N9" smd circle
			(at -9.99998 -5.999988 270)
			(size 0.4572 0.4572)
			(layers "F.Cu" "F.Mask" "F.Paste")
			(net "GND")
		)
		(pad "N10" smd circle
			(at -8.999982 -5.999988 270)
			(size 0.4572 0.4572)
			(layers "F.Cu" "F.Mask" "F.Paste")
			(net "GND")
		)
		(pad "N11" smd circle
			(at -7.999984 -5.999988 270)
			(size 0.4572 0.4572)
			(layers "F.Cu" "F.Mask" "F.Paste")
			(net "GND")
		)
		(pad "N12" smd circle
			(at -6.999986 -5.999988 270)
			(size 0.4572 0.4572)
			(layers "F.Cu" "F.Mask" "F.Paste")
			(net "GND")
		)
		(pad "N13" smd circle
			(at -5.999988 -5.999988 270)
			(size 0.4572 0.4572)
			(layers "F.Cu" "F.Mask" "F.Paste")
			(net "GND")
		)
		(pad "N14" smd circle
			(at -4.99999 -5.999988 270)
			(size 0.4572 0.4572)
			(layers "F.Cu" "F.Mask" "F.Paste")
			(net "DUT_VDD")
		)
		(pad "N15" smd circle
			(at -3.999992 -5.999988 270)
			(size 0.4572 0.4572)
			(layers "F.Cu" "F.Mask" "F.Paste")
			(net "GND")
		)
		(pad "N16" smd circle
			(at -2.999994 -5.999988 270)
			(size 0.4572 0.4572)
			(layers "F.Cu" "F.Mask" "F.Paste")
			(net "DUT_VDD")
		)
		(pad "N17" smd circle
			(at -1.999996 -5.999988 270)
			(size 0.4572 0.4572)
			(layers "F.Cu" "F.Mask" "F.Paste")
			(net "GND")
		)
		(pad "N18" smd circle
			(at -0.999998 -5.999988 270)
			(size 0.4572 0.4572)
			(layers "F.Cu" "F.Mask" "F.Paste")
			(net "DUT_VDD")
		)
		(pad "N19" smd circle
			(at 0 -5.999988 270)
			(size 0.4572 0.4572)
			(layers "F.Cu" "F.Mask" "F.Paste")
			(net "GND")
		)
		(pad "N20" smd circle
			(at 0.999998 -5.999988 270)
			(size 0.4572 0.4572)
			(layers "F.Cu" "F.Mask" "F.Paste")
			(net "DUT_VDD")
		)
		(pad "N21" smd circle
			(at 1.999996 -5.999988 270)
			(size 0.4572 0.4572)
			(layers "F.Cu" "F.Mask" "F.Paste")
			(net "GND")
		)
		(pad "N22" smd circle
			(at 2.999994 -5.999988 270)
			(size 0.4572 0.4572)
			(layers "F.Cu" "F.Mask" "F.Paste")
			(net "DUT_VDD")
		)
		(pad "N23" smd circle
			(at 3.999992 -5.999988 270)
			(size 0.4572 0.4572)
			(layers "F.Cu" "F.Mask" "F.Paste")
			(net "GND")
		)
		(pad "N24" smd circle
			(at 4.99999 -5.999988 270)
			(size 0.4572 0.4572)
			(layers "F.Cu" "F.Mask" "F.Paste")
			(net "DUT_VDD")
		)
		(pad "N25" smd circle
			(at 5.999988 -5.999988 270)
			(size 0.4572 0.4572)
			(layers "F.Cu" "F.Mask" "F.Paste")
			(net "GND")
		)
		(pad "N26" smd circle
			(at 6.999986 -5.999988 270)
			(size 0.4572 0.4572)
			(layers "F.Cu" "F.Mask" "F.Paste")
			(net "DUT_VDDO_REF")
		)
		(pad "N27" smd circle
			(at 7.999984 -5.999988 270)
			(size 0.4572 0.4572)
			(layers "F.Cu" "F.Mask" "F.Paste")
			(net "TWI_SRST#9")
		)
		(pad "N28" smd circle
			(at 8.999982 -5.999988 270)
			(size 0.4572 0.4572)
			(layers "F.Cu" "F.Mask" "F.Paste")
			(net "IOEXP_INT#_1")
		)
		(pad "N29" smd circle
			(at 9.99998 -5.999988 270)
			(size 0.4572 0.4572)
			(layers "F.Cu" "F.Mask" "F.Paste")
			(net "GND")
		)
		(pad "N30" smd circle
			(at 10.999978 -5.999988 270)
			(size 0.4572 0.4572)
			(layers "F.Cu" "F.Mask" "F.Paste")
			(net "TWI_SRST#7")
		)
		(pad "N31" smd circle
			(at 11.999976 -5.999988 270)
			(size 0.4572 0.4572)
			(layers "F.Cu" "F.Mask" "F.Paste")
			(net "IOEXP_INT#_2")
		)
		(pad "N32" smd circle
			(at 12.999974 -5.999988 270)
			(size 0.4572 0.4572)
			(layers "F.Cu" "F.Mask" "F.Paste")
			(net "TWI_SCL10")
		)
		(pad "N33" smd circle
			(at 13.999972 -5.999988 270)
			(size 0.4572 0.4572)
			(layers "F.Cu" "F.Mask" "F.Paste")
			(net "TWI_SDA10")
		)
		(pad "N34" smd circle
			(at 14.99997 -5.999988 270)
			(size 0.4572 0.4572)
			(layers "F.Cu" "F.Mask" "F.Paste")
			(net "DUT_VDDO")
		)
		(pad "N35" smd circle
			(at 15.999968 -5.999988 270)
			(size 0.4572 0.4572)
			(layers "F.Cu" "F.Mask" "F.Paste")
			(net "GND")
		)
		(pad "N36" smd circle
			(at 16.999966 -5.999988 270)
			(size 0.4572 0.4572)
			(layers "F.Cu" "F.Mask" "F.Paste")
			(net "PCIE_RX_P4")
		)
		(pad "N37" smd circle
			(at 17.999964 -5.999988 270)
			(size 0.4572 0.4572)
			(layers "F.Cu" "F.Mask" "F.Paste")
			(net "PCIE_RX_N4")
		)
		(pad "P2" smd circle
			(at -16.999966 -4.99999 270)
			(size 0.4572 0.4572)
			(layers "F.Cu" "F.Mask" "F.Paste")
			(net "PCIE_TX_CAP_N43")
		)
		(pad "P3" smd circle
			(at -15.999968 -4.99999 270)
			(size 0.4572 0.4572)
			(layers "F.Cu" "F.Mask" "F.Paste")
			(net "PCIE_TX_CAP_P43")
		)
		(pad "P4" smd circle
			(at -14.99997 -4.99999 270)
			(size 0.4572 0.4572)
			(layers "F.Cu" "F.Mask" "F.Paste")
			(net "GND")
		)
		(pad "P5" smd circle
			(at -13.999972 -4.99999 270)
			(size 0.4572 0.4572)
			(layers "F.Cu" "F.Mask" "F.Paste")
			(net "PCIE_RX_N43")
		)
		(pad "P6" smd circle
			(at -12.999974 -4.99999 270)
			(size 0.4572 0.4572)
			(layers "F.Cu" "F.Mask" "F.Paste")
			(net "PCIE_RX_P43")
		)
		(pad "P7" smd circle
			(at -11.999976 -4.99999 270)
			(size 0.4572 0.4572)
			(layers "F.Cu" "F.Mask" "F.Paste")
			(net "GND")
		)
		(pad "P8" smd circle
			(at -10.999978 -4.99999 270)
			(size 0.4572 0.4572)
			(layers "F.Cu" "F.Mask" "F.Paste")
			(net "DUT_AVD_TX")
		)
		(pad "P9" smd circle
			(at -9.99998 -4.99999 270)
			(size 0.4572 0.4572)
			(layers "F.Cu" "F.Mask" "F.Paste")
			(net "GND")
		)
		(pad "P10" smd circle
			(at -8.999982 -4.99999 270)
			(size 0.4572 0.4572)
			(layers "F.Cu" "F.Mask" "F.Paste")
			(net "DUT_AVD_TX")
		)
		(pad "P11" smd circle
			(at -7.999984 -4.99999 270)
			(size 0.4572 0.4572)
			(layers "F.Cu" "F.Mask" "F.Paste")
			(net "GND")
		)
		(pad "P12" smd circle
			(at -6.999986 -4.99999 270)
			(size 0.4572 0.4572)
			(layers "F.Cu" "F.Mask" "F.Paste")
			(net "GND")
		)
		(pad "P13" smd circle
			(at -5.999988 -4.99999 270)
			(size 0.4572 0.4572)
			(layers "F.Cu" "F.Mask" "F.Paste")
			(net "DUT_VDD")
		)
		(pad "P14" smd circle
			(at -4.99999 -4.99999 270)
			(size 0.4572 0.4572)
			(layers "F.Cu" "F.Mask" "F.Paste")
			(net "GND")
		)
		(pad "P15" smd circle
			(at -3.999992 -4.99999 270)
			(size 0.4572 0.4572)
			(layers "F.Cu" "F.Mask" "F.Paste")
			(net "DUT_VDD")
		)
		(pad "P16" smd circle
			(at -2.999994 -4.99999 270)
			(size 0.4572 0.4572)
			(layers "F.Cu" "F.Mask" "F.Paste")
			(net "GND")
		)
		(pad "P17" smd circle
			(at -1.999996 -4.99999 270)
			(size 0.4572 0.4572)
			(layers "F.Cu" "F.Mask" "F.Paste")
			(net "DUT_VDD")
		)
		(pad "P18" smd circle
			(at -0.999998 -4.99999 270)
			(size 0.4572 0.4572)
			(layers "F.Cu" "F.Mask" "F.Paste")
			(net "GND")
		)
		(pad "P19" smd circle
			(at 0 -4.99999 270)
			(size 0.4572 0.4572)
			(layers "F.Cu" "F.Mask" "F.Paste")
			(net "DUT_VDD")
		)
		(pad "P20" smd circle
			(at 0.999998 -4.99999 270)
			(size 0.4572 0.4572)
			(layers "F.Cu" "F.Mask" "F.Paste")
			(net "GND")
		)
		(pad "P21" smd circle
			(at 1.999996 -4.99999 270)
			(size 0.4572 0.4572)
			(layers "F.Cu" "F.Mask" "F.Paste")
			(net "DUT_VDD")
		)
		(pad "P22" smd circle
			(at 2.999994 -4.99999 270)
			(size 0.4572 0.4572)
			(layers "F.Cu" "F.Mask" "F.Paste")
			(net "GND")
		)
		(pad "P23" smd circle
			(at 3.999992 -4.99999 270)
			(size 0.4572 0.4572)
			(layers "F.Cu" "F.Mask" "F.Paste")
			(net "DUT_VDD")
		)
		(pad "P24" smd circle
			(at 4.99999 -4.99999 270)
			(size 0.4572 0.4572)
			(layers "F.Cu" "F.Mask" "F.Paste")
			(net "GND")
		)
		(pad "P25" smd circle
			(at 5.999988 -4.99999 270)
			(size 0.4572 0.4572)
			(layers "F.Cu" "F.Mask" "F.Paste")
			(net "DUT_VDD")
		)
		(pad "P26" smd circle
			(at 6.999986 -4.99999 270)
			(size 0.4572 0.4572)
			(layers "F.Cu" "F.Mask" "F.Paste")
			(net "GND")
		)
		(pad "P27" smd circle
			(at 7.999984 -4.99999 270)
			(size 0.4572 0.4572)
			(layers "F.Cu" "F.Mask" "F.Paste")
			(net "VSS_572")
		)
		(pad "P28" smd circle
			(at 8.999982 -4.99999 270)
			(size 0.4572 0.4572)
			(layers "F.Cu" "F.Mask" "F.Paste")
			(net "DUT_VDDO")
		)
		(pad "P29" smd circle
			(at 9.99998 -4.99999 270)
			(size 0.4572 0.4572)
			(layers "F.Cu" "F.Mask" "F.Paste")
			(net "TWI_SCL3")
		)
		(pad "P30" smd circle
			(at 10.999978 -4.99999 270)
			(size 0.4572 0.4572)
			(layers "F.Cu" "F.Mask" "F.Paste")
			(net "TWI_SRST#3")
		)
		(pad "P31" smd circle
			(at 11.999976 -4.99999 270)
			(size 0.4572 0.4572)
			(layers "F.Cu" "F.Mask" "F.Paste")
			(net "GND")
		)
		(pad "P32" smd circle
			(at 12.999974 -4.99999 270)
			(size 0.4572 0.4572)
			(layers "F.Cu" "F.Mask" "F.Paste")
			(net "TWI_SDA3")
		)
		(pad "P33" smd circle
			(at 13.999972 -4.99999 270)
			(size 0.4572 0.4572)
			(layers "F.Cu" "F.Mask" "F.Paste")
			(net "TWI_SRST#4")
		)
		(pad "P34" smd circle
			(at 14.99997 -4.99999 270)
			(size 0.4572 0.4572)
			(layers "F.Cu" "F.Mask" "F.Paste")
			(net "GND")
		)
		(pad "P35" smd circle
			(at 15.999968 -4.99999 270)
			(size 0.4572 0.4572)
			(layers "F.Cu" "F.Mask" "F.Paste")
			(net "PCIE_RX_P3")
		)
		(pad "P36" smd circle
			(at 16.999966 -4.99999 270)
			(size 0.4572 0.4572)
			(layers "F.Cu" "F.Mask" "F.Paste")
			(net "PCIE_RX_N3")
		)
		(pad "R1" smd circle
			(at -17.999964 -3.999992 270)
			(size 0.4572 0.4572)
			(layers "F.Cu" "F.Mask" "F.Paste")
			(net "PCIE_TX_CAP_N44")
		)
		(pad "R2" smd circle
			(at -16.999966 -3.999992 270)
			(size 0.4572 0.4572)
			(layers "F.Cu" "F.Mask" "F.Paste")
			(net "PCIE_TX_CAP_P44")
		)
		(pad "R3" smd circle
			(at -15.999968 -3.999992 270)
			(size 0.4572 0.4572)
			(layers "F.Cu" "F.Mask" "F.Paste")
			(net "GND")
		)
		(pad "R4" smd circle
			(at -14.99997 -3.999992 270)
			(size 0.4572 0.4572)
			(layers "F.Cu" "F.Mask" "F.Paste")
			(net "PCIE_RX_N44")
		)
		(pad "R5" smd circle
			(at -13.999972 -3.999992 270)
			(size 0.4572 0.4572)
			(layers "F.Cu" "F.Mask" "F.Paste")
			(net "PCIE_RX_P44")
		)
		(pad "R6" smd circle
			(at -12.999974 -3.999992 270)
			(size 0.4572 0.4572)
			(layers "F.Cu" "F.Mask" "F.Paste")
			(net "GND")
		)
		(pad "R7" smd circle
			(at -11.999976 -3.999992 270)
			(size 0.4572 0.4572)
			(layers "F.Cu" "F.Mask" "F.Paste")
			(net "DUT_AVD_TX")
		)
		(pad "R8" smd circle
			(at -10.999978 -3.999992 270)
			(size 0.4572 0.4572)
			(layers "F.Cu" "F.Mask" "F.Paste")
			(net "GND")
		)
		(pad "R9" smd circle
			(at -9.99998 -3.999992 270)
			(size 0.4572 0.4572)
			(layers "F.Cu" "F.Mask" "F.Paste")
			(net "DUT_AVD_TX")
		)
		(pad "R10" smd circle
			(at -8.999982 -3.999992 270)
			(size 0.4572 0.4572)
			(layers "F.Cu" "F.Mask" "F.Paste")
			(net "GND")
		)
		(pad "R11" smd circle
			(at -7.999984 -3.999992 270)
			(size 0.4572 0.4572)
			(layers "F.Cu" "F.Mask" "F.Paste")
			(net "DUT_AVD_TX")
		)
		(pad "R12" smd circle
			(at -6.999986 -3.999992 270)
			(size 0.4572 0.4572)
			(layers "F.Cu" "F.Mask" "F.Paste")
			(net "GND")
		)
		(pad "R13" smd circle
			(at -5.999988 -3.999992 270)
			(size 0.4572 0.4572)
			(layers "F.Cu" "F.Mask" "F.Paste")
			(net "GND")
		)
		(pad "R14" smd circle
			(at -4.99999 -3.999992 270)
			(size 0.4572 0.4572)
			(layers "F.Cu" "F.Mask" "F.Paste")
			(net "DUT_VDD")
		)
		(pad "R15" smd circle
			(at -3.999992 -3.999992 270)
			(size 0.4572 0.4572)
			(layers "F.Cu" "F.Mask" "F.Paste")
			(net "GND")
		)
		(pad "R16" smd circle
			(at -2.999994 -3.999992 270)
			(size 0.4572 0.4572)
			(layers "F.Cu" "F.Mask" "F.Paste")
			(net "DUT_VDD")
		)
		(pad "R17" smd circle
			(at -1.999996 -3.999992 270)
			(size 0.4572 0.4572)
			(layers "F.Cu" "F.Mask" "F.Paste")
			(net "GND")
		)
		(pad "R18" smd circle
			(at -0.999998 -3.999992 270)
			(size 0.4572 0.4572)
			(layers "F.Cu" "F.Mask" "F.Paste")
			(net "DUT_VDD")
		)
		(pad "R19" smd circle
			(at 0 -3.999992 270)
			(size 0.4572 0.4572)
			(layers "F.Cu" "F.Mask" "F.Paste")
			(net "GND")
		)
		(pad "R20" smd circle
			(at 0.999998 -3.999992 270)
			(size 0.4572 0.4572)
			(layers "F.Cu" "F.Mask" "F.Paste")
			(net "DUT_VDD")
		)
		(pad "R21" smd circle
			(at 1.999996 -3.999992 270)
			(size 0.4572 0.4572)
			(layers "F.Cu" "F.Mask" "F.Paste")
			(net "GND")
		)
		(pad "R22" smd circle
			(at 2.999994 -3.999992 270)
			(size 0.4572 0.4572)
			(layers "F.Cu" "F.Mask" "F.Paste")
			(net "DUT_VDD")
		)
		(pad "R23" smd circle
			(at 3.999992 -3.999992 270)
			(size 0.4572 0.4572)
			(layers "F.Cu" "F.Mask" "F.Paste")
			(net "GND")
		)
		(pad "R24" smd circle
			(at 4.99999 -3.999992 270)
			(size 0.4572 0.4572)
			(layers "F.Cu" "F.Mask" "F.Paste")
			(net "DUT_VDD")
		)
		(pad "R25" smd circle
			(at 5.999988 -3.999992 270)
			(size 0.4572 0.4572)
			(layers "F.Cu" "F.Mask" "F.Paste")
			(net "GND")
		)
		(pad "R26" smd circle
			(at 6.999986 -3.999992 270)
			(size 0.4572 0.4572)
			(layers "F.Cu" "F.Mask" "F.Paste")
			(net "DUT_VDDO")
		)
		(pad "R27" smd circle
			(at 7.999984 -3.999992 270)
			(size 0.4572 0.4572)
			(layers "F.Cu" "F.Mask" "F.Paste")
			(net "TWI_SCL4")
		)
		(pad "R28" smd circle
			(at 8.999982 -3.999992 270)
			(size 0.4572 0.4572)
			(layers "F.Cu" "F.Mask" "F.Paste")
			(net "TWI_SDA4")
		)
		(pad "R29" smd circle
			(at 9.99998 -3.999992 270)
			(size 0.4572 0.4572)
			(layers "F.Cu" "F.Mask" "F.Paste")
			(net "TPIN")
		)
		(pad "R30" smd circle
			(at 10.999978 -3.999992 270)
			(size 0.4572 0.4572)
			(layers "F.Cu" "F.Mask" "F.Paste")
			(net "PM8536_HB")
		)
		(pad "R31" smd circle
			(at 11.999976 -3.999992 270)
			(size 0.4572 0.4572)
			(layers "F.Cu" "F.Mask" "F.Paste")
			(net "UART_USOUT")
		)
		(pad "R32" smd circle
			(at 12.999974 -3.999992 270)
			(size 0.4572 0.4572)
			(layers "F.Cu" "F.Mask" "F.Paste")
			(net "UART_USIN")
		)
		(pad "R33" smd circle
			(at 13.999972 -3.999992 270)
			(size 0.4572 0.4572)
			(layers "F.Cu" "F.Mask" "F.Paste")
			(net "LBI_DATA_0")
		)
		(pad "R34" smd circle
			(at 14.99997 -3.999992 270)
			(size 0.4572 0.4572)
			(layers "F.Cu" "F.Mask" "F.Paste")
			(net "DUT_VDDO")
		)
		(pad "R35" smd circle
			(at 15.999968 -3.999992 270)
			(size 0.4572 0.4572)
			(layers "F.Cu" "F.Mask" "F.Paste")
			(net "GND")
		)
		(pad "R36" smd circle
			(at 16.999966 -3.999992 270)
			(size 0.4572 0.4572)
			(layers "F.Cu" "F.Mask" "F.Paste")
			(net "PCIE_RX_P2")
		)
		(pad "R37" smd circle
			(at 17.999964 -3.999992 270)
			(size 0.4572 0.4572)
			(layers "F.Cu" "F.Mask" "F.Paste")
			(net "PCIE_RX_N2")
		)
		(pad "T2" smd circle
			(at -16.999966 -2.999994 270)
			(size 0.4572 0.4572)
			(layers "F.Cu" "F.Mask" "F.Paste")
			(net "PCIE_TX_CAP_N45")
		)
		(pad "T3" smd circle
			(at -15.999968 -2.999994 270)
			(size 0.4572 0.4572)
			(layers "F.Cu" "F.Mask" "F.Paste")
			(net "PCIE_TX_CAP_P45")
		)
		(pad "T4" smd circle
			(at -14.99997 -2.999994 270)
			(size 0.4572 0.4572)
			(layers "F.Cu" "F.Mask" "F.Paste")
			(net "GND")
		)
		(pad "T5" smd circle
			(at -13.999972 -2.999994 270)
			(size 0.4572 0.4572)
			(layers "F.Cu" "F.Mask" "F.Paste")
			(net "PCIE_RX_N45")
		)
		(pad "T6" smd circle
			(at -12.999974 -2.999994 270)
			(size 0.4572 0.4572)
			(layers "F.Cu" "F.Mask" "F.Paste")
			(net "PCIE_RX_P45")
		)
		(pad "T7" smd circle
			(at -11.999976 -2.999994 270)
			(size 0.4572 0.4572)
			(layers "F.Cu" "F.Mask" "F.Paste")
			(net "GND")
		)
		(pad "T8" smd circle
			(at -10.999978 -2.999994 270)
			(size 0.4572 0.4572)
			(layers "F.Cu" "F.Mask" "F.Paste")
			(net "DUT_AVD_TX")
		)
		(pad "T9" smd circle
			(at -9.99998 -2.999994 270)
			(size 0.4572 0.4572)
			(layers "F.Cu" "F.Mask" "F.Paste")
			(net "GND")
		)
		(pad "T10" smd circle
			(at -8.999982 -2.999994 270)
			(size 0.4572 0.4572)
			(layers "F.Cu" "F.Mask" "F.Paste")
			(net "DUT_AVD_TX")
		)
		(pad "T11" smd circle
			(at -7.999984 -2.999994 270)
			(size 0.4572 0.4572)
			(layers "F.Cu" "F.Mask" "F.Paste")
			(net "GND")
		)
		(pad "T12" smd circle
			(at -6.999986 -2.999994 270)
			(size 0.4572 0.4572)
			(layers "F.Cu" "F.Mask" "F.Paste")
			(net "GND")
		)
		(pad "T13" smd circle
			(at -5.999988 -2.999994 270)
			(size 0.4572 0.4572)
			(layers "F.Cu" "F.Mask" "F.Paste")
			(net "DUT_VDD")
		)
		(pad "T14" smd circle
			(at -4.99999 -2.999994 270)
			(size 0.4572 0.4572)
			(layers "F.Cu" "F.Mask" "F.Paste")
			(net "GND")
		)
		(pad "T15" smd circle
			(at -3.999992 -2.999994 270)
			(size 0.4572 0.4572)
			(layers "F.Cu" "F.Mask" "F.Paste")
			(net "DUT_VDD")
		)
		(pad "T16" smd circle
			(at -2.999994 -2.999994 270)
			(size 0.4572 0.4572)
			(layers "F.Cu" "F.Mask" "F.Paste")
			(net "GND")
		)
		(pad "T17" smd circle
			(at -1.999996 -2.999994 270)
			(size 0.4572 0.4572)
			(layers "F.Cu" "F.Mask" "F.Paste")
			(net "DUT_VDD")
		)
		(pad "T18" smd circle
			(at -0.999998 -2.999994 270)
			(size 0.4572 0.4572)
			(layers "F.Cu" "F.Mask" "F.Paste")
			(net "GND")
		)
		(pad "T19" smd circle
			(at 0 -2.999994 270)
			(size 0.4572 0.4572)
			(layers "F.Cu" "F.Mask" "F.Paste")
			(net "DUT_VDD")
		)
		(pad "T20" smd circle
			(at 0.999998 -2.999994 270)
			(size 0.4572 0.4572)
			(layers "F.Cu" "F.Mask" "F.Paste")
			(net "GND")
		)
		(pad "T21" smd circle
			(at 1.999996 -2.999994 270)
			(size 0.4572 0.4572)
			(layers "F.Cu" "F.Mask" "F.Paste")
			(net "DUT_VDD")
		)
		(pad "T22" smd circle
			(at 2.999994 -2.999994 270)
			(size 0.4572 0.4572)
			(layers "F.Cu" "F.Mask" "F.Paste")
			(net "GND")
		)
		(pad "T23" smd circle
			(at 3.999992 -2.999994 270)
			(size 0.4572 0.4572)
			(layers "F.Cu" "F.Mask" "F.Paste")
			(net "DUT_VDD")
		)
		(pad "T24" smd circle
			(at 4.99999 -2.999994 270)
			(size 0.4572 0.4572)
			(layers "F.Cu" "F.Mask" "F.Paste")
			(net "GND")
		)
		(pad "T25" smd circle
			(at 5.999988 -2.999994 270)
			(size 0.4572 0.4572)
			(layers "F.Cu" "F.Mask" "F.Paste")
			(net "DUT_VDD")
		)
		(pad "T26" smd circle
			(at 6.999986 -2.999994 270)
			(size 0.4572 0.4572)
			(layers "F.Cu" "F.Mask" "F.Paste")
			(net "GND")
		)
		(pad "T27" smd circle
			(at 7.999984 -2.999994 270)
			(size 0.4572 0.4572)
			(layers "F.Cu" "F.Mask" "F.Paste")
			(net "RS232_UCTSB0")
		)
		(pad "T28" smd circle
			(at 8.999982 -2.999994 270)
			(size 0.4572 0.4572)
			(layers "F.Cu" "F.Mask" "F.Paste")
			(net "RS232_URTSB0")
		)
		(pad "T29" smd circle
			(at 9.99998 -2.999994 270)
			(size 0.4572 0.4572)
			(layers "F.Cu" "F.Mask" "F.Paste")
			(net "GND")
		)
		(pad "T30" smd circle
			(at 10.999978 -2.999994 270)
			(size 0.4572 0.4572)
			(layers "F.Cu" "F.Mask" "F.Paste")
			(net "LBI_DATA_1")
		)
		(pad "T31" smd circle
			(at 11.999976 -2.999994 270)
			(size 0.4572 0.4572)
			(layers "F.Cu" "F.Mask" "F.Paste")
			(net "LBI_DATA_2")
		)
		(pad "T32" smd circle
			(at 12.999974 -2.999994 270)
			(size 0.4572 0.4572)
			(layers "F.Cu" "F.Mask" "F.Paste")
			(net "LBI_DATA_4")
		)
		(pad "T33" smd circle
			(at 13.999972 -2.999994 270)
			(size 0.4572 0.4572)
			(layers "F.Cu" "F.Mask" "F.Paste")
			(net "LBI_DATA_3")
		)
		(pad "T34" smd circle
			(at 14.99997 -2.999994 270)
			(size 0.4572 0.4572)
			(layers "F.Cu" "F.Mask" "F.Paste")
			(net "GND")
		)
		(pad "T35" smd circle
			(at 15.999968 -2.999994 270)
			(size 0.4572 0.4572)
			(layers "F.Cu" "F.Mask" "F.Paste")
			(net "PCIE_RX_P1")
		)
		(pad "T36" smd circle
			(at 16.999966 -2.999994 270)
			(size 0.4572 0.4572)
			(layers "F.Cu" "F.Mask" "F.Paste")
			(net "PCIE_RX_N1")
		)
		(pad "U1" smd circle
			(at -17.999964 -1.999996 270)
			(size 0.4572 0.4572)
			(layers "F.Cu" "F.Mask" "F.Paste")
			(net "PCIE_TX_CAP_N46")
		)
		(pad "U2" smd circle
			(at -16.999966 -1.999996 270)
			(size 0.4572 0.4572)
			(layers "F.Cu" "F.Mask" "F.Paste")
			(net "PCIE_TX_CAP_P46")
		)
		(pad "U3" smd circle
			(at -15.999968 -1.999996 270)
			(size 0.4572 0.4572)
			(layers "F.Cu" "F.Mask" "F.Paste")
			(net "GND")
		)
		(pad "U4" smd circle
			(at -14.99997 -1.999996 270)
			(size 0.4572 0.4572)
			(layers "F.Cu" "F.Mask" "F.Paste")
			(net "PCIE_RX_N46")
		)
		(pad "U5" smd circle
			(at -13.999972 -1.999996 270)
			(size 0.4572 0.4572)
			(layers "F.Cu" "F.Mask" "F.Paste")
			(net "PCIE_RX_P46")
		)
		(pad "U6" smd circle
			(at -12.999974 -1.999996 270)
			(size 0.4572 0.4572)
			(layers "F.Cu" "F.Mask" "F.Paste")
			(net "GND")
		)
		(pad "U7" smd circle
			(at -11.999976 -1.999996 270)
			(size 0.4572 0.4572)
			(layers "F.Cu" "F.Mask" "F.Paste")
			(net "DUT_AVD_TX")
		)
		(pad "U8" smd circle
			(at -10.999978 -1.999996 270)
			(size 0.4572 0.4572)
			(layers "F.Cu" "F.Mask" "F.Paste")
			(net "GND")
		)
		(pad "U9" smd circle
			(at -9.99998 -1.999996 270)
			(size 0.4572 0.4572)
			(layers "F.Cu" "F.Mask" "F.Paste")
			(net "DUT_AVD_TX")
		)
		(pad "U10" smd circle
			(at -8.999982 -1.999996 270)
			(size 0.4572 0.4572)
			(layers "F.Cu" "F.Mask" "F.Paste")
			(net "GND")
		)
		(pad "U11" smd circle
			(at -7.999984 -1.999996 270)
			(size 0.4572 0.4572)
			(layers "F.Cu" "F.Mask" "F.Paste")
			(net "DUT_AVD_TX")
		)
		(pad "U12" smd circle
			(at -6.999986 -1.999996 270)
			(size 0.4572 0.4572)
			(layers "F.Cu" "F.Mask" "F.Paste")
			(net "GND")
		)
		(pad "U13" smd circle
			(at -5.999988 -1.999996 270)
			(size 0.4572 0.4572)
			(layers "F.Cu" "F.Mask" "F.Paste")
			(net "GND")
		)
		(pad "U14" smd circle
			(at -4.99999 -1.999996 270)
			(size 0.4572 0.4572)
			(layers "F.Cu" "F.Mask" "F.Paste")
			(net "DUT_VDD")
		)
		(pad "U15" smd circle
			(at -3.999992 -1.999996 270)
			(size 0.4572 0.4572)
			(layers "F.Cu" "F.Mask" "F.Paste")
			(net "GND")
		)
		(pad "U16" smd circle
			(at -2.999994 -1.999996 270)
			(size 0.4572 0.4572)
			(layers "F.Cu" "F.Mask" "F.Paste")
			(net "DUT_VDD")
		)
		(pad "U17" smd circle
			(at -1.999996 -1.999996 270)
			(size 0.4572 0.4572)
			(layers "F.Cu" "F.Mask" "F.Paste")
			(net "GND")
		)
		(pad "U18" smd circle
			(at -0.999998 -1.999996 270)
			(size 0.4572 0.4572)
			(layers "F.Cu" "F.Mask" "F.Paste")
			(net "DUT_VDD")
		)
		(pad "U19" smd circle
			(at 0 -1.999996 270)
			(size 0.4572 0.4572)
			(layers "F.Cu" "F.Mask" "F.Paste")
			(net "GND")
		)
		(pad "U20" smd circle
			(at 0.999998 -1.999996 270)
			(size 0.4572 0.4572)
			(layers "F.Cu" "F.Mask" "F.Paste")
			(net "DUT_VDD")
		)
		(pad "U21" smd circle
			(at 1.999996 -1.999996 270)
			(size 0.4572 0.4572)
			(layers "F.Cu" "F.Mask" "F.Paste")
			(net "GND")
		)
		(pad "U22" smd circle
			(at 2.999994 -1.999996 270)
			(size 0.4572 0.4572)
			(layers "F.Cu" "F.Mask" "F.Paste")
			(net "DUT_VDD")
		)
		(pad "U23" smd circle
			(at 3.999992 -1.999996 270)
			(size 0.4572 0.4572)
			(layers "F.Cu" "F.Mask" "F.Paste")
			(net "GND")
		)
		(pad "U24" smd circle
			(at 4.99999 -1.999996 270)
			(size 0.4572 0.4572)
			(layers "F.Cu" "F.Mask" "F.Paste")
			(net "DUT_VDD")
		)
		(pad "U25" smd circle
			(at 5.999988 -1.999996 270)
			(size 0.4572 0.4572)
			(layers "F.Cu" "F.Mask" "F.Paste")
			(net "GND")
		)
		(pad "U26" smd circle
			(at 6.999986 -1.999996 270)
			(size 0.4572 0.4572)
			(layers "F.Cu" "F.Mask" "F.Paste")
			(net "DUT_VDDO")
		)
		(pad "U27" smd circle
			(at 7.999984 -1.999996 270)
			(size 0.4572 0.4572)
			(layers "F.Cu" "F.Mask" "F.Paste")
			(net "LBI_DATA_7")
		)
		(pad "U28" smd circle
			(at 8.999982 -1.999996 270)
			(size 0.4572 0.4572)
			(layers "F.Cu" "F.Mask" "F.Paste")
			(net "LBI_DATA_5")
		)
		(pad "U29" smd circle
			(at 9.99998 -1.999996 270)
			(size 0.4572 0.4572)
			(layers "F.Cu" "F.Mask" "F.Paste")
			(net "LBI_DATA_6")
		)
		(pad "U30" smd circle
			(at 10.999978 -1.999996 270)
			(size 0.4572 0.4572)
			(layers "F.Cu" "F.Mask" "F.Paste")
			(net "LBI_BYTEN#")
		)
		(pad "U31" smd circle
			(at 11.999976 -1.999996 270)
			(size 0.4572 0.4572)
			(layers "F.Cu" "F.Mask" "F.Paste")
			(net "DUT_VDDO")
		)
		(pad "U32" smd circle
			(at 12.999974 -1.999996 270)
			(size 0.4572 0.4572)
			(layers "F.Cu" "F.Mask" "F.Paste")
			(net "LBI_OE#")
		)
		(pad "U33" smd circle
			(at 13.999972 -1.999996 270)
			(size 0.4572 0.4572)
			(layers "F.Cu" "F.Mask" "F.Paste")
			(net "LBI_CE#3")
		)
		(pad "U34" smd circle
			(at 14.99997 -1.999996 270)
			(size 0.4572 0.4572)
			(layers "F.Cu" "F.Mask" "F.Paste")
			(net "DUT_VDDO")
		)
		(pad "U35" smd circle
			(at 15.999968 -1.999996 270)
			(size 0.4572 0.4572)
			(layers "F.Cu" "F.Mask" "F.Paste")
			(net "GND")
		)
		(pad "U36" smd circle
			(at 16.999966 -1.999996 270)
			(size 0.4572 0.4572)
			(layers "F.Cu" "F.Mask" "F.Paste")
			(net "PCIE_RX_P0")
		)
		(pad "U37" smd circle
			(at 17.999964 -1.999996 270)
			(size 0.4572 0.4572)
			(layers "F.Cu" "F.Mask" "F.Paste")
			(net "PCIE_RX_N0")
		)
		(pad "V2" smd circle
			(at -16.999966 -0.999998 270)
			(size 0.4572 0.4572)
			(layers "F.Cu" "F.Mask" "F.Paste")
			(net "PCIE_TX_CAP_N47")
		)
		(pad "V3" smd circle
			(at -15.999968 -0.999998 270)
			(size 0.4572 0.4572)
			(layers "F.Cu" "F.Mask" "F.Paste")
			(net "PCIE_TX_CAP_P47")
		)
		(pad "V4" smd circle
			(at -14.99997 -0.999998 270)
			(size 0.4572 0.4572)
			(layers "F.Cu" "F.Mask" "F.Paste")
			(net "GND")
		)
		(pad "V5" smd circle
			(at -13.999972 -0.999998 270)
			(size 0.4572 0.4572)
			(layers "F.Cu" "F.Mask" "F.Paste")
			(net "PCIE_RX_N47")
		)
		(pad "V6" smd circle
			(at -12.999974 -0.999998 270)
			(size 0.4572 0.4572)
			(layers "F.Cu" "F.Mask" "F.Paste")
			(net "PCIE_RX_P47")
		)
		(pad "V7" smd circle
			(at -11.999976 -0.999998 270)
			(size 0.4572 0.4572)
			(layers "F.Cu" "F.Mask" "F.Paste")
			(net "GND")
		)
		(pad "V8" smd circle
			(at -10.999978 -0.999998 270)
			(size 0.4572 0.4572)
			(layers "F.Cu" "F.Mask" "F.Paste")
			(net "DUT_AVD_TX")
		)
		(pad "V9" smd circle
			(at -9.99998 -0.999998 270)
			(size 0.4572 0.4572)
			(layers "F.Cu" "F.Mask" "F.Paste")
			(net "GND")
		)
		(pad "V10" smd circle
			(at -8.999982 -0.999998 270)
			(size 0.4572 0.4572)
			(layers "F.Cu" "F.Mask" "F.Paste")
			(net "DUT_AVD_TX")
		)
		(pad "V11" smd circle
			(at -7.999984 -0.999998 270)
			(size 0.4572 0.4572)
			(layers "F.Cu" "F.Mask" "F.Paste")
			(net "GND")
		)
		(pad "V12" smd circle
			(at -6.999986 -0.999998 270)
			(size 0.4572 0.4572)
			(layers "F.Cu" "F.Mask" "F.Paste")
			(net "GND")
		)
		(pad "V13" smd circle
			(at -5.999988 -0.999998 270)
			(size 0.4572 0.4572)
			(layers "F.Cu" "F.Mask" "F.Paste")
			(net "DUT_VDD")
		)
		(pad "V14" smd circle
			(at -4.99999 -0.999998 270)
			(size 0.4572 0.4572)
			(layers "F.Cu" "F.Mask" "F.Paste")
			(net "GND")
		)
		(pad "V15" smd circle
			(at -3.999992 -0.999998 270)
			(size 0.4572 0.4572)
			(layers "F.Cu" "F.Mask" "F.Paste")
			(net "DUT_VDD")
		)
		(pad "V16" smd circle
			(at -2.999994 -0.999998 270)
			(size 0.4572 0.4572)
			(layers "F.Cu" "F.Mask" "F.Paste")
			(net "GND")
		)
		(pad "V17" smd circle
			(at -1.999996 -0.999998 270)
			(size 0.4572 0.4572)
			(layers "F.Cu" "F.Mask" "F.Paste")
			(net "DUT_VDD")
		)
		(pad "V18" smd circle
			(at -0.999998 -0.999998 270)
			(size 0.4572 0.4572)
			(layers "F.Cu" "F.Mask" "F.Paste")
			(net "GND")
		)
		(pad "V19" smd circle
			(at 0 -0.999998 270)
			(size 0.4572 0.4572)
			(layers "F.Cu" "F.Mask" "F.Paste")
			(net "DUT_VDD")
		)
		(pad "V20" smd circle
			(at 0.999998 -0.999998 270)
			(size 0.4572 0.4572)
			(layers "F.Cu" "F.Mask" "F.Paste")
			(net "GND")
		)
		(pad "V21" smd circle
			(at 1.999996 -0.999998 270)
			(size 0.4572 0.4572)
			(layers "F.Cu" "F.Mask" "F.Paste")
			(net "DUT_VDD")
		)
		(pad "V22" smd circle
			(at 2.999994 -0.999998 270)
			(size 0.4572 0.4572)
			(layers "F.Cu" "F.Mask" "F.Paste")
			(net "GND")
		)
		(pad "V23" smd circle
			(at 3.999992 -0.999998 270)
			(size 0.4572 0.4572)
			(layers "F.Cu" "F.Mask" "F.Paste")
			(net "DUT_VDD")
		)
		(pad "V24" smd circle
			(at 4.99999 -0.999998 270)
			(size 0.4572 0.4572)
			(layers "F.Cu" "F.Mask" "F.Paste")
			(net "GND")
		)
		(pad "V25" smd circle
			(at 5.999988 -0.999998 270)
			(size 0.4572 0.4572)
			(layers "F.Cu" "F.Mask" "F.Paste")
			(net "DUT_AVD_PCIE_Q")
		)
		(pad "V26" smd circle
			(at 6.999986 -0.999998 270)
			(size 0.4572 0.4572)
			(layers "F.Cu" "F.Mask" "F.Paste")
			(net "GND")
		)
		(pad "V27" smd circle
			(at 7.999984 -0.999998 270)
			(size 0.4572 0.4572)
			(layers "F.Cu" "F.Mask" "F.Paste")
			(net "LBI_WE#")
		)
		(pad "V28" smd circle
			(at 8.999982 -0.999998 270)
			(size 0.4572 0.4572)
			(layers "F.Cu" "F.Mask" "F.Paste")
			(net "DUT_VDDO_REF")
		)
		(pad "V29" smd circle
			(at 9.99998 -0.999998 270)
			(size 0.4572 0.4572)
			(layers "F.Cu" "F.Mask" "F.Paste")
			(net "Net_326")
		)
		(pad "V30" smd circle
			(at 10.999978 -0.999998 270)
			(size 0.4572 0.4572)
			(layers "F.Cu" "F.Mask" "F.Paste")
			(net "LBI_DATA15")
		)
		(pad "V31" smd circle
			(at 11.999976 -0.999998 270)
			(size 0.4572 0.4572)
			(layers "F.Cu" "F.Mask" "F.Paste")
			(net "LBI_CE#0")
		)
		(pad "V32" smd circle
			(at 12.999974 -0.999998 270)
			(size 0.4572 0.4572)
			(layers "F.Cu" "F.Mask" "F.Paste")
			(net "GND")
		)
		(pad "V33" smd circle
			(at 13.999972 -0.999998 270)
			(size 0.4572 0.4572)
			(layers "F.Cu" "F.Mask" "F.Paste")
			(net "LBI_CE#2")
		)
		(pad "V34" smd circle
			(at 14.99997 -0.999998 270)
			(size 0.4572 0.4572)
			(layers "F.Cu" "F.Mask" "F.Paste")
			(net "BOOTSTRAP_R_0")
		)
		(pad "V35" smd circle
			(at 15.999968 -0.999998 270)
			(size 0.4572 0.4572)
			(layers "F.Cu" "F.Mask" "F.Paste")
			(net "GND")
		)
		(pad "V36" smd circle
			(at 16.999966 -0.999998 270)
			(size 0.4572 0.4572)
			(layers "F.Cu" "F.Mask" "F.Paste")
			(net "GND")
		)
		(pad "V37" smd circle
			(at 17.999964 -0.999998 270)
			(size 0.4572 0.4572)
			(layers "F.Cu" "F.Mask" "F.Paste")
			(net "GND")
		)
		(pad "W1" smd circle
			(at -17.999964 0 270)
			(size 0.4572 0.4572)
			(layers "F.Cu" "F.Mask" "F.Paste")
			(net "GND")
		)
		(pad "W2" smd circle
			(at -16.999966 0 270)
			(size 0.4572 0.4572)
			(layers "F.Cu" "F.Mask" "F.Paste")
			(net "GND")
		)
		(pad "W3" smd circle
			(at -15.999968 0 270)
			(size 0.4572 0.4572)
			(layers "F.Cu" "F.Mask" "F.Paste")
			(net "GND")
		)
		(pad "W4" smd circle
			(at -14.99997 0 270)
			(size 0.4572 0.4572)
			(layers "F.Cu" "F.Mask" "F.Paste")
			(net "GND")
		)
		(pad "W5" smd circle
			(at -13.999972 0 270)
			(size 0.4572 0.4572)
			(layers "F.Cu" "F.Mask" "F.Paste")
			(net "GND")
		)
		(pad "W6" smd circle
			(at -12.999974 0 270)
			(size 0.4572 0.4572)
			(layers "F.Cu" "F.Mask" "F.Paste")
			(net "GND")
		)
		(pad "W7" smd circle
			(at -11.999976 0 270)
			(size 0.4572 0.4572)
			(layers "F.Cu" "F.Mask" "F.Paste")
			(net "DUT_AVD_TX")
		)
		(pad "W8" smd circle
			(at -10.999978 0 270)
			(size 0.4572 0.4572)
			(layers "F.Cu" "F.Mask" "F.Paste")
			(net "GND")
		)
		(pad "W9" smd circle
			(at -9.99998 0 270)
			(size 0.4572 0.4572)
			(layers "F.Cu" "F.Mask" "F.Paste")
			(net "DUT_AVD_TX")
		)
		(pad "W10" smd circle
			(at -8.999982 0 270)
			(size 0.4572 0.4572)
			(layers "F.Cu" "F.Mask" "F.Paste")
			(net "GND")
		)
		(pad "W11" smd circle
			(at -7.999984 0 270)
			(size 0.4572 0.4572)
			(layers "F.Cu" "F.Mask" "F.Paste")
			(net "DUT_AVD_TX")
		)
		(pad "W12" smd circle
			(at -6.999986 0 270)
			(size 0.4572 0.4572)
			(layers "F.Cu" "F.Mask" "F.Paste")
			(net "GND")
		)
		(pad "W13" smd circle
			(at -5.999988 0 270)
			(size 0.4572 0.4572)
			(layers "F.Cu" "F.Mask" "F.Paste")
			(net "GND")
		)
		(pad "W14" smd circle
			(at -4.99999 0 270)
			(size 0.4572 0.4572)
			(layers "F.Cu" "F.Mask" "F.Paste")
			(net "DUT_VDD")
		)
		(pad "W15" smd circle
			(at -3.999992 0 270)
			(size 0.4572 0.4572)
			(layers "F.Cu" "F.Mask" "F.Paste")
			(net "GND")
		)
		(pad "W16" smd circle
			(at -2.999994 0 270)
			(size 0.4572 0.4572)
			(layers "F.Cu" "F.Mask" "F.Paste")
			(net "DUT_VDD")
		)
		(pad "W17" smd circle
			(at -1.999996 0 270)
			(size 0.4572 0.4572)
			(layers "F.Cu" "F.Mask" "F.Paste")
			(net "GND")
		)
		(pad "W18" smd circle
			(at -0.999998 0 270)
			(size 0.4572 0.4572)
			(layers "F.Cu" "F.Mask" "F.Paste")
			(net "DUT_VDD")
		)
		(pad "W19" smd circle
			(at 0 0 270)
			(size 0.4572 0.4572)
			(layers "F.Cu" "F.Mask" "F.Paste")
			(net "GND")
		)
		(pad "W20" smd circle
			(at 0.999998 0 270)
			(size 0.4572 0.4572)
			(layers "F.Cu" "F.Mask" "F.Paste")
			(net "DUT_VDD")
		)
		(pad "W21" smd circle
			(at 1.999996 0 270)
			(size 0.4572 0.4572)
			(layers "F.Cu" "F.Mask" "F.Paste")
			(net "GND")
		)
		(pad "W22" smd circle
			(at 2.999994 0 270)
			(size 0.4572 0.4572)
			(layers "F.Cu" "F.Mask" "F.Paste")
			(net "DUT_VDD")
		)
		(pad "W23" smd circle
			(at 3.999992 0 270)
			(size 0.4572 0.4572)
			(layers "F.Cu" "F.Mask" "F.Paste")
			(net "GND")
		)
		(pad "W24" smd circle
			(at 4.99999 0 270)
			(size 0.4572 0.4572)
			(layers "F.Cu" "F.Mask" "F.Paste")
			(net "DUT_VDD")
		)
		(pad "W25" smd circle
			(at 5.999988 0 270)
			(size 0.4572 0.4572)
			(layers "F.Cu" "F.Mask" "F.Paste")
			(net "GND")
		)
		(pad "W26" smd circle
			(at 6.999986 0 270)
			(size 0.4572 0.4572)
			(layers "F.Cu" "F.Mask" "F.Paste")
			(net "DUT_VDDO_REF")
		)
		(pad "W27" smd circle
			(at 7.999984 0 270)
			(size 0.4572 0.4572)
			(layers "F.Cu" "F.Mask" "F.Paste")
			(net "BOOTSTRAP_R_6")
		)
		(pad "W28" smd circle
			(at 8.999982 0 270)
			(size 0.4572 0.4572)
			(layers "F.Cu" "F.Mask" "F.Paste")
			(net "GND")
		)
		(pad "W29" smd circle
			(at 9.99998 0 270)
			(size 0.4572 0.4572)
			(layers "F.Cu" "F.Mask" "F.Paste")
			(net "PCIE_REFCLK_H0_P")
		)
		(pad "W30" smd circle
			(at 10.999978 0 270)
			(size 0.4572 0.4572)
			(layers "F.Cu" "F.Mask" "F.Paste")
			(net "PCIE_REFCLK_H0_N")
		)
		(pad "W31" smd circle
			(at 11.999976 0 270)
			(size 0.4572 0.4572)
			(layers "F.Cu" "F.Mask" "F.Paste")
			(net "BOOTSTRAP_R_7")
		)
		(pad "W32" smd circle
			(at 12.999974 0 270)
			(size 0.4572 0.4572)
			(layers "F.Cu" "F.Mask" "F.Paste")
			(net "Net_328")
		)
		(pad "W33" smd circle
			(at 13.999972 0 270)
			(size 0.4572 0.4572)
			(layers "F.Cu" "F.Mask" "F.Paste")
			(net "Net_327")
		)
		(pad "W34" smd circle
			(at 14.99997 0 270)
			(size 0.4572 0.4572)
			(layers "F.Cu" "F.Mask" "F.Paste")
			(net "BOOTSTRAP_R_2")
		)
		(pad "W35" smd circle
			(at 15.999968 0 270)
			(size 0.4572 0.4572)
			(layers "F.Cu" "F.Mask" "F.Paste")
			(net "BOOTSTRAP_R_1")
		)
		(pad "W36" smd circle
			(at 16.999966 0 270)
			(size 0.4572 0.4572)
			(layers "F.Cu" "F.Mask" "F.Paste")
			(net "BOOTSTRAP_R_5")
		)
		(pad "W37" smd circle
			(at 17.999964 0 270)
			(size 0.4572 0.4572)
			(layers "F.Cu" "F.Mask" "F.Paste")
			(net "BOOTSTRAP_R_3")
		)
		(pad "Y2" smd circle
			(at -16.999966 0.999998 270)
			(size 0.4572 0.4572)
			(layers "F.Cu" "F.Mask" "F.Paste")
			(net "PCIE_TX_CAP_N48")
		)
		(pad "Y3" smd circle
			(at -15.999968 0.999998 270)
			(size 0.4572 0.4572)
			(layers "F.Cu" "F.Mask" "F.Paste")
			(net "PCIE_TX_CAP_P48")
		)
		(pad "Y4" smd circle
			(at -14.99997 0.999998 270)
			(size 0.4572 0.4572)
			(layers "F.Cu" "F.Mask" "F.Paste")
			(net "GND")
		)
		(pad "Y5" smd circle
			(at -13.999972 0.999998 270)
			(size 0.4572 0.4572)
			(layers "F.Cu" "F.Mask" "F.Paste")
			(net "PCIE_RX_N48")
		)
		(pad "Y6" smd circle
			(at -12.999974 0.999998 270)
			(size 0.4572 0.4572)
			(layers "F.Cu" "F.Mask" "F.Paste")
			(net "PCIE_RX_P48")
		)
		(pad "Y7" smd circle
			(at -11.999976 0.999998 270)
			(size 0.4572 0.4572)
			(layers "F.Cu" "F.Mask" "F.Paste")
			(net "GND")
		)
		(pad "Y8" smd circle
			(at -10.999978 0.999998 270)
			(size 0.4572 0.4572)
			(layers "F.Cu" "F.Mask" "F.Paste")
			(net "DUT_AVD_TX")
		)
		(pad "Y9" smd circle
			(at -9.99998 0.999998 270)
			(size 0.4572 0.4572)
			(layers "F.Cu" "F.Mask" "F.Paste")
			(net "GND")
		)
		(pad "Y10" smd circle
			(at -8.999982 0.999998 270)
			(size 0.4572 0.4572)
			(layers "F.Cu" "F.Mask" "F.Paste")
			(net "DUT_AVD_TX")
		)
		(pad "Y11" smd circle
			(at -7.999984 0.999998 270)
			(size 0.4572 0.4572)
			(layers "F.Cu" "F.Mask" "F.Paste")
			(net "GND")
		)
		(pad "Y12" smd circle
			(at -6.999986 0.999998 270)
			(size 0.4572 0.4572)
			(layers "F.Cu" "F.Mask" "F.Paste")
			(net "GND")
		)
		(pad "Y13" smd circle
			(at -5.999988 0.999998 270)
			(size 0.4572 0.4572)
			(layers "F.Cu" "F.Mask" "F.Paste")
			(net "DUT_VDD")
		)
		(pad "Y14" smd circle
			(at -4.99999 0.999998 270)
			(size 0.4572 0.4572)
			(layers "F.Cu" "F.Mask" "F.Paste")
			(net "GND")
		)
		(pad "Y15" smd circle
			(at -3.999992 0.999998 270)
			(size 0.4572 0.4572)
			(layers "F.Cu" "F.Mask" "F.Paste")
			(net "DUT_VDD")
		)
		(pad "Y16" smd circle
			(at -2.999994 0.999998 270)
			(size 0.4572 0.4572)
			(layers "F.Cu" "F.Mask" "F.Paste")
			(net "GND")
		)
		(pad "Y17" smd circle
			(at -1.999996 0.999998 270)
			(size 0.4572 0.4572)
			(layers "F.Cu" "F.Mask" "F.Paste")
			(net "DUT_VDD")
		)
		(pad "Y18" smd circle
			(at -0.999998 0.999998 270)
			(size 0.4572 0.4572)
			(layers "F.Cu" "F.Mask" "F.Paste")
			(net "GND")
		)
		(pad "Y19" smd circle
			(at 0 0.999998 270)
			(size 0.4572 0.4572)
			(layers "F.Cu" "F.Mask" "F.Paste")
			(net "DUT_VDD")
		)
		(pad "Y20" smd circle
			(at 0.999998 0.999998 270)
			(size 0.4572 0.4572)
			(layers "F.Cu" "F.Mask" "F.Paste")
			(net "GND")
		)
		(pad "Y21" smd circle
			(at 1.999996 0.999998 270)
			(size 0.4572 0.4572)
			(layers "F.Cu" "F.Mask" "F.Paste")
			(net "DUT_VDD")
		)
		(pad "Y22" smd circle
			(at 2.999994 0.999998 270)
			(size 0.4572 0.4572)
			(layers "F.Cu" "F.Mask" "F.Paste")
			(net "GND")
		)
		(pad "Y23" smd circle
			(at 3.999992 0.999998 270)
			(size 0.4572 0.4572)
			(layers "F.Cu" "F.Mask" "F.Paste")
			(net "DUT_VDD")
		)
		(pad "Y24" smd circle
			(at 4.99999 0.999998 270)
			(size 0.4572 0.4572)
			(layers "F.Cu" "F.Mask" "F.Paste")
			(net "GND")
		)
		(pad "Y25" smd circle
			(at 5.999988 0.999998 270)
			(size 0.4572 0.4572)
			(layers "F.Cu" "F.Mask" "F.Paste")
			(net "DUT_VDD")
		)
		(pad "Y26" smd circle
			(at 6.999986 0.999998 270)
			(size 0.4572 0.4572)
			(layers "F.Cu" "F.Mask" "F.Paste")
			(net "GND")
		)
		(pad "Y27" smd circle
			(at 7.999984 0.999998 270)
			(size 0.4572 0.4572)
			(layers "F.Cu" "F.Mask" "F.Paste")
			(net "BOOTSTRAP_R_9")
		)
		(pad "Y28" smd circle
			(at 8.999982 0.999998 270)
			(size 0.4572 0.4572)
			(layers "F.Cu" "F.Mask" "F.Paste")
			(net "BOOTSTRAP_R_8")
		)
		(pad "Y29" smd circle
			(at 9.99998 0.999998 270)
			(size 0.4572 0.4572)
			(layers "F.Cu" "F.Mask" "F.Paste")
			(net "PCIE_REFCLK_D_P")
		)
		(pad "Y30" smd circle
			(at 10.999978 0.999998 270)
			(size 0.4572 0.4572)
			(layers "F.Cu" "F.Mask" "F.Paste")
			(net "PCIE_REFCLK_D_N")
		)
		(pad "Y31" smd circle
			(at 11.999976 0.999998 270)
			(size 0.4572 0.4572)
			(layers "F.Cu" "F.Mask" "F.Paste")
			(net "GND")
		)
		(pad "Y32" smd circle
			(at 12.999974 0.999998 270)
			(size 0.4572 0.4572)
			(layers "F.Cu" "F.Mask" "F.Paste")
			(net "PCIE_REFCLK_S1_P")
		)
		(pad "Y33" smd circle
			(at 13.999972 0.999998 270)
			(size 0.4572 0.4572)
			(layers "F.Cu" "F.Mask" "F.Paste")
			(net "PCIE_REFCLK_S1_N")
		)
		(pad "Y34" smd circle
			(at 14.99997 0.999998 270)
			(size 0.4572 0.4572)
			(layers "F.Cu" "F.Mask" "F.Paste")
			(net "BOOTSTRAP_R_4")
		)
		(pad "Y35" smd circle
			(at 15.999968 0.999998 270)
			(size 0.4572 0.4572)
			(layers "F.Cu" "F.Mask" "F.Paste")
			(net "GND")
		)
		(pad "Y36" smd circle
			(at 16.999966 0.999998 270)
			(size 0.4572 0.4572)
			(layers "F.Cu" "F.Mask" "F.Paste")
			(net "GND")
		)
		(pad "Y37" smd circle
			(at 17.999964 0.999998 270)
			(size 0.4572 0.4572)
			(layers "F.Cu" "F.Mask" "F.Paste")
			(net "GND")
		)
		(zone
			(layer "F.Cu")
			(hatch none 0.5)
			(connect_pads
				(clearance 0)
			)
			(min_thickness 0.25)
			(keepout
				(tracks allowed)
				(vias not_allowed)
				(pads allowed)
				(copperpour not_allowed)
				(footprints allowed)
			)
			(placement
				(enabled no)
				(sheetname "")
			)
			(fill
				(thermal_gap 0.5)
				(thermal_bridge_width 0.5)
				(island_removal_mode 0)
			)
			(polygon
				(pts
					(arc
						(start 222.981012 -62.999874)
						(mid 222.219012 -62.999874)
						(end 222.981012 -62.999874)
					)
				)
			)
		)
		(zone
			(layer "F.Cu")
			(hatch none 0.5)
			(connect_pads
				(clearance 0)
			)
			(min_thickness 0.25)
			(keepout
				(tracks allowed)
				(vias not_allowed)
				(pads allowed)
				(copperpour not_allowed)
				(footprints allowed)
			)
			(placement
				(enabled no)
				(sheetname "")
			)
			(fill
				(thermal_gap 0.5)
				(thermal_bridge_width 0.5)
				(island_removal_mode 0)
			)
			(polygon
				(pts
					(arc
						(start 222.981012 -61.999876)
						(mid 222.219012 -61.999876)
						(end 222.981012 -61.999876)
					)
				)
			)
		)
		(zone
			(layer "F.Cu")
			(hatch none 0.5)
			(connect_pads
				(clearance 0)
			)
			(min_thickness 0.25)
			(keepout
				(tracks allowed)
				(vias not_allowed)
				(pads allowed)
				(copperpour not_allowed)
				(footprints allowed)
			)
			(placement
				(enabled no)
				(sheetname "")
			)
			(fill
				(thermal_gap 0.5)
				(thermal_bridge_width 0.5)
				(island_removal_mode 0)
			)
			(polygon
				(pts
					(arc
						(start 222.981012 -60.999878)
						(mid 222.219012 -60.999878)
						(end 222.981012 -60.999878)
					)
				)
			)
		)
		(zone
			(layer "F.Cu")
			(hatch none 0.5)
			(connect_pads
				(clearance 0)
			)
			(min_thickness 0.25)
			(keepout
				(tracks allowed)
				(vias not_allowed)
				(pads allowed)
				(copperpour not_allowed)
				(footprints allowed)
			)
			(placement
				(enabled no)
				(sheetname "")
			)
			(fill
				(thermal_gap 0.5)
				(thermal_bridge_width 0.5)
				(island_removal_mode 0)
			)
			(polygon
				(pts
					(arc
						(start 222.981012 -59.99988)
						(mid 222.219012 -59.99988)
						(end 222.981012 -59.99988)
					)
				)
			)
		)
		(zone
			(layer "F.Cu")
			(hatch none 0.5)
			(connect_pads
				(clearance 0)
			)
			(min_thickness 0.25)
			(keepout
				(tracks allowed)
				(vias not_allowed)
				(pads allowed)
				(copperpour not_allowed)
				(footprints allowed)
			)
			(placement
				(enabled no)
				(sheetname "")
			)
			(fill
				(thermal_gap 0.5)
				(thermal_bridge_width 0.5)
				(island_removal_mode 0)
			)
			(polygon
				(pts
					(arc
						(start 222.981012 -57.999884)
						(mid 222.219012 -57.999884)
						(end 222.981012 -57.999884)
					)
				)
			)
		)
		(zone
			(layer "F.Cu")
			(hatch none 0.5)
			(connect_pads
				(clearance 0)
			)
			(min_thickness 0.25)
			(keepout
				(tracks allowed)
				(vias not_allowed)
				(pads allowed)
				(copperpour not_allowed)
				(footprints allowed)
			)
			(placement
				(enabled no)
				(sheetname "")
			)
			(fill
				(thermal_gap 0.5)
				(thermal_bridge_width 0.5)
				(island_removal_mode 0)
			)
			(polygon
				(pts
					(arc
						(start 222.981012 -55.999888)
						(mid 222.219012 -55.999888)
						(end 222.981012 -55.999888)
					)
				)
			)
		)
		(zone
			(layer "F.Cu")
			(hatch none 0.5)
			(connect_pads
				(clearance 0)
			)
			(min_thickness 0.25)
			(keepout
				(tracks allowed)
				(vias not_allowed)
				(pads allowed)
				(copperpour not_allowed)
				(footprints allowed)
			)
			(placement
				(enabled no)
				(sheetname "")
			)
			(fill
				(thermal_gap 0.5)
				(thermal_bridge_width 0.5)
				(island_removal_mode 0)
			)
			(polygon
				(pts
					(arc
						(start 222.981012 -53.999892)
						(mid 222.219012 -53.999892)
						(end 222.981012 -53.999892)
					)
				)
			)
		)
		(zone
			(layer "F.Cu")
			(hatch none 0.5)
			(connect_pads
				(clearance 0)
			)
			(min_thickness 0.25)
			(keepout
				(tracks allowed)
				(vias not_allowed)
				(pads allowed)
				(copperpour not_allowed)
				(footprints allowed)
			)
			(placement
				(enabled no)
				(sheetname "")
			)
			(fill
				(thermal_gap 0.5)
				(thermal_bridge_width 0.5)
				(island_removal_mode 0)
			)
			(polygon
				(pts
					(arc
						(start 222.981012 -51.999896)
						(mid 222.219012 -51.999896)
						(end 222.981012 -51.999896)
					)
				)
			)
		)
		(zone
			(layer "F.Cu")
			(hatch none 0.5)
			(connect_pads
				(clearance 0)
			)
			(min_thickness 0.25)
			(keepout
				(tracks allowed)
				(vias not_allowed)
				(pads allowed)
				(copperpour not_allowed)
				(footprints allowed)
			)
			(placement
				(enabled no)
				(sheetname "")
			)
			(fill
				(thermal_gap 0.5)
				(thermal_bridge_width 0.5)
				(island_removal_mode 0)
			)
			(polygon
				(pts
					(arc
						(start 222.981012 -50.999898)
						(mid 222.219012 -50.999898)
						(end 222.981012 -50.999898)
					)
				)
			)
		)
		(zone
			(layer "F.Cu")
			(hatch none 0.5)
			(connect_pads
				(clearance 0)
			)
			(min_thickness 0.25)
			(keepout
				(tracks allowed)
				(vias not_allowed)
				(pads allowed)
				(copperpour not_allowed)
				(footprints allowed)
			)
			(placement
				(enabled no)
				(sheetname "")
			)
			(fill
				(thermal_gap 0.5)
				(thermal_bridge_width 0.5)
				(island_removal_mode 0)
			)
			(polygon
				(pts
					(arc
						(start 222.981012 -48.999902)
						(mid 222.219012 -48.999902)
						(end 222.981012 -48.999902)
					)
				)
			)
		)
		(zone
			(layer "F.Cu")
			(hatch none 0.5)
			(connect_pads
				(clearance 0)
			)
			(min_thickness 0.25)
			(keepout
				(tracks allowed)
				(vias not_allowed)
				(pads allowed)
				(copperpour not_allowed)
				(footprints allowed)
			)
			(placement
				(enabled no)
				(sheetname "")
			)
			(fill
				(thermal_gap 0.5)
				(thermal_bridge_width 0.5)
				(island_removal_mode 0)
			)
			(polygon
				(pts
					(arc
						(start 222.981012 -46.999906)
						(mid 222.219012 -46.999906)
						(end 222.981012 -46.999906)
					)
				)
			)
		)
		(zone
			(layer "F.Cu")
			(hatch none 0.5)
			(connect_pads
				(clearance 0)
			)
			(min_thickness 0.25)
			(keepout
				(tracks allowed)
				(vias not_allowed)
				(pads allowed)
				(copperpour not_allowed)
				(footprints allowed)
			)
			(placement
				(enabled no)
				(sheetname "")
			)
			(fill
				(thermal_gap 0.5)
				(thermal_bridge_width 0.5)
				(island_removal_mode 0)
			)
			(polygon
				(pts
					(arc
						(start 222.981012 -44.99991)
						(mid 222.219012 -44.99991)
						(end 222.981012 -44.99991)
					)
				)
			)
		)
		(zone
			(layer "F.Cu")
			(hatch none 0.5)
			(connect_pads
				(clearance 0)
			)
			(min_thickness 0.25)
			(keepout
				(tracks allowed)
				(vias not_allowed)
				(pads allowed)
				(copperpour not_allowed)
				(footprints allowed)
			)
			(placement
				(enabled no)
				(sheetname "")
			)
			(fill
				(thermal_gap 0.5)
				(thermal_bridge_width 0.5)
				(island_removal_mode 0)
			)
			(polygon
				(pts
					(arc
						(start 222.981012 -42.999914)
						(mid 222.219012 -42.999914)
						(end 222.981012 -42.999914)
					)
				)
			)
		)
		(zone
			(layer "F.Cu")
			(hatch none 0.5)
			(connect_pads
				(clearance 0)
			)
			(min_thickness 0.25)
			(keepout
				(tracks allowed)
				(vias not_allowed)
				(pads allowed)
				(copperpour not_allowed)
				(footprints allowed)
			)
			(placement
				(enabled no)
				(sheetname "")
			)
			(fill
				(thermal_gap 0.5)
				(thermal_bridge_width 0.5)
				(island_removal_mode 0)
			)
			(polygon
				(pts
					(arc
						(start 222.981012 -41.999916)
						(mid 222.219012 -41.999916)
						(end 222.981012 -41.999916)
					)
				)
			)
		)
		(zone
			(layer "F.Cu")
			(hatch none 0.5)
			(connect_pads
				(clearance 0)
			)
			(min_thickness 0.25)
			(keepout
				(tracks allowed)
				(vias not_allowed)
				(pads allowed)
				(copperpour not_allowed)
				(footprints allowed)
			)
			(placement
				(enabled no)
				(sheetname "")
			)
			(fill
				(thermal_gap 0.5)
				(thermal_bridge_width 0.5)
				(island_removal_mode 0)
			)
			(polygon
				(pts
					(arc
						(start 222.981012 -39.99992)
						(mid 222.219012 -39.99992)
						(end 222.981012 -39.99992)
					)
				)
			)
		)
		(zone
			(layer "F.Cu")
			(hatch none 0.5)
			(connect_pads
				(clearance 0)
			)
			(min_thickness 0.25)
			(keepout
				(tracks allowed)
				(vias not_allowed)
				(pads allowed)
				(copperpour not_allowed)
				(footprints allowed)
			)
			(placement
				(enabled no)
				(sheetname "")
			)
			(fill
				(thermal_gap 0.5)
				(thermal_bridge_width 0.5)
				(island_removal_mode 0)
			)
			(polygon
				(pts
					(arc
						(start 222.981012 -37.999924)
						(mid 222.219012 -37.999924)
						(end 222.981012 -37.999924)
					)
				)
			)
		)
		(zone
			(layer "F.Cu")
			(hatch none 0.5)
			(connect_pads
				(clearance 0)
			)
			(min_thickness 0.25)
			(keepout
				(tracks allowed)
				(vias not_allowed)
				(pads allowed)
				(copperpour not_allowed)
				(footprints allowed)
			)
			(placement
				(enabled no)
				(sheetname "")
			)
			(fill
				(thermal_gap 0.5)
				(thermal_bridge_width 0.5)
				(island_removal_mode 0)
			)
			(polygon
				(pts
					(arc
						(start 222.981012 -35.999928)
						(mid 222.219012 -35.999928)
						(end 222.981012 -35.999928)
					)
				)
			)
		)
		(zone
			(layer "F.Cu")
			(hatch none 0.5)
			(connect_pads
				(clearance 0)
			)
			(min_thickness 0.25)
			(keepout
				(tracks allowed)
				(vias not_allowed)
				(pads allowed)
				(copperpour not_allowed)
				(footprints allowed)
			)
			(placement
				(enabled no)
				(sheetname "")
			)
			(fill
				(thermal_gap 0.5)
				(thermal_bridge_width 0.5)
				(island_removal_mode 0)
			)
			(polygon
				(pts
					(arc
						(start 222.981012 -33.999932)
						(mid 222.219012 -33.999932)
						(end 222.981012 -33.999932)
					)
				)
			)
		)
		(zone
			(layer "F.Cu")
			(hatch none 0.5)
			(connect_pads
				(clearance 0)
			)
			(min_thickness 0.25)
			(keepout
				(tracks allowed)
				(vias not_allowed)
				(pads allowed)
				(copperpour not_allowed)
				(footprints allowed)
			)
			(placement
				(enabled no)
				(sheetname "")
			)
			(fill
				(thermal_gap 0.5)
				(thermal_bridge_width 0.5)
				(island_removal_mode 0)
			)
			(polygon
				(pts
					(arc
						(start 222.981012 -32.999934)
						(mid 222.219012 -32.999934)
						(end 222.981012 -32.999934)
					)
				)
			)
		)
		(zone
			(layer "F.Cu")
			(hatch none 0.5)
			(connect_pads
				(clearance 0)
			)
			(min_thickness 0.25)
			(keepout
				(tracks allowed)
				(vias not_allowed)
				(pads allowed)
				(copperpour not_allowed)
				(footprints allowed)
			)
			(placement
				(enabled no)
				(sheetname "")
			)
			(fill
				(thermal_gap 0.5)
				(thermal_bridge_width 0.5)
				(island_removal_mode 0)
			)
			(polygon
				(pts
					(arc
						(start 223.98101 -62.999874)
						(mid 223.21901 -62.999874)
						(end 223.98101 -62.999874)
					)
				)
			)
		)
		(zone
			(layer "F.Cu")
			(hatch none 0.5)
			(connect_pads
				(clearance 0)
			)
			(min_thickness 0.25)
			(keepout
				(tracks allowed)
				(vias not_allowed)
				(pads allowed)
				(copperpour not_allowed)
				(footprints allowed)
			)
			(placement
				(enabled no)
				(sheetname "")
			)
			(fill
				(thermal_gap 0.5)
				(thermal_bridge_width 0.5)
				(island_removal_mode 0)
			)
			(polygon
				(pts
					(arc
						(start 223.98101 -61.999876)
						(mid 223.21901 -61.999876)
						(end 223.98101 -61.999876)
					)
				)
			)
		)
		(zone
			(layer "F.Cu")
			(hatch none 0.5)
			(connect_pads
				(clearance 0)
			)
			(min_thickness 0.25)
			(keepout
				(tracks allowed)
				(vias not_allowed)
				(pads allowed)
				(copperpour not_allowed)
				(footprints allowed)
			)
			(placement
				(enabled no)
				(sheetname "")
			)
			(fill
				(thermal_gap 0.5)
				(thermal_bridge_width 0.5)
				(island_removal_mode 0)
			)
			(polygon
				(pts
					(arc
						(start 223.98101 -60.999878)
						(mid 223.21901 -60.999878)
						(end 223.98101 -60.999878)
					)
				)
			)
		)
		(zone
			(layer "F.Cu")
			(hatch none 0.5)
			(connect_pads
				(clearance 0)
			)
			(min_thickness 0.25)
			(keepout
				(tracks allowed)
				(vias not_allowed)
				(pads allowed)
				(copperpour not_allowed)
				(footprints allowed)
			)
			(placement
				(enabled no)
				(sheetname "")
			)
			(fill
				(thermal_gap 0.5)
				(thermal_bridge_width 0.5)
				(island_removal_mode 0)
			)
			(polygon
				(pts
					(arc
						(start 223.98101 -59.99988)
						(mid 223.21901 -59.99988)
						(end 223.98101 -59.99988)
					)
				)
			)
		)
		(zone
			(layer "F.Cu")
			(hatch none 0.5)
			(connect_pads
				(clearance 0)
			)
			(min_thickness 0.25)
			(keepout
				(tracks allowed)
				(vias not_allowed)
				(pads allowed)
				(copperpour not_allowed)
				(footprints allowed)
			)
			(placement
				(enabled no)
				(sheetname "")
			)
			(fill
				(thermal_gap 0.5)
				(thermal_bridge_width 0.5)
				(island_removal_mode 0)
			)
			(polygon
				(pts
					(arc
						(start 223.98101 -58.999882)
						(mid 223.21901 -58.999882)
						(end 223.98101 -58.999882)
					)
				)
			)
		)
		(zone
			(layer "F.Cu")
			(hatch none 0.5)
			(connect_pads
				(clearance 0)
			)
			(min_thickness 0.25)
			(keepout
				(tracks allowed)
				(vias not_allowed)
				(pads allowed)
				(copperpour not_allowed)
				(footprints allowed)
			)
			(placement
				(enabled no)
				(sheetname "")
			)
			(fill
				(thermal_gap 0.5)
				(thermal_bridge_width 0.5)
				(island_removal_mode 0)
			)
			(polygon
				(pts
					(arc
						(start 223.98101 -57.999884)
						(mid 223.21901 -57.999884)
						(end 223.98101 -57.999884)
					)
				)
			)
		)
		(zone
			(layer "F.Cu")
			(hatch none 0.5)
			(connect_pads
				(clearance 0)
			)
			(min_thickness 0.25)
			(keepout
				(tracks allowed)
				(vias not_allowed)
				(pads allowed)
				(copperpour not_allowed)
				(footprints allowed)
			)
			(placement
				(enabled no)
				(sheetname "")
			)
			(fill
				(thermal_gap 0.5)
				(thermal_bridge_width 0.5)
				(island_removal_mode 0)
			)
			(polygon
				(pts
					(arc
						(start 223.98101 -56.999886)
						(mid 223.21901 -56.999886)
						(end 223.98101 -56.999886)
					)
				)
			)
		)
		(zone
			(layer "F.Cu")
			(hatch none 0.5)
			(connect_pads
				(clearance 0)
			)
			(min_thickness 0.25)
			(keepout
				(tracks allowed)
				(vias not_allowed)
				(pads allowed)
				(copperpour not_allowed)
				(footprints allowed)
			)
			(placement
				(enabled no)
				(sheetname "")
			)
			(fill
				(thermal_gap 0.5)
				(thermal_bridge_width 0.5)
				(island_removal_mode 0)
			)
			(polygon
				(pts
					(arc
						(start 223.98101 -55.999888)
						(mid 223.21901 -55.999888)
						(end 223.98101 -55.999888)
					)
				)
			)
		)
		(zone
			(layer "F.Cu")
			(hatch none 0.5)
			(connect_pads
				(clearance 0)
			)
			(min_thickness 0.25)
			(keepout
				(tracks allowed)
				(vias not_allowed)
				(pads allowed)
				(copperpour not_allowed)
				(footprints allowed)
			)
			(placement
				(enabled no)
				(sheetname "")
			)
			(fill
				(thermal_gap 0.5)
				(thermal_bridge_width 0.5)
				(island_removal_mode 0)
			)
			(polygon
				(pts
					(arc
						(start 223.98101 -54.99989)
						(mid 223.21901 -54.99989)
						(end 223.98101 -54.99989)
					)
				)
			)
		)
		(zone
			(layer "F.Cu")
			(hatch none 0.5)
			(connect_pads
				(clearance 0)
			)
			(min_thickness 0.25)
			(keepout
				(tracks allowed)
				(vias not_allowed)
				(pads allowed)
				(copperpour not_allowed)
				(footprints allowed)
			)
			(placement
				(enabled no)
				(sheetname "")
			)
			(fill
				(thermal_gap 0.5)
				(thermal_bridge_width 0.5)
				(island_removal_mode 0)
			)
			(polygon
				(pts
					(arc
						(start 223.98101 -53.999892)
						(mid 223.21901 -53.999892)
						(end 223.98101 -53.999892)
					)
				)
			)
		)
		(zone
			(layer "F.Cu")
			(hatch none 0.5)
			(connect_pads
				(clearance 0)
			)
			(min_thickness 0.25)
			(keepout
				(tracks allowed)
				(vias not_allowed)
				(pads allowed)
				(copperpour not_allowed)
				(footprints allowed)
			)
			(placement
				(enabled no)
				(sheetname "")
			)
			(fill
				(thermal_gap 0.5)
				(thermal_bridge_width 0.5)
				(island_removal_mode 0)
			)
			(polygon
				(pts
					(arc
						(start 223.98101 -52.999894)
						(mid 223.21901 -52.999894)
						(end 223.98101 -52.999894)
					)
				)
			)
		)
		(zone
			(layer "F.Cu")
			(hatch none 0.5)
			(connect_pads
				(clearance 0)
			)
			(min_thickness 0.25)
			(keepout
				(tracks allowed)
				(vias not_allowed)
				(pads allowed)
				(copperpour not_allowed)
				(footprints allowed)
			)
			(placement
				(enabled no)
				(sheetname "")
			)
			(fill
				(thermal_gap 0.5)
				(thermal_bridge_width 0.5)
				(island_removal_mode 0)
			)
			(polygon
				(pts
					(arc
						(start 223.98101 -51.999896)
						(mid 223.21901 -51.999896)
						(end 223.98101 -51.999896)
					)
				)
			)
		)
		(zone
			(layer "F.Cu")
			(hatch none 0.5)
			(connect_pads
				(clearance 0)
			)
			(min_thickness 0.25)
			(keepout
				(tracks allowed)
				(vias not_allowed)
				(pads allowed)
				(copperpour not_allowed)
				(footprints allowed)
			)
			(placement
				(enabled no)
				(sheetname "")
			)
			(fill
				(thermal_gap 0.5)
				(thermal_bridge_width 0.5)
				(island_removal_mode 0)
			)
			(polygon
				(pts
					(arc
						(start 223.98101 -50.999898)
						(mid 223.21901 -50.999898)
						(end 223.98101 -50.999898)
					)
				)
			)
		)
		(zone
			(layer "F.Cu")
			(hatch none 0.5)
			(connect_pads
				(clearance 0)
			)
			(min_thickness 0.25)
			(keepout
				(tracks allowed)
				(vias not_allowed)
				(pads allowed)
				(copperpour not_allowed)
				(footprints allowed)
			)
			(placement
				(enabled no)
				(sheetname "")
			)
			(fill
				(thermal_gap 0.5)
				(thermal_bridge_width 0.5)
				(island_removal_mode 0)
			)
			(polygon
				(pts
					(arc
						(start 223.98101 -49.9999)
						(mid 223.21901 -49.9999)
						(end 223.98101 -49.9999)
					)
				)
			)
		)
		(zone
			(layer "F.Cu")
			(hatch none 0.5)
			(connect_pads
				(clearance 0)
			)
			(min_thickness 0.25)
			(keepout
				(tracks allowed)
				(vias not_allowed)
				(pads allowed)
				(copperpour not_allowed)
				(footprints allowed)
			)
			(placement
				(enabled no)
				(sheetname "")
			)
			(fill
				(thermal_gap 0.5)
				(thermal_bridge_width 0.5)
				(island_removal_mode 0)
			)
			(polygon
				(pts
					(arc
						(start 223.98101 -48.999902)
						(mid 223.21901 -48.999902)
						(end 223.98101 -48.999902)
					)
				)
			)
		)
		(zone
			(layer "F.Cu")
			(hatch none 0.5)
			(connect_pads
				(clearance 0)
			)
			(min_thickness 0.25)
			(keepout
				(tracks allowed)
				(vias not_allowed)
				(pads allowed)
				(copperpour not_allowed)
				(footprints allowed)
			)
			(placement
				(enabled no)
				(sheetname "")
			)
			(fill
				(thermal_gap 0.5)
				(thermal_bridge_width 0.5)
				(island_removal_mode 0)
			)
			(polygon
				(pts
					(arc
						(start 223.98101 -47.999904)
						(mid 223.21901 -47.999904)
						(end 223.98101 -47.999904)
					)
				)
			)
		)
		(zone
			(layer "F.Cu")
			(hatch none 0.5)
			(connect_pads
				(clearance 0)
			)
			(min_thickness 0.25)
			(keepout
				(tracks allowed)
				(vias not_allowed)
				(pads allowed)
				(copperpour not_allowed)
				(footprints allowed)
			)
			(placement
				(enabled no)
				(sheetname "")
			)
			(fill
				(thermal_gap 0.5)
				(thermal_bridge_width 0.5)
				(island_removal_mode 0)
			)
			(polygon
				(pts
					(arc
						(start 223.98101 -46.999906)
						(mid 223.21901 -46.999906)
						(end 223.98101 -46.999906)
					)
				)
			)
		)
		(zone
			(layer "F.Cu")
			(hatch none 0.5)
			(connect_pads
				(clearance 0)
			)
			(min_thickness 0.25)
			(keepout
				(tracks allowed)
				(vias not_allowed)
				(pads allowed)
				(copperpour not_allowed)
				(footprints allowed)
			)
			(placement
				(enabled no)
				(sheetname "")
			)
			(fill
				(thermal_gap 0.5)
				(thermal_bridge_width 0.5)
				(island_removal_mode 0)
			)
			(polygon
				(pts
					(arc
						(start 223.98101 -45.999908)
						(mid 223.21901 -45.999908)
						(end 223.98101 -45.999908)
					)
				)
			)
		)
		(zone
			(layer "F.Cu")
			(hatch none 0.5)
			(connect_pads
				(clearance 0)
			)
			(min_thickness 0.25)
			(keepout
				(tracks allowed)
				(vias not_allowed)
				(pads allowed)
				(copperpour not_allowed)
				(footprints allowed)
			)
			(placement
				(enabled no)
				(sheetname "")
			)
			(fill
				(thermal_gap 0.5)
				(thermal_bridge_width 0.5)
				(island_removal_mode 0)
			)
			(polygon
				(pts
					(arc
						(start 223.98101 -44.99991)
						(mid 223.21901 -44.99991)
						(end 223.98101 -44.99991)
					)
				)
			)
		)
		(zone
			(layer "F.Cu")
			(hatch none 0.5)
			(connect_pads
				(clearance 0)
			)
			(min_thickness 0.25)
			(keepout
				(tracks allowed)
				(vias not_allowed)
				(pads allowed)
				(copperpour not_allowed)
				(footprints allowed)
			)
			(placement
				(enabled no)
				(sheetname "")
			)
			(fill
				(thermal_gap 0.5)
				(thermal_bridge_width 0.5)
				(island_removal_mode 0)
			)
			(polygon
				(pts
					(arc
						(start 223.98101 -43.999912)
						(mid 223.21901 -43.999912)
						(end 223.98101 -43.999912)
					)
				)
			)
		)
		(zone
			(layer "F.Cu")
			(hatch none 0.5)
			(connect_pads
				(clearance 0)
			)
			(min_thickness 0.25)
			(keepout
				(tracks allowed)
				(vias not_allowed)
				(pads allowed)
				(copperpour not_allowed)
				(footprints allowed)
			)
			(placement
				(enabled no)
				(sheetname "")
			)
			(fill
				(thermal_gap 0.5)
				(thermal_bridge_width 0.5)
				(island_removal_mode 0)
			)
			(polygon
				(pts
					(arc
						(start 223.98101 -42.999914)
						(mid 223.21901 -42.999914)
						(end 223.98101 -42.999914)
					)
				)
			)
		)
		(zone
			(layer "F.Cu")
			(hatch none 0.5)
			(connect_pads
				(clearance 0)
			)
			(min_thickness 0.25)
			(keepout
				(tracks allowed)
				(vias not_allowed)
				(pads allowed)
				(copperpour not_allowed)
				(footprints allowed)
			)
			(placement
				(enabled no)
				(sheetname "")
			)
			(fill
				(thermal_gap 0.5)
				(thermal_bridge_width 0.5)
				(island_removal_mode 0)
			)
			(polygon
				(pts
					(arc
						(start 223.98101 -41.999916)
						(mid 223.21901 -41.999916)
						(end 223.98101 -41.999916)
					)
				)
			)
		)
		(zone
			(layer "F.Cu")
			(hatch none 0.5)
			(connect_pads
				(clearance 0)
			)
			(min_thickness 0.25)
			(keepout
				(tracks allowed)
				(vias not_allowed)
				(pads allowed)
				(copperpour not_allowed)
				(footprints allowed)
			)
			(placement
				(enabled no)
				(sheetname "")
			)
			(fill
				(thermal_gap 0.5)
				(thermal_bridge_width 0.5)
				(island_removal_mode 0)
			)
			(polygon
				(pts
					(arc
						(start 223.98101 -40.999918)
						(mid 223.21901 -40.999918)
						(end 223.98101 -40.999918)
					)
				)
			)
		)
		(zone
			(layer "F.Cu")
			(hatch none 0.5)
			(connect_pads
				(clearance 0)
			)
			(min_thickness 0.25)
			(keepout
				(tracks allowed)
				(vias not_allowed)
				(pads allowed)
				(copperpour not_allowed)
				(footprints allowed)
			)
			(placement
				(enabled no)
				(sheetname "")
			)
			(fill
				(thermal_gap 0.5)
				(thermal_bridge_width 0.5)
				(island_removal_mode 0)
			)
			(polygon
				(pts
					(arc
						(start 223.98101 -39.99992)
						(mid 223.21901 -39.99992)
						(end 223.98101 -39.99992)
					)
				)
			)
		)
		(zone
			(layer "F.Cu")
			(hatch none 0.5)
			(connect_pads
				(clearance 0)
			)
			(min_thickness 0.25)
			(keepout
				(tracks allowed)
				(vias not_allowed)
				(pads allowed)
				(copperpour not_allowed)
				(footprints allowed)
			)
			(placement
				(enabled no)
				(sheetname "")
			)
			(fill
				(thermal_gap 0.5)
				(thermal_bridge_width 0.5)
				(island_removal_mode 0)
			)
			(polygon
				(pts
					(arc
						(start 223.98101 -38.999922)
						(mid 223.21901 -38.999922)
						(end 223.98101 -38.999922)
					)
				)
			)
		)
		(zone
			(layer "F.Cu")
			(hatch none 0.5)
			(connect_pads
				(clearance 0)
			)
			(min_thickness 0.25)
			(keepout
				(tracks allowed)
				(vias not_allowed)
				(pads allowed)
				(copperpour not_allowed)
				(footprints allowed)
			)
			(placement
				(enabled no)
				(sheetname "")
			)
			(fill
				(thermal_gap 0.5)
				(thermal_bridge_width 0.5)
				(island_removal_mode 0)
			)
			(polygon
				(pts
					(arc
						(start 223.98101 -37.999924)
						(mid 223.21901 -37.999924)
						(end 223.98101 -37.999924)
					)
				)
			)
		)
		(zone
			(layer "F.Cu")
			(hatch none 0.5)
			(connect_pads
				(clearance 0)
			)
			(min_thickness 0.25)
			(keepout
				(tracks allowed)
				(vias not_allowed)
				(pads allowed)
				(copperpour not_allowed)
				(footprints allowed)
			)
			(placement
				(enabled no)
				(sheetname "")
			)
			(fill
				(thermal_gap 0.5)
				(thermal_bridge_width 0.5)
				(island_removal_mode 0)
			)
			(polygon
				(pts
					(arc
						(start 223.98101 -36.999926)
						(mid 223.21901 -36.999926)
						(end 223.98101 -36.999926)
					)
				)
			)
		)
		(zone
			(layer "F.Cu")
			(hatch none 0.5)
			(connect_pads
				(clearance 0)
			)
			(min_thickness 0.25)
			(keepout
				(tracks allowed)
				(vias not_allowed)
				(pads allowed)
				(copperpour not_allowed)
				(footprints allowed)
			)
			(placement
				(enabled no)
				(sheetname "")
			)
			(fill
				(thermal_gap 0.5)
				(thermal_bridge_width 0.5)
				(island_removal_mode 0)
			)
			(polygon
				(pts
					(arc
						(start 223.98101 -35.999928)
						(mid 223.21901 -35.999928)
						(end 223.98101 -35.999928)
					)
				)
			)
		)
		(zone
			(layer "F.Cu")
			(hatch none 0.5)
			(connect_pads
				(clearance 0)
			)
			(min_thickness 0.25)
			(keepout
				(tracks allowed)
				(vias not_allowed)
				(pads allowed)
				(copperpour not_allowed)
				(footprints allowed)
			)
			(placement
				(enabled no)
				(sheetname "")
			)
			(fill
				(thermal_gap 0.5)
				(thermal_bridge_width 0.5)
				(island_removal_mode 0)
			)
			(polygon
				(pts
					(arc
						(start 223.98101 -34.99993)
						(mid 223.21901 -34.99993)
						(end 223.98101 -34.99993)
					)
				)
			)
		)
		(zone
			(layer "F.Cu")
			(hatch none 0.5)
			(connect_pads
				(clearance 0)
			)
			(min_thickness 0.25)
			(keepout
				(tracks allowed)
				(vias not_allowed)
				(pads allowed)
				(copperpour not_allowed)
				(footprints allowed)
			)
			(placement
				(enabled no)
				(sheetname "")
			)
			(fill
				(thermal_gap 0.5)
				(thermal_bridge_width 0.5)
				(island_removal_mode 0)
			)
			(polygon
				(pts
					(arc
						(start 223.98101 -33.999932)
						(mid 223.21901 -33.999932)
						(end 223.98101 -33.999932)
					)
				)
			)
		)
		(zone
			(layer "F.Cu")
			(hatch none 0.5)
			(connect_pads
				(clearance 0)
			)
			(min_thickness 0.25)
			(keepout
				(tracks allowed)
				(vias not_allowed)
				(pads allowed)
				(copperpour not_allowed)
				(footprints allowed)
			)
			(placement
				(enabled no)
				(sheetname "")
			)
			(fill
				(thermal_gap 0.5)
				(thermal_bridge_width 0.5)
				(island_removal_mode 0)
			)
			(polygon
				(pts
					(arc
						(start 223.98101 -32.999934)
						(mid 223.21901 -32.999934)
						(end 223.98101 -32.999934)
					)
				)
			)
		)
		(zone
			(layer "F.Cu")
			(hatch none 0.5)
			(connect_pads
				(clearance 0)
			)
			(min_thickness 0.25)
			(keepout
				(tracks allowed)
				(vias not_allowed)
				(pads allowed)
				(copperpour not_allowed)
				(footprints allowed)
			)
			(placement
				(enabled no)
				(sheetname "")
			)
			(fill
				(thermal_gap 0.5)
				(thermal_bridge_width 0.5)
				(island_removal_mode 0)
			)
			(polygon
				(pts
					(arc
						(start 224.981008 -62.999874)
						(mid 224.219008 -62.999874)
						(end 224.981008 -62.999874)
					)
				)
			)
		)
		(zone
			(layer "F.Cu")
			(hatch none 0.5)
			(connect_pads
				(clearance 0)
			)
			(min_thickness 0.25)
			(keepout
				(tracks allowed)
				(vias not_allowed)
				(pads allowed)
				(copperpour not_allowed)
				(footprints allowed)
			)
			(placement
				(enabled no)
				(sheetname "")
			)
			(fill
				(thermal_gap 0.5)
				(thermal_bridge_width 0.5)
				(island_removal_mode 0)
			)
			(polygon
				(pts
					(arc
						(start 224.981008 -61.999876)
						(mid 224.219008 -61.999876)
						(end 224.981008 -61.999876)
					)
				)
			)
		)
		(zone
			(layer "F.Cu")
			(hatch none 0.5)
			(connect_pads
				(clearance 0)
			)
			(min_thickness 0.25)
			(keepout
				(tracks allowed)
				(vias not_allowed)
				(pads allowed)
				(copperpour not_allowed)
				(footprints allowed)
			)
			(placement
				(enabled no)
				(sheetname "")
			)
			(fill
				(thermal_gap 0.5)
				(thermal_bridge_width 0.5)
				(island_removal_mode 0)
			)
			(polygon
				(pts
					(arc
						(start 224.981008 -60.999878)
						(mid 224.219008 -60.999878)
						(end 224.981008 -60.999878)
					)
				)
			)
		)
		(zone
			(layer "F.Cu")
			(hatch none 0.5)
			(connect_pads
				(clearance 0)
			)
			(min_thickness 0.25)
			(keepout
				(tracks allowed)
				(vias not_allowed)
				(pads allowed)
				(copperpour not_allowed)
				(footprints allowed)
			)
			(placement
				(enabled no)
				(sheetname "")
			)
			(fill
				(thermal_gap 0.5)
				(thermal_bridge_width 0.5)
				(island_removal_mode 0)
			)
			(polygon
				(pts
					(arc
						(start 224.981008 -59.99988)
						(mid 224.219008 -59.99988)
						(end 224.981008 -59.99988)
					)
				)
			)
		)
		(zone
			(layer "F.Cu")
			(hatch none 0.5)
			(connect_pads
				(clearance 0)
			)
			(min_thickness 0.25)
			(keepout
				(tracks allowed)
				(vias not_allowed)
				(pads allowed)
				(copperpour not_allowed)
				(footprints allowed)
			)
			(placement
				(enabled no)
				(sheetname "")
			)
			(fill
				(thermal_gap 0.5)
				(thermal_bridge_width 0.5)
				(island_removal_mode 0)
			)
			(polygon
				(pts
					(arc
						(start 224.981008 -58.999882)
						(mid 224.219008 -58.999882)
						(end 224.981008 -58.999882)
					)
				)
			)
		)
		(zone
			(layer "F.Cu")
			(hatch none 0.5)
			(connect_pads
				(clearance 0)
			)
			(min_thickness 0.25)
			(keepout
				(tracks allowed)
				(vias not_allowed)
				(pads allowed)
				(copperpour not_allowed)
				(footprints allowed)
			)
			(placement
				(enabled no)
				(sheetname "")
			)
			(fill
				(thermal_gap 0.5)
				(thermal_bridge_width 0.5)
				(island_removal_mode 0)
			)
			(polygon
				(pts
					(arc
						(start 224.981008 -57.999884)
						(mid 224.219008 -57.999884)
						(end 224.981008 -57.999884)
					)
				)
			)
		)
		(zone
			(layer "F.Cu")
			(hatch none 0.5)
			(connect_pads
				(clearance 0)
			)
			(min_thickness 0.25)
			(keepout
				(tracks allowed)
				(vias not_allowed)
				(pads allowed)
				(copperpour not_allowed)
				(footprints allowed)
			)
			(placement
				(enabled no)
				(sheetname "")
			)
			(fill
				(thermal_gap 0.5)
				(thermal_bridge_width 0.5)
				(island_removal_mode 0)
			)
			(polygon
				(pts
					(arc
						(start 224.981008 -56.999886)
						(mid 224.219008 -56.999886)
						(end 224.981008 -56.999886)
					)
				)
			)
		)
		(zone
			(layer "F.Cu")
			(hatch none 0.5)
			(connect_pads
				(clearance 0)
			)
			(min_thickness 0.25)
			(keepout
				(tracks allowed)
				(vias not_allowed)
				(pads allowed)
				(copperpour not_allowed)
				(footprints allowed)
			)
			(placement
				(enabled no)
				(sheetname "")
			)
			(fill
				(thermal_gap 0.5)
				(thermal_bridge_width 0.5)
				(island_removal_mode 0)
			)
			(polygon
				(pts
					(arc
						(start 224.981008 -55.999888)
						(mid 224.219008 -55.999888)
						(end 224.981008 -55.999888)
					)
				)
			)
		)
		(zone
			(layer "F.Cu")
			(hatch none 0.5)
			(connect_pads
				(clearance 0)
			)
			(min_thickness 0.25)
			(keepout
				(tracks allowed)
				(vias not_allowed)
				(pads allowed)
				(copperpour not_allowed)
				(footprints allowed)
			)
			(placement
				(enabled no)
				(sheetname "")
			)
			(fill
				(thermal_gap 0.5)
				(thermal_bridge_width 0.5)
				(island_removal_mode 0)
			)
			(polygon
				(pts
					(arc
						(start 224.981008 -54.99989)
						(mid 224.219008 -54.99989)
						(end 224.981008 -54.99989)
					)
				)
			)
		)
		(zone
			(layer "F.Cu")
			(hatch none 0.5)
			(connect_pads
				(clearance 0)
			)
			(min_thickness 0.25)
			(keepout
				(tracks allowed)
				(vias not_allowed)
				(pads allowed)
				(copperpour not_allowed)
				(footprints allowed)
			)
			(placement
				(enabled no)
				(sheetname "")
			)
			(fill
				(thermal_gap 0.5)
				(thermal_bridge_width 0.5)
				(island_removal_mode 0)
			)
			(polygon
				(pts
					(arc
						(start 224.981008 -53.999892)
						(mid 224.219008 -53.999892)
						(end 224.981008 -53.999892)
					)
				)
			)
		)
		(zone
			(layer "F.Cu")
			(hatch none 0.5)
			(connect_pads
				(clearance 0)
			)
			(min_thickness 0.25)
			(keepout
				(tracks allowed)
				(vias not_allowed)
				(pads allowed)
				(copperpour not_allowed)
				(footprints allowed)
			)
			(placement
				(enabled no)
				(sheetname "")
			)
			(fill
				(thermal_gap 0.5)
				(thermal_bridge_width 0.5)
				(island_removal_mode 0)
			)
			(polygon
				(pts
					(arc
						(start 224.981008 -52.999894)
						(mid 224.219008 -52.999894)
						(end 224.981008 -52.999894)
					)
				)
			)
		)
		(zone
			(layer "F.Cu")
			(hatch none 0.5)
			(connect_pads
				(clearance 0)
			)
			(min_thickness 0.25)
			(keepout
				(tracks allowed)
				(vias not_allowed)
				(pads allowed)
				(copperpour not_allowed)
				(footprints allowed)
			)
			(placement
				(enabled no)
				(sheetname "")
			)
			(fill
				(thermal_gap 0.5)
				(thermal_bridge_width 0.5)
				(island_removal_mode 0)
			)
			(polygon
				(pts
					(arc
						(start 224.981008 -51.999896)
						(mid 224.219008 -51.999896)
						(end 224.981008 -51.999896)
					)
				)
			)
		)
		(zone
			(layer "F.Cu")
			(hatch none 0.5)
			(connect_pads
				(clearance 0)
			)
			(min_thickness 0.25)
			(keepout
				(tracks allowed)
				(vias not_allowed)
				(pads allowed)
				(copperpour not_allowed)
				(footprints allowed)
			)
			(placement
				(enabled no)
				(sheetname "")
			)
			(fill
				(thermal_gap 0.5)
				(thermal_bridge_width 0.5)
				(island_removal_mode 0)
			)
			(polygon
				(pts
					(arc
						(start 224.981008 -50.999898)
						(mid 224.219008 -50.999898)
						(end 224.981008 -50.999898)
					)
				)
			)
		)
		(zone
			(layer "F.Cu")
			(hatch none 0.5)
			(connect_pads
				(clearance 0)
			)
			(min_thickness 0.25)
			(keepout
				(tracks allowed)
				(vias not_allowed)
				(pads allowed)
				(copperpour not_allowed)
				(footprints allowed)
			)
			(placement
				(enabled no)
				(sheetname "")
			)
			(fill
				(thermal_gap 0.5)
				(thermal_bridge_width 0.5)
				(island_removal_mode 0)
			)
			(polygon
				(pts
					(arc
						(start 224.981008 -49.9999)
						(mid 224.219008 -49.9999)
						(end 224.981008 -49.9999)
					)
				)
			)
		)
		(zone
			(layer "F.Cu")
			(hatch none 0.5)
			(connect_pads
				(clearance 0)
			)
			(min_thickness 0.25)
			(keepout
				(tracks allowed)
				(vias not_allowed)
				(pads allowed)
				(copperpour not_allowed)
				(footprints allowed)
			)
			(placement
				(enabled no)
				(sheetname "")
			)
			(fill
				(thermal_gap 0.5)
				(thermal_bridge_width 0.5)
				(island_removal_mode 0)
			)
			(polygon
				(pts
					(arc
						(start 224.981008 -48.999902)
						(mid 224.219008 -48.999902)
						(end 224.981008 -48.999902)
					)
				)
			)
		)
		(zone
			(layer "F.Cu")
			(hatch none 0.5)
			(connect_pads
				(clearance 0)
			)
			(min_thickness 0.25)
			(keepout
				(tracks allowed)
				(vias not_allowed)
				(pads allowed)
				(copperpour not_allowed)
				(footprints allowed)
			)
			(placement
				(enabled no)
				(sheetname "")
			)
			(fill
				(thermal_gap 0.5)
				(thermal_bridge_width 0.5)
				(island_removal_mode 0)
			)
			(polygon
				(pts
					(arc
						(start 224.981008 -47.999904)
						(mid 224.219008 -47.999904)
						(end 224.981008 -47.999904)
					)
				)
			)
		)
		(zone
			(layer "F.Cu")
			(hatch none 0.5)
			(connect_pads
				(clearance 0)
			)
			(min_thickness 0.25)
			(keepout
				(tracks allowed)
				(vias not_allowed)
				(pads allowed)
				(copperpour not_allowed)
				(footprints allowed)
			)
			(placement
				(enabled no)
				(sheetname "")
			)
			(fill
				(thermal_gap 0.5)
				(thermal_bridge_width 0.5)
				(island_removal_mode 0)
			)
			(polygon
				(pts
					(arc
						(start 224.981008 -46.999906)
						(mid 224.219008 -46.999906)
						(end 224.981008 -46.999906)
					)
				)
			)
		)
		(zone
			(layer "F.Cu")
			(hatch none 0.5)
			(connect_pads
				(clearance 0)
			)
			(min_thickness 0.25)
			(keepout
				(tracks allowed)
				(vias not_allowed)
				(pads allowed)
				(copperpour not_allowed)
				(footprints allowed)
			)
			(placement
				(enabled no)
				(sheetname "")
			)
			(fill
				(thermal_gap 0.5)
				(thermal_bridge_width 0.5)
				(island_removal_mode 0)
			)
			(polygon
				(pts
					(arc
						(start 224.981008 -45.999908)
						(mid 224.219008 -45.999908)
						(end 224.981008 -45.999908)
					)
				)
			)
		)
		(zone
			(layer "F.Cu")
			(hatch none 0.5)
			(connect_pads
				(clearance 0)
			)
			(min_thickness 0.25)
			(keepout
				(tracks allowed)
				(vias not_allowed)
				(pads allowed)
				(copperpour not_allowed)
				(footprints allowed)
			)
			(placement
				(enabled no)
				(sheetname "")
			)
			(fill
				(thermal_gap 0.5)
				(thermal_bridge_width 0.5)
				(island_removal_mode 0)
			)
			(polygon
				(pts
					(arc
						(start 224.981008 -44.99991)
						(mid 224.219008 -44.99991)
						(end 224.981008 -44.99991)
					)
				)
			)
		)
		(zone
			(layer "F.Cu")
			(hatch none 0.5)
			(connect_pads
				(clearance 0)
			)
			(min_thickness 0.25)
			(keepout
				(tracks allowed)
				(vias not_allowed)
				(pads allowed)
				(copperpour not_allowed)
				(footprints allowed)
			)
			(placement
				(enabled no)
				(sheetname "")
			)
			(fill
				(thermal_gap 0.5)
				(thermal_bridge_width 0.5)
				(island_removal_mode 0)
			)
			(polygon
				(pts
					(arc
						(start 224.981008 -43.999912)
						(mid 224.219008 -43.999912)
						(end 224.981008 -43.999912)
					)
				)
			)
		)
		(zone
			(layer "F.Cu")
			(hatch none 0.5)
			(connect_pads
				(clearance 0)
			)
			(min_thickness 0.25)
			(keepout
				(tracks allowed)
				(vias not_allowed)
				(pads allowed)
				(copperpour not_allowed)
				(footprints allowed)
			)
			(placement
				(enabled no)
				(sheetname "")
			)
			(fill
				(thermal_gap 0.5)
				(thermal_bridge_width 0.5)
				(island_removal_mode 0)
			)
			(polygon
				(pts
					(arc
						(start 224.981008 -42.999914)
						(mid 224.219008 -42.999914)
						(end 224.981008 -42.999914)
					)
				)
			)
		)
		(zone
			(layer "F.Cu")
			(hatch none 0.5)
			(connect_pads
				(clearance 0)
			)
			(min_thickness 0.25)
			(keepout
				(tracks allowed)
				(vias not_allowed)
				(pads allowed)
				(copperpour not_allowed)
				(footprints allowed)
			)
			(placement
				(enabled no)
				(sheetname "")
			)
			(fill
				(thermal_gap 0.5)
				(thermal_bridge_width 0.5)
				(island_removal_mode 0)
			)
			(polygon
				(pts
					(arc
						(start 224.981008 -41.999916)
						(mid 224.219008 -41.999916)
						(end 224.981008 -41.999916)
					)
				)
			)
		)
		(zone
			(layer "F.Cu")
			(hatch none 0.5)
			(connect_pads
				(clearance 0)
			)
			(min_thickness 0.25)
			(keepout
				(tracks allowed)
				(vias not_allowed)
				(pads allowed)
				(copperpour not_allowed)
				(footprints allowed)
			)
			(placement
				(enabled no)
				(sheetname "")
			)
			(fill
				(thermal_gap 0.5)
				(thermal_bridge_width 0.5)
				(island_removal_mode 0)
			)
			(polygon
				(pts
					(arc
						(start 224.981008 -40.999918)
						(mid 224.219008 -40.999918)
						(end 224.981008 -40.999918)
					)
				)
			)
		)
		(zone
			(layer "F.Cu")
			(hatch none 0.5)
			(connect_pads
				(clearance 0)
			)
			(min_thickness 0.25)
			(keepout
				(tracks allowed)
				(vias not_allowed)
				(pads allowed)
				(copperpour not_allowed)
				(footprints allowed)
			)
			(placement
				(enabled no)
				(sheetname "")
			)
			(fill
				(thermal_gap 0.5)
				(thermal_bridge_width 0.5)
				(island_removal_mode 0)
			)
			(polygon
				(pts
					(arc
						(start 224.981008 -39.99992)
						(mid 224.219008 -39.99992)
						(end 224.981008 -39.99992)
					)
				)
			)
		)
		(zone
			(layer "F.Cu")
			(hatch none 0.5)
			(connect_pads
				(clearance 0)
			)
			(min_thickness 0.25)
			(keepout
				(tracks allowed)
				(vias not_allowed)
				(pads allowed)
				(copperpour not_allowed)
				(footprints allowed)
			)
			(placement
				(enabled no)
				(sheetname "")
			)
			(fill
				(thermal_gap 0.5)
				(thermal_bridge_width 0.5)
				(island_removal_mode 0)
			)
			(polygon
				(pts
					(arc
						(start 224.981008 -38.999922)
						(mid 224.219008 -38.999922)
						(end 224.981008 -38.999922)
					)
				)
			)
		)
		(zone
			(layer "F.Cu")
			(hatch none 0.5)
			(connect_pads
				(clearance 0)
			)
			(min_thickness 0.25)
			(keepout
				(tracks allowed)
				(vias not_allowed)
				(pads allowed)
				(copperpour not_allowed)
				(footprints allowed)
			)
			(placement
				(enabled no)
				(sheetname "")
			)
			(fill
				(thermal_gap 0.5)
				(thermal_bridge_width 0.5)
				(island_removal_mode 0)
			)
			(polygon
				(pts
					(arc
						(start 224.981008 -37.999924)
						(mid 224.219008 -37.999924)
						(end 224.981008 -37.999924)
					)
				)
			)
		)
		(zone
			(layer "F.Cu")
			(hatch none 0.5)
			(connect_pads
				(clearance 0)
			)
			(min_thickness 0.25)
			(keepout
				(tracks allowed)
				(vias not_allowed)
				(pads allowed)
				(copperpour not_allowed)
				(footprints allowed)
			)
			(placement
				(enabled no)
				(sheetname "")
			)
			(fill
				(thermal_gap 0.5)
				(thermal_bridge_width 0.5)
				(island_removal_mode 0)
			)
			(polygon
				(pts
					(arc
						(start 224.981008 -36.999926)
						(mid 224.219008 -36.999926)
						(end 224.981008 -36.999926)
					)
				)
			)
		)
		(zone
			(layer "F.Cu")
			(hatch none 0.5)
			(connect_pads
				(clearance 0)
			)
			(min_thickness 0.25)
			(keepout
				(tracks allowed)
				(vias not_allowed)
				(pads allowed)
				(copperpour not_allowed)
				(footprints allowed)
			)
			(placement
				(enabled no)
				(sheetname "")
			)
			(fill
				(thermal_gap 0.5)
				(thermal_bridge_width 0.5)
				(island_removal_mode 0)
			)
			(polygon
				(pts
					(arc
						(start 224.981008 -35.999928)
						(mid 224.219008 -35.999928)
						(end 224.981008 -35.999928)
					)
				)
			)
		)
		(zone
			(layer "F.Cu")
			(hatch none 0.5)
			(connect_pads
				(clearance 0)
			)
			(min_thickness 0.25)
			(keepout
				(tracks allowed)
				(vias not_allowed)
				(pads allowed)
				(copperpour not_allowed)
				(footprints allowed)
			)
			(placement
				(enabled no)
				(sheetname "")
			)
			(fill
				(thermal_gap 0.5)
				(thermal_bridge_width 0.5)
				(island_removal_mode 0)
			)
			(polygon
				(pts
					(arc
						(start 224.981008 -34.99993)
						(mid 224.219008 -34.99993)
						(end 224.981008 -34.99993)
					)
				)
			)
		)
		(zone
			(layer "F.Cu")
			(hatch none 0.5)
			(connect_pads
				(clearance 0)
			)
			(min_thickness 0.25)
			(keepout
				(tracks allowed)
				(vias not_allowed)
				(pads allowed)
				(copperpour not_allowed)
				(footprints allowed)
			)
			(placement
				(enabled no)
				(sheetname "")
			)
			(fill
				(thermal_gap 0.5)
				(thermal_bridge_width 0.5)
				(island_removal_mode 0)
			)
			(polygon
				(pts
					(arc
						(start 224.981008 -33.999932)
						(mid 224.219008 -33.999932)
						(end 224.981008 -33.999932)
					)
				)
			)
		)
		(zone
			(layer "F.Cu")
			(hatch none 0.5)
			(connect_pads
				(clearance 0)
			)
			(min_thickness 0.25)
			(keepout
				(tracks allowed)
				(vias not_allowed)
				(pads allowed)
				(copperpour not_allowed)
				(footprints allowed)
			)
			(placement
				(enabled no)
				(sheetname "")
			)
			(fill
				(thermal_gap 0.5)
				(thermal_bridge_width 0.5)
				(island_removal_mode 0)
			)
			(polygon
				(pts
					(arc
						(start 224.981008 -32.999934)
						(mid 224.219008 -32.999934)
						(end 224.981008 -32.999934)
					)
				)
			)
		)
		(zone
			(layer "F.Cu")
			(hatch none 0.5)
			(connect_pads
				(clearance 0)
			)
			(min_thickness 0.25)
			(keepout
				(tracks allowed)
				(vias not_allowed)
				(pads allowed)
				(copperpour not_allowed)
				(footprints allowed)
			)
			(placement
				(enabled no)
				(sheetname "")
			)
			(fill
				(thermal_gap 0.5)
				(thermal_bridge_width 0.5)
				(island_removal_mode 0)
			)
			(polygon
				(pts
					(arc
						(start 225.981006 -65.999868)
						(mid 225.219006 -65.999868)
						(end 225.981006 -65.999868)
					)
				)
			)
		)
		(zone
			(layer "F.Cu")
			(hatch none 0.5)
			(connect_pads
				(clearance 0)
			)
			(min_thickness 0.25)
			(keepout
				(tracks allowed)
				(vias not_allowed)
				(pads allowed)
				(copperpour not_allowed)
				(footprints allowed)
			)
			(placement
				(enabled no)
				(sheetname "")
			)
			(fill
				(thermal_gap 0.5)
				(thermal_bridge_width 0.5)
				(island_removal_mode 0)
			)
			(polygon
				(pts
					(arc
						(start 225.981006 -64.99987)
						(mid 225.219006 -64.99987)
						(end 225.981006 -64.99987)
					)
				)
			)
		)
		(zone
			(layer "F.Cu")
			(hatch none 0.5)
			(connect_pads
				(clearance 0)
			)
			(min_thickness 0.25)
			(keepout
				(tracks allowed)
				(vias not_allowed)
				(pads allowed)
				(copperpour not_allowed)
				(footprints allowed)
			)
			(placement
				(enabled no)
				(sheetname "")
			)
			(fill
				(thermal_gap 0.5)
				(thermal_bridge_width 0.5)
				(island_removal_mode 0)
			)
			(polygon
				(pts
					(arc
						(start 225.981006 -63.999872)
						(mid 225.219006 -63.999872)
						(end 225.981006 -63.999872)
					)
				)
			)
		)
		(zone
			(layer "F.Cu")
			(hatch none 0.5)
			(connect_pads
				(clearance 0)
			)
			(min_thickness 0.25)
			(keepout
				(tracks allowed)
				(vias not_allowed)
				(pads allowed)
				(copperpour not_allowed)
				(footprints allowed)
			)
			(placement
				(enabled no)
				(sheetname "")
			)
			(fill
				(thermal_gap 0.5)
				(thermal_bridge_width 0.5)
				(island_removal_mode 0)
			)
			(polygon
				(pts
					(arc
						(start 225.981006 -62.999874)
						(mid 225.219006 -62.999874)
						(end 225.981006 -62.999874)
					)
				)
			)
		)
		(zone
			(layer "F.Cu")
			(hatch none 0.5)
			(connect_pads
				(clearance 0)
			)
			(min_thickness 0.25)
			(keepout
				(tracks allowed)
				(vias not_allowed)
				(pads allowed)
				(copperpour not_allowed)
				(footprints allowed)
			)
			(placement
				(enabled no)
				(sheetname "")
			)
			(fill
				(thermal_gap 0.5)
				(thermal_bridge_width 0.5)
				(island_removal_mode 0)
			)
			(polygon
				(pts
					(arc
						(start 225.981006 -61.999876)
						(mid 225.219006 -61.999876)
						(end 225.981006 -61.999876)
					)
				)
			)
		)
		(zone
			(layer "F.Cu")
			(hatch none 0.5)
			(connect_pads
				(clearance 0)
			)
			(min_thickness 0.25)
			(keepout
				(tracks allowed)
				(vias not_allowed)
				(pads allowed)
				(copperpour not_allowed)
				(footprints allowed)
			)
			(placement
				(enabled no)
				(sheetname "")
			)
			(fill
				(thermal_gap 0.5)
				(thermal_bridge_width 0.5)
				(island_removal_mode 0)
			)
			(polygon
				(pts
					(arc
						(start 225.981006 -60.999878)
						(mid 225.219006 -60.999878)
						(end 225.981006 -60.999878)
					)
				)
			)
		)
		(zone
			(layer "F.Cu")
			(hatch none 0.5)
			(connect_pads
				(clearance 0)
			)
			(min_thickness 0.25)
			(keepout
				(tracks allowed)
				(vias not_allowed)
				(pads allowed)
				(copperpour not_allowed)
				(footprints allowed)
			)
			(placement
				(enabled no)
				(sheetname "")
			)
			(fill
				(thermal_gap 0.5)
				(thermal_bridge_width 0.5)
				(island_removal_mode 0)
			)
			(polygon
				(pts
					(arc
						(start 225.981006 -59.99988)
						(mid 225.219006 -59.99988)
						(end 225.981006 -59.99988)
					)
				)
			)
		)
		(zone
			(layer "F.Cu")
			(hatch none 0.5)
			(connect_pads
				(clearance 0)
			)
			(min_thickness 0.25)
			(keepout
				(tracks allowed)
				(vias not_allowed)
				(pads allowed)
				(copperpour not_allowed)
				(footprints allowed)
			)
			(placement
				(enabled no)
				(sheetname "")
			)
			(fill
				(thermal_gap 0.5)
				(thermal_bridge_width 0.5)
				(island_removal_mode 0)
			)
			(polygon
				(pts
					(arc
						(start 225.981006 -58.999882)
						(mid 225.219006 -58.999882)
						(end 225.981006 -58.999882)
					)
				)
			)
		)
		(zone
			(layer "F.Cu")
			(hatch none 0.5)
			(connect_pads
				(clearance 0)
			)
			(min_thickness 0.25)
			(keepout
				(tracks allowed)
				(vias not_allowed)
				(pads allowed)
				(copperpour not_allowed)
				(footprints allowed)
			)
			(placement
				(enabled no)
				(sheetname "")
			)
			(fill
				(thermal_gap 0.5)
				(thermal_bridge_width 0.5)
				(island_removal_mode 0)
			)
			(polygon
				(pts
					(arc
						(start 225.981006 -57.999884)
						(mid 225.219006 -57.999884)
						(end 225.981006 -57.999884)
					)
				)
			)
		)
		(zone
			(layer "F.Cu")
			(hatch none 0.5)
			(connect_pads
				(clearance 0)
			)
			(min_thickness 0.25)
			(keepout
				(tracks allowed)
				(vias not_allowed)
				(pads allowed)
				(copperpour not_allowed)
				(footprints allowed)
			)
			(placement
				(enabled no)
				(sheetname "")
			)
			(fill
				(thermal_gap 0.5)
				(thermal_bridge_width 0.5)
				(island_removal_mode 0)
			)
			(polygon
				(pts
					(arc
						(start 225.981006 -56.999886)
						(mid 225.219006 -56.999886)
						(end 225.981006 -56.999886)
					)
				)
			)
		)
		(zone
			(layer "F.Cu")
			(hatch none 0.5)
			(connect_pads
				(clearance 0)
			)
			(min_thickness 0.25)
			(keepout
				(tracks allowed)
				(vias not_allowed)
				(pads allowed)
				(copperpour not_allowed)
				(footprints allowed)
			)
			(placement
				(enabled no)
				(sheetname "")
			)
			(fill
				(thermal_gap 0.5)
				(thermal_bridge_width 0.5)
				(island_removal_mode 0)
			)
			(polygon
				(pts
					(arc
						(start 225.981006 -55.999888)
						(mid 225.219006 -55.999888)
						(end 225.981006 -55.999888)
					)
				)
			)
		)
		(zone
			(layer "F.Cu")
			(hatch none 0.5)
			(connect_pads
				(clearance 0)
			)
			(min_thickness 0.25)
			(keepout
				(tracks allowed)
				(vias not_allowed)
				(pads allowed)
				(copperpour not_allowed)
				(footprints allowed)
			)
			(placement
				(enabled no)
				(sheetname "")
			)
			(fill
				(thermal_gap 0.5)
				(thermal_bridge_width 0.5)
				(island_removal_mode 0)
			)
			(polygon
				(pts
					(arc
						(start 225.981006 -54.99989)
						(mid 225.219006 -54.99989)
						(end 225.981006 -54.99989)
					)
				)
			)
		)
		(zone
			(layer "F.Cu")
			(hatch none 0.5)
			(connect_pads
				(clearance 0)
			)
			(min_thickness 0.25)
			(keepout
				(tracks allowed)
				(vias not_allowed)
				(pads allowed)
				(copperpour not_allowed)
				(footprints allowed)
			)
			(placement
				(enabled no)
				(sheetname "")
			)
			(fill
				(thermal_gap 0.5)
				(thermal_bridge_width 0.5)
				(island_removal_mode 0)
			)
			(polygon
				(pts
					(arc
						(start 225.981006 -53.999892)
						(mid 225.219006 -53.999892)
						(end 225.981006 -53.999892)
					)
				)
			)
		)
		(zone
			(layer "F.Cu")
			(hatch none 0.5)
			(connect_pads
				(clearance 0)
			)
			(min_thickness 0.25)
			(keepout
				(tracks allowed)
				(vias not_allowed)
				(pads allowed)
				(copperpour not_allowed)
				(footprints allowed)
			)
			(placement
				(enabled no)
				(sheetname "")
			)
			(fill
				(thermal_gap 0.5)
				(thermal_bridge_width 0.5)
				(island_removal_mode 0)
			)
			(polygon
				(pts
					(arc
						(start 225.981006 -52.999894)
						(mid 225.219006 -52.999894)
						(end 225.981006 -52.999894)
					)
				)
			)
		)
		(zone
			(layer "F.Cu")
			(hatch none 0.5)
			(connect_pads
				(clearance 0)
			)
			(min_thickness 0.25)
			(keepout
				(tracks allowed)
				(vias not_allowed)
				(pads allowed)
				(copperpour not_allowed)
				(footprints allowed)
			)
			(placement
				(enabled no)
				(sheetname "")
			)
			(fill
				(thermal_gap 0.5)
				(thermal_bridge_width 0.5)
				(island_removal_mode 0)
			)
			(polygon
				(pts
					(arc
						(start 225.981006 -51.999896)
						(mid 225.219006 -51.999896)
						(end 225.981006 -51.999896)
					)
				)
			)
		)
		(zone
			(layer "F.Cu")
			(hatch none 0.5)
			(connect_pads
				(clearance 0)
			)
			(min_thickness 0.25)
			(keepout
				(tracks allowed)
				(vias not_allowed)
				(pads allowed)
				(copperpour not_allowed)
				(footprints allowed)
			)
			(placement
				(enabled no)
				(sheetname "")
			)
			(fill
				(thermal_gap 0.5)
				(thermal_bridge_width 0.5)
				(island_removal_mode 0)
			)
			(polygon
				(pts
					(arc
						(start 225.981006 -50.999898)
						(mid 225.219006 -50.999898)
						(end 225.981006 -50.999898)
					)
				)
			)
		)
		(zone
			(layer "F.Cu")
			(hatch none 0.5)
			(connect_pads
				(clearance 0)
			)
			(min_thickness 0.25)
			(keepout
				(tracks allowed)
				(vias not_allowed)
				(pads allowed)
				(copperpour not_allowed)
				(footprints allowed)
			)
			(placement
				(enabled no)
				(sheetname "")
			)
			(fill
				(thermal_gap 0.5)
				(thermal_bridge_width 0.5)
				(island_removal_mode 0)
			)
			(polygon
				(pts
					(arc
						(start 225.981006 -49.9999)
						(mid 225.219006 -49.9999)
						(end 225.981006 -49.9999)
					)
				)
			)
		)
		(zone
			(layer "F.Cu")
			(hatch none 0.5)
			(connect_pads
				(clearance 0)
			)
			(min_thickness 0.25)
			(keepout
				(tracks allowed)
				(vias not_allowed)
				(pads allowed)
				(copperpour not_allowed)
				(footprints allowed)
			)
			(placement
				(enabled no)
				(sheetname "")
			)
			(fill
				(thermal_gap 0.5)
				(thermal_bridge_width 0.5)
				(island_removal_mode 0)
			)
			(polygon
				(pts
					(arc
						(start 225.981006 -48.999902)
						(mid 225.219006 -48.999902)
						(end 225.981006 -48.999902)
					)
				)
			)
		)
		(zone
			(layer "F.Cu")
			(hatch none 0.5)
			(connect_pads
				(clearance 0)
			)
			(min_thickness 0.25)
			(keepout
				(tracks allowed)
				(vias not_allowed)
				(pads allowed)
				(copperpour not_allowed)
				(footprints allowed)
			)
			(placement
				(enabled no)
				(sheetname "")
			)
			(fill
				(thermal_gap 0.5)
				(thermal_bridge_width 0.5)
				(island_removal_mode 0)
			)
			(polygon
				(pts
					(arc
						(start 225.981006 -47.999904)
						(mid 225.219006 -47.999904)
						(end 225.981006 -47.999904)
					)
				)
			)
		)
		(zone
			(layer "F.Cu")
			(hatch none 0.5)
			(connect_pads
				(clearance 0)
			)
			(min_thickness 0.25)
			(keepout
				(tracks allowed)
				(vias not_allowed)
				(pads allowed)
				(copperpour not_allowed)
				(footprints allowed)
			)
			(placement
				(enabled no)
				(sheetname "")
			)
			(fill
				(thermal_gap 0.5)
				(thermal_bridge_width 0.5)
				(island_removal_mode 0)
			)
			(polygon
				(pts
					(arc
						(start 225.981006 -46.999906)
						(mid 225.219006 -46.999906)
						(end 225.981006 -46.999906)
					)
				)
			)
		)
		(zone
			(layer "F.Cu")
			(hatch none 0.5)
			(connect_pads
				(clearance 0)
			)
			(min_thickness 0.25)
			(keepout
				(tracks allowed)
				(vias not_allowed)
				(pads allowed)
				(copperpour not_allowed)
				(footprints allowed)
			)
			(placement
				(enabled no)
				(sheetname "")
			)
			(fill
				(thermal_gap 0.5)
				(thermal_bridge_width 0.5)
				(island_removal_mode 0)
			)
			(polygon
				(pts
					(arc
						(start 225.981006 -45.999908)
						(mid 225.219006 -45.999908)
						(end 225.981006 -45.999908)
					)
				)
			)
		)
		(zone
			(layer "F.Cu")
			(hatch none 0.5)
			(connect_pads
				(clearance 0)
			)
			(min_thickness 0.25)
			(keepout
				(tracks allowed)
				(vias not_allowed)
				(pads allowed)
				(copperpour not_allowed)
				(footprints allowed)
			)
			(placement
				(enabled no)
				(sheetname "")
			)
			(fill
				(thermal_gap 0.5)
				(thermal_bridge_width 0.5)
				(island_removal_mode 0)
			)
			(polygon
				(pts
					(arc
						(start 225.981006 -44.99991)
						(mid 225.219006 -44.99991)
						(end 225.981006 -44.99991)
					)
				)
			)
		)
		(zone
			(layer "F.Cu")
			(hatch none 0.5)
			(connect_pads
				(clearance 0)
			)
			(min_thickness 0.25)
			(keepout
				(tracks allowed)
				(vias not_allowed)
				(pads allowed)
				(copperpour not_allowed)
				(footprints allowed)
			)
			(placement
				(enabled no)
				(sheetname "")
			)
			(fill
				(thermal_gap 0.5)
				(thermal_bridge_width 0.5)
				(island_removal_mode 0)
			)
			(polygon
				(pts
					(arc
						(start 225.981006 -43.999912)
						(mid 225.219006 -43.999912)
						(end 225.981006 -43.999912)
					)
				)
			)
		)
		(zone
			(layer "F.Cu")
			(hatch none 0.5)
			(connect_pads
				(clearance 0)
			)
			(min_thickness 0.25)
			(keepout
				(tracks allowed)
				(vias not_allowed)
				(pads allowed)
				(copperpour not_allowed)
				(footprints allowed)
			)
			(placement
				(enabled no)
				(sheetname "")
			)
			(fill
				(thermal_gap 0.5)
				(thermal_bridge_width 0.5)
				(island_removal_mode 0)
			)
			(polygon
				(pts
					(arc
						(start 225.981006 -42.999914)
						(mid 225.219006 -42.999914)
						(end 225.981006 -42.999914)
					)
				)
			)
		)
		(zone
			(layer "F.Cu")
			(hatch none 0.5)
			(connect_pads
				(clearance 0)
			)
			(min_thickness 0.25)
			(keepout
				(tracks allowed)
				(vias not_allowed)
				(pads allowed)
				(copperpour not_allowed)
				(footprints allowed)
			)
			(placement
				(enabled no)
				(sheetname "")
			)
			(fill
				(thermal_gap 0.5)
				(thermal_bridge_width 0.5)
				(island_removal_mode 0)
			)
			(polygon
				(pts
					(arc
						(start 225.981006 -41.999916)
						(mid 225.219006 -41.999916)
						(end 225.981006 -41.999916)
					)
				)
			)
		)
		(zone
			(layer "F.Cu")
			(hatch none 0.5)
			(connect_pads
				(clearance 0)
			)
			(min_thickness 0.25)
			(keepout
				(tracks allowed)
				(vias not_allowed)
				(pads allowed)
				(copperpour not_allowed)
				(footprints allowed)
			)
			(placement
				(enabled no)
				(sheetname "")
			)
			(fill
				(thermal_gap 0.5)
				(thermal_bridge_width 0.5)
				(island_removal_mode 0)
			)
			(polygon
				(pts
					(arc
						(start 225.981006 -40.999918)
						(mid 225.219006 -40.999918)
						(end 225.981006 -40.999918)
					)
				)
			)
		)
		(zone
			(layer "F.Cu")
			(hatch none 0.5)
			(connect_pads
				(clearance 0)
			)
			(min_thickness 0.25)
			(keepout
				(tracks allowed)
				(vias not_allowed)
				(pads allowed)
				(copperpour not_allowed)
				(footprints allowed)
			)
			(placement
				(enabled no)
				(sheetname "")
			)
			(fill
				(thermal_gap 0.5)
				(thermal_bridge_width 0.5)
				(island_removal_mode 0)
			)
			(polygon
				(pts
					(arc
						(start 225.981006 -39.99992)
						(mid 225.219006 -39.99992)
						(end 225.981006 -39.99992)
					)
				)
			)
		)
		(zone
			(layer "F.Cu")
			(hatch none 0.5)
			(connect_pads
				(clearance 0)
			)
			(min_thickness 0.25)
			(keepout
				(tracks allowed)
				(vias not_allowed)
				(pads allowed)
				(copperpour not_allowed)
				(footprints allowed)
			)
			(placement
				(enabled no)
				(sheetname "")
			)
			(fill
				(thermal_gap 0.5)
				(thermal_bridge_width 0.5)
				(island_removal_mode 0)
			)
			(polygon
				(pts
					(arc
						(start 225.981006 -38.999922)
						(mid 225.219006 -38.999922)
						(end 225.981006 -38.999922)
					)
				)
			)
		)
		(zone
			(layer "F.Cu")
			(hatch none 0.5)
			(connect_pads
				(clearance 0)
			)
			(min_thickness 0.25)
			(keepout
				(tracks allowed)
				(vias not_allowed)
				(pads allowed)
				(copperpour not_allowed)
				(footprints allowed)
			)
			(placement
				(enabled no)
				(sheetname "")
			)
			(fill
				(thermal_gap 0.5)
				(thermal_bridge_width 0.5)
				(island_removal_mode 0)
			)
			(polygon
				(pts
					(arc
						(start 225.981006 -37.999924)
						(mid 225.219006 -37.999924)
						(end 225.981006 -37.999924)
					)
				)
			)
		)
		(zone
			(layer "F.Cu")
			(hatch none 0.5)
			(connect_pads
				(clearance 0)
			)
			(min_thickness 0.25)
			(keepout
				(tracks allowed)
				(vias not_allowed)
				(pads allowed)
				(copperpour not_allowed)
				(footprints allowed)
			)
			(placement
				(enabled no)
				(sheetname "")
			)
			(fill
				(thermal_gap 0.5)
				(thermal_bridge_width 0.5)
				(island_removal_mode 0)
			)
			(polygon
				(pts
					(arc
						(start 225.981006 -36.999926)
						(mid 225.219006 -36.999926)
						(end 225.981006 -36.999926)
					)
				)
			)
		)
		(zone
			(layer "F.Cu")
			(hatch none 0.5)
			(connect_pads
				(clearance 0)
			)
			(min_thickness 0.25)
			(keepout
				(tracks allowed)
				(vias not_allowed)
				(pads allowed)
				(copperpour not_allowed)
				(footprints allowed)
			)
			(placement
				(enabled no)
				(sheetname "")
			)
			(fill
				(thermal_gap 0.5)
				(thermal_bridge_width 0.5)
				(island_removal_mode 0)
			)
			(polygon
				(pts
					(arc
						(start 225.981006 -35.999928)
						(mid 225.219006 -35.999928)
						(end 225.981006 -35.999928)
					)
				)
			)
		)
		(zone
			(layer "F.Cu")
			(hatch none 0.5)
			(connect_pads
				(clearance 0)
			)
			(min_thickness 0.25)
			(keepout
				(tracks allowed)
				(vias not_allowed)
				(pads allowed)
				(copperpour not_allowed)
				(footprints allowed)
			)
			(placement
				(enabled no)
				(sheetname "")
			)
			(fill
				(thermal_gap 0.5)
				(thermal_bridge_width 0.5)
				(island_removal_mode 0)
			)
			(polygon
				(pts
					(arc
						(start 225.981006 -34.99993)
						(mid 225.219006 -34.99993)
						(end 225.981006 -34.99993)
					)
				)
			)
		)
		(zone
			(layer "F.Cu")
			(hatch none 0.5)
			(connect_pads
				(clearance 0)
			)
			(min_thickness 0.25)
			(keepout
				(tracks allowed)
				(vias not_allowed)
				(pads allowed)
				(copperpour not_allowed)
				(footprints allowed)
			)
			(placement
				(enabled no)
				(sheetname "")
			)
			(fill
				(thermal_gap 0.5)
				(thermal_bridge_width 0.5)
				(island_removal_mode 0)
			)
			(polygon
				(pts
					(arc
						(start 225.981006 -33.999932)
						(mid 225.219006 -33.999932)
						(end 225.981006 -33.999932)
					)
				)
			)
		)
		(zone
			(layer "F.Cu")
			(hatch none 0.5)
			(connect_pads
				(clearance 0)
			)
			(min_thickness 0.25)
			(keepout
				(tracks allowed)
				(vias not_allowed)
				(pads allowed)
				(copperpour not_allowed)
				(footprints allowed)
			)
			(placement
				(enabled no)
				(sheetname "")
			)
			(fill
				(thermal_gap 0.5)
				(thermal_bridge_width 0.5)
				(island_removal_mode 0)
			)
			(polygon
				(pts
					(arc
						(start 225.981006 -32.999934)
						(mid 225.219006 -32.999934)
						(end 225.981006 -32.999934)
					)
				)
			)
		)
		(zone
			(layer "F.Cu")
			(hatch none 0.5)
			(connect_pads
				(clearance 0)
			)
			(min_thickness 0.25)
			(keepout
				(tracks allowed)
				(vias not_allowed)
				(pads allowed)
				(copperpour not_allowed)
				(footprints allowed)
			)
			(placement
				(enabled no)
				(sheetname "")
			)
			(fill
				(thermal_gap 0.5)
				(thermal_bridge_width 0.5)
				(island_removal_mode 0)
			)
			(polygon
				(pts
					(arc
						(start 225.981006 -31.999936)
						(mid 225.219006 -31.999936)
						(end 225.981006 -31.999936)
					)
				)
			)
		)
		(zone
			(layer "F.Cu")
			(hatch none 0.5)
			(connect_pads
				(clearance 0)
			)
			(min_thickness 0.25)
			(keepout
				(tracks allowed)
				(vias not_allowed)
				(pads allowed)
				(copperpour not_allowed)
				(footprints allowed)
			)
			(placement
				(enabled no)
				(sheetname "")
			)
			(fill
				(thermal_gap 0.5)
				(thermal_bridge_width 0.5)
				(island_removal_mode 0)
			)
			(polygon
				(pts
					(arc
						(start 225.981006 -30.999938)
						(mid 225.219006 -30.999938)
						(end 225.981006 -30.999938)
					)
				)
			)
		)
		(zone
			(layer "F.Cu")
			(hatch none 0.5)
			(connect_pads
				(clearance 0)
			)
			(min_thickness 0.25)
			(keepout
				(tracks allowed)
				(vias not_allowed)
				(pads allowed)
				(copperpour not_allowed)
				(footprints allowed)
			)
			(placement
				(enabled no)
				(sheetname "")
			)
			(fill
				(thermal_gap 0.5)
				(thermal_bridge_width 0.5)
				(island_removal_mode 0)
			)
			(polygon
				(pts
					(arc
						(start 225.981006 -29.99994)
						(mid 225.219006 -29.99994)
						(end 225.981006 -29.99994)
					)
				)
			)
		)
		(zone
			(layer "F.Cu")
			(hatch none 0.5)
			(connect_pads
				(clearance 0)
			)
			(min_thickness 0.25)
			(keepout
				(tracks allowed)
				(vias not_allowed)
				(pads allowed)
				(copperpour not_allowed)
				(footprints allowed)
			)
			(placement
				(enabled no)
				(sheetname "")
			)
			(fill
				(thermal_gap 0.5)
				(thermal_bridge_width 0.5)
				(island_removal_mode 0)
			)
			(polygon
				(pts
					(arc
						(start 226.981004 -64.99987)
						(mid 226.219004 -64.99987)
						(end 226.981004 -64.99987)
					)
				)
			)
		)
		(zone
			(layer "F.Cu")
			(hatch none 0.5)
			(connect_pads
				(clearance 0)
			)
			(min_thickness 0.25)
			(keepout
				(tracks allowed)
				(vias not_allowed)
				(pads allowed)
				(copperpour not_allowed)
				(footprints allowed)
			)
			(placement
				(enabled no)
				(sheetname "")
			)
			(fill
				(thermal_gap 0.5)
				(thermal_bridge_width 0.5)
				(island_removal_mode 0)
			)
			(polygon
				(pts
					(arc
						(start 226.981004 -63.999872)
						(mid 226.219004 -63.999872)
						(end 226.981004 -63.999872)
					)
				)
			)
		)
		(zone
			(layer "F.Cu")
			(hatch none 0.5)
			(connect_pads
				(clearance 0)
			)
			(min_thickness 0.25)
			(keepout
				(tracks allowed)
				(vias not_allowed)
				(pads allowed)
				(copperpour not_allowed)
				(footprints allowed)
			)
			(placement
				(enabled no)
				(sheetname "")
			)
			(fill
				(thermal_gap 0.5)
				(thermal_bridge_width 0.5)
				(island_removal_mode 0)
			)
			(polygon
				(pts
					(arc
						(start 226.981004 -62.999874)
						(mid 226.219004 -62.999874)
						(end 226.981004 -62.999874)
					)
				)
			)
		)
		(zone
			(layer "F.Cu")
			(hatch none 0.5)
			(connect_pads
				(clearance 0)
			)
			(min_thickness 0.25)
			(keepout
				(tracks allowed)
				(vias not_allowed)
				(pads allowed)
				(copperpour not_allowed)
				(footprints allowed)
			)
			(placement
				(enabled no)
				(sheetname "")
			)
			(fill
				(thermal_gap 0.5)
				(thermal_bridge_width 0.5)
				(island_removal_mode 0)
			)
			(polygon
				(pts
					(arc
						(start 226.981004 -61.999876)
						(mid 226.219004 -61.999876)
						(end 226.981004 -61.999876)
					)
				)
			)
		)
		(zone
			(layer "F.Cu")
			(hatch none 0.5)
			(connect_pads
				(clearance 0)
			)
			(min_thickness 0.25)
			(keepout
				(tracks allowed)
				(vias not_allowed)
				(pads allowed)
				(copperpour not_allowed)
				(footprints allowed)
			)
			(placement
				(enabled no)
				(sheetname "")
			)
			(fill
				(thermal_gap 0.5)
				(thermal_bridge_width 0.5)
				(island_removal_mode 0)
			)
			(polygon
				(pts
					(arc
						(start 226.981004 -60.999878)
						(mid 226.219004 -60.999878)
						(end 226.981004 -60.999878)
					)
				)
			)
		)
		(zone
			(layer "F.Cu")
			(hatch none 0.5)
			(connect_pads
				(clearance 0)
			)
			(min_thickness 0.25)
			(keepout
				(tracks allowed)
				(vias not_allowed)
				(pads allowed)
				(copperpour not_allowed)
				(footprints allowed)
			)
			(placement
				(enabled no)
				(sheetname "")
			)
			(fill
				(thermal_gap 0.5)
				(thermal_bridge_width 0.5)
				(island_removal_mode 0)
			)
			(polygon
				(pts
					(arc
						(start 226.981004 -59.99988)
						(mid 226.219004 -59.99988)
						(end 226.981004 -59.99988)
					)
				)
			)
		)
		(zone
			(layer "F.Cu")
			(hatch none 0.5)
			(connect_pads
				(clearance 0)
			)
			(min_thickness 0.25)
			(keepout
				(tracks allowed)
				(vias not_allowed)
				(pads allowed)
				(copperpour not_allowed)
				(footprints allowed)
			)
			(placement
				(enabled no)
				(sheetname "")
			)
			(fill
				(thermal_gap 0.5)
				(thermal_bridge_width 0.5)
				(island_removal_mode 0)
			)
			(polygon
				(pts
					(arc
						(start 226.981004 -58.999882)
						(mid 226.219004 -58.999882)
						(end 226.981004 -58.999882)
					)
				)
			)
		)
		(zone
			(layer "F.Cu")
			(hatch none 0.5)
			(connect_pads
				(clearance 0)
			)
			(min_thickness 0.25)
			(keepout
				(tracks allowed)
				(vias not_allowed)
				(pads allowed)
				(copperpour not_allowed)
				(footprints allowed)
			)
			(placement
				(enabled no)
				(sheetname "")
			)
			(fill
				(thermal_gap 0.5)
				(thermal_bridge_width 0.5)
				(island_removal_mode 0)
			)
			(polygon
				(pts
					(arc
						(start 226.981004 -57.999884)
						(mid 226.219004 -57.999884)
						(end 226.981004 -57.999884)
					)
				)
			)
		)
		(zone
			(layer "F.Cu")
			(hatch none 0.5)
			(connect_pads
				(clearance 0)
			)
			(min_thickness 0.25)
			(keepout
				(tracks allowed)
				(vias not_allowed)
				(pads allowed)
				(copperpour not_allowed)
				(footprints allowed)
			)
			(placement
				(enabled no)
				(sheetname "")
			)
			(fill
				(thermal_gap 0.5)
				(thermal_bridge_width 0.5)
				(island_removal_mode 0)
			)
			(polygon
				(pts
					(arc
						(start 226.981004 -56.999886)
						(mid 226.219004 -56.999886)
						(end 226.981004 -56.999886)
					)
				)
			)
		)
		(zone
			(layer "F.Cu")
			(hatch none 0.5)
			(connect_pads
				(clearance 0)
			)
			(min_thickness 0.25)
			(keepout
				(tracks allowed)
				(vias not_allowed)
				(pads allowed)
				(copperpour not_allowed)
				(footprints allowed)
			)
			(placement
				(enabled no)
				(sheetname "")
			)
			(fill
				(thermal_gap 0.5)
				(thermal_bridge_width 0.5)
				(island_removal_mode 0)
			)
			(polygon
				(pts
					(arc
						(start 226.981004 -55.999888)
						(mid 226.219004 -55.999888)
						(end 226.981004 -55.999888)
					)
				)
			)
		)
		(zone
			(layer "F.Cu")
			(hatch none 0.5)
			(connect_pads
				(clearance 0)
			)
			(min_thickness 0.25)
			(keepout
				(tracks allowed)
				(vias not_allowed)
				(pads allowed)
				(copperpour not_allowed)
				(footprints allowed)
			)
			(placement
				(enabled no)
				(sheetname "")
			)
			(fill
				(thermal_gap 0.5)
				(thermal_bridge_width 0.5)
				(island_removal_mode 0)
			)
			(polygon
				(pts
					(arc
						(start 226.981004 -54.99989)
						(mid 226.219004 -54.99989)
						(end 226.981004 -54.99989)
					)
				)
			)
		)
		(zone
			(layer "F.Cu")
			(hatch none 0.5)
			(connect_pads
				(clearance 0)
			)
			(min_thickness 0.25)
			(keepout
				(tracks allowed)
				(vias not_allowed)
				(pads allowed)
				(copperpour not_allowed)
				(footprints allowed)
			)
			(placement
				(enabled no)
				(sheetname "")
			)
			(fill
				(thermal_gap 0.5)
				(thermal_bridge_width 0.5)
				(island_removal_mode 0)
			)
			(polygon
				(pts
					(arc
						(start 226.981004 -53.999892)
						(mid 226.219004 -53.999892)
						(end 226.981004 -53.999892)
					)
				)
			)
		)
		(zone
			(layer "F.Cu")
			(hatch none 0.5)
			(connect_pads
				(clearance 0)
			)
			(min_thickness 0.25)
			(keepout
				(tracks allowed)
				(vias not_allowed)
				(pads allowed)
				(copperpour not_allowed)
				(footprints allowed)
			)
			(placement
				(enabled no)
				(sheetname "")
			)
			(fill
				(thermal_gap 0.5)
				(thermal_bridge_width 0.5)
				(island_removal_mode 0)
			)
			(polygon
				(pts
					(arc
						(start 226.981004 -52.999894)
						(mid 226.219004 -52.999894)
						(end 226.981004 -52.999894)
					)
				)
			)
		)
		(zone
			(layer "F.Cu")
			(hatch none 0.5)
			(connect_pads
				(clearance 0)
			)
			(min_thickness 0.25)
			(keepout
				(tracks allowed)
				(vias not_allowed)
				(pads allowed)
				(copperpour not_allowed)
				(footprints allowed)
			)
			(placement
				(enabled no)
				(sheetname "")
			)
			(fill
				(thermal_gap 0.5)
				(thermal_bridge_width 0.5)
				(island_removal_mode 0)
			)
			(polygon
				(pts
					(arc
						(start 226.981004 -51.999896)
						(mid 226.219004 -51.999896)
						(end 226.981004 -51.999896)
					)
				)
			)
		)
		(zone
			(layer "F.Cu")
			(hatch none 0.5)
			(connect_pads
				(clearance 0)
			)
			(min_thickness 0.25)
			(keepout
				(tracks allowed)
				(vias not_allowed)
				(pads allowed)
				(copperpour not_allowed)
				(footprints allowed)
			)
			(placement
				(enabled no)
				(sheetname "")
			)
			(fill
				(thermal_gap 0.5)
				(thermal_bridge_width 0.5)
				(island_removal_mode 0)
			)
			(polygon
				(pts
					(arc
						(start 226.981004 -50.999898)
						(mid 226.219004 -50.999898)
						(end 226.981004 -50.999898)
					)
				)
			)
		)
		(zone
			(layer "F.Cu")
			(hatch none 0.5)
			(connect_pads
				(clearance 0)
			)
			(min_thickness 0.25)
			(keepout
				(tracks allowed)
				(vias not_allowed)
				(pads allowed)
				(copperpour not_allowed)
				(footprints allowed)
			)
			(placement
				(enabled no)
				(sheetname "")
			)
			(fill
				(thermal_gap 0.5)
				(thermal_bridge_width 0.5)
				(island_removal_mode 0)
			)
			(polygon
				(pts
					(arc
						(start 226.981004 -49.9999)
						(mid 226.219004 -49.9999)
						(end 226.981004 -49.9999)
					)
				)
			)
		)
		(zone
			(layer "F.Cu")
			(hatch none 0.5)
			(connect_pads
				(clearance 0)
			)
			(min_thickness 0.25)
			(keepout
				(tracks allowed)
				(vias not_allowed)
				(pads allowed)
				(copperpour not_allowed)
				(footprints allowed)
			)
			(placement
				(enabled no)
				(sheetname "")
			)
			(fill
				(thermal_gap 0.5)
				(thermal_bridge_width 0.5)
				(island_removal_mode 0)
			)
			(polygon
				(pts
					(arc
						(start 226.981004 -48.999902)
						(mid 226.219004 -48.999902)
						(end 226.981004 -48.999902)
					)
				)
			)
		)
		(zone
			(layer "F.Cu")
			(hatch none 0.5)
			(connect_pads
				(clearance 0)
			)
			(min_thickness 0.25)
			(keepout
				(tracks allowed)
				(vias not_allowed)
				(pads allowed)
				(copperpour not_allowed)
				(footprints allowed)
			)
			(placement
				(enabled no)
				(sheetname "")
			)
			(fill
				(thermal_gap 0.5)
				(thermal_bridge_width 0.5)
				(island_removal_mode 0)
			)
			(polygon
				(pts
					(arc
						(start 226.981004 -47.999904)
						(mid 226.219004 -47.999904)
						(end 226.981004 -47.999904)
					)
				)
			)
		)
		(zone
			(layer "F.Cu")
			(hatch none 0.5)
			(connect_pads
				(clearance 0)
			)
			(min_thickness 0.25)
			(keepout
				(tracks allowed)
				(vias not_allowed)
				(pads allowed)
				(copperpour not_allowed)
				(footprints allowed)
			)
			(placement
				(enabled no)
				(sheetname "")
			)
			(fill
				(thermal_gap 0.5)
				(thermal_bridge_width 0.5)
				(island_removal_mode 0)
			)
			(polygon
				(pts
					(arc
						(start 226.981004 -46.999906)
						(mid 226.219004 -46.999906)
						(end 226.981004 -46.999906)
					)
				)
			)
		)
		(zone
			(layer "F.Cu")
			(hatch none 0.5)
			(connect_pads
				(clearance 0)
			)
			(min_thickness 0.25)
			(keepout
				(tracks allowed)
				(vias not_allowed)
				(pads allowed)
				(copperpour not_allowed)
				(footprints allowed)
			)
			(placement
				(enabled no)
				(sheetname "")
			)
			(fill
				(thermal_gap 0.5)
				(thermal_bridge_width 0.5)
				(island_removal_mode 0)
			)
			(polygon
				(pts
					(arc
						(start 226.981004 -45.999908)
						(mid 226.219004 -45.999908)
						(end 226.981004 -45.999908)
					)
				)
			)
		)
		(zone
			(layer "F.Cu")
			(hatch none 0.5)
			(connect_pads
				(clearance 0)
			)
			(min_thickness 0.25)
			(keepout
				(tracks allowed)
				(vias not_allowed)
				(pads allowed)
				(copperpour not_allowed)
				(footprints allowed)
			)
			(placement
				(enabled no)
				(sheetname "")
			)
			(fill
				(thermal_gap 0.5)
				(thermal_bridge_width 0.5)
				(island_removal_mode 0)
			)
			(polygon
				(pts
					(arc
						(start 226.981004 -44.99991)
						(mid 226.219004 -44.99991)
						(end 226.981004 -44.99991)
					)
				)
			)
		)
		(zone
			(layer "F.Cu")
			(hatch none 0.5)
			(connect_pads
				(clearance 0)
			)
			(min_thickness 0.25)
			(keepout
				(tracks allowed)
				(vias not_allowed)
				(pads allowed)
				(copperpour not_allowed)
				(footprints allowed)
			)
			(placement
				(enabled no)
				(sheetname "")
			)
			(fill
				(thermal_gap 0.5)
				(thermal_bridge_width 0.5)
				(island_removal_mode 0)
			)
			(polygon
				(pts
					(arc
						(start 226.981004 -43.999912)
						(mid 226.219004 -43.999912)
						(end 226.981004 -43.999912)
					)
				)
			)
		)
		(zone
			(layer "F.Cu")
			(hatch none 0.5)
			(connect_pads
				(clearance 0)
			)
			(min_thickness 0.25)
			(keepout
				(tracks allowed)
				(vias not_allowed)
				(pads allowed)
				(copperpour not_allowed)
				(footprints allowed)
			)
			(placement
				(enabled no)
				(sheetname "")
			)
			(fill
				(thermal_gap 0.5)
				(thermal_bridge_width 0.5)
				(island_removal_mode 0)
			)
			(polygon
				(pts
					(arc
						(start 226.981004 -42.999914)
						(mid 226.219004 -42.999914)
						(end 226.981004 -42.999914)
					)
				)
			)
		)
		(zone
			(layer "F.Cu")
			(hatch none 0.5)
			(connect_pads
				(clearance 0)
			)
			(min_thickness 0.25)
			(keepout
				(tracks allowed)
				(vias not_allowed)
				(pads allowed)
				(copperpour not_allowed)
				(footprints allowed)
			)
			(placement
				(enabled no)
				(sheetname "")
			)
			(fill
				(thermal_gap 0.5)
				(thermal_bridge_width 0.5)
				(island_removal_mode 0)
			)
			(polygon
				(pts
					(arc
						(start 226.981004 -41.999916)
						(mid 226.219004 -41.999916)
						(end 226.981004 -41.999916)
					)
				)
			)
		)
		(zone
			(layer "F.Cu")
			(hatch none 0.5)
			(connect_pads
				(clearance 0)
			)
			(min_thickness 0.25)
			(keepout
				(tracks allowed)
				(vias not_allowed)
				(pads allowed)
				(copperpour not_allowed)
				(footprints allowed)
			)
			(placement
				(enabled no)
				(sheetname "")
			)
			(fill
				(thermal_gap 0.5)
				(thermal_bridge_width 0.5)
				(island_removal_mode 0)
			)
			(polygon
				(pts
					(arc
						(start 226.981004 -40.999918)
						(mid 226.219004 -40.999918)
						(end 226.981004 -40.999918)
					)
				)
			)
		)
		(zone
			(layer "F.Cu")
			(hatch none 0.5)
			(connect_pads
				(clearance 0)
			)
			(min_thickness 0.25)
			(keepout
				(tracks allowed)
				(vias not_allowed)
				(pads allowed)
				(copperpour not_allowed)
				(footprints allowed)
			)
			(placement
				(enabled no)
				(sheetname "")
			)
			(fill
				(thermal_gap 0.5)
				(thermal_bridge_width 0.5)
				(island_removal_mode 0)
			)
			(polygon
				(pts
					(arc
						(start 226.981004 -39.99992)
						(mid 226.219004 -39.99992)
						(end 226.981004 -39.99992)
					)
				)
			)
		)
		(zone
			(layer "F.Cu")
			(hatch none 0.5)
			(connect_pads
				(clearance 0)
			)
			(min_thickness 0.25)
			(keepout
				(tracks allowed)
				(vias not_allowed)
				(pads allowed)
				(copperpour not_allowed)
				(footprints allowed)
			)
			(placement
				(enabled no)
				(sheetname "")
			)
			(fill
				(thermal_gap 0.5)
				(thermal_bridge_width 0.5)
				(island_removal_mode 0)
			)
			(polygon
				(pts
					(arc
						(start 226.981004 -38.999922)
						(mid 226.219004 -38.999922)
						(end 226.981004 -38.999922)
					)
				)
			)
		)
		(zone
			(layer "F.Cu")
			(hatch none 0.5)
			(connect_pads
				(clearance 0)
			)
			(min_thickness 0.25)
			(keepout
				(tracks allowed)
				(vias not_allowed)
				(pads allowed)
				(copperpour not_allowed)
				(footprints allowed)
			)
			(placement
				(enabled no)
				(sheetname "")
			)
			(fill
				(thermal_gap 0.5)
				(thermal_bridge_width 0.5)
				(island_removal_mode 0)
			)
			(polygon
				(pts
					(arc
						(start 226.981004 -37.999924)
						(mid 226.219004 -37.999924)
						(end 226.981004 -37.999924)
					)
				)
			)
		)
		(zone
			(layer "F.Cu")
			(hatch none 0.5)
			(connect_pads
				(clearance 0)
			)
			(min_thickness 0.25)
			(keepout
				(tracks allowed)
				(vias not_allowed)
				(pads allowed)
				(copperpour not_allowed)
				(footprints allowed)
			)
			(placement
				(enabled no)
				(sheetname "")
			)
			(fill
				(thermal_gap 0.5)
				(thermal_bridge_width 0.5)
				(island_removal_mode 0)
			)
			(polygon
				(pts
					(arc
						(start 226.981004 -36.999926)
						(mid 226.219004 -36.999926)
						(end 226.981004 -36.999926)
					)
				)
			)
		)
		(zone
			(layer "F.Cu")
			(hatch none 0.5)
			(connect_pads
				(clearance 0)
			)
			(min_thickness 0.25)
			(keepout
				(tracks allowed)
				(vias not_allowed)
				(pads allowed)
				(copperpour not_allowed)
				(footprints allowed)
			)
			(placement
				(enabled no)
				(sheetname "")
			)
			(fill
				(thermal_gap 0.5)
				(thermal_bridge_width 0.5)
				(island_removal_mode 0)
			)
			(polygon
				(pts
					(arc
						(start 226.981004 -35.999928)
						(mid 226.219004 -35.999928)
						(end 226.981004 -35.999928)
					)
				)
			)
		)
		(zone
			(layer "F.Cu")
			(hatch none 0.5)
			(connect_pads
				(clearance 0)
			)
			(min_thickness 0.25)
			(keepout
				(tracks allowed)
				(vias not_allowed)
				(pads allowed)
				(copperpour not_allowed)
				(footprints allowed)
			)
			(placement
				(enabled no)
				(sheetname "")
			)
			(fill
				(thermal_gap 0.5)
				(thermal_bridge_width 0.5)
				(island_removal_mode 0)
			)
			(polygon
				(pts
					(arc
						(start 226.981004 -34.99993)
						(mid 226.219004 -34.99993)
						(end 226.981004 -34.99993)
					)
				)
			)
		)
		(zone
			(layer "F.Cu")
			(hatch none 0.5)
			(connect_pads
				(clearance 0)
			)
			(min_thickness 0.25)
			(keepout
				(tracks allowed)
				(vias not_allowed)
				(pads allowed)
				(copperpour not_allowed)
				(footprints allowed)
			)
			(placement
				(enabled no)
				(sheetname "")
			)
			(fill
				(thermal_gap 0.5)
				(thermal_bridge_width 0.5)
				(island_removal_mode 0)
			)
			(polygon
				(pts
					(arc
						(start 226.981004 -33.999932)
						(mid 226.219004 -33.999932)
						(end 226.981004 -33.999932)
					)
				)
			)
		)
		(zone
			(layer "F.Cu")
			(hatch none 0.5)
			(connect_pads
				(clearance 0)
			)
			(min_thickness 0.25)
			(keepout
				(tracks allowed)
				(vias not_allowed)
				(pads allowed)
				(copperpour not_allowed)
				(footprints allowed)
			)
			(placement
				(enabled no)
				(sheetname "")
			)
			(fill
				(thermal_gap 0.5)
				(thermal_bridge_width 0.5)
				(island_removal_mode 0)
			)
			(polygon
				(pts
					(arc
						(start 226.981004 -32.999934)
						(mid 226.219004 -32.999934)
						(end 226.981004 -32.999934)
					)
				)
			)
		)
		(zone
			(layer "F.Cu")
			(hatch none 0.5)
			(connect_pads
				(clearance 0)
			)
			(min_thickness 0.25)
			(keepout
				(tracks allowed)
				(vias not_allowed)
				(pads allowed)
				(copperpour not_allowed)
				(footprints allowed)
			)
			(placement
				(enabled no)
				(sheetname "")
			)
			(fill
				(thermal_gap 0.5)
				(thermal_bridge_width 0.5)
				(island_removal_mode 0)
			)
			(polygon
				(pts
					(arc
						(start 226.981004 -31.999936)
						(mid 226.219004 -31.999936)
						(end 226.981004 -31.999936)
					)
				)
			)
		)
		(zone
			(layer "F.Cu")
			(hatch none 0.5)
			(connect_pads
				(clearance 0)
			)
			(min_thickness 0.25)
			(keepout
				(tracks allowed)
				(vias not_allowed)
				(pads allowed)
				(copperpour not_allowed)
				(footprints allowed)
			)
			(placement
				(enabled no)
				(sheetname "")
			)
			(fill
				(thermal_gap 0.5)
				(thermal_bridge_width 0.5)
				(island_removal_mode 0)
			)
			(polygon
				(pts
					(arc
						(start 226.981004 -30.999938)
						(mid 226.219004 -30.999938)
						(end 226.981004 -30.999938)
					)
				)
			)
		)
		(zone
			(layer "F.Cu")
			(hatch none 0.5)
			(connect_pads
				(clearance 0)
			)
			(min_thickness 0.25)
			(keepout
				(tracks allowed)
				(vias not_allowed)
				(pads allowed)
				(copperpour not_allowed)
				(footprints allowed)
			)
			(placement
				(enabled no)
				(sheetname "")
			)
			(fill
				(thermal_gap 0.5)
				(thermal_bridge_width 0.5)
				(island_removal_mode 0)
			)
			(polygon
				(pts
					(arc
						(start 227.981002 -65.999868)
						(mid 227.219002 -65.999868)
						(end 227.981002 -65.999868)
					)
				)
			)
		)
		(zone
			(layer "F.Cu")
			(hatch none 0.5)
			(connect_pads
				(clearance 0)
			)
			(min_thickness 0.25)
			(keepout
				(tracks allowed)
				(vias not_allowed)
				(pads allowed)
				(copperpour not_allowed)
				(footprints allowed)
			)
			(placement
				(enabled no)
				(sheetname "")
			)
			(fill
				(thermal_gap 0.5)
				(thermal_bridge_width 0.5)
				(island_removal_mode 0)
			)
			(polygon
				(pts
					(arc
						(start 227.981002 -64.99987)
						(mid 227.219002 -64.99987)
						(end 227.981002 -64.99987)
					)
				)
			)
		)
		(zone
			(layer "F.Cu")
			(hatch none 0.5)
			(connect_pads
				(clearance 0)
			)
			(min_thickness 0.25)
			(keepout
				(tracks allowed)
				(vias not_allowed)
				(pads allowed)
				(copperpour not_allowed)
				(footprints allowed)
			)
			(placement
				(enabled no)
				(sheetname "")
			)
			(fill
				(thermal_gap 0.5)
				(thermal_bridge_width 0.5)
				(island_removal_mode 0)
			)
			(polygon
				(pts
					(arc
						(start 227.981002 -63.999872)
						(mid 227.219002 -63.999872)
						(end 227.981002 -63.999872)
					)
				)
			)
		)
		(zone
			(layer "F.Cu")
			(hatch none 0.5)
			(connect_pads
				(clearance 0)
			)
			(min_thickness 0.25)
			(keepout
				(tracks allowed)
				(vias not_allowed)
				(pads allowed)
				(copperpour not_allowed)
				(footprints allowed)
			)
			(placement
				(enabled no)
				(sheetname "")
			)
			(fill
				(thermal_gap 0.5)
				(thermal_bridge_width 0.5)
				(island_removal_mode 0)
			)
			(polygon
				(pts
					(arc
						(start 227.981002 -62.999874)
						(mid 227.219002 -62.999874)
						(end 227.981002 -62.999874)
					)
				)
			)
		)
		(zone
			(layer "F.Cu")
			(hatch none 0.5)
			(connect_pads
				(clearance 0)
			)
			(min_thickness 0.25)
			(keepout
				(tracks allowed)
				(vias not_allowed)
				(pads allowed)
				(copperpour not_allowed)
				(footprints allowed)
			)
			(placement
				(enabled no)
				(sheetname "")
			)
			(fill
				(thermal_gap 0.5)
				(thermal_bridge_width 0.5)
				(island_removal_mode 0)
			)
			(polygon
				(pts
					(arc
						(start 227.981002 -61.999876)
						(mid 227.219002 -61.999876)
						(end 227.981002 -61.999876)
					)
				)
			)
		)
		(zone
			(layer "F.Cu")
			(hatch none 0.5)
			(connect_pads
				(clearance 0)
			)
			(min_thickness 0.25)
			(keepout
				(tracks allowed)
				(vias not_allowed)
				(pads allowed)
				(copperpour not_allowed)
				(footprints allowed)
			)
			(placement
				(enabled no)
				(sheetname "")
			)
			(fill
				(thermal_gap 0.5)
				(thermal_bridge_width 0.5)
				(island_removal_mode 0)
			)
			(polygon
				(pts
					(arc
						(start 227.981002 -60.999878)
						(mid 227.219002 -60.999878)
						(end 227.981002 -60.999878)
					)
				)
			)
		)
		(zone
			(layer "F.Cu")
			(hatch none 0.5)
			(connect_pads
				(clearance 0)
			)
			(min_thickness 0.25)
			(keepout
				(tracks allowed)
				(vias not_allowed)
				(pads allowed)
				(copperpour not_allowed)
				(footprints allowed)
			)
			(placement
				(enabled no)
				(sheetname "")
			)
			(fill
				(thermal_gap 0.5)
				(thermal_bridge_width 0.5)
				(island_removal_mode 0)
			)
			(polygon
				(pts
					(arc
						(start 227.981002 -59.99988)
						(mid 227.219002 -59.99988)
						(end 227.981002 -59.99988)
					)
				)
			)
		)
		(zone
			(layer "F.Cu")
			(hatch none 0.5)
			(connect_pads
				(clearance 0)
			)
			(min_thickness 0.25)
			(keepout
				(tracks allowed)
				(vias not_allowed)
				(pads allowed)
				(copperpour not_allowed)
				(footprints allowed)
			)
			(placement
				(enabled no)
				(sheetname "")
			)
			(fill
				(thermal_gap 0.5)
				(thermal_bridge_width 0.5)
				(island_removal_mode 0)
			)
			(polygon
				(pts
					(arc
						(start 227.981002 -58.999882)
						(mid 227.219002 -58.999882)
						(end 227.981002 -58.999882)
					)
				)
			)
		)
		(zone
			(layer "F.Cu")
			(hatch none 0.5)
			(connect_pads
				(clearance 0)
			)
			(min_thickness 0.25)
			(keepout
				(tracks allowed)
				(vias not_allowed)
				(pads allowed)
				(copperpour not_allowed)
				(footprints allowed)
			)
			(placement
				(enabled no)
				(sheetname "")
			)
			(fill
				(thermal_gap 0.5)
				(thermal_bridge_width 0.5)
				(island_removal_mode 0)
			)
			(polygon
				(pts
					(arc
						(start 227.981002 -57.999884)
						(mid 227.219002 -57.999884)
						(end 227.981002 -57.999884)
					)
				)
			)
		)
		(zone
			(layer "F.Cu")
			(hatch none 0.5)
			(connect_pads
				(clearance 0)
			)
			(min_thickness 0.25)
			(keepout
				(tracks allowed)
				(vias not_allowed)
				(pads allowed)
				(copperpour not_allowed)
				(footprints allowed)
			)
			(placement
				(enabled no)
				(sheetname "")
			)
			(fill
				(thermal_gap 0.5)
				(thermal_bridge_width 0.5)
				(island_removal_mode 0)
			)
			(polygon
				(pts
					(arc
						(start 227.981002 -56.999886)
						(mid 227.219002 -56.999886)
						(end 227.981002 -56.999886)
					)
				)
			)
		)
		(zone
			(layer "F.Cu")
			(hatch none 0.5)
			(connect_pads
				(clearance 0)
			)
			(min_thickness 0.25)
			(keepout
				(tracks allowed)
				(vias not_allowed)
				(pads allowed)
				(copperpour not_allowed)
				(footprints allowed)
			)
			(placement
				(enabled no)
				(sheetname "")
			)
			(fill
				(thermal_gap 0.5)
				(thermal_bridge_width 0.5)
				(island_removal_mode 0)
			)
			(polygon
				(pts
					(arc
						(start 227.981002 -55.999888)
						(mid 227.219002 -55.999888)
						(end 227.981002 -55.999888)
					)
				)
			)
		)
		(zone
			(layer "F.Cu")
			(hatch none 0.5)
			(connect_pads
				(clearance 0)
			)
			(min_thickness 0.25)
			(keepout
				(tracks allowed)
				(vias not_allowed)
				(pads allowed)
				(copperpour not_allowed)
				(footprints allowed)
			)
			(placement
				(enabled no)
				(sheetname "")
			)
			(fill
				(thermal_gap 0.5)
				(thermal_bridge_width 0.5)
				(island_removal_mode 0)
			)
			(polygon
				(pts
					(arc
						(start 227.981002 -54.99989)
						(mid 227.219002 -54.99989)
						(end 227.981002 -54.99989)
					)
				)
			)
		)
		(zone
			(layer "F.Cu")
			(hatch none 0.5)
			(connect_pads
				(clearance 0)
			)
			(min_thickness 0.25)
			(keepout
				(tracks allowed)
				(vias not_allowed)
				(pads allowed)
				(copperpour not_allowed)
				(footprints allowed)
			)
			(placement
				(enabled no)
				(sheetname "")
			)
			(fill
				(thermal_gap 0.5)
				(thermal_bridge_width 0.5)
				(island_removal_mode 0)
			)
			(polygon
				(pts
					(arc
						(start 227.981002 -53.999892)
						(mid 227.219002 -53.999892)
						(end 227.981002 -53.999892)
					)
				)
			)
		)
		(zone
			(layer "F.Cu")
			(hatch none 0.5)
			(connect_pads
				(clearance 0)
			)
			(min_thickness 0.25)
			(keepout
				(tracks allowed)
				(vias not_allowed)
				(pads allowed)
				(copperpour not_allowed)
				(footprints allowed)
			)
			(placement
				(enabled no)
				(sheetname "")
			)
			(fill
				(thermal_gap 0.5)
				(thermal_bridge_width 0.5)
				(island_removal_mode 0)
			)
			(polygon
				(pts
					(arc
						(start 227.981002 -52.999894)
						(mid 227.219002 -52.999894)
						(end 227.981002 -52.999894)
					)
				)
			)
		)
		(zone
			(layer "F.Cu")
			(hatch none 0.5)
			(connect_pads
				(clearance 0)
			)
			(min_thickness 0.25)
			(keepout
				(tracks allowed)
				(vias not_allowed)
				(pads allowed)
				(copperpour not_allowed)
				(footprints allowed)
			)
			(placement
				(enabled no)
				(sheetname "")
			)
			(fill
				(thermal_gap 0.5)
				(thermal_bridge_width 0.5)
				(island_removal_mode 0)
			)
			(polygon
				(pts
					(arc
						(start 227.981002 -51.999896)
						(mid 227.219002 -51.999896)
						(end 227.981002 -51.999896)
					)
				)
			)
		)
		(zone
			(layer "F.Cu")
			(hatch none 0.5)
			(connect_pads
				(clearance 0)
			)
			(min_thickness 0.25)
			(keepout
				(tracks allowed)
				(vias not_allowed)
				(pads allowed)
				(copperpour not_allowed)
				(footprints allowed)
			)
			(placement
				(enabled no)
				(sheetname "")
			)
			(fill
				(thermal_gap 0.5)
				(thermal_bridge_width 0.5)
				(island_removal_mode 0)
			)
			(polygon
				(pts
					(arc
						(start 227.981002 -50.999898)
						(mid 227.219002 -50.999898)
						(end 227.981002 -50.999898)
					)
				)
			)
		)
		(zone
			(layer "F.Cu")
			(hatch none 0.5)
			(connect_pads
				(clearance 0)
			)
			(min_thickness 0.25)
			(keepout
				(tracks allowed)
				(vias not_allowed)
				(pads allowed)
				(copperpour not_allowed)
				(footprints allowed)
			)
			(placement
				(enabled no)
				(sheetname "")
			)
			(fill
				(thermal_gap 0.5)
				(thermal_bridge_width 0.5)
				(island_removal_mode 0)
			)
			(polygon
				(pts
					(arc
						(start 227.981002 -49.9999)
						(mid 227.219002 -49.9999)
						(end 227.981002 -49.9999)
					)
				)
			)
		)
		(zone
			(layer "F.Cu")
			(hatch none 0.5)
			(connect_pads
				(clearance 0)
			)
			(min_thickness 0.25)
			(keepout
				(tracks allowed)
				(vias not_allowed)
				(pads allowed)
				(copperpour not_allowed)
				(footprints allowed)
			)
			(placement
				(enabled no)
				(sheetname "")
			)
			(fill
				(thermal_gap 0.5)
				(thermal_bridge_width 0.5)
				(island_removal_mode 0)
			)
			(polygon
				(pts
					(arc
						(start 227.981002 -48.999902)
						(mid 227.219002 -48.999902)
						(end 227.981002 -48.999902)
					)
				)
			)
		)
		(zone
			(layer "F.Cu")
			(hatch none 0.5)
			(connect_pads
				(clearance 0)
			)
			(min_thickness 0.25)
			(keepout
				(tracks allowed)
				(vias not_allowed)
				(pads allowed)
				(copperpour not_allowed)
				(footprints allowed)
			)
			(placement
				(enabled no)
				(sheetname "")
			)
			(fill
				(thermal_gap 0.5)
				(thermal_bridge_width 0.5)
				(island_removal_mode 0)
			)
			(polygon
				(pts
					(arc
						(start 227.981002 -47.999904)
						(mid 227.219002 -47.999904)
						(end 227.981002 -47.999904)
					)
				)
			)
		)
		(zone
			(layer "F.Cu")
			(hatch none 0.5)
			(connect_pads
				(clearance 0)
			)
			(min_thickness 0.25)
			(keepout
				(tracks allowed)
				(vias not_allowed)
				(pads allowed)
				(copperpour not_allowed)
				(footprints allowed)
			)
			(placement
				(enabled no)
				(sheetname "")
			)
			(fill
				(thermal_gap 0.5)
				(thermal_bridge_width 0.5)
				(island_removal_mode 0)
			)
			(polygon
				(pts
					(arc
						(start 227.981002 -46.999906)
						(mid 227.219002 -46.999906)
						(end 227.981002 -46.999906)
					)
				)
			)
		)
		(zone
			(layer "F.Cu")
			(hatch none 0.5)
			(connect_pads
				(clearance 0)
			)
			(min_thickness 0.25)
			(keepout
				(tracks allowed)
				(vias not_allowed)
				(pads allowed)
				(copperpour not_allowed)
				(footprints allowed)
			)
			(placement
				(enabled no)
				(sheetname "")
			)
			(fill
				(thermal_gap 0.5)
				(thermal_bridge_width 0.5)
				(island_removal_mode 0)
			)
			(polygon
				(pts
					(arc
						(start 227.981002 -45.999908)
						(mid 227.219002 -45.999908)
						(end 227.981002 -45.999908)
					)
				)
			)
		)
		(zone
			(layer "F.Cu")
			(hatch none 0.5)
			(connect_pads
				(clearance 0)
			)
			(min_thickness 0.25)
			(keepout
				(tracks allowed)
				(vias not_allowed)
				(pads allowed)
				(copperpour not_allowed)
				(footprints allowed)
			)
			(placement
				(enabled no)
				(sheetname "")
			)
			(fill
				(thermal_gap 0.5)
				(thermal_bridge_width 0.5)
				(island_removal_mode 0)
			)
			(polygon
				(pts
					(arc
						(start 227.981002 -44.99991)
						(mid 227.219002 -44.99991)
						(end 227.981002 -44.99991)
					)
				)
			)
		)
		(zone
			(layer "F.Cu")
			(hatch none 0.5)
			(connect_pads
				(clearance 0)
			)
			(min_thickness 0.25)
			(keepout
				(tracks allowed)
				(vias not_allowed)
				(pads allowed)
				(copperpour not_allowed)
				(footprints allowed)
			)
			(placement
				(enabled no)
				(sheetname "")
			)
			(fill
				(thermal_gap 0.5)
				(thermal_bridge_width 0.5)
				(island_removal_mode 0)
			)
			(polygon
				(pts
					(arc
						(start 227.981002 -43.999912)
						(mid 227.219002 -43.999912)
						(end 227.981002 -43.999912)
					)
				)
			)
		)
		(zone
			(layer "F.Cu")
			(hatch none 0.5)
			(connect_pads
				(clearance 0)
			)
			(min_thickness 0.25)
			(keepout
				(tracks allowed)
				(vias not_allowed)
				(pads allowed)
				(copperpour not_allowed)
				(footprints allowed)
			)
			(placement
				(enabled no)
				(sheetname "")
			)
			(fill
				(thermal_gap 0.5)
				(thermal_bridge_width 0.5)
				(island_removal_mode 0)
			)
			(polygon
				(pts
					(arc
						(start 227.981002 -42.999914)
						(mid 227.219002 -42.999914)
						(end 227.981002 -42.999914)
					)
				)
			)
		)
		(zone
			(layer "F.Cu")
			(hatch none 0.5)
			(connect_pads
				(clearance 0)
			)
			(min_thickness 0.25)
			(keepout
				(tracks allowed)
				(vias not_allowed)
				(pads allowed)
				(copperpour not_allowed)
				(footprints allowed)
			)
			(placement
				(enabled no)
				(sheetname "")
			)
			(fill
				(thermal_gap 0.5)
				(thermal_bridge_width 0.5)
				(island_removal_mode 0)
			)
			(polygon
				(pts
					(arc
						(start 227.981002 -41.999916)
						(mid 227.219002 -41.999916)
						(end 227.981002 -41.999916)
					)
				)
			)
		)
		(zone
			(layer "F.Cu")
			(hatch none 0.5)
			(connect_pads
				(clearance 0)
			)
			(min_thickness 0.25)
			(keepout
				(tracks allowed)
				(vias not_allowed)
				(pads allowed)
				(copperpour not_allowed)
				(footprints allowed)
			)
			(placement
				(enabled no)
				(sheetname "")
			)
			(fill
				(thermal_gap 0.5)
				(thermal_bridge_width 0.5)
				(island_removal_mode 0)
			)
			(polygon
				(pts
					(arc
						(start 227.981002 -40.999918)
						(mid 227.219002 -40.999918)
						(end 227.981002 -40.999918)
					)
				)
			)
		)
		(zone
			(layer "F.Cu")
			(hatch none 0.5)
			(connect_pads
				(clearance 0)
			)
			(min_thickness 0.25)
			(keepout
				(tracks allowed)
				(vias not_allowed)
				(pads allowed)
				(copperpour not_allowed)
				(footprints allowed)
			)
			(placement
				(enabled no)
				(sheetname "")
			)
			(fill
				(thermal_gap 0.5)
				(thermal_bridge_width 0.5)
				(island_removal_mode 0)
			)
			(polygon
				(pts
					(arc
						(start 227.981002 -39.99992)
						(mid 227.219002 -39.99992)
						(end 227.981002 -39.99992)
					)
				)
			)
		)
		(zone
			(layer "F.Cu")
			(hatch none 0.5)
			(connect_pads
				(clearance 0)
			)
			(min_thickness 0.25)
			(keepout
				(tracks allowed)
				(vias not_allowed)
				(pads allowed)
				(copperpour not_allowed)
				(footprints allowed)
			)
			(placement
				(enabled no)
				(sheetname "")
			)
			(fill
				(thermal_gap 0.5)
				(thermal_bridge_width 0.5)
				(island_removal_mode 0)
			)
			(polygon
				(pts
					(arc
						(start 227.981002 -38.999922)
						(mid 227.219002 -38.999922)
						(end 227.981002 -38.999922)
					)
				)
			)
		)
		(zone
			(layer "F.Cu")
			(hatch none 0.5)
			(connect_pads
				(clearance 0)
			)
			(min_thickness 0.25)
			(keepout
				(tracks allowed)
				(vias not_allowed)
				(pads allowed)
				(copperpour not_allowed)
				(footprints allowed)
			)
			(placement
				(enabled no)
				(sheetname "")
			)
			(fill
				(thermal_gap 0.5)
				(thermal_bridge_width 0.5)
				(island_removal_mode 0)
			)
			(polygon
				(pts
					(arc
						(start 227.981002 -37.999924)
						(mid 227.219002 -37.999924)
						(end 227.981002 -37.999924)
					)
				)
			)
		)
		(zone
			(layer "F.Cu")
			(hatch none 0.5)
			(connect_pads
				(clearance 0)
			)
			(min_thickness 0.25)
			(keepout
				(tracks allowed)
				(vias not_allowed)
				(pads allowed)
				(copperpour not_allowed)
				(footprints allowed)
			)
			(placement
				(enabled no)
				(sheetname "")
			)
			(fill
				(thermal_gap 0.5)
				(thermal_bridge_width 0.5)
				(island_removal_mode 0)
			)
			(polygon
				(pts
					(arc
						(start 227.981002 -36.999926)
						(mid 227.219002 -36.999926)
						(end 227.981002 -36.999926)
					)
				)
			)
		)
		(zone
			(layer "F.Cu")
			(hatch none 0.5)
			(connect_pads
				(clearance 0)
			)
			(min_thickness 0.25)
			(keepout
				(tracks allowed)
				(vias not_allowed)
				(pads allowed)
				(copperpour not_allowed)
				(footprints allowed)
			)
			(placement
				(enabled no)
				(sheetname "")
			)
			(fill
				(thermal_gap 0.5)
				(thermal_bridge_width 0.5)
				(island_removal_mode 0)
			)
			(polygon
				(pts
					(arc
						(start 227.981002 -35.999928)
						(mid 227.219002 -35.999928)
						(end 227.981002 -35.999928)
					)
				)
			)
		)
		(zone
			(layer "F.Cu")
			(hatch none 0.5)
			(connect_pads
				(clearance 0)
			)
			(min_thickness 0.25)
			(keepout
				(tracks allowed)
				(vias not_allowed)
				(pads allowed)
				(copperpour not_allowed)
				(footprints allowed)
			)
			(placement
				(enabled no)
				(sheetname "")
			)
			(fill
				(thermal_gap 0.5)
				(thermal_bridge_width 0.5)
				(island_removal_mode 0)
			)
			(polygon
				(pts
					(arc
						(start 227.981002 -34.99993)
						(mid 227.219002 -34.99993)
						(end 227.981002 -34.99993)
					)
				)
			)
		)
		(zone
			(layer "F.Cu")
			(hatch none 0.5)
			(connect_pads
				(clearance 0)
			)
			(min_thickness 0.25)
			(keepout
				(tracks allowed)
				(vias not_allowed)
				(pads allowed)
				(copperpour not_allowed)
				(footprints allowed)
			)
			(placement
				(enabled no)
				(sheetname "")
			)
			(fill
				(thermal_gap 0.5)
				(thermal_bridge_width 0.5)
				(island_removal_mode 0)
			)
			(polygon
				(pts
					(arc
						(start 227.981002 -33.999932)
						(mid 227.219002 -33.999932)
						(end 227.981002 -33.999932)
					)
				)
			)
		)
		(zone
			(layer "F.Cu")
			(hatch none 0.5)
			(connect_pads
				(clearance 0)
			)
			(min_thickness 0.25)
			(keepout
				(tracks allowed)
				(vias not_allowed)
				(pads allowed)
				(copperpour not_allowed)
				(footprints allowed)
			)
			(placement
				(enabled no)
				(sheetname "")
			)
			(fill
				(thermal_gap 0.5)
				(thermal_bridge_width 0.5)
				(island_removal_mode 0)
			)
			(polygon
				(pts
					(arc
						(start 227.981002 -32.999934)
						(mid 227.219002 -32.999934)
						(end 227.981002 -32.999934)
					)
				)
			)
		)
		(zone
			(layer "F.Cu")
			(hatch none 0.5)
			(connect_pads
				(clearance 0)
			)
			(min_thickness 0.25)
			(keepout
				(tracks allowed)
				(vias not_allowed)
				(pads allowed)
				(copperpour not_allowed)
				(footprints allowed)
			)
			(placement
				(enabled no)
				(sheetname "")
			)
			(fill
				(thermal_gap 0.5)
				(thermal_bridge_width 0.5)
				(island_removal_mode 0)
			)
			(polygon
				(pts
					(arc
						(start 227.981002 -31.999936)
						(mid 227.219002 -31.999936)
						(end 227.981002 -31.999936)
					)
				)
			)
		)
		(zone
			(layer "F.Cu")
			(hatch none 0.5)
			(connect_pads
				(clearance 0)
			)
			(min_thickness 0.25)
			(keepout
				(tracks allowed)
				(vias not_allowed)
				(pads allowed)
				(copperpour not_allowed)
				(footprints allowed)
			)
			(placement
				(enabled no)
				(sheetname "")
			)
			(fill
				(thermal_gap 0.5)
				(thermal_bridge_width 0.5)
				(island_removal_mode 0)
			)
			(polygon
				(pts
					(arc
						(start 227.981002 -30.999938)
						(mid 227.219002 -30.999938)
						(end 227.981002 -30.999938)
					)
				)
			)
		)
		(zone
			(layer "F.Cu")
			(hatch none 0.5)
			(connect_pads
				(clearance 0)
			)
			(min_thickness 0.25)
			(keepout
				(tracks allowed)
				(vias not_allowed)
				(pads allowed)
				(copperpour not_allowed)
				(footprints allowed)
			)
			(placement
				(enabled no)
				(sheetname "")
			)
			(fill
				(thermal_gap 0.5)
				(thermal_bridge_width 0.5)
				(island_removal_mode 0)
			)
			(polygon
				(pts
					(arc
						(start 227.981002 -29.99994)
						(mid 227.219002 -29.99994)
						(end 227.981002 -29.99994)
					)
				)
			)
		)
		(zone
			(layer "F.Cu")
			(hatch none 0.5)
			(connect_pads
				(clearance 0)
			)
			(min_thickness 0.25)
			(keepout
				(tracks allowed)
				(vias not_allowed)
				(pads allowed)
				(copperpour not_allowed)
				(footprints allowed)
			)
			(placement
				(enabled no)
				(sheetname "")
			)
			(fill
				(thermal_gap 0.5)
				(thermal_bridge_width 0.5)
				(island_removal_mode 0)
			)
			(polygon
				(pts
					(arc
						(start 228.981 -64.99987)
						(mid 228.219 -64.99987)
						(end 228.981 -64.99987)
					)
				)
			)
		)
		(zone
			(layer "F.Cu")
			(hatch none 0.5)
			(connect_pads
				(clearance 0)
			)
			(min_thickness 0.25)
			(keepout
				(tracks allowed)
				(vias not_allowed)
				(pads allowed)
				(copperpour not_allowed)
				(footprints allowed)
			)
			(placement
				(enabled no)
				(sheetname "")
			)
			(fill
				(thermal_gap 0.5)
				(thermal_bridge_width 0.5)
				(island_removal_mode 0)
			)
			(polygon
				(pts
					(arc
						(start 228.981 -63.999872)
						(mid 228.219 -63.999872)
						(end 228.981 -63.999872)
					)
				)
			)
		)
		(zone
			(layer "F.Cu")
			(hatch none 0.5)
			(connect_pads
				(clearance 0)
			)
			(min_thickness 0.25)
			(keepout
				(tracks allowed)
				(vias not_allowed)
				(pads allowed)
				(copperpour not_allowed)
				(footprints allowed)
			)
			(placement
				(enabled no)
				(sheetname "")
			)
			(fill
				(thermal_gap 0.5)
				(thermal_bridge_width 0.5)
				(island_removal_mode 0)
			)
			(polygon
				(pts
					(arc
						(start 228.981 -62.999874)
						(mid 228.219 -62.999874)
						(end 228.981 -62.999874)
					)
				)
			)
		)
		(zone
			(layer "F.Cu")
			(hatch none 0.5)
			(connect_pads
				(clearance 0)
			)
			(min_thickness 0.25)
			(keepout
				(tracks allowed)
				(vias not_allowed)
				(pads allowed)
				(copperpour not_allowed)
				(footprints allowed)
			)
			(placement
				(enabled no)
				(sheetname "")
			)
			(fill
				(thermal_gap 0.5)
				(thermal_bridge_width 0.5)
				(island_removal_mode 0)
			)
			(polygon
				(pts
					(arc
						(start 228.981 -61.999876)
						(mid 228.219 -61.999876)
						(end 228.981 -61.999876)
					)
				)
			)
		)
		(zone
			(layer "F.Cu")
			(hatch none 0.5)
			(connect_pads
				(clearance 0)
			)
			(min_thickness 0.25)
			(keepout
				(tracks allowed)
				(vias not_allowed)
				(pads allowed)
				(copperpour not_allowed)
				(footprints allowed)
			)
			(placement
				(enabled no)
				(sheetname "")
			)
			(fill
				(thermal_gap 0.5)
				(thermal_bridge_width 0.5)
				(island_removal_mode 0)
			)
			(polygon
				(pts
					(arc
						(start 228.981 -60.999878)
						(mid 228.219 -60.999878)
						(end 228.981 -60.999878)
					)
				)
			)
		)
		(zone
			(layer "F.Cu")
			(hatch none 0.5)
			(connect_pads
				(clearance 0)
			)
			(min_thickness 0.25)
			(keepout
				(tracks allowed)
				(vias not_allowed)
				(pads allowed)
				(copperpour not_allowed)
				(footprints allowed)
			)
			(placement
				(enabled no)
				(sheetname "")
			)
			(fill
				(thermal_gap 0.5)
				(thermal_bridge_width 0.5)
				(island_removal_mode 0)
			)
			(polygon
				(pts
					(arc
						(start 228.981 -59.99988)
						(mid 228.219 -59.99988)
						(end 228.981 -59.99988)
					)
				)
			)
		)
		(zone
			(layer "F.Cu")
			(hatch none 0.5)
			(connect_pads
				(clearance 0)
			)
			(min_thickness 0.25)
			(keepout
				(tracks allowed)
				(vias not_allowed)
				(pads allowed)
				(copperpour not_allowed)
				(footprints allowed)
			)
			(placement
				(enabled no)
				(sheetname "")
			)
			(fill
				(thermal_gap 0.5)
				(thermal_bridge_width 0.5)
				(island_removal_mode 0)
			)
			(polygon
				(pts
					(arc
						(start 228.981 -58.999882)
						(mid 228.219 -58.999882)
						(end 228.981 -58.999882)
					)
				)
			)
		)
		(zone
			(layer "F.Cu")
			(hatch none 0.5)
			(connect_pads
				(clearance 0)
			)
			(min_thickness 0.25)
			(keepout
				(tracks allowed)
				(vias not_allowed)
				(pads allowed)
				(copperpour not_allowed)
				(footprints allowed)
			)
			(placement
				(enabled no)
				(sheetname "")
			)
			(fill
				(thermal_gap 0.5)
				(thermal_bridge_width 0.5)
				(island_removal_mode 0)
			)
			(polygon
				(pts
					(arc
						(start 228.981 -57.999884)
						(mid 228.219 -57.999884)
						(end 228.981 -57.999884)
					)
				)
			)
		)
		(zone
			(layer "F.Cu")
			(hatch none 0.5)
			(connect_pads
				(clearance 0)
			)
			(min_thickness 0.25)
			(keepout
				(tracks allowed)
				(vias not_allowed)
				(pads allowed)
				(copperpour not_allowed)
				(footprints allowed)
			)
			(placement
				(enabled no)
				(sheetname "")
			)
			(fill
				(thermal_gap 0.5)
				(thermal_bridge_width 0.5)
				(island_removal_mode 0)
			)
			(polygon
				(pts
					(arc
						(start 228.981 -56.999886)
						(mid 228.219 -56.999886)
						(end 228.981 -56.999886)
					)
				)
			)
		)
		(zone
			(layer "F.Cu")
			(hatch none 0.5)
			(connect_pads
				(clearance 0)
			)
			(min_thickness 0.25)
			(keepout
				(tracks allowed)
				(vias not_allowed)
				(pads allowed)
				(copperpour not_allowed)
				(footprints allowed)
			)
			(placement
				(enabled no)
				(sheetname "")
			)
			(fill
				(thermal_gap 0.5)
				(thermal_bridge_width 0.5)
				(island_removal_mode 0)
			)
			(polygon
				(pts
					(arc
						(start 228.981 -55.999888)
						(mid 228.219 -55.999888)
						(end 228.981 -55.999888)
					)
				)
			)
		)
		(zone
			(layer "F.Cu")
			(hatch none 0.5)
			(connect_pads
				(clearance 0)
			)
			(min_thickness 0.25)
			(keepout
				(tracks allowed)
				(vias not_allowed)
				(pads allowed)
				(copperpour not_allowed)
				(footprints allowed)
			)
			(placement
				(enabled no)
				(sheetname "")
			)
			(fill
				(thermal_gap 0.5)
				(thermal_bridge_width 0.5)
				(island_removal_mode 0)
			)
			(polygon
				(pts
					(arc
						(start 228.981 -54.99989)
						(mid 228.219 -54.99989)
						(end 228.981 -54.99989)
					)
				)
			)
		)
		(zone
			(layer "F.Cu")
			(hatch none 0.5)
			(connect_pads
				(clearance 0)
			)
			(min_thickness 0.25)
			(keepout
				(tracks allowed)
				(vias not_allowed)
				(pads allowed)
				(copperpour not_allowed)
				(footprints allowed)
			)
			(placement
				(enabled no)
				(sheetname "")
			)
			(fill
				(thermal_gap 0.5)
				(thermal_bridge_width 0.5)
				(island_removal_mode 0)
			)
			(polygon
				(pts
					(arc
						(start 228.981 -53.999892)
						(mid 228.219 -53.999892)
						(end 228.981 -53.999892)
					)
				)
			)
		)
		(zone
			(layer "F.Cu")
			(hatch none 0.5)
			(connect_pads
				(clearance 0)
			)
			(min_thickness 0.25)
			(keepout
				(tracks allowed)
				(vias not_allowed)
				(pads allowed)
				(copperpour not_allowed)
				(footprints allowed)
			)
			(placement
				(enabled no)
				(sheetname "")
			)
			(fill
				(thermal_gap 0.5)
				(thermal_bridge_width 0.5)
				(island_removal_mode 0)
			)
			(polygon
				(pts
					(arc
						(start 228.981 -52.999894)
						(mid 228.219 -52.999894)
						(end 228.981 -52.999894)
					)
				)
			)
		)
		(zone
			(layer "F.Cu")
			(hatch none 0.5)
			(connect_pads
				(clearance 0)
			)
			(min_thickness 0.25)
			(keepout
				(tracks allowed)
				(vias not_allowed)
				(pads allowed)
				(copperpour not_allowed)
				(footprints allowed)
			)
			(placement
				(enabled no)
				(sheetname "")
			)
			(fill
				(thermal_gap 0.5)
				(thermal_bridge_width 0.5)
				(island_removal_mode 0)
			)
			(polygon
				(pts
					(arc
						(start 228.981 -51.999896)
						(mid 228.219 -51.999896)
						(end 228.981 -51.999896)
					)
				)
			)
		)
		(zone
			(layer "F.Cu")
			(hatch none 0.5)
			(connect_pads
				(clearance 0)
			)
			(min_thickness 0.25)
			(keepout
				(tracks allowed)
				(vias not_allowed)
				(pads allowed)
				(copperpour not_allowed)
				(footprints allowed)
			)
			(placement
				(enabled no)
				(sheetname "")
			)
			(fill
				(thermal_gap 0.5)
				(thermal_bridge_width 0.5)
				(island_removal_mode 0)
			)
			(polygon
				(pts
					(arc
						(start 228.981 -50.999898)
						(mid 228.219 -50.999898)
						(end 228.981 -50.999898)
					)
				)
			)
		)
		(zone
			(layer "F.Cu")
			(hatch none 0.5)
			(connect_pads
				(clearance 0)
			)
			(min_thickness 0.25)
			(keepout
				(tracks allowed)
				(vias not_allowed)
				(pads allowed)
				(copperpour not_allowed)
				(footprints allowed)
			)
			(placement
				(enabled no)
				(sheetname "")
			)
			(fill
				(thermal_gap 0.5)
				(thermal_bridge_width 0.5)
				(island_removal_mode 0)
			)
			(polygon
				(pts
					(arc
						(start 228.981 -49.9999)
						(mid 228.219 -49.9999)
						(end 228.981 -49.9999)
					)
				)
			)
		)
		(zone
			(layer "F.Cu")
			(hatch none 0.5)
			(connect_pads
				(clearance 0)
			)
			(min_thickness 0.25)
			(keepout
				(tracks allowed)
				(vias not_allowed)
				(pads allowed)
				(copperpour not_allowed)
				(footprints allowed)
			)
			(placement
				(enabled no)
				(sheetname "")
			)
			(fill
				(thermal_gap 0.5)
				(thermal_bridge_width 0.5)
				(island_removal_mode 0)
			)
			(polygon
				(pts
					(arc
						(start 228.981 -48.999902)
						(mid 228.219 -48.999902)
						(end 228.981 -48.999902)
					)
				)
			)
		)
		(zone
			(layer "F.Cu")
			(hatch none 0.5)
			(connect_pads
				(clearance 0)
			)
			(min_thickness 0.25)
			(keepout
				(tracks allowed)
				(vias not_allowed)
				(pads allowed)
				(copperpour not_allowed)
				(footprints allowed)
			)
			(placement
				(enabled no)
				(sheetname "")
			)
			(fill
				(thermal_gap 0.5)
				(thermal_bridge_width 0.5)
				(island_removal_mode 0)
			)
			(polygon
				(pts
					(arc
						(start 228.981 -47.999904)
						(mid 228.219 -47.999904)
						(end 228.981 -47.999904)
					)
				)
			)
		)
		(zone
			(layer "F.Cu")
			(hatch none 0.5)
			(connect_pads
				(clearance 0)
			)
			(min_thickness 0.25)
			(keepout
				(tracks allowed)
				(vias not_allowed)
				(pads allowed)
				(copperpour not_allowed)
				(footprints allowed)
			)
			(placement
				(enabled no)
				(sheetname "")
			)
			(fill
				(thermal_gap 0.5)
				(thermal_bridge_width 0.5)
				(island_removal_mode 0)
			)
			(polygon
				(pts
					(arc
						(start 228.981 -46.999906)
						(mid 228.219 -46.999906)
						(end 228.981 -46.999906)
					)
				)
			)
		)
		(zone
			(layer "F.Cu")
			(hatch none 0.5)
			(connect_pads
				(clearance 0)
			)
			(min_thickness 0.25)
			(keepout
				(tracks allowed)
				(vias not_allowed)
				(pads allowed)
				(copperpour not_allowed)
				(footprints allowed)
			)
			(placement
				(enabled no)
				(sheetname "")
			)
			(fill
				(thermal_gap 0.5)
				(thermal_bridge_width 0.5)
				(island_removal_mode 0)
			)
			(polygon
				(pts
					(arc
						(start 228.981 -45.999908)
						(mid 228.219 -45.999908)
						(end 228.981 -45.999908)
					)
				)
			)
		)
		(zone
			(layer "F.Cu")
			(hatch none 0.5)
			(connect_pads
				(clearance 0)
			)
			(min_thickness 0.25)
			(keepout
				(tracks allowed)
				(vias not_allowed)
				(pads allowed)
				(copperpour not_allowed)
				(footprints allowed)
			)
			(placement
				(enabled no)
				(sheetname "")
			)
			(fill
				(thermal_gap 0.5)
				(thermal_bridge_width 0.5)
				(island_removal_mode 0)
			)
			(polygon
				(pts
					(arc
						(start 228.981 -44.99991)
						(mid 228.219 -44.99991)
						(end 228.981 -44.99991)
					)
				)
			)
		)
		(zone
			(layer "F.Cu")
			(hatch none 0.5)
			(connect_pads
				(clearance 0)
			)
			(min_thickness 0.25)
			(keepout
				(tracks allowed)
				(vias not_allowed)
				(pads allowed)
				(copperpour not_allowed)
				(footprints allowed)
			)
			(placement
				(enabled no)
				(sheetname "")
			)
			(fill
				(thermal_gap 0.5)
				(thermal_bridge_width 0.5)
				(island_removal_mode 0)
			)
			(polygon
				(pts
					(arc
						(start 228.981 -43.999912)
						(mid 228.219 -43.999912)
						(end 228.981 -43.999912)
					)
				)
			)
		)
		(zone
			(layer "F.Cu")
			(hatch none 0.5)
			(connect_pads
				(clearance 0)
			)
			(min_thickness 0.25)
			(keepout
				(tracks allowed)
				(vias not_allowed)
				(pads allowed)
				(copperpour not_allowed)
				(footprints allowed)
			)
			(placement
				(enabled no)
				(sheetname "")
			)
			(fill
				(thermal_gap 0.5)
				(thermal_bridge_width 0.5)
				(island_removal_mode 0)
			)
			(polygon
				(pts
					(arc
						(start 228.981 -42.999914)
						(mid 228.219 -42.999914)
						(end 228.981 -42.999914)
					)
				)
			)
		)
		(zone
			(layer "F.Cu")
			(hatch none 0.5)
			(connect_pads
				(clearance 0)
			)
			(min_thickness 0.25)
			(keepout
				(tracks allowed)
				(vias not_allowed)
				(pads allowed)
				(copperpour not_allowed)
				(footprints allowed)
			)
			(placement
				(enabled no)
				(sheetname "")
			)
			(fill
				(thermal_gap 0.5)
				(thermal_bridge_width 0.5)
				(island_removal_mode 0)
			)
			(polygon
				(pts
					(arc
						(start 228.981 -41.999916)
						(mid 228.219 -41.999916)
						(end 228.981 -41.999916)
					)
				)
			)
		)
		(zone
			(layer "F.Cu")
			(hatch none 0.5)
			(connect_pads
				(clearance 0)
			)
			(min_thickness 0.25)
			(keepout
				(tracks allowed)
				(vias not_allowed)
				(pads allowed)
				(copperpour not_allowed)
				(footprints allowed)
			)
			(placement
				(enabled no)
				(sheetname "")
			)
			(fill
				(thermal_gap 0.5)
				(thermal_bridge_width 0.5)
				(island_removal_mode 0)
			)
			(polygon
				(pts
					(arc
						(start 228.981 -40.999918)
						(mid 228.219 -40.999918)
						(end 228.981 -40.999918)
					)
				)
			)
		)
		(zone
			(layer "F.Cu")
			(hatch none 0.5)
			(connect_pads
				(clearance 0)
			)
			(min_thickness 0.25)
			(keepout
				(tracks allowed)
				(vias not_allowed)
				(pads allowed)
				(copperpour not_allowed)
				(footprints allowed)
			)
			(placement
				(enabled no)
				(sheetname "")
			)
			(fill
				(thermal_gap 0.5)
				(thermal_bridge_width 0.5)
				(island_removal_mode 0)
			)
			(polygon
				(pts
					(arc
						(start 228.981 -39.99992)
						(mid 228.219 -39.99992)
						(end 228.981 -39.99992)
					)
				)
			)
		)
		(zone
			(layer "F.Cu")
			(hatch none 0.5)
			(connect_pads
				(clearance 0)
			)
			(min_thickness 0.25)
			(keepout
				(tracks allowed)
				(vias not_allowed)
				(pads allowed)
				(copperpour not_allowed)
				(footprints allowed)
			)
			(placement
				(enabled no)
				(sheetname "")
			)
			(fill
				(thermal_gap 0.5)
				(thermal_bridge_width 0.5)
				(island_removal_mode 0)
			)
			(polygon
				(pts
					(arc
						(start 228.981 -38.999922)
						(mid 228.219 -38.999922)
						(end 228.981 -38.999922)
					)
				)
			)
		)
		(zone
			(layer "F.Cu")
			(hatch none 0.5)
			(connect_pads
				(clearance 0)
			)
			(min_thickness 0.25)
			(keepout
				(tracks allowed)
				(vias not_allowed)
				(pads allowed)
				(copperpour not_allowed)
				(footprints allowed)
			)
			(placement
				(enabled no)
				(sheetname "")
			)
			(fill
				(thermal_gap 0.5)
				(thermal_bridge_width 0.5)
				(island_removal_mode 0)
			)
			(polygon
				(pts
					(arc
						(start 228.981 -37.999924)
						(mid 228.219 -37.999924)
						(end 228.981 -37.999924)
					)
				)
			)
		)
		(zone
			(layer "F.Cu")
			(hatch none 0.5)
			(connect_pads
				(clearance 0)
			)
			(min_thickness 0.25)
			(keepout
				(tracks allowed)
				(vias not_allowed)
				(pads allowed)
				(copperpour not_allowed)
				(footprints allowed)
			)
			(placement
				(enabled no)
				(sheetname "")
			)
			(fill
				(thermal_gap 0.5)
				(thermal_bridge_width 0.5)
				(island_removal_mode 0)
			)
			(polygon
				(pts
					(arc
						(start 228.981 -36.999926)
						(mid 228.219 -36.999926)
						(end 228.981 -36.999926)
					)
				)
			)
		)
		(zone
			(layer "F.Cu")
			(hatch none 0.5)
			(connect_pads
				(clearance 0)
			)
			(min_thickness 0.25)
			(keepout
				(tracks allowed)
				(vias not_allowed)
				(pads allowed)
				(copperpour not_allowed)
				(footprints allowed)
			)
			(placement
				(enabled no)
				(sheetname "")
			)
			(fill
				(thermal_gap 0.5)
				(thermal_bridge_width 0.5)
				(island_removal_mode 0)
			)
			(polygon
				(pts
					(arc
						(start 228.981 -35.999928)
						(mid 228.219 -35.999928)
						(end 228.981 -35.999928)
					)
				)
			)
		)
		(zone
			(layer "F.Cu")
			(hatch none 0.5)
			(connect_pads
				(clearance 0)
			)
			(min_thickness 0.25)
			(keepout
				(tracks allowed)
				(vias not_allowed)
				(pads allowed)
				(copperpour not_allowed)
				(footprints allowed)
			)
			(placement
				(enabled no)
				(sheetname "")
			)
			(fill
				(thermal_gap 0.5)
				(thermal_bridge_width 0.5)
				(island_removal_mode 0)
			)
			(polygon
				(pts
					(arc
						(start 228.981 -34.99993)
						(mid 228.219 -34.99993)
						(end 228.981 -34.99993)
					)
				)
			)
		)
		(zone
			(layer "F.Cu")
			(hatch none 0.5)
			(connect_pads
				(clearance 0)
			)
			(min_thickness 0.25)
			(keepout
				(tracks allowed)
				(vias not_allowed)
				(pads allowed)
				(copperpour not_allowed)
				(footprints allowed)
			)
			(placement
				(enabled no)
				(sheetname "")
			)
			(fill
				(thermal_gap 0.5)
				(thermal_bridge_width 0.5)
				(island_removal_mode 0)
			)
			(polygon
				(pts
					(arc
						(start 228.981 -33.999932)
						(mid 228.219 -33.999932)
						(end 228.981 -33.999932)
					)
				)
			)
		)
		(zone
			(layer "F.Cu")
			(hatch none 0.5)
			(connect_pads
				(clearance 0)
			)
			(min_thickness 0.25)
			(keepout
				(tracks allowed)
				(vias not_allowed)
				(pads allowed)
				(copperpour not_allowed)
				(footprints allowed)
			)
			(placement
				(enabled no)
				(sheetname "")
			)
			(fill
				(thermal_gap 0.5)
				(thermal_bridge_width 0.5)
				(island_removal_mode 0)
			)
			(polygon
				(pts
					(arc
						(start 228.981 -32.999934)
						(mid 228.219 -32.999934)
						(end 228.981 -32.999934)
					)
				)
			)
		)
		(zone
			(layer "F.Cu")
			(hatch none 0.5)
			(connect_pads
				(clearance 0)
			)
			(min_thickness 0.25)
			(keepout
				(tracks allowed)
				(vias not_allowed)
				(pads allowed)
				(copperpour not_allowed)
				(footprints allowed)
			)
			(placement
				(enabled no)
				(sheetname "")
			)
			(fill
				(thermal_gap 0.5)
				(thermal_bridge_width 0.5)
				(island_removal_mode 0)
			)
			(polygon
				(pts
					(arc
						(start 228.981 -31.999936)
						(mid 228.219 -31.999936)
						(end 228.981 -31.999936)
					)
				)
			)
		)
		(zone
			(layer "F.Cu")
			(hatch none 0.5)
			(connect_pads
				(clearance 0)
			)
			(min_thickness 0.25)
			(keepout
				(tracks allowed)
				(vias not_allowed)
				(pads allowed)
				(copperpour not_allowed)
				(footprints allowed)
			)
			(placement
				(enabled no)
				(sheetname "")
			)
			(fill
				(thermal_gap 0.5)
				(thermal_bridge_width 0.5)
				(island_removal_mode 0)
			)
			(polygon
				(pts
					(arc
						(start 228.981 -30.999938)
						(mid 228.219 -30.999938)
						(end 228.981 -30.999938)
					)
				)
			)
		)
		(zone
			(layer "F.Cu")
			(hatch none 0.5)
			(connect_pads
				(clearance 0)
			)
			(min_thickness 0.25)
			(keepout
				(tracks allowed)
				(vias not_allowed)
				(pads allowed)
				(copperpour not_allowed)
				(footprints allowed)
			)
			(placement
				(enabled no)
				(sheetname "")
			)
			(fill
				(thermal_gap 0.5)
				(thermal_bridge_width 0.5)
				(island_removal_mode 0)
			)
			(polygon
				(pts
					(arc
						(start 229.980998 -65.999868)
						(mid 229.218998 -65.999868)
						(end 229.980998 -65.999868)
					)
				)
			)
		)
		(zone
			(layer "F.Cu")
			(hatch none 0.5)
			(connect_pads
				(clearance 0)
			)
			(min_thickness 0.25)
			(keepout
				(tracks allowed)
				(vias not_allowed)
				(pads allowed)
				(copperpour not_allowed)
				(footprints allowed)
			)
			(placement
				(enabled no)
				(sheetname "")
			)
			(fill
				(thermal_gap 0.5)
				(thermal_bridge_width 0.5)
				(island_removal_mode 0)
			)
			(polygon
				(pts
					(arc
						(start 229.980998 -64.99987)
						(mid 229.218998 -64.99987)
						(end 229.980998 -64.99987)
					)
				)
			)
		)
		(zone
			(layer "F.Cu")
			(hatch none 0.5)
			(connect_pads
				(clearance 0)
			)
			(min_thickness 0.25)
			(keepout
				(tracks allowed)
				(vias not_allowed)
				(pads allowed)
				(copperpour not_allowed)
				(footprints allowed)
			)
			(placement
				(enabled no)
				(sheetname "")
			)
			(fill
				(thermal_gap 0.5)
				(thermal_bridge_width 0.5)
				(island_removal_mode 0)
			)
			(polygon
				(pts
					(arc
						(start 229.980998 -63.999872)
						(mid 229.218998 -63.999872)
						(end 229.980998 -63.999872)
					)
				)
			)
		)
		(zone
			(layer "F.Cu")
			(hatch none 0.5)
			(connect_pads
				(clearance 0)
			)
			(min_thickness 0.25)
			(keepout
				(tracks allowed)
				(vias not_allowed)
				(pads allowed)
				(copperpour not_allowed)
				(footprints allowed)
			)
			(placement
				(enabled no)
				(sheetname "")
			)
			(fill
				(thermal_gap 0.5)
				(thermal_bridge_width 0.5)
				(island_removal_mode 0)
			)
			(polygon
				(pts
					(arc
						(start 229.980998 -62.999874)
						(mid 229.218998 -62.999874)
						(end 229.980998 -62.999874)
					)
				)
			)
		)
		(zone
			(layer "F.Cu")
			(hatch none 0.5)
			(connect_pads
				(clearance 0)
			)
			(min_thickness 0.25)
			(keepout
				(tracks allowed)
				(vias not_allowed)
				(pads allowed)
				(copperpour not_allowed)
				(footprints allowed)
			)
			(placement
				(enabled no)
				(sheetname "")
			)
			(fill
				(thermal_gap 0.5)
				(thermal_bridge_width 0.5)
				(island_removal_mode 0)
			)
			(polygon
				(pts
					(arc
						(start 229.980998 -61.999876)
						(mid 229.218998 -61.999876)
						(end 229.980998 -61.999876)
					)
				)
			)
		)
		(zone
			(layer "F.Cu")
			(hatch none 0.5)
			(connect_pads
				(clearance 0)
			)
			(min_thickness 0.25)
			(keepout
				(tracks allowed)
				(vias not_allowed)
				(pads allowed)
				(copperpour not_allowed)
				(footprints allowed)
			)
			(placement
				(enabled no)
				(sheetname "")
			)
			(fill
				(thermal_gap 0.5)
				(thermal_bridge_width 0.5)
				(island_removal_mode 0)
			)
			(polygon
				(pts
					(arc
						(start 229.980998 -60.999878)
						(mid 229.218998 -60.999878)
						(end 229.980998 -60.999878)
					)
				)
			)
		)
		(zone
			(layer "F.Cu")
			(hatch none 0.5)
			(connect_pads
				(clearance 0)
			)
			(min_thickness 0.25)
			(keepout
				(tracks allowed)
				(vias not_allowed)
				(pads allowed)
				(copperpour not_allowed)
				(footprints allowed)
			)
			(placement
				(enabled no)
				(sheetname "")
			)
			(fill
				(thermal_gap 0.5)
				(thermal_bridge_width 0.5)
				(island_removal_mode 0)
			)
			(polygon
				(pts
					(arc
						(start 229.980998 -59.99988)
						(mid 229.218998 -59.99988)
						(end 229.980998 -59.99988)
					)
				)
			)
		)
		(zone
			(layer "F.Cu")
			(hatch none 0.5)
			(connect_pads
				(clearance 0)
			)
			(min_thickness 0.25)
			(keepout
				(tracks allowed)
				(vias not_allowed)
				(pads allowed)
				(copperpour not_allowed)
				(footprints allowed)
			)
			(placement
				(enabled no)
				(sheetname "")
			)
			(fill
				(thermal_gap 0.5)
				(thermal_bridge_width 0.5)
				(island_removal_mode 0)
			)
			(polygon
				(pts
					(arc
						(start 229.980998 -58.999882)
						(mid 229.218998 -58.999882)
						(end 229.980998 -58.999882)
					)
				)
			)
		)
		(zone
			(layer "F.Cu")
			(hatch none 0.5)
			(connect_pads
				(clearance 0)
			)
			(min_thickness 0.25)
			(keepout
				(tracks allowed)
				(vias not_allowed)
				(pads allowed)
				(copperpour not_allowed)
				(footprints allowed)
			)
			(placement
				(enabled no)
				(sheetname "")
			)
			(fill
				(thermal_gap 0.5)
				(thermal_bridge_width 0.5)
				(island_removal_mode 0)
			)
			(polygon
				(pts
					(arc
						(start 229.980998 -57.999884)
						(mid 229.218998 -57.999884)
						(end 229.980998 -57.999884)
					)
				)
			)
		)
		(zone
			(layer "F.Cu")
			(hatch none 0.5)
			(connect_pads
				(clearance 0)
			)
			(min_thickness 0.25)
			(keepout
				(tracks allowed)
				(vias not_allowed)
				(pads allowed)
				(copperpour not_allowed)
				(footprints allowed)
			)
			(placement
				(enabled no)
				(sheetname "")
			)
			(fill
				(thermal_gap 0.5)
				(thermal_bridge_width 0.5)
				(island_removal_mode 0)
			)
			(polygon
				(pts
					(arc
						(start 229.980998 -56.999886)
						(mid 229.218998 -56.999886)
						(end 229.980998 -56.999886)
					)
				)
			)
		)
		(zone
			(layer "F.Cu")
			(hatch none 0.5)
			(connect_pads
				(clearance 0)
			)
			(min_thickness 0.25)
			(keepout
				(tracks allowed)
				(vias not_allowed)
				(pads allowed)
				(copperpour not_allowed)
				(footprints allowed)
			)
			(placement
				(enabled no)
				(sheetname "")
			)
			(fill
				(thermal_gap 0.5)
				(thermal_bridge_width 0.5)
				(island_removal_mode 0)
			)
			(polygon
				(pts
					(arc
						(start 229.980998 -55.999888)
						(mid 229.218998 -55.999888)
						(end 229.980998 -55.999888)
					)
				)
			)
		)
		(zone
			(layer "F.Cu")
			(hatch none 0.5)
			(connect_pads
				(clearance 0)
			)
			(min_thickness 0.25)
			(keepout
				(tracks allowed)
				(vias not_allowed)
				(pads allowed)
				(copperpour not_allowed)
				(footprints allowed)
			)
			(placement
				(enabled no)
				(sheetname "")
			)
			(fill
				(thermal_gap 0.5)
				(thermal_bridge_width 0.5)
				(island_removal_mode 0)
			)
			(polygon
				(pts
					(arc
						(start 229.980998 -54.99989)
						(mid 229.218998 -54.99989)
						(end 229.980998 -54.99989)
					)
				)
			)
		)
		(zone
			(layer "F.Cu")
			(hatch none 0.5)
			(connect_pads
				(clearance 0)
			)
			(min_thickness 0.25)
			(keepout
				(tracks allowed)
				(vias not_allowed)
				(pads allowed)
				(copperpour not_allowed)
				(footprints allowed)
			)
			(placement
				(enabled no)
				(sheetname "")
			)
			(fill
				(thermal_gap 0.5)
				(thermal_bridge_width 0.5)
				(island_removal_mode 0)
			)
			(polygon
				(pts
					(arc
						(start 229.980998 -53.999892)
						(mid 229.218998 -53.999892)
						(end 229.980998 -53.999892)
					)
				)
			)
		)
		(zone
			(layer "F.Cu")
			(hatch none 0.5)
			(connect_pads
				(clearance 0)
			)
			(min_thickness 0.25)
			(keepout
				(tracks allowed)
				(vias not_allowed)
				(pads allowed)
				(copperpour not_allowed)
				(footprints allowed)
			)
			(placement
				(enabled no)
				(sheetname "")
			)
			(fill
				(thermal_gap 0.5)
				(thermal_bridge_width 0.5)
				(island_removal_mode 0)
			)
			(polygon
				(pts
					(arc
						(start 229.980998 -52.999894)
						(mid 229.218998 -52.999894)
						(end 229.980998 -52.999894)
					)
				)
			)
		)
		(zone
			(layer "F.Cu")
			(hatch none 0.5)
			(connect_pads
				(clearance 0)
			)
			(min_thickness 0.25)
			(keepout
				(tracks allowed)
				(vias not_allowed)
				(pads allowed)
				(copperpour not_allowed)
				(footprints allowed)
			)
			(placement
				(enabled no)
				(sheetname "")
			)
			(fill
				(thermal_gap 0.5)
				(thermal_bridge_width 0.5)
				(island_removal_mode 0)
			)
			(polygon
				(pts
					(arc
						(start 229.980998 -51.999896)
						(mid 229.218998 -51.999896)
						(end 229.980998 -51.999896)
					)
				)
			)
		)
		(zone
			(layer "F.Cu")
			(hatch none 0.5)
			(connect_pads
				(clearance 0)
			)
			(min_thickness 0.25)
			(keepout
				(tracks allowed)
				(vias not_allowed)
				(pads allowed)
				(copperpour not_allowed)
				(footprints allowed)
			)
			(placement
				(enabled no)
				(sheetname "")
			)
			(fill
				(thermal_gap 0.5)
				(thermal_bridge_width 0.5)
				(island_removal_mode 0)
			)
			(polygon
				(pts
					(arc
						(start 229.980998 -50.999898)
						(mid 229.218998 -50.999898)
						(end 229.980998 -50.999898)
					)
				)
			)
		)
		(zone
			(layer "F.Cu")
			(hatch none 0.5)
			(connect_pads
				(clearance 0)
			)
			(min_thickness 0.25)
			(keepout
				(tracks allowed)
				(vias not_allowed)
				(pads allowed)
				(copperpour not_allowed)
				(footprints allowed)
			)
			(placement
				(enabled no)
				(sheetname "")
			)
			(fill
				(thermal_gap 0.5)
				(thermal_bridge_width 0.5)
				(island_removal_mode 0)
			)
			(polygon
				(pts
					(arc
						(start 229.980998 -49.9999)
						(mid 229.218998 -49.9999)
						(end 229.980998 -49.9999)
					)
				)
			)
		)
		(zone
			(layer "F.Cu")
			(hatch none 0.5)
			(connect_pads
				(clearance 0)
			)
			(min_thickness 0.25)
			(keepout
				(tracks allowed)
				(vias not_allowed)
				(pads allowed)
				(copperpour not_allowed)
				(footprints allowed)
			)
			(placement
				(enabled no)
				(sheetname "")
			)
			(fill
				(thermal_gap 0.5)
				(thermal_bridge_width 0.5)
				(island_removal_mode 0)
			)
			(polygon
				(pts
					(arc
						(start 229.980998 -48.999902)
						(mid 229.218998 -48.999902)
						(end 229.980998 -48.999902)
					)
				)
			)
		)
		(zone
			(layer "F.Cu")
			(hatch none 0.5)
			(connect_pads
				(clearance 0)
			)
			(min_thickness 0.25)
			(keepout
				(tracks allowed)
				(vias not_allowed)
				(pads allowed)
				(copperpour not_allowed)
				(footprints allowed)
			)
			(placement
				(enabled no)
				(sheetname "")
			)
			(fill
				(thermal_gap 0.5)
				(thermal_bridge_width 0.5)
				(island_removal_mode 0)
			)
			(polygon
				(pts
					(arc
						(start 229.980998 -47.999904)
						(mid 229.218998 -47.999904)
						(end 229.980998 -47.999904)
					)
				)
			)
		)
		(zone
			(layer "F.Cu")
			(hatch none 0.5)
			(connect_pads
				(clearance 0)
			)
			(min_thickness 0.25)
			(keepout
				(tracks allowed)
				(vias not_allowed)
				(pads allowed)
				(copperpour not_allowed)
				(footprints allowed)
			)
			(placement
				(enabled no)
				(sheetname "")
			)
			(fill
				(thermal_gap 0.5)
				(thermal_bridge_width 0.5)
				(island_removal_mode 0)
			)
			(polygon
				(pts
					(arc
						(start 229.980998 -46.999906)
						(mid 229.218998 -46.999906)
						(end 229.980998 -46.999906)
					)
				)
			)
		)
		(zone
			(layer "F.Cu")
			(hatch none 0.5)
			(connect_pads
				(clearance 0)
			)
			(min_thickness 0.25)
			(keepout
				(tracks allowed)
				(vias not_allowed)
				(pads allowed)
				(copperpour not_allowed)
				(footprints allowed)
			)
			(placement
				(enabled no)
				(sheetname "")
			)
			(fill
				(thermal_gap 0.5)
				(thermal_bridge_width 0.5)
				(island_removal_mode 0)
			)
			(polygon
				(pts
					(arc
						(start 229.980998 -45.999908)
						(mid 229.218998 -45.999908)
						(end 229.980998 -45.999908)
					)
				)
			)
		)
		(zone
			(layer "F.Cu")
			(hatch none 0.5)
			(connect_pads
				(clearance 0)
			)
			(min_thickness 0.25)
			(keepout
				(tracks allowed)
				(vias not_allowed)
				(pads allowed)
				(copperpour not_allowed)
				(footprints allowed)
			)
			(placement
				(enabled no)
				(sheetname "")
			)
			(fill
				(thermal_gap 0.5)
				(thermal_bridge_width 0.5)
				(island_removal_mode 0)
			)
			(polygon
				(pts
					(arc
						(start 229.980998 -44.99991)
						(mid 229.218998 -44.99991)
						(end 229.980998 -44.99991)
					)
				)
			)
		)
		(zone
			(layer "F.Cu")
			(hatch none 0.5)
			(connect_pads
				(clearance 0)
			)
			(min_thickness 0.25)
			(keepout
				(tracks allowed)
				(vias not_allowed)
				(pads allowed)
				(copperpour not_allowed)
				(footprints allowed)
			)
			(placement
				(enabled no)
				(sheetname "")
			)
			(fill
				(thermal_gap 0.5)
				(thermal_bridge_width 0.5)
				(island_removal_mode 0)
			)
			(polygon
				(pts
					(arc
						(start 229.980998 -43.999912)
						(mid 229.218998 -43.999912)
						(end 229.980998 -43.999912)
					)
				)
			)
		)
		(zone
			(layer "F.Cu")
			(hatch none 0.5)
			(connect_pads
				(clearance 0)
			)
			(min_thickness 0.25)
			(keepout
				(tracks allowed)
				(vias not_allowed)
				(pads allowed)
				(copperpour not_allowed)
				(footprints allowed)
			)
			(placement
				(enabled no)
				(sheetname "")
			)
			(fill
				(thermal_gap 0.5)
				(thermal_bridge_width 0.5)
				(island_removal_mode 0)
			)
			(polygon
				(pts
					(arc
						(start 229.980998 -42.999914)
						(mid 229.218998 -42.999914)
						(end 229.980998 -42.999914)
					)
				)
			)
		)
		(zone
			(layer "F.Cu")
			(hatch none 0.5)
			(connect_pads
				(clearance 0)
			)
			(min_thickness 0.25)
			(keepout
				(tracks allowed)
				(vias not_allowed)
				(pads allowed)
				(copperpour not_allowed)
				(footprints allowed)
			)
			(placement
				(enabled no)
				(sheetname "")
			)
			(fill
				(thermal_gap 0.5)
				(thermal_bridge_width 0.5)
				(island_removal_mode 0)
			)
			(polygon
				(pts
					(arc
						(start 229.980998 -41.999916)
						(mid 229.218998 -41.999916)
						(end 229.980998 -41.999916)
					)
				)
			)
		)
		(zone
			(layer "F.Cu")
			(hatch none 0.5)
			(connect_pads
				(clearance 0)
			)
			(min_thickness 0.25)
			(keepout
				(tracks allowed)
				(vias not_allowed)
				(pads allowed)
				(copperpour not_allowed)
				(footprints allowed)
			)
			(placement
				(enabled no)
				(sheetname "")
			)
			(fill
				(thermal_gap 0.5)
				(thermal_bridge_width 0.5)
				(island_removal_mode 0)
			)
			(polygon
				(pts
					(arc
						(start 229.980998 -40.999918)
						(mid 229.218998 -40.999918)
						(end 229.980998 -40.999918)
					)
				)
			)
		)
		(zone
			(layer "F.Cu")
			(hatch none 0.5)
			(connect_pads
				(clearance 0)
			)
			(min_thickness 0.25)
			(keepout
				(tracks allowed)
				(vias not_allowed)
				(pads allowed)
				(copperpour not_allowed)
				(footprints allowed)
			)
			(placement
				(enabled no)
				(sheetname "")
			)
			(fill
				(thermal_gap 0.5)
				(thermal_bridge_width 0.5)
				(island_removal_mode 0)
			)
			(polygon
				(pts
					(arc
						(start 229.980998 -39.99992)
						(mid 229.218998 -39.99992)
						(end 229.980998 -39.99992)
					)
				)
			)
		)
		(zone
			(layer "F.Cu")
			(hatch none 0.5)
			(connect_pads
				(clearance 0)
			)
			(min_thickness 0.25)
			(keepout
				(tracks allowed)
				(vias not_allowed)
				(pads allowed)
				(copperpour not_allowed)
				(footprints allowed)
			)
			(placement
				(enabled no)
				(sheetname "")
			)
			(fill
				(thermal_gap 0.5)
				(thermal_bridge_width 0.5)
				(island_removal_mode 0)
			)
			(polygon
				(pts
					(arc
						(start 229.980998 -38.999922)
						(mid 229.218998 -38.999922)
						(end 229.980998 -38.999922)
					)
				)
			)
		)
		(zone
			(layer "F.Cu")
			(hatch none 0.5)
			(connect_pads
				(clearance 0)
			)
			(min_thickness 0.25)
			(keepout
				(tracks allowed)
				(vias not_allowed)
				(pads allowed)
				(copperpour not_allowed)
				(footprints allowed)
			)
			(placement
				(enabled no)
				(sheetname "")
			)
			(fill
				(thermal_gap 0.5)
				(thermal_bridge_width 0.5)
				(island_removal_mode 0)
			)
			(polygon
				(pts
					(arc
						(start 229.980998 -37.999924)
						(mid 229.218998 -37.999924)
						(end 229.980998 -37.999924)
					)
				)
			)
		)
		(zone
			(layer "F.Cu")
			(hatch none 0.5)
			(connect_pads
				(clearance 0)
			)
			(min_thickness 0.25)
			(keepout
				(tracks allowed)
				(vias not_allowed)
				(pads allowed)
				(copperpour not_allowed)
				(footprints allowed)
			)
			(placement
				(enabled no)
				(sheetname "")
			)
			(fill
				(thermal_gap 0.5)
				(thermal_bridge_width 0.5)
				(island_removal_mode 0)
			)
			(polygon
				(pts
					(arc
						(start 229.980998 -36.999926)
						(mid 229.218998 -36.999926)
						(end 229.980998 -36.999926)
					)
				)
			)
		)
		(zone
			(layer "F.Cu")
			(hatch none 0.5)
			(connect_pads
				(clearance 0)
			)
			(min_thickness 0.25)
			(keepout
				(tracks allowed)
				(vias not_allowed)
				(pads allowed)
				(copperpour not_allowed)
				(footprints allowed)
			)
			(placement
				(enabled no)
				(sheetname "")
			)
			(fill
				(thermal_gap 0.5)
				(thermal_bridge_width 0.5)
				(island_removal_mode 0)
			)
			(polygon
				(pts
					(arc
						(start 229.980998 -35.999928)
						(mid 229.218998 -35.999928)
						(end 229.980998 -35.999928)
					)
				)
			)
		)
		(zone
			(layer "F.Cu")
			(hatch none 0.5)
			(connect_pads
				(clearance 0)
			)
			(min_thickness 0.25)
			(keepout
				(tracks allowed)
				(vias not_allowed)
				(pads allowed)
				(copperpour not_allowed)
				(footprints allowed)
			)
			(placement
				(enabled no)
				(sheetname "")
			)
			(fill
				(thermal_gap 0.5)
				(thermal_bridge_width 0.5)
				(island_removal_mode 0)
			)
			(polygon
				(pts
					(arc
						(start 229.980998 -34.99993)
						(mid 229.218998 -34.99993)
						(end 229.980998 -34.99993)
					)
				)
			)
		)
		(zone
			(layer "F.Cu")
			(hatch none 0.5)
			(connect_pads
				(clearance 0)
			)
			(min_thickness 0.25)
			(keepout
				(tracks allowed)
				(vias not_allowed)
				(pads allowed)
				(copperpour not_allowed)
				(footprints allowed)
			)
			(placement
				(enabled no)
				(sheetname "")
			)
			(fill
				(thermal_gap 0.5)
				(thermal_bridge_width 0.5)
				(island_removal_mode 0)
			)
			(polygon
				(pts
					(arc
						(start 229.980998 -33.999932)
						(mid 229.218998 -33.999932)
						(end 229.980998 -33.999932)
					)
				)
			)
		)
		(zone
			(layer "F.Cu")
			(hatch none 0.5)
			(connect_pads
				(clearance 0)
			)
			(min_thickness 0.25)
			(keepout
				(tracks allowed)
				(vias not_allowed)
				(pads allowed)
				(copperpour not_allowed)
				(footprints allowed)
			)
			(placement
				(enabled no)
				(sheetname "")
			)
			(fill
				(thermal_gap 0.5)
				(thermal_bridge_width 0.5)
				(island_removal_mode 0)
			)
			(polygon
				(pts
					(arc
						(start 229.980998 -32.999934)
						(mid 229.218998 -32.999934)
						(end 229.980998 -32.999934)
					)
				)
			)
		)
		(zone
			(layer "F.Cu")
			(hatch none 0.5)
			(connect_pads
				(clearance 0)
			)
			(min_thickness 0.25)
			(keepout
				(tracks allowed)
				(vias not_allowed)
				(pads allowed)
				(copperpour not_allowed)
				(footprints allowed)
			)
			(placement
				(enabled no)
				(sheetname "")
			)
			(fill
				(thermal_gap 0.5)
				(thermal_bridge_width 0.5)
				(island_removal_mode 0)
			)
			(polygon
				(pts
					(arc
						(start 229.980998 -31.999936)
						(mid 229.218998 -31.999936)
						(end 229.980998 -31.999936)
					)
				)
			)
		)
		(zone
			(layer "F.Cu")
			(hatch none 0.5)
			(connect_pads
				(clearance 0)
			)
			(min_thickness 0.25)
			(keepout
				(tracks allowed)
				(vias not_allowed)
				(pads allowed)
				(copperpour not_allowed)
				(footprints allowed)
			)
			(placement
				(enabled no)
				(sheetname "")
			)
			(fill
				(thermal_gap 0.5)
				(thermal_bridge_width 0.5)
				(island_removal_mode 0)
			)
			(polygon
				(pts
					(arc
						(start 229.980998 -30.999938)
						(mid 229.218998 -30.999938)
						(end 229.980998 -30.999938)
					)
				)
			)
		)
		(zone
			(layer "F.Cu")
			(hatch none 0.5)
			(connect_pads
				(clearance 0)
			)
			(min_thickness 0.25)
			(keepout
				(tracks allowed)
				(vias not_allowed)
				(pads allowed)
				(copperpour not_allowed)
				(footprints allowed)
			)
			(placement
				(enabled no)
				(sheetname "")
			)
			(fill
				(thermal_gap 0.5)
				(thermal_bridge_width 0.5)
				(island_removal_mode 0)
			)
			(polygon
				(pts
					(arc
						(start 229.980998 -29.99994)
						(mid 229.218998 -29.99994)
						(end 229.980998 -29.99994)
					)
				)
			)
		)
		(zone
			(layer "F.Cu")
			(hatch none 0.5)
			(connect_pads
				(clearance 0)
			)
			(min_thickness 0.25)
			(keepout
				(tracks allowed)
				(vias not_allowed)
				(pads allowed)
				(copperpour not_allowed)
				(footprints allowed)
			)
			(placement
				(enabled no)
				(sheetname "")
			)
			(fill
				(thermal_gap 0.5)
				(thermal_bridge_width 0.5)
				(island_removal_mode 0)
			)
			(polygon
				(pts
					(arc
						(start 230.980996 -64.99987)
						(mid 230.218996 -64.99987)
						(end 230.980996 -64.99987)
					)
				)
			)
		)
		(zone
			(layer "F.Cu")
			(hatch none 0.5)
			(connect_pads
				(clearance 0)
			)
			(min_thickness 0.25)
			(keepout
				(tracks allowed)
				(vias not_allowed)
				(pads allowed)
				(copperpour not_allowed)
				(footprints allowed)
			)
			(placement
				(enabled no)
				(sheetname "")
			)
			(fill
				(thermal_gap 0.5)
				(thermal_bridge_width 0.5)
				(island_removal_mode 0)
			)
			(polygon
				(pts
					(arc
						(start 230.980996 -63.999872)
						(mid 230.218996 -63.999872)
						(end 230.980996 -63.999872)
					)
				)
			)
		)
		(zone
			(layer "F.Cu")
			(hatch none 0.5)
			(connect_pads
				(clearance 0)
			)
			(min_thickness 0.25)
			(keepout
				(tracks allowed)
				(vias not_allowed)
				(pads allowed)
				(copperpour not_allowed)
				(footprints allowed)
			)
			(placement
				(enabled no)
				(sheetname "")
			)
			(fill
				(thermal_gap 0.5)
				(thermal_bridge_width 0.5)
				(island_removal_mode 0)
			)
			(polygon
				(pts
					(arc
						(start 230.980996 -62.999874)
						(mid 230.218996 -62.999874)
						(end 230.980996 -62.999874)
					)
				)
			)
		)
		(zone
			(layer "F.Cu")
			(hatch none 0.5)
			(connect_pads
				(clearance 0)
			)
			(min_thickness 0.25)
			(keepout
				(tracks allowed)
				(vias not_allowed)
				(pads allowed)
				(copperpour not_allowed)
				(footprints allowed)
			)
			(placement
				(enabled no)
				(sheetname "")
			)
			(fill
				(thermal_gap 0.5)
				(thermal_bridge_width 0.5)
				(island_removal_mode 0)
			)
			(polygon
				(pts
					(arc
						(start 230.980996 -61.999876)
						(mid 230.218996 -61.999876)
						(end 230.980996 -61.999876)
					)
				)
			)
		)
		(zone
			(layer "F.Cu")
			(hatch none 0.5)
			(connect_pads
				(clearance 0)
			)
			(min_thickness 0.25)
			(keepout
				(tracks allowed)
				(vias not_allowed)
				(pads allowed)
				(copperpour not_allowed)
				(footprints allowed)
			)
			(placement
				(enabled no)
				(sheetname "")
			)
			(fill
				(thermal_gap 0.5)
				(thermal_bridge_width 0.5)
				(island_removal_mode 0)
			)
			(polygon
				(pts
					(arc
						(start 230.980996 -60.999878)
						(mid 230.218996 -60.999878)
						(end 230.980996 -60.999878)
					)
				)
			)
		)
		(zone
			(layer "F.Cu")
			(hatch none 0.5)
			(connect_pads
				(clearance 0)
			)
			(min_thickness 0.25)
			(keepout
				(tracks allowed)
				(vias not_allowed)
				(pads allowed)
				(copperpour not_allowed)
				(footprints allowed)
			)
			(placement
				(enabled no)
				(sheetname "")
			)
			(fill
				(thermal_gap 0.5)
				(thermal_bridge_width 0.5)
				(island_removal_mode 0)
			)
			(polygon
				(pts
					(arc
						(start 230.980996 -59.99988)
						(mid 230.218996 -59.99988)
						(end 230.980996 -59.99988)
					)
				)
			)
		)
		(zone
			(layer "F.Cu")
			(hatch none 0.5)
			(connect_pads
				(clearance 0)
			)
			(min_thickness 0.25)
			(keepout
				(tracks allowed)
				(vias not_allowed)
				(pads allowed)
				(copperpour not_allowed)
				(footprints allowed)
			)
			(placement
				(enabled no)
				(sheetname "")
			)
			(fill
				(thermal_gap 0.5)
				(thermal_bridge_width 0.5)
				(island_removal_mode 0)
			)
			(polygon
				(pts
					(arc
						(start 230.980996 -58.999882)
						(mid 230.218996 -58.999882)
						(end 230.980996 -58.999882)
					)
				)
			)
		)
		(zone
			(layer "F.Cu")
			(hatch none 0.5)
			(connect_pads
				(clearance 0)
			)
			(min_thickness 0.25)
			(keepout
				(tracks allowed)
				(vias not_allowed)
				(pads allowed)
				(copperpour not_allowed)
				(footprints allowed)
			)
			(placement
				(enabled no)
				(sheetname "")
			)
			(fill
				(thermal_gap 0.5)
				(thermal_bridge_width 0.5)
				(island_removal_mode 0)
			)
			(polygon
				(pts
					(arc
						(start 230.980996 -57.999884)
						(mid 230.218996 -57.999884)
						(end 230.980996 -57.999884)
					)
				)
			)
		)
		(zone
			(layer "F.Cu")
			(hatch none 0.5)
			(connect_pads
				(clearance 0)
			)
			(min_thickness 0.25)
			(keepout
				(tracks allowed)
				(vias not_allowed)
				(pads allowed)
				(copperpour not_allowed)
				(footprints allowed)
			)
			(placement
				(enabled no)
				(sheetname "")
			)
			(fill
				(thermal_gap 0.5)
				(thermal_bridge_width 0.5)
				(island_removal_mode 0)
			)
			(polygon
				(pts
					(arc
						(start 230.980996 -56.999886)
						(mid 230.218996 -56.999886)
						(end 230.980996 -56.999886)
					)
				)
			)
		)
		(zone
			(layer "F.Cu")
			(hatch none 0.5)
			(connect_pads
				(clearance 0)
			)
			(min_thickness 0.25)
			(keepout
				(tracks allowed)
				(vias not_allowed)
				(pads allowed)
				(copperpour not_allowed)
				(footprints allowed)
			)
			(placement
				(enabled no)
				(sheetname "")
			)
			(fill
				(thermal_gap 0.5)
				(thermal_bridge_width 0.5)
				(island_removal_mode 0)
			)
			(polygon
				(pts
					(arc
						(start 230.980996 -55.999888)
						(mid 230.218996 -55.999888)
						(end 230.980996 -55.999888)
					)
				)
			)
		)
		(zone
			(layer "F.Cu")
			(hatch none 0.5)
			(connect_pads
				(clearance 0)
			)
			(min_thickness 0.25)
			(keepout
				(tracks allowed)
				(vias not_allowed)
				(pads allowed)
				(copperpour not_allowed)
				(footprints allowed)
			)
			(placement
				(enabled no)
				(sheetname "")
			)
			(fill
				(thermal_gap 0.5)
				(thermal_bridge_width 0.5)
				(island_removal_mode 0)
			)
			(polygon
				(pts
					(arc
						(start 230.980996 -54.99989)
						(mid 230.218996 -54.99989)
						(end 230.980996 -54.99989)
					)
				)
			)
		)
		(zone
			(layer "F.Cu")
			(hatch none 0.5)
			(connect_pads
				(clearance 0)
			)
			(min_thickness 0.25)
			(keepout
				(tracks allowed)
				(vias not_allowed)
				(pads allowed)
				(copperpour not_allowed)
				(footprints allowed)
			)
			(placement
				(enabled no)
				(sheetname "")
			)
			(fill
				(thermal_gap 0.5)
				(thermal_bridge_width 0.5)
				(island_removal_mode 0)
			)
			(polygon
				(pts
					(arc
						(start 230.980996 -53.999892)
						(mid 230.218996 -53.999892)
						(end 230.980996 -53.999892)
					)
				)
			)
		)
		(zone
			(layer "F.Cu")
			(hatch none 0.5)
			(connect_pads
				(clearance 0)
			)
			(min_thickness 0.25)
			(keepout
				(tracks allowed)
				(vias not_allowed)
				(pads allowed)
				(copperpour not_allowed)
				(footprints allowed)
			)
			(placement
				(enabled no)
				(sheetname "")
			)
			(fill
				(thermal_gap 0.5)
				(thermal_bridge_width 0.5)
				(island_removal_mode 0)
			)
			(polygon
				(pts
					(arc
						(start 230.980996 -52.999894)
						(mid 230.218996 -52.999894)
						(end 230.980996 -52.999894)
					)
				)
			)
		)
		(zone
			(layer "F.Cu")
			(hatch none 0.5)
			(connect_pads
				(clearance 0)
			)
			(min_thickness 0.25)
			(keepout
				(tracks allowed)
				(vias not_allowed)
				(pads allowed)
				(copperpour not_allowed)
				(footprints allowed)
			)
			(placement
				(enabled no)
				(sheetname "")
			)
			(fill
				(thermal_gap 0.5)
				(thermal_bridge_width 0.5)
				(island_removal_mode 0)
			)
			(polygon
				(pts
					(arc
						(start 230.980996 -51.999896)
						(mid 230.218996 -51.999896)
						(end 230.980996 -51.999896)
					)
				)
			)
		)
		(zone
			(layer "F.Cu")
			(hatch none 0.5)
			(connect_pads
				(clearance 0)
			)
			(min_thickness 0.25)
			(keepout
				(tracks allowed)
				(vias not_allowed)
				(pads allowed)
				(copperpour not_allowed)
				(footprints allowed)
			)
			(placement
				(enabled no)
				(sheetname "")
			)
			(fill
				(thermal_gap 0.5)
				(thermal_bridge_width 0.5)
				(island_removal_mode 0)
			)
			(polygon
				(pts
					(arc
						(start 230.980996 -50.999898)
						(mid 230.218996 -50.999898)
						(end 230.980996 -50.999898)
					)
				)
			)
		)
		(zone
			(layer "F.Cu")
			(hatch none 0.5)
			(connect_pads
				(clearance 0)
			)
			(min_thickness 0.25)
			(keepout
				(tracks allowed)
				(vias not_allowed)
				(pads allowed)
				(copperpour not_allowed)
				(footprints allowed)
			)
			(placement
				(enabled no)
				(sheetname "")
			)
			(fill
				(thermal_gap 0.5)
				(thermal_bridge_width 0.5)
				(island_removal_mode 0)
			)
			(polygon
				(pts
					(arc
						(start 230.980996 -49.9999)
						(mid 230.218996 -49.9999)
						(end 230.980996 -49.9999)
					)
				)
			)
		)
		(zone
			(layer "F.Cu")
			(hatch none 0.5)
			(connect_pads
				(clearance 0)
			)
			(min_thickness 0.25)
			(keepout
				(tracks allowed)
				(vias not_allowed)
				(pads allowed)
				(copperpour not_allowed)
				(footprints allowed)
			)
			(placement
				(enabled no)
				(sheetname "")
			)
			(fill
				(thermal_gap 0.5)
				(thermal_bridge_width 0.5)
				(island_removal_mode 0)
			)
			(polygon
				(pts
					(arc
						(start 230.980996 -48.999902)
						(mid 230.218996 -48.999902)
						(end 230.980996 -48.999902)
					)
				)
			)
		)
		(zone
			(layer "F.Cu")
			(hatch none 0.5)
			(connect_pads
				(clearance 0)
			)
			(min_thickness 0.25)
			(keepout
				(tracks allowed)
				(vias not_allowed)
				(pads allowed)
				(copperpour not_allowed)
				(footprints allowed)
			)
			(placement
				(enabled no)
				(sheetname "")
			)
			(fill
				(thermal_gap 0.5)
				(thermal_bridge_width 0.5)
				(island_removal_mode 0)
			)
			(polygon
				(pts
					(arc
						(start 230.980996 -47.999904)
						(mid 230.218996 -47.999904)
						(end 230.980996 -47.999904)
					)
				)
			)
		)
		(zone
			(layer "F.Cu")
			(hatch none 0.5)
			(connect_pads
				(clearance 0)
			)
			(min_thickness 0.25)
			(keepout
				(tracks allowed)
				(vias not_allowed)
				(pads allowed)
				(copperpour not_allowed)
				(footprints allowed)
			)
			(placement
				(enabled no)
				(sheetname "")
			)
			(fill
				(thermal_gap 0.5)
				(thermal_bridge_width 0.5)
				(island_removal_mode 0)
			)
			(polygon
				(pts
					(arc
						(start 230.980996 -46.999906)
						(mid 230.218996 -46.999906)
						(end 230.980996 -46.999906)
					)
				)
			)
		)
		(zone
			(layer "F.Cu")
			(hatch none 0.5)
			(connect_pads
				(clearance 0)
			)
			(min_thickness 0.25)
			(keepout
				(tracks allowed)
				(vias not_allowed)
				(pads allowed)
				(copperpour not_allowed)
				(footprints allowed)
			)
			(placement
				(enabled no)
				(sheetname "")
			)
			(fill
				(thermal_gap 0.5)
				(thermal_bridge_width 0.5)
				(island_removal_mode 0)
			)
			(polygon
				(pts
					(arc
						(start 230.980996 -45.999908)
						(mid 230.218996 -45.999908)
						(end 230.980996 -45.999908)
					)
				)
			)
		)
		(zone
			(layer "F.Cu")
			(hatch none 0.5)
			(connect_pads
				(clearance 0)
			)
			(min_thickness 0.25)
			(keepout
				(tracks allowed)
				(vias not_allowed)
				(pads allowed)
				(copperpour not_allowed)
				(footprints allowed)
			)
			(placement
				(enabled no)
				(sheetname "")
			)
			(fill
				(thermal_gap 0.5)
				(thermal_bridge_width 0.5)
				(island_removal_mode 0)
			)
			(polygon
				(pts
					(arc
						(start 230.980996 -44.99991)
						(mid 230.218996 -44.99991)
						(end 230.980996 -44.99991)
					)
				)
			)
		)
		(zone
			(layer "F.Cu")
			(hatch none 0.5)
			(connect_pads
				(clearance 0)
			)
			(min_thickness 0.25)
			(keepout
				(tracks allowed)
				(vias not_allowed)
				(pads allowed)
				(copperpour not_allowed)
				(footprints allowed)
			)
			(placement
				(enabled no)
				(sheetname "")
			)
			(fill
				(thermal_gap 0.5)
				(thermal_bridge_width 0.5)
				(island_removal_mode 0)
			)
			(polygon
				(pts
					(arc
						(start 230.980996 -43.999912)
						(mid 230.218996 -43.999912)
						(end 230.980996 -43.999912)
					)
				)
			)
		)
		(zone
			(layer "F.Cu")
			(hatch none 0.5)
			(connect_pads
				(clearance 0)
			)
			(min_thickness 0.25)
			(keepout
				(tracks allowed)
				(vias not_allowed)
				(pads allowed)
				(copperpour not_allowed)
				(footprints allowed)
			)
			(placement
				(enabled no)
				(sheetname "")
			)
			(fill
				(thermal_gap 0.5)
				(thermal_bridge_width 0.5)
				(island_removal_mode 0)
			)
			(polygon
				(pts
					(arc
						(start 230.980996 -42.999914)
						(mid 230.218996 -42.999914)
						(end 230.980996 -42.999914)
					)
				)
			)
		)
		(zone
			(layer "F.Cu")
			(hatch none 0.5)
			(connect_pads
				(clearance 0)
			)
			(min_thickness 0.25)
			(keepout
				(tracks allowed)
				(vias not_allowed)
				(pads allowed)
				(copperpour not_allowed)
				(footprints allowed)
			)
			(placement
				(enabled no)
				(sheetname "")
			)
			(fill
				(thermal_gap 0.5)
				(thermal_bridge_width 0.5)
				(island_removal_mode 0)
			)
			(polygon
				(pts
					(arc
						(start 230.980996 -41.999916)
						(mid 230.218996 -41.999916)
						(end 230.980996 -41.999916)
					)
				)
			)
		)
		(zone
			(layer "F.Cu")
			(hatch none 0.5)
			(connect_pads
				(clearance 0)
			)
			(min_thickness 0.25)
			(keepout
				(tracks allowed)
				(vias not_allowed)
				(pads allowed)
				(copperpour not_allowed)
				(footprints allowed)
			)
			(placement
				(enabled no)
				(sheetname "")
			)
			(fill
				(thermal_gap 0.5)
				(thermal_bridge_width 0.5)
				(island_removal_mode 0)
			)
			(polygon
				(pts
					(arc
						(start 230.980996 -40.999918)
						(mid 230.218996 -40.999918)
						(end 230.980996 -40.999918)
					)
				)
			)
		)
		(zone
			(layer "F.Cu")
			(hatch none 0.5)
			(connect_pads
				(clearance 0)
			)
			(min_thickness 0.25)
			(keepout
				(tracks allowed)
				(vias not_allowed)
				(pads allowed)
				(copperpour not_allowed)
				(footprints allowed)
			)
			(placement
				(enabled no)
				(sheetname "")
			)
			(fill
				(thermal_gap 0.5)
				(thermal_bridge_width 0.5)
				(island_removal_mode 0)
			)
			(polygon
				(pts
					(arc
						(start 230.980996 -39.99992)
						(mid 230.218996 -39.99992)
						(end 230.980996 -39.99992)
					)
				)
			)
		)
		(zone
			(layer "F.Cu")
			(hatch none 0.5)
			(connect_pads
				(clearance 0)
			)
			(min_thickness 0.25)
			(keepout
				(tracks allowed)
				(vias not_allowed)
				(pads allowed)
				(copperpour not_allowed)
				(footprints allowed)
			)
			(placement
				(enabled no)
				(sheetname "")
			)
			(fill
				(thermal_gap 0.5)
				(thermal_bridge_width 0.5)
				(island_removal_mode 0)
			)
			(polygon
				(pts
					(arc
						(start 230.980996 -38.999922)
						(mid 230.218996 -38.999922)
						(end 230.980996 -38.999922)
					)
				)
			)
		)
		(zone
			(layer "F.Cu")
			(hatch none 0.5)
			(connect_pads
				(clearance 0)
			)
			(min_thickness 0.25)
			(keepout
				(tracks allowed)
				(vias not_allowed)
				(pads allowed)
				(copperpour not_allowed)
				(footprints allowed)
			)
			(placement
				(enabled no)
				(sheetname "")
			)
			(fill
				(thermal_gap 0.5)
				(thermal_bridge_width 0.5)
				(island_removal_mode 0)
			)
			(polygon
				(pts
					(arc
						(start 230.980996 -37.999924)
						(mid 230.218996 -37.999924)
						(end 230.980996 -37.999924)
					)
				)
			)
		)
		(zone
			(layer "F.Cu")
			(hatch none 0.5)
			(connect_pads
				(clearance 0)
			)
			(min_thickness 0.25)
			(keepout
				(tracks allowed)
				(vias not_allowed)
				(pads allowed)
				(copperpour not_allowed)
				(footprints allowed)
			)
			(placement
				(enabled no)
				(sheetname "")
			)
			(fill
				(thermal_gap 0.5)
				(thermal_bridge_width 0.5)
				(island_removal_mode 0)
			)
			(polygon
				(pts
					(arc
						(start 230.980996 -36.999926)
						(mid 230.218996 -36.999926)
						(end 230.980996 -36.999926)
					)
				)
			)
		)
		(zone
			(layer "F.Cu")
			(hatch none 0.5)
			(connect_pads
				(clearance 0)
			)
			(min_thickness 0.25)
			(keepout
				(tracks allowed)
				(vias not_allowed)
				(pads allowed)
				(copperpour not_allowed)
				(footprints allowed)
			)
			(placement
				(enabled no)
				(sheetname "")
			)
			(fill
				(thermal_gap 0.5)
				(thermal_bridge_width 0.5)
				(island_removal_mode 0)
			)
			(polygon
				(pts
					(arc
						(start 230.980996 -35.999928)
						(mid 230.218996 -35.999928)
						(end 230.980996 -35.999928)
					)
				)
			)
		)
		(zone
			(layer "F.Cu")
			(hatch none 0.5)
			(connect_pads
				(clearance 0)
			)
			(min_thickness 0.25)
			(keepout
				(tracks allowed)
				(vias not_allowed)
				(pads allowed)
				(copperpour not_allowed)
				(footprints allowed)
			)
			(placement
				(enabled no)
				(sheetname "")
			)
			(fill
				(thermal_gap 0.5)
				(thermal_bridge_width 0.5)
				(island_removal_mode 0)
			)
			(polygon
				(pts
					(arc
						(start 230.980996 -34.99993)
						(mid 230.218996 -34.99993)
						(end 230.980996 -34.99993)
					)
				)
			)
		)
		(zone
			(layer "F.Cu")
			(hatch none 0.5)
			(connect_pads
				(clearance 0)
			)
			(min_thickness 0.25)
			(keepout
				(tracks allowed)
				(vias not_allowed)
				(pads allowed)
				(copperpour not_allowed)
				(footprints allowed)
			)
			(placement
				(enabled no)
				(sheetname "")
			)
			(fill
				(thermal_gap 0.5)
				(thermal_bridge_width 0.5)
				(island_removal_mode 0)
			)
			(polygon
				(pts
					(arc
						(start 230.980996 -33.999932)
						(mid 230.218996 -33.999932)
						(end 230.980996 -33.999932)
					)
				)
			)
		)
		(zone
			(layer "F.Cu")
			(hatch none 0.5)
			(connect_pads
				(clearance 0)
			)
			(min_thickness 0.25)
			(keepout
				(tracks allowed)
				(vias not_allowed)
				(pads allowed)
				(copperpour not_allowed)
				(footprints allowed)
			)
			(placement
				(enabled no)
				(sheetname "")
			)
			(fill
				(thermal_gap 0.5)
				(thermal_bridge_width 0.5)
				(island_removal_mode 0)
			)
			(polygon
				(pts
					(arc
						(start 230.980996 -32.999934)
						(mid 230.218996 -32.999934)
						(end 230.980996 -32.999934)
					)
				)
			)
		)
		(zone
			(layer "F.Cu")
			(hatch none 0.5)
			(connect_pads
				(clearance 0)
			)
			(min_thickness 0.25)
			(keepout
				(tracks allowed)
				(vias not_allowed)
				(pads allowed)
				(copperpour not_allowed)
				(footprints allowed)
			)
			(placement
				(enabled no)
				(sheetname "")
			)
			(fill
				(thermal_gap 0.5)
				(thermal_bridge_width 0.5)
				(island_removal_mode 0)
			)
			(polygon
				(pts
					(arc
						(start 230.980996 -31.999936)
						(mid 230.218996 -31.999936)
						(end 230.980996 -31.999936)
					)
				)
			)
		)
		(zone
			(layer "F.Cu")
			(hatch none 0.5)
			(connect_pads
				(clearance 0)
			)
			(min_thickness 0.25)
			(keepout
				(tracks allowed)
				(vias not_allowed)
				(pads allowed)
				(copperpour not_allowed)
				(footprints allowed)
			)
			(placement
				(enabled no)
				(sheetname "")
			)
			(fill
				(thermal_gap 0.5)
				(thermal_bridge_width 0.5)
				(island_removal_mode 0)
			)
			(polygon
				(pts
					(arc
						(start 230.980996 -30.999938)
						(mid 230.218996 -30.999938)
						(end 230.980996 -30.999938)
					)
				)
			)
		)
		(zone
			(layer "F.Cu")
			(hatch none 0.5)
			(connect_pads
				(clearance 0)
			)
			(min_thickness 0.25)
			(keepout
				(tracks allowed)
				(vias not_allowed)
				(pads allowed)
				(copperpour not_allowed)
				(footprints allowed)
			)
			(placement
				(enabled no)
				(sheetname "")
			)
			(fill
				(thermal_gap 0.5)
				(thermal_bridge_width 0.5)
				(island_removal_mode 0)
			)
			(polygon
				(pts
					(arc
						(start 230.980996 -29.99994)
						(mid 230.218996 -29.99994)
						(end 230.980996 -29.99994)
					)
				)
			)
		)
		(zone
			(layer "F.Cu")
			(hatch none 0.5)
			(connect_pads
				(clearance 0)
			)
			(min_thickness 0.25)
			(keepout
				(tracks allowed)
				(vias not_allowed)
				(pads allowed)
				(copperpour not_allowed)
				(footprints allowed)
			)
			(placement
				(enabled no)
				(sheetname "")
			)
			(fill
				(thermal_gap 0.5)
				(thermal_bridge_width 0.5)
				(island_removal_mode 0)
			)
			(polygon
				(pts
					(arc
						(start 231.980994 -65.999868)
						(mid 231.218994 -65.999868)
						(end 231.980994 -65.999868)
					)
				)
			)
		)
		(zone
			(layer "F.Cu")
			(hatch none 0.5)
			(connect_pads
				(clearance 0)
			)
			(min_thickness 0.25)
			(keepout
				(tracks allowed)
				(vias not_allowed)
				(pads allowed)
				(copperpour not_allowed)
				(footprints allowed)
			)
			(placement
				(enabled no)
				(sheetname "")
			)
			(fill
				(thermal_gap 0.5)
				(thermal_bridge_width 0.5)
				(island_removal_mode 0)
			)
			(polygon
				(pts
					(arc
						(start 231.980994 -64.99987)
						(mid 231.218994 -64.99987)
						(end 231.980994 -64.99987)
					)
				)
			)
		)
		(zone
			(layer "F.Cu")
			(hatch none 0.5)
			(connect_pads
				(clearance 0)
			)
			(min_thickness 0.25)
			(keepout
				(tracks allowed)
				(vias not_allowed)
				(pads allowed)
				(copperpour not_allowed)
				(footprints allowed)
			)
			(placement
				(enabled no)
				(sheetname "")
			)
			(fill
				(thermal_gap 0.5)
				(thermal_bridge_width 0.5)
				(island_removal_mode 0)
			)
			(polygon
				(pts
					(arc
						(start 231.980994 -63.999872)
						(mid 231.218994 -63.999872)
						(end 231.980994 -63.999872)
					)
				)
			)
		)
		(zone
			(layer "F.Cu")
			(hatch none 0.5)
			(connect_pads
				(clearance 0)
			)
			(min_thickness 0.25)
			(keepout
				(tracks allowed)
				(vias not_allowed)
				(pads allowed)
				(copperpour not_allowed)
				(footprints allowed)
			)
			(placement
				(enabled no)
				(sheetname "")
			)
			(fill
				(thermal_gap 0.5)
				(thermal_bridge_width 0.5)
				(island_removal_mode 0)
			)
			(polygon
				(pts
					(arc
						(start 231.980994 -62.999874)
						(mid 231.218994 -62.999874)
						(end 231.980994 -62.999874)
					)
				)
			)
		)
		(zone
			(layer "F.Cu")
			(hatch none 0.5)
			(connect_pads
				(clearance 0)
			)
			(min_thickness 0.25)
			(keepout
				(tracks allowed)
				(vias not_allowed)
				(pads allowed)
				(copperpour not_allowed)
				(footprints allowed)
			)
			(placement
				(enabled no)
				(sheetname "")
			)
			(fill
				(thermal_gap 0.5)
				(thermal_bridge_width 0.5)
				(island_removal_mode 0)
			)
			(polygon
				(pts
					(arc
						(start 231.980994 -61.999876)
						(mid 231.218994 -61.999876)
						(end 231.980994 -61.999876)
					)
				)
			)
		)
		(zone
			(layer "F.Cu")
			(hatch none 0.5)
			(connect_pads
				(clearance 0)
			)
			(min_thickness 0.25)
			(keepout
				(tracks allowed)
				(vias not_allowed)
				(pads allowed)
				(copperpour not_allowed)
				(footprints allowed)
			)
			(placement
				(enabled no)
				(sheetname "")
			)
			(fill
				(thermal_gap 0.5)
				(thermal_bridge_width 0.5)
				(island_removal_mode 0)
			)
			(polygon
				(pts
					(arc
						(start 231.980994 -60.999878)
						(mid 231.218994 -60.999878)
						(end 231.980994 -60.999878)
					)
				)
			)
		)
		(zone
			(layer "F.Cu")
			(hatch none 0.5)
			(connect_pads
				(clearance 0)
			)
			(min_thickness 0.25)
			(keepout
				(tracks allowed)
				(vias not_allowed)
				(pads allowed)
				(copperpour not_allowed)
				(footprints allowed)
			)
			(placement
				(enabled no)
				(sheetname "")
			)
			(fill
				(thermal_gap 0.5)
				(thermal_bridge_width 0.5)
				(island_removal_mode 0)
			)
			(polygon
				(pts
					(arc
						(start 231.980994 -59.99988)
						(mid 231.218994 -59.99988)
						(end 231.980994 -59.99988)
					)
				)
			)
		)
		(zone
			(layer "F.Cu")
			(hatch none 0.5)
			(connect_pads
				(clearance 0)
			)
			(min_thickness 0.25)
			(keepout
				(tracks allowed)
				(vias not_allowed)
				(pads allowed)
				(copperpour not_allowed)
				(footprints allowed)
			)
			(placement
				(enabled no)
				(sheetname "")
			)
			(fill
				(thermal_gap 0.5)
				(thermal_bridge_width 0.5)
				(island_removal_mode 0)
			)
			(polygon
				(pts
					(arc
						(start 231.980994 -58.999882)
						(mid 231.218994 -58.999882)
						(end 231.980994 -58.999882)
					)
				)
			)
		)
		(zone
			(layer "F.Cu")
			(hatch none 0.5)
			(connect_pads
				(clearance 0)
			)
			(min_thickness 0.25)
			(keepout
				(tracks allowed)
				(vias not_allowed)
				(pads allowed)
				(copperpour not_allowed)
				(footprints allowed)
			)
			(placement
				(enabled no)
				(sheetname "")
			)
			(fill
				(thermal_gap 0.5)
				(thermal_bridge_width 0.5)
				(island_removal_mode 0)
			)
			(polygon
				(pts
					(arc
						(start 231.980994 -57.999884)
						(mid 231.218994 -57.999884)
						(end 231.980994 -57.999884)
					)
				)
			)
		)
		(zone
			(layer "F.Cu")
			(hatch none 0.5)
			(connect_pads
				(clearance 0)
			)
			(min_thickness 0.25)
			(keepout
				(tracks allowed)
				(vias not_allowed)
				(pads allowed)
				(copperpour not_allowed)
				(footprints allowed)
			)
			(placement
				(enabled no)
				(sheetname "")
			)
			(fill
				(thermal_gap 0.5)
				(thermal_bridge_width 0.5)
				(island_removal_mode 0)
			)
			(polygon
				(pts
					(arc
						(start 231.980994 -56.999886)
						(mid 231.218994 -56.999886)
						(end 231.980994 -56.999886)
					)
				)
			)
		)
		(zone
			(layer "F.Cu")
			(hatch none 0.5)
			(connect_pads
				(clearance 0)
			)
			(min_thickness 0.25)
			(keepout
				(tracks allowed)
				(vias not_allowed)
				(pads allowed)
				(copperpour not_allowed)
				(footprints allowed)
			)
			(placement
				(enabled no)
				(sheetname "")
			)
			(fill
				(thermal_gap 0.5)
				(thermal_bridge_width 0.5)
				(island_removal_mode 0)
			)
			(polygon
				(pts
					(arc
						(start 231.980994 -55.999888)
						(mid 231.218994 -55.999888)
						(end 231.980994 -55.999888)
					)
				)
			)
		)
		(zone
			(layer "F.Cu")
			(hatch none 0.5)
			(connect_pads
				(clearance 0)
			)
			(min_thickness 0.25)
			(keepout
				(tracks allowed)
				(vias not_allowed)
				(pads allowed)
				(copperpour not_allowed)
				(footprints allowed)
			)
			(placement
				(enabled no)
				(sheetname "")
			)
			(fill
				(thermal_gap 0.5)
				(thermal_bridge_width 0.5)
				(island_removal_mode 0)
			)
			(polygon
				(pts
					(arc
						(start 231.980994 -54.99989)
						(mid 231.218994 -54.99989)
						(end 231.980994 -54.99989)
					)
				)
			)
		)
		(zone
			(layer "F.Cu")
			(hatch none 0.5)
			(connect_pads
				(clearance 0)
			)
			(min_thickness 0.25)
			(keepout
				(tracks allowed)
				(vias not_allowed)
				(pads allowed)
				(copperpour not_allowed)
				(footprints allowed)
			)
			(placement
				(enabled no)
				(sheetname "")
			)
			(fill
				(thermal_gap 0.5)
				(thermal_bridge_width 0.5)
				(island_removal_mode 0)
			)
			(polygon
				(pts
					(arc
						(start 231.980994 -53.999892)
						(mid 231.218994 -53.999892)
						(end 231.980994 -53.999892)
					)
				)
			)
		)
		(zone
			(layer "F.Cu")
			(hatch none 0.5)
			(connect_pads
				(clearance 0)
			)
			(min_thickness 0.25)
			(keepout
				(tracks allowed)
				(vias not_allowed)
				(pads allowed)
				(copperpour not_allowed)
				(footprints allowed)
			)
			(placement
				(enabled no)
				(sheetname "")
			)
			(fill
				(thermal_gap 0.5)
				(thermal_bridge_width 0.5)
				(island_removal_mode 0)
			)
			(polygon
				(pts
					(arc
						(start 231.980994 -52.999894)
						(mid 231.218994 -52.999894)
						(end 231.980994 -52.999894)
					)
				)
			)
		)
		(zone
			(layer "F.Cu")
			(hatch none 0.5)
			(connect_pads
				(clearance 0)
			)
			(min_thickness 0.25)
			(keepout
				(tracks allowed)
				(vias not_allowed)
				(pads allowed)
				(copperpour not_allowed)
				(footprints allowed)
			)
			(placement
				(enabled no)
				(sheetname "")
			)
			(fill
				(thermal_gap 0.5)
				(thermal_bridge_width 0.5)
				(island_removal_mode 0)
			)
			(polygon
				(pts
					(arc
						(start 231.980994 -51.999896)
						(mid 231.218994 -51.999896)
						(end 231.980994 -51.999896)
					)
				)
			)
		)
		(zone
			(layer "F.Cu")
			(hatch none 0.5)
			(connect_pads
				(clearance 0)
			)
			(min_thickness 0.25)
			(keepout
				(tracks allowed)
				(vias not_allowed)
				(pads allowed)
				(copperpour not_allowed)
				(footprints allowed)
			)
			(placement
				(enabled no)
				(sheetname "")
			)
			(fill
				(thermal_gap 0.5)
				(thermal_bridge_width 0.5)
				(island_removal_mode 0)
			)
			(polygon
				(pts
					(arc
						(start 231.980994 -50.999898)
						(mid 231.218994 -50.999898)
						(end 231.980994 -50.999898)
					)
				)
			)
		)
		(zone
			(layer "F.Cu")
			(hatch none 0.5)
			(connect_pads
				(clearance 0)
			)
			(min_thickness 0.25)
			(keepout
				(tracks allowed)
				(vias not_allowed)
				(pads allowed)
				(copperpour not_allowed)
				(footprints allowed)
			)
			(placement
				(enabled no)
				(sheetname "")
			)
			(fill
				(thermal_gap 0.5)
				(thermal_bridge_width 0.5)
				(island_removal_mode 0)
			)
			(polygon
				(pts
					(arc
						(start 231.980994 -49.9999)
						(mid 231.218994 -49.9999)
						(end 231.980994 -49.9999)
					)
				)
			)
		)
		(zone
			(layer "F.Cu")
			(hatch none 0.5)
			(connect_pads
				(clearance 0)
			)
			(min_thickness 0.25)
			(keepout
				(tracks allowed)
				(vias not_allowed)
				(pads allowed)
				(copperpour not_allowed)
				(footprints allowed)
			)
			(placement
				(enabled no)
				(sheetname "")
			)
			(fill
				(thermal_gap 0.5)
				(thermal_bridge_width 0.5)
				(island_removal_mode 0)
			)
			(polygon
				(pts
					(arc
						(start 231.980994 -48.999902)
						(mid 231.218994 -48.999902)
						(end 231.980994 -48.999902)
					)
				)
			)
		)
		(zone
			(layer "F.Cu")
			(hatch none 0.5)
			(connect_pads
				(clearance 0)
			)
			(min_thickness 0.25)
			(keepout
				(tracks allowed)
				(vias not_allowed)
				(pads allowed)
				(copperpour not_allowed)
				(footprints allowed)
			)
			(placement
				(enabled no)
				(sheetname "")
			)
			(fill
				(thermal_gap 0.5)
				(thermal_bridge_width 0.5)
				(island_removal_mode 0)
			)
			(polygon
				(pts
					(arc
						(start 231.980994 -47.999904)
						(mid 231.218994 -47.999904)
						(end 231.980994 -47.999904)
					)
				)
			)
		)
		(zone
			(layer "F.Cu")
			(hatch none 0.5)
			(connect_pads
				(clearance 0)
			)
			(min_thickness 0.25)
			(keepout
				(tracks allowed)
				(vias not_allowed)
				(pads allowed)
				(copperpour not_allowed)
				(footprints allowed)
			)
			(placement
				(enabled no)
				(sheetname "")
			)
			(fill
				(thermal_gap 0.5)
				(thermal_bridge_width 0.5)
				(island_removal_mode 0)
			)
			(polygon
				(pts
					(arc
						(start 231.980994 -46.999906)
						(mid 231.218994 -46.999906)
						(end 231.980994 -46.999906)
					)
				)
			)
		)
		(zone
			(layer "F.Cu")
			(hatch none 0.5)
			(connect_pads
				(clearance 0)
			)
			(min_thickness 0.25)
			(keepout
				(tracks allowed)
				(vias not_allowed)
				(pads allowed)
				(copperpour not_allowed)
				(footprints allowed)
			)
			(placement
				(enabled no)
				(sheetname "")
			)
			(fill
				(thermal_gap 0.5)
				(thermal_bridge_width 0.5)
				(island_removal_mode 0)
			)
			(polygon
				(pts
					(arc
						(start 231.980994 -45.999908)
						(mid 231.218994 -45.999908)
						(end 231.980994 -45.999908)
					)
				)
			)
		)
		(zone
			(layer "F.Cu")
			(hatch none 0.5)
			(connect_pads
				(clearance 0)
			)
			(min_thickness 0.25)
			(keepout
				(tracks allowed)
				(vias not_allowed)
				(pads allowed)
				(copperpour not_allowed)
				(footprints allowed)
			)
			(placement
				(enabled no)
				(sheetname "")
			)
			(fill
				(thermal_gap 0.5)
				(thermal_bridge_width 0.5)
				(island_removal_mode 0)
			)
			(polygon
				(pts
					(arc
						(start 231.980994 -44.99991)
						(mid 231.218994 -44.99991)
						(end 231.980994 -44.99991)
					)
				)
			)
		)
		(zone
			(layer "F.Cu")
			(hatch none 0.5)
			(connect_pads
				(clearance 0)
			)
			(min_thickness 0.25)
			(keepout
				(tracks allowed)
				(vias not_allowed)
				(pads allowed)
				(copperpour not_allowed)
				(footprints allowed)
			)
			(placement
				(enabled no)
				(sheetname "")
			)
			(fill
				(thermal_gap 0.5)
				(thermal_bridge_width 0.5)
				(island_removal_mode 0)
			)
			(polygon
				(pts
					(arc
						(start 231.980994 -43.999912)
						(mid 231.218994 -43.999912)
						(end 231.980994 -43.999912)
					)
				)
			)
		)
		(zone
			(layer "F.Cu")
			(hatch none 0.5)
			(connect_pads
				(clearance 0)
			)
			(min_thickness 0.25)
			(keepout
				(tracks allowed)
				(vias not_allowed)
				(pads allowed)
				(copperpour not_allowed)
				(footprints allowed)
			)
			(placement
				(enabled no)
				(sheetname "")
			)
			(fill
				(thermal_gap 0.5)
				(thermal_bridge_width 0.5)
				(island_removal_mode 0)
			)
			(polygon
				(pts
					(arc
						(start 231.980994 -42.999914)
						(mid 231.218994 -42.999914)
						(end 231.980994 -42.999914)
					)
				)
			)
		)
		(zone
			(layer "F.Cu")
			(hatch none 0.5)
			(connect_pads
				(clearance 0)
			)
			(min_thickness 0.25)
			(keepout
				(tracks allowed)
				(vias not_allowed)
				(pads allowed)
				(copperpour not_allowed)
				(footprints allowed)
			)
			(placement
				(enabled no)
				(sheetname "")
			)
			(fill
				(thermal_gap 0.5)
				(thermal_bridge_width 0.5)
				(island_removal_mode 0)
			)
			(polygon
				(pts
					(arc
						(start 231.980994 -41.999916)
						(mid 231.218994 -41.999916)
						(end 231.980994 -41.999916)
					)
				)
			)
		)
		(zone
			(layer "F.Cu")
			(hatch none 0.5)
			(connect_pads
				(clearance 0)
			)
			(min_thickness 0.25)
			(keepout
				(tracks allowed)
				(vias not_allowed)
				(pads allowed)
				(copperpour not_allowed)
				(footprints allowed)
			)
			(placement
				(enabled no)
				(sheetname "")
			)
			(fill
				(thermal_gap 0.5)
				(thermal_bridge_width 0.5)
				(island_removal_mode 0)
			)
			(polygon
				(pts
					(arc
						(start 231.980994 -40.999918)
						(mid 231.218994 -40.999918)
						(end 231.980994 -40.999918)
					)
				)
			)
		)
		(zone
			(layer "F.Cu")
			(hatch none 0.5)
			(connect_pads
				(clearance 0)
			)
			(min_thickness 0.25)
			(keepout
				(tracks allowed)
				(vias not_allowed)
				(pads allowed)
				(copperpour not_allowed)
				(footprints allowed)
			)
			(placement
				(enabled no)
				(sheetname "")
			)
			(fill
				(thermal_gap 0.5)
				(thermal_bridge_width 0.5)
				(island_removal_mode 0)
			)
			(polygon
				(pts
					(arc
						(start 231.980994 -39.99992)
						(mid 231.218994 -39.99992)
						(end 231.980994 -39.99992)
					)
				)
			)
		)
		(zone
			(layer "F.Cu")
			(hatch none 0.5)
			(connect_pads
				(clearance 0)
			)
			(min_thickness 0.25)
			(keepout
				(tracks allowed)
				(vias not_allowed)
				(pads allowed)
				(copperpour not_allowed)
				(footprints allowed)
			)
			(placement
				(enabled no)
				(sheetname "")
			)
			(fill
				(thermal_gap 0.5)
				(thermal_bridge_width 0.5)
				(island_removal_mode 0)
			)
			(polygon
				(pts
					(arc
						(start 231.980994 -38.999922)
						(mid 231.218994 -38.999922)
						(end 231.980994 -38.999922)
					)
				)
			)
		)
		(zone
			(layer "F.Cu")
			(hatch none 0.5)
			(connect_pads
				(clearance 0)
			)
			(min_thickness 0.25)
			(keepout
				(tracks allowed)
				(vias not_allowed)
				(pads allowed)
				(copperpour not_allowed)
				(footprints allowed)
			)
			(placement
				(enabled no)
				(sheetname "")
			)
			(fill
				(thermal_gap 0.5)
				(thermal_bridge_width 0.5)
				(island_removal_mode 0)
			)
			(polygon
				(pts
					(arc
						(start 231.980994 -37.999924)
						(mid 231.218994 -37.999924)
						(end 231.980994 -37.999924)
					)
				)
			)
		)
		(zone
			(layer "F.Cu")
			(hatch none 0.5)
			(connect_pads
				(clearance 0)
			)
			(min_thickness 0.25)
			(keepout
				(tracks allowed)
				(vias not_allowed)
				(pads allowed)
				(copperpour not_allowed)
				(footprints allowed)
			)
			(placement
				(enabled no)
				(sheetname "")
			)
			(fill
				(thermal_gap 0.5)
				(thermal_bridge_width 0.5)
				(island_removal_mode 0)
			)
			(polygon
				(pts
					(arc
						(start 231.980994 -36.999926)
						(mid 231.218994 -36.999926)
						(end 231.980994 -36.999926)
					)
				)
			)
		)
		(zone
			(layer "F.Cu")
			(hatch none 0.5)
			(connect_pads
				(clearance 0)
			)
			(min_thickness 0.25)
			(keepout
				(tracks allowed)
				(vias not_allowed)
				(pads allowed)
				(copperpour not_allowed)
				(footprints allowed)
			)
			(placement
				(enabled no)
				(sheetname "")
			)
			(fill
				(thermal_gap 0.5)
				(thermal_bridge_width 0.5)
				(island_removal_mode 0)
			)
			(polygon
				(pts
					(arc
						(start 231.980994 -35.999928)
						(mid 231.218994 -35.999928)
						(end 231.980994 -35.999928)
					)
				)
			)
		)
		(zone
			(layer "F.Cu")
			(hatch none 0.5)
			(connect_pads
				(clearance 0)
			)
			(min_thickness 0.25)
			(keepout
				(tracks allowed)
				(vias not_allowed)
				(pads allowed)
				(copperpour not_allowed)
				(footprints allowed)
			)
			(placement
				(enabled no)
				(sheetname "")
			)
			(fill
				(thermal_gap 0.5)
				(thermal_bridge_width 0.5)
				(island_removal_mode 0)
			)
			(polygon
				(pts
					(arc
						(start 231.980994 -34.99993)
						(mid 231.218994 -34.99993)
						(end 231.980994 -34.99993)
					)
				)
			)
		)
		(zone
			(layer "F.Cu")
			(hatch none 0.5)
			(connect_pads
				(clearance 0)
			)
			(min_thickness 0.25)
			(keepout
				(tracks allowed)
				(vias not_allowed)
				(pads allowed)
				(copperpour not_allowed)
				(footprints allowed)
			)
			(placement
				(enabled no)
				(sheetname "")
			)
			(fill
				(thermal_gap 0.5)
				(thermal_bridge_width 0.5)
				(island_removal_mode 0)
			)
			(polygon
				(pts
					(arc
						(start 231.980994 -33.999932)
						(mid 231.218994 -33.999932)
						(end 231.980994 -33.999932)
					)
				)
			)
		)
		(zone
			(layer "F.Cu")
			(hatch none 0.5)
			(connect_pads
				(clearance 0)
			)
			(min_thickness 0.25)
			(keepout
				(tracks allowed)
				(vias not_allowed)
				(pads allowed)
				(copperpour not_allowed)
				(footprints allowed)
			)
			(placement
				(enabled no)
				(sheetname "")
			)
			(fill
				(thermal_gap 0.5)
				(thermal_bridge_width 0.5)
				(island_removal_mode 0)
			)
			(polygon
				(pts
					(arc
						(start 231.980994 -32.999934)
						(mid 231.218994 -32.999934)
						(end 231.980994 -32.999934)
					)
				)
			)
		)
		(zone
			(layer "F.Cu")
			(hatch none 0.5)
			(connect_pads
				(clearance 0)
			)
			(min_thickness 0.25)
			(keepout
				(tracks allowed)
				(vias not_allowed)
				(pads allowed)
				(copperpour not_allowed)
				(footprints allowed)
			)
			(placement
				(enabled no)
				(sheetname "")
			)
			(fill
				(thermal_gap 0.5)
				(thermal_bridge_width 0.5)
				(island_removal_mode 0)
			)
			(polygon
				(pts
					(arc
						(start 231.980994 -31.999936)
						(mid 231.218994 -31.999936)
						(end 231.980994 -31.999936)
					)
				)
			)
		)
		(zone
			(layer "F.Cu")
			(hatch none 0.5)
			(connect_pads
				(clearance 0)
			)
			(min_thickness 0.25)
			(keepout
				(tracks allowed)
				(vias not_allowed)
				(pads allowed)
				(copperpour not_allowed)
				(footprints allowed)
			)
			(placement
				(enabled no)
				(sheetname "")
			)
			(fill
				(thermal_gap 0.5)
				(thermal_bridge_width 0.5)
				(island_removal_mode 0)
			)
			(polygon
				(pts
					(arc
						(start 231.980994 -30.999938)
						(mid 231.218994 -30.999938)
						(end 231.980994 -30.999938)
					)
				)
			)
		)
		(zone
			(layer "F.Cu")
			(hatch none 0.5)
			(connect_pads
				(clearance 0)
			)
			(min_thickness 0.25)
			(keepout
				(tracks allowed)
				(vias not_allowed)
				(pads allowed)
				(copperpour not_allowed)
				(footprints allowed)
			)
			(placement
				(enabled no)
				(sheetname "")
			)
			(fill
				(thermal_gap 0.5)
				(thermal_bridge_width 0.5)
				(island_removal_mode 0)
			)
			(polygon
				(pts
					(arc
						(start 232.980992 -65.999868)
						(mid 232.218992 -65.999868)
						(end 232.980992 -65.999868)
					)
				)
			)
		)
		(zone
			(layer "F.Cu")
			(hatch none 0.5)
			(connect_pads
				(clearance 0)
			)
			(min_thickness 0.25)
			(keepout
				(tracks allowed)
				(vias not_allowed)
				(pads allowed)
				(copperpour not_allowed)
				(footprints allowed)
			)
			(placement
				(enabled no)
				(sheetname "")
			)
			(fill
				(thermal_gap 0.5)
				(thermal_bridge_width 0.5)
				(island_removal_mode 0)
			)
			(polygon
				(pts
					(arc
						(start 232.980992 -64.99987)
						(mid 232.218992 -64.99987)
						(end 232.980992 -64.99987)
					)
				)
			)
		)
		(zone
			(layer "F.Cu")
			(hatch none 0.5)
			(connect_pads
				(clearance 0)
			)
			(min_thickness 0.25)
			(keepout
				(tracks allowed)
				(vias not_allowed)
				(pads allowed)
				(copperpour not_allowed)
				(footprints allowed)
			)
			(placement
				(enabled no)
				(sheetname "")
			)
			(fill
				(thermal_gap 0.5)
				(thermal_bridge_width 0.5)
				(island_removal_mode 0)
			)
			(polygon
				(pts
					(arc
						(start 232.980992 -63.999872)
						(mid 232.218992 -63.999872)
						(end 232.980992 -63.999872)
					)
				)
			)
		)
		(zone
			(layer "F.Cu")
			(hatch none 0.5)
			(connect_pads
				(clearance 0)
			)
			(min_thickness 0.25)
			(keepout
				(tracks allowed)
				(vias not_allowed)
				(pads allowed)
				(copperpour not_allowed)
				(footprints allowed)
			)
			(placement
				(enabled no)
				(sheetname "")
			)
			(fill
				(thermal_gap 0.5)
				(thermal_bridge_width 0.5)
				(island_removal_mode 0)
			)
			(polygon
				(pts
					(arc
						(start 232.980992 -62.999874)
						(mid 232.218992 -62.999874)
						(end 232.980992 -62.999874)
					)
				)
			)
		)
		(zone
			(layer "F.Cu")
			(hatch none 0.5)
			(connect_pads
				(clearance 0)
			)
			(min_thickness 0.25)
			(keepout
				(tracks allowed)
				(vias not_allowed)
				(pads allowed)
				(copperpour not_allowed)
				(footprints allowed)
			)
			(placement
				(enabled no)
				(sheetname "")
			)
			(fill
				(thermal_gap 0.5)
				(thermal_bridge_width 0.5)
				(island_removal_mode 0)
			)
			(polygon
				(pts
					(arc
						(start 232.980992 -61.999876)
						(mid 232.218992 -61.999876)
						(end 232.980992 -61.999876)
					)
				)
			)
		)
		(zone
			(layer "F.Cu")
			(hatch none 0.5)
			(connect_pads
				(clearance 0)
			)
			(min_thickness 0.25)
			(keepout
				(tracks allowed)
				(vias not_allowed)
				(pads allowed)
				(copperpour not_allowed)
				(footprints allowed)
			)
			(placement
				(enabled no)
				(sheetname "")
			)
			(fill
				(thermal_gap 0.5)
				(thermal_bridge_width 0.5)
				(island_removal_mode 0)
			)
			(polygon
				(pts
					(arc
						(start 232.980992 -60.999878)
						(mid 232.218992 -60.999878)
						(end 232.980992 -60.999878)
					)
				)
			)
		)
		(zone
			(layer "F.Cu")
			(hatch none 0.5)
			(connect_pads
				(clearance 0)
			)
			(min_thickness 0.25)
			(keepout
				(tracks allowed)
				(vias not_allowed)
				(pads allowed)
				(copperpour not_allowed)
				(footprints allowed)
			)
			(placement
				(enabled no)
				(sheetname "")
			)
			(fill
				(thermal_gap 0.5)
				(thermal_bridge_width 0.5)
				(island_removal_mode 0)
			)
			(polygon
				(pts
					(arc
						(start 232.980992 -59.99988)
						(mid 232.218992 -59.99988)
						(end 232.980992 -59.99988)
					)
				)
			)
		)
		(zone
			(layer "F.Cu")
			(hatch none 0.5)
			(connect_pads
				(clearance 0)
			)
			(min_thickness 0.25)
			(keepout
				(tracks allowed)
				(vias not_allowed)
				(pads allowed)
				(copperpour not_allowed)
				(footprints allowed)
			)
			(placement
				(enabled no)
				(sheetname "")
			)
			(fill
				(thermal_gap 0.5)
				(thermal_bridge_width 0.5)
				(island_removal_mode 0)
			)
			(polygon
				(pts
					(arc
						(start 232.980992 -58.999882)
						(mid 232.218992 -58.999882)
						(end 232.980992 -58.999882)
					)
				)
			)
		)
		(zone
			(layer "F.Cu")
			(hatch none 0.5)
			(connect_pads
				(clearance 0)
			)
			(min_thickness 0.25)
			(keepout
				(tracks allowed)
				(vias not_allowed)
				(pads allowed)
				(copperpour not_allowed)
				(footprints allowed)
			)
			(placement
				(enabled no)
				(sheetname "")
			)
			(fill
				(thermal_gap 0.5)
				(thermal_bridge_width 0.5)
				(island_removal_mode 0)
			)
			(polygon
				(pts
					(arc
						(start 232.980992 -57.999884)
						(mid 232.218992 -57.999884)
						(end 232.980992 -57.999884)
					)
				)
			)
		)
		(zone
			(layer "F.Cu")
			(hatch none 0.5)
			(connect_pads
				(clearance 0)
			)
			(min_thickness 0.25)
			(keepout
				(tracks allowed)
				(vias not_allowed)
				(pads allowed)
				(copperpour not_allowed)
				(footprints allowed)
			)
			(placement
				(enabled no)
				(sheetname "")
			)
			(fill
				(thermal_gap 0.5)
				(thermal_bridge_width 0.5)
				(island_removal_mode 0)
			)
			(polygon
				(pts
					(arc
						(start 232.980992 -56.999886)
						(mid 232.218992 -56.999886)
						(end 232.980992 -56.999886)
					)
				)
			)
		)
		(zone
			(layer "F.Cu")
			(hatch none 0.5)
			(connect_pads
				(clearance 0)
			)
			(min_thickness 0.25)
			(keepout
				(tracks allowed)
				(vias not_allowed)
				(pads allowed)
				(copperpour not_allowed)
				(footprints allowed)
			)
			(placement
				(enabled no)
				(sheetname "")
			)
			(fill
				(thermal_gap 0.5)
				(thermal_bridge_width 0.5)
				(island_removal_mode 0)
			)
			(polygon
				(pts
					(arc
						(start 232.980992 -55.999888)
						(mid 232.218992 -55.999888)
						(end 232.980992 -55.999888)
					)
				)
			)
		)
		(zone
			(layer "F.Cu")
			(hatch none 0.5)
			(connect_pads
				(clearance 0)
			)
			(min_thickness 0.25)
			(keepout
				(tracks allowed)
				(vias not_allowed)
				(pads allowed)
				(copperpour not_allowed)
				(footprints allowed)
			)
			(placement
				(enabled no)
				(sheetname "")
			)
			(fill
				(thermal_gap 0.5)
				(thermal_bridge_width 0.5)
				(island_removal_mode 0)
			)
			(polygon
				(pts
					(arc
						(start 232.980992 -54.99989)
						(mid 232.218992 -54.99989)
						(end 232.980992 -54.99989)
					)
				)
			)
		)
		(zone
			(layer "F.Cu")
			(hatch none 0.5)
			(connect_pads
				(clearance 0)
			)
			(min_thickness 0.25)
			(keepout
				(tracks allowed)
				(vias not_allowed)
				(pads allowed)
				(copperpour not_allowed)
				(footprints allowed)
			)
			(placement
				(enabled no)
				(sheetname "")
			)
			(fill
				(thermal_gap 0.5)
				(thermal_bridge_width 0.5)
				(island_removal_mode 0)
			)
			(polygon
				(pts
					(arc
						(start 232.980992 -53.999892)
						(mid 232.218992 -53.999892)
						(end 232.980992 -53.999892)
					)
				)
			)
		)
		(zone
			(layer "F.Cu")
			(hatch none 0.5)
			(connect_pads
				(clearance 0)
			)
			(min_thickness 0.25)
			(keepout
				(tracks allowed)
				(vias not_allowed)
				(pads allowed)
				(copperpour not_allowed)
				(footprints allowed)
			)
			(placement
				(enabled no)
				(sheetname "")
			)
			(fill
				(thermal_gap 0.5)
				(thermal_bridge_width 0.5)
				(island_removal_mode 0)
			)
			(polygon
				(pts
					(arc
						(start 232.980992 -52.999894)
						(mid 232.218992 -52.999894)
						(end 232.980992 -52.999894)
					)
				)
			)
		)
		(zone
			(layer "F.Cu")
			(hatch none 0.5)
			(connect_pads
				(clearance 0)
			)
			(min_thickness 0.25)
			(keepout
				(tracks allowed)
				(vias not_allowed)
				(pads allowed)
				(copperpour not_allowed)
				(footprints allowed)
			)
			(placement
				(enabled no)
				(sheetname "")
			)
			(fill
				(thermal_gap 0.5)
				(thermal_bridge_width 0.5)
				(island_removal_mode 0)
			)
			(polygon
				(pts
					(arc
						(start 232.980992 -51.999896)
						(mid 232.218992 -51.999896)
						(end 232.980992 -51.999896)
					)
				)
			)
		)
		(zone
			(layer "F.Cu")
			(hatch none 0.5)
			(connect_pads
				(clearance 0)
			)
			(min_thickness 0.25)
			(keepout
				(tracks allowed)
				(vias not_allowed)
				(pads allowed)
				(copperpour not_allowed)
				(footprints allowed)
			)
			(placement
				(enabled no)
				(sheetname "")
			)
			(fill
				(thermal_gap 0.5)
				(thermal_bridge_width 0.5)
				(island_removal_mode 0)
			)
			(polygon
				(pts
					(arc
						(start 232.980992 -50.999898)
						(mid 232.218992 -50.999898)
						(end 232.980992 -50.999898)
					)
				)
			)
		)
		(zone
			(layer "F.Cu")
			(hatch none 0.5)
			(connect_pads
				(clearance 0)
			)
			(min_thickness 0.25)
			(keepout
				(tracks allowed)
				(vias not_allowed)
				(pads allowed)
				(copperpour not_allowed)
				(footprints allowed)
			)
			(placement
				(enabled no)
				(sheetname "")
			)
			(fill
				(thermal_gap 0.5)
				(thermal_bridge_width 0.5)
				(island_removal_mode 0)
			)
			(polygon
				(pts
					(arc
						(start 232.980992 -49.9999)
						(mid 232.218992 -49.9999)
						(end 232.980992 -49.9999)
					)
				)
			)
		)
		(zone
			(layer "F.Cu")
			(hatch none 0.5)
			(connect_pads
				(clearance 0)
			)
			(min_thickness 0.25)
			(keepout
				(tracks allowed)
				(vias not_allowed)
				(pads allowed)
				(copperpour not_allowed)
				(footprints allowed)
			)
			(placement
				(enabled no)
				(sheetname "")
			)
			(fill
				(thermal_gap 0.5)
				(thermal_bridge_width 0.5)
				(island_removal_mode 0)
			)
			(polygon
				(pts
					(arc
						(start 232.980992 -48.999902)
						(mid 232.218992 -48.999902)
						(end 232.980992 -48.999902)
					)
				)
			)
		)
		(zone
			(layer "F.Cu")
			(hatch none 0.5)
			(connect_pads
				(clearance 0)
			)
			(min_thickness 0.25)
			(keepout
				(tracks allowed)
				(vias not_allowed)
				(pads allowed)
				(copperpour not_allowed)
				(footprints allowed)
			)
			(placement
				(enabled no)
				(sheetname "")
			)
			(fill
				(thermal_gap 0.5)
				(thermal_bridge_width 0.5)
				(island_removal_mode 0)
			)
			(polygon
				(pts
					(arc
						(start 232.980992 -47.999904)
						(mid 232.218992 -47.999904)
						(end 232.980992 -47.999904)
					)
				)
			)
		)
		(zone
			(layer "F.Cu")
			(hatch none 0.5)
			(connect_pads
				(clearance 0)
			)
			(min_thickness 0.25)
			(keepout
				(tracks allowed)
				(vias not_allowed)
				(pads allowed)
				(copperpour not_allowed)
				(footprints allowed)
			)
			(placement
				(enabled no)
				(sheetname "")
			)
			(fill
				(thermal_gap 0.5)
				(thermal_bridge_width 0.5)
				(island_removal_mode 0)
			)
			(polygon
				(pts
					(arc
						(start 232.980992 -46.999906)
						(mid 232.218992 -46.999906)
						(end 232.980992 -46.999906)
					)
				)
			)
		)
		(zone
			(layer "F.Cu")
			(hatch none 0.5)
			(connect_pads
				(clearance 0)
			)
			(min_thickness 0.25)
			(keepout
				(tracks allowed)
				(vias not_allowed)
				(pads allowed)
				(copperpour not_allowed)
				(footprints allowed)
			)
			(placement
				(enabled no)
				(sheetname "")
			)
			(fill
				(thermal_gap 0.5)
				(thermal_bridge_width 0.5)
				(island_removal_mode 0)
			)
			(polygon
				(pts
					(arc
						(start 232.980992 -45.999908)
						(mid 232.218992 -45.999908)
						(end 232.980992 -45.999908)
					)
				)
			)
		)
		(zone
			(layer "F.Cu")
			(hatch none 0.5)
			(connect_pads
				(clearance 0)
			)
			(min_thickness 0.25)
			(keepout
				(tracks allowed)
				(vias not_allowed)
				(pads allowed)
				(copperpour not_allowed)
				(footprints allowed)
			)
			(placement
				(enabled no)
				(sheetname "")
			)
			(fill
				(thermal_gap 0.5)
				(thermal_bridge_width 0.5)
				(island_removal_mode 0)
			)
			(polygon
				(pts
					(arc
						(start 232.980992 -44.99991)
						(mid 232.218992 -44.99991)
						(end 232.980992 -44.99991)
					)
				)
			)
		)
		(zone
			(layer "F.Cu")
			(hatch none 0.5)
			(connect_pads
				(clearance 0)
			)
			(min_thickness 0.25)
			(keepout
				(tracks allowed)
				(vias not_allowed)
				(pads allowed)
				(copperpour not_allowed)
				(footprints allowed)
			)
			(placement
				(enabled no)
				(sheetname "")
			)
			(fill
				(thermal_gap 0.5)
				(thermal_bridge_width 0.5)
				(island_removal_mode 0)
			)
			(polygon
				(pts
					(arc
						(start 232.980992 -43.999912)
						(mid 232.218992 -43.999912)
						(end 232.980992 -43.999912)
					)
				)
			)
		)
		(zone
			(layer "F.Cu")
			(hatch none 0.5)
			(connect_pads
				(clearance 0)
			)
			(min_thickness 0.25)
			(keepout
				(tracks allowed)
				(vias not_allowed)
				(pads allowed)
				(copperpour not_allowed)
				(footprints allowed)
			)
			(placement
				(enabled no)
				(sheetname "")
			)
			(fill
				(thermal_gap 0.5)
				(thermal_bridge_width 0.5)
				(island_removal_mode 0)
			)
			(polygon
				(pts
					(arc
						(start 232.980992 -42.999914)
						(mid 232.218992 -42.999914)
						(end 232.980992 -42.999914)
					)
				)
			)
		)
		(zone
			(layer "F.Cu")
			(hatch none 0.5)
			(connect_pads
				(clearance 0)
			)
			(min_thickness 0.25)
			(keepout
				(tracks allowed)
				(vias not_allowed)
				(pads allowed)
				(copperpour not_allowed)
				(footprints allowed)
			)
			(placement
				(enabled no)
				(sheetname "")
			)
			(fill
				(thermal_gap 0.5)
				(thermal_bridge_width 0.5)
				(island_removal_mode 0)
			)
			(polygon
				(pts
					(arc
						(start 232.980992 -41.999916)
						(mid 232.218992 -41.999916)
						(end 232.980992 -41.999916)
					)
				)
			)
		)
		(zone
			(layer "F.Cu")
			(hatch none 0.5)
			(connect_pads
				(clearance 0)
			)
			(min_thickness 0.25)
			(keepout
				(tracks allowed)
				(vias not_allowed)
				(pads allowed)
				(copperpour not_allowed)
				(footprints allowed)
			)
			(placement
				(enabled no)
				(sheetname "")
			)
			(fill
				(thermal_gap 0.5)
				(thermal_bridge_width 0.5)
				(island_removal_mode 0)
			)
			(polygon
				(pts
					(arc
						(start 232.980992 -40.999918)
						(mid 232.218992 -40.999918)
						(end 232.980992 -40.999918)
					)
				)
			)
		)
		(zone
			(layer "F.Cu")
			(hatch none 0.5)
			(connect_pads
				(clearance 0)
			)
			(min_thickness 0.25)
			(keepout
				(tracks allowed)
				(vias not_allowed)
				(pads allowed)
				(copperpour not_allowed)
				(footprints allowed)
			)
			(placement
				(enabled no)
				(sheetname "")
			)
			(fill
				(thermal_gap 0.5)
				(thermal_bridge_width 0.5)
				(island_removal_mode 0)
			)
			(polygon
				(pts
					(arc
						(start 232.980992 -39.99992)
						(mid 232.218992 -39.99992)
						(end 232.980992 -39.99992)
					)
				)
			)
		)
		(zone
			(layer "F.Cu")
			(hatch none 0.5)
			(connect_pads
				(clearance 0)
			)
			(min_thickness 0.25)
			(keepout
				(tracks allowed)
				(vias not_allowed)
				(pads allowed)
				(copperpour not_allowed)
				(footprints allowed)
			)
			(placement
				(enabled no)
				(sheetname "")
			)
			(fill
				(thermal_gap 0.5)
				(thermal_bridge_width 0.5)
				(island_removal_mode 0)
			)
			(polygon
				(pts
					(arc
						(start 232.980992 -38.999922)
						(mid 232.218992 -38.999922)
						(end 232.980992 -38.999922)
					)
				)
			)
		)
		(zone
			(layer "F.Cu")
			(hatch none 0.5)
			(connect_pads
				(clearance 0)
			)
			(min_thickness 0.25)
			(keepout
				(tracks allowed)
				(vias not_allowed)
				(pads allowed)
				(copperpour not_allowed)
				(footprints allowed)
			)
			(placement
				(enabled no)
				(sheetname "")
			)
			(fill
				(thermal_gap 0.5)
				(thermal_bridge_width 0.5)
				(island_removal_mode 0)
			)
			(polygon
				(pts
					(arc
						(start 232.980992 -37.999924)
						(mid 232.218992 -37.999924)
						(end 232.980992 -37.999924)
					)
				)
			)
		)
		(zone
			(layer "F.Cu")
			(hatch none 0.5)
			(connect_pads
				(clearance 0)
			)
			(min_thickness 0.25)
			(keepout
				(tracks allowed)
				(vias not_allowed)
				(pads allowed)
				(copperpour not_allowed)
				(footprints allowed)
			)
			(placement
				(enabled no)
				(sheetname "")
			)
			(fill
				(thermal_gap 0.5)
				(thermal_bridge_width 0.5)
				(island_removal_mode 0)
			)
			(polygon
				(pts
					(arc
						(start 232.980992 -36.999926)
						(mid 232.218992 -36.999926)
						(end 232.980992 -36.999926)
					)
				)
			)
		)
		(zone
			(layer "F.Cu")
			(hatch none 0.5)
			(connect_pads
				(clearance 0)
			)
			(min_thickness 0.25)
			(keepout
				(tracks allowed)
				(vias not_allowed)
				(pads allowed)
				(copperpour not_allowed)
				(footprints allowed)
			)
			(placement
				(enabled no)
				(sheetname "")
			)
			(fill
				(thermal_gap 0.5)
				(thermal_bridge_width 0.5)
				(island_removal_mode 0)
			)
			(polygon
				(pts
					(arc
						(start 232.980992 -35.999928)
						(mid 232.218992 -35.999928)
						(end 232.980992 -35.999928)
					)
				)
			)
		)
		(zone
			(layer "F.Cu")
			(hatch none 0.5)
			(connect_pads
				(clearance 0)
			)
			(min_thickness 0.25)
			(keepout
				(tracks allowed)
				(vias not_allowed)
				(pads allowed)
				(copperpour not_allowed)
				(footprints allowed)
			)
			(placement
				(enabled no)
				(sheetname "")
			)
			(fill
				(thermal_gap 0.5)
				(thermal_bridge_width 0.5)
				(island_removal_mode 0)
			)
			(polygon
				(pts
					(arc
						(start 232.980992 -34.99993)
						(mid 232.218992 -34.99993)
						(end 232.980992 -34.99993)
					)
				)
			)
		)
		(zone
			(layer "F.Cu")
			(hatch none 0.5)
			(connect_pads
				(clearance 0)
			)
			(min_thickness 0.25)
			(keepout
				(tracks allowed)
				(vias not_allowed)
				(pads allowed)
				(copperpour not_allowed)
				(footprints allowed)
			)
			(placement
				(enabled no)
				(sheetname "")
			)
			(fill
				(thermal_gap 0.5)
				(thermal_bridge_width 0.5)
				(island_removal_mode 0)
			)
			(polygon
				(pts
					(arc
						(start 232.980992 -33.999932)
						(mid 232.218992 -33.999932)
						(end 232.980992 -33.999932)
					)
				)
			)
		)
		(zone
			(layer "F.Cu")
			(hatch none 0.5)
			(connect_pads
				(clearance 0)
			)
			(min_thickness 0.25)
			(keepout
				(tracks allowed)
				(vias not_allowed)
				(pads allowed)
				(copperpour not_allowed)
				(footprints allowed)
			)
			(placement
				(enabled no)
				(sheetname "")
			)
			(fill
				(thermal_gap 0.5)
				(thermal_bridge_width 0.5)
				(island_removal_mode 0)
			)
			(polygon
				(pts
					(arc
						(start 232.980992 -32.999934)
						(mid 232.218992 -32.999934)
						(end 232.980992 -32.999934)
					)
				)
			)
		)
		(zone
			(layer "F.Cu")
			(hatch none 0.5)
			(connect_pads
				(clearance 0)
			)
			(min_thickness 0.25)
			(keepout
				(tracks allowed)
				(vias not_allowed)
				(pads allowed)
				(copperpour not_allowed)
				(footprints allowed)
			)
			(placement
				(enabled no)
				(sheetname "")
			)
			(fill
				(thermal_gap 0.5)
				(thermal_bridge_width 0.5)
				(island_removal_mode 0)
			)
			(polygon
				(pts
					(arc
						(start 232.980992 -31.999936)
						(mid 232.218992 -31.999936)
						(end 232.980992 -31.999936)
					)
				)
			)
		)
		(zone
			(layer "F.Cu")
			(hatch none 0.5)
			(connect_pads
				(clearance 0)
			)
			(min_thickness 0.25)
			(keepout
				(tracks allowed)
				(vias not_allowed)
				(pads allowed)
				(copperpour not_allowed)
				(footprints allowed)
			)
			(placement
				(enabled no)
				(sheetname "")
			)
			(fill
				(thermal_gap 0.5)
				(thermal_bridge_width 0.5)
				(island_removal_mode 0)
			)
			(polygon
				(pts
					(arc
						(start 232.980992 -30.999938)
						(mid 232.218992 -30.999938)
						(end 232.980992 -30.999938)
					)
				)
			)
		)
		(zone
			(layer "F.Cu")
			(hatch none 0.5)
			(connect_pads
				(clearance 0)
			)
			(min_thickness 0.25)
			(keepout
				(tracks allowed)
				(vias not_allowed)
				(pads allowed)
				(copperpour not_allowed)
				(footprints allowed)
			)
			(placement
				(enabled no)
				(sheetname "")
			)
			(fill
				(thermal_gap 0.5)
				(thermal_bridge_width 0.5)
				(island_removal_mode 0)
			)
			(polygon
				(pts
					(arc
						(start 232.980992 -29.99994)
						(mid 232.218992 -29.99994)
						(end 232.980992 -29.99994)
					)
				)
			)
		)
		(zone
			(layer "F.Cu")
			(hatch none 0.5)
			(connect_pads
				(clearance 0)
			)
			(min_thickness 0.25)
			(keepout
				(tracks allowed)
				(vias not_allowed)
				(pads allowed)
				(copperpour not_allowed)
				(footprints allowed)
			)
			(placement
				(enabled no)
				(sheetname "")
			)
			(fill
				(thermal_gap 0.5)
				(thermal_bridge_width 0.5)
				(island_removal_mode 0)
			)
			(polygon
				(pts
					(arc
						(start 233.98099 -64.99987)
						(mid 233.21899 -64.99987)
						(end 233.98099 -64.99987)
					)
				)
			)
		)
		(zone
			(layer "F.Cu")
			(hatch none 0.5)
			(connect_pads
				(clearance 0)
			)
			(min_thickness 0.25)
			(keepout
				(tracks allowed)
				(vias not_allowed)
				(pads allowed)
				(copperpour not_allowed)
				(footprints allowed)
			)
			(placement
				(enabled no)
				(sheetname "")
			)
			(fill
				(thermal_gap 0.5)
				(thermal_bridge_width 0.5)
				(island_removal_mode 0)
			)
			(polygon
				(pts
					(arc
						(start 233.98099 -63.999872)
						(mid 233.21899 -63.999872)
						(end 233.98099 -63.999872)
					)
				)
			)
		)
		(zone
			(layer "F.Cu")
			(hatch none 0.5)
			(connect_pads
				(clearance 0)
			)
			(min_thickness 0.25)
			(keepout
				(tracks allowed)
				(vias not_allowed)
				(pads allowed)
				(copperpour not_allowed)
				(footprints allowed)
			)
			(placement
				(enabled no)
				(sheetname "")
			)
			(fill
				(thermal_gap 0.5)
				(thermal_bridge_width 0.5)
				(island_removal_mode 0)
			)
			(polygon
				(pts
					(arc
						(start 233.98099 -62.999874)
						(mid 233.21899 -62.999874)
						(end 233.98099 -62.999874)
					)
				)
			)
		)
		(zone
			(layer "F.Cu")
			(hatch none 0.5)
			(connect_pads
				(clearance 0)
			)
			(min_thickness 0.25)
			(keepout
				(tracks allowed)
				(vias not_allowed)
				(pads allowed)
				(copperpour not_allowed)
				(footprints allowed)
			)
			(placement
				(enabled no)
				(sheetname "")
			)
			(fill
				(thermal_gap 0.5)
				(thermal_bridge_width 0.5)
				(island_removal_mode 0)
			)
			(polygon
				(pts
					(arc
						(start 233.98099 -61.999876)
						(mid 233.21899 -61.999876)
						(end 233.98099 -61.999876)
					)
				)
			)
		)
		(zone
			(layer "F.Cu")
			(hatch none 0.5)
			(connect_pads
				(clearance 0)
			)
			(min_thickness 0.25)
			(keepout
				(tracks allowed)
				(vias not_allowed)
				(pads allowed)
				(copperpour not_allowed)
				(footprints allowed)
			)
			(placement
				(enabled no)
				(sheetname "")
			)
			(fill
				(thermal_gap 0.5)
				(thermal_bridge_width 0.5)
				(island_removal_mode 0)
			)
			(polygon
				(pts
					(arc
						(start 233.98099 -60.999878)
						(mid 233.21899 -60.999878)
						(end 233.98099 -60.999878)
					)
				)
			)
		)
		(zone
			(layer "F.Cu")
			(hatch none 0.5)
			(connect_pads
				(clearance 0)
			)
			(min_thickness 0.25)
			(keepout
				(tracks allowed)
				(vias not_allowed)
				(pads allowed)
				(copperpour not_allowed)
				(footprints allowed)
			)
			(placement
				(enabled no)
				(sheetname "")
			)
			(fill
				(thermal_gap 0.5)
				(thermal_bridge_width 0.5)
				(island_removal_mode 0)
			)
			(polygon
				(pts
					(arc
						(start 233.98099 -59.99988)
						(mid 233.21899 -59.99988)
						(end 233.98099 -59.99988)
					)
				)
			)
		)
		(zone
			(layer "F.Cu")
			(hatch none 0.5)
			(connect_pads
				(clearance 0)
			)
			(min_thickness 0.25)
			(keepout
				(tracks allowed)
				(vias not_allowed)
				(pads allowed)
				(copperpour not_allowed)
				(footprints allowed)
			)
			(placement
				(enabled no)
				(sheetname "")
			)
			(fill
				(thermal_gap 0.5)
				(thermal_bridge_width 0.5)
				(island_removal_mode 0)
			)
			(polygon
				(pts
					(arc
						(start 233.98099 -58.999882)
						(mid 233.21899 -58.999882)
						(end 233.98099 -58.999882)
					)
				)
			)
		)
		(zone
			(layer "F.Cu")
			(hatch none 0.5)
			(connect_pads
				(clearance 0)
			)
			(min_thickness 0.25)
			(keepout
				(tracks allowed)
				(vias not_allowed)
				(pads allowed)
				(copperpour not_allowed)
				(footprints allowed)
			)
			(placement
				(enabled no)
				(sheetname "")
			)
			(fill
				(thermal_gap 0.5)
				(thermal_bridge_width 0.5)
				(island_removal_mode 0)
			)
			(polygon
				(pts
					(arc
						(start 233.98099 -57.999884)
						(mid 233.21899 -57.999884)
						(end 233.98099 -57.999884)
					)
				)
			)
		)
		(zone
			(layer "F.Cu")
			(hatch none 0.5)
			(connect_pads
				(clearance 0)
			)
			(min_thickness 0.25)
			(keepout
				(tracks allowed)
				(vias not_allowed)
				(pads allowed)
				(copperpour not_allowed)
				(footprints allowed)
			)
			(placement
				(enabled no)
				(sheetname "")
			)
			(fill
				(thermal_gap 0.5)
				(thermal_bridge_width 0.5)
				(island_removal_mode 0)
			)
			(polygon
				(pts
					(arc
						(start 233.98099 -56.999886)
						(mid 233.21899 -56.999886)
						(end 233.98099 -56.999886)
					)
				)
			)
		)
		(zone
			(layer "F.Cu")
			(hatch none 0.5)
			(connect_pads
				(clearance 0)
			)
			(min_thickness 0.25)
			(keepout
				(tracks allowed)
				(vias not_allowed)
				(pads allowed)
				(copperpour not_allowed)
				(footprints allowed)
			)
			(placement
				(enabled no)
				(sheetname "")
			)
			(fill
				(thermal_gap 0.5)
				(thermal_bridge_width 0.5)
				(island_removal_mode 0)
			)
			(polygon
				(pts
					(arc
						(start 233.98099 -55.999888)
						(mid 233.21899 -55.999888)
						(end 233.98099 -55.999888)
					)
				)
			)
		)
		(zone
			(layer "F.Cu")
			(hatch none 0.5)
			(connect_pads
				(clearance 0)
			)
			(min_thickness 0.25)
			(keepout
				(tracks allowed)
				(vias not_allowed)
				(pads allowed)
				(copperpour not_allowed)
				(footprints allowed)
			)
			(placement
				(enabled no)
				(sheetname "")
			)
			(fill
				(thermal_gap 0.5)
				(thermal_bridge_width 0.5)
				(island_removal_mode 0)
			)
			(polygon
				(pts
					(arc
						(start 233.98099 -54.99989)
						(mid 233.21899 -54.99989)
						(end 233.98099 -54.99989)
					)
				)
			)
		)
		(zone
			(layer "F.Cu")
			(hatch none 0.5)
			(connect_pads
				(clearance 0)
			)
			(min_thickness 0.25)
			(keepout
				(tracks allowed)
				(vias not_allowed)
				(pads allowed)
				(copperpour not_allowed)
				(footprints allowed)
			)
			(placement
				(enabled no)
				(sheetname "")
			)
			(fill
				(thermal_gap 0.5)
				(thermal_bridge_width 0.5)
				(island_removal_mode 0)
			)
			(polygon
				(pts
					(arc
						(start 233.98099 -53.999892)
						(mid 233.21899 -53.999892)
						(end 233.98099 -53.999892)
					)
				)
			)
		)
		(zone
			(layer "F.Cu")
			(hatch none 0.5)
			(connect_pads
				(clearance 0)
			)
			(min_thickness 0.25)
			(keepout
				(tracks allowed)
				(vias not_allowed)
				(pads allowed)
				(copperpour not_allowed)
				(footprints allowed)
			)
			(placement
				(enabled no)
				(sheetname "")
			)
			(fill
				(thermal_gap 0.5)
				(thermal_bridge_width 0.5)
				(island_removal_mode 0)
			)
			(polygon
				(pts
					(arc
						(start 233.98099 -52.999894)
						(mid 233.21899 -52.999894)
						(end 233.98099 -52.999894)
					)
				)
			)
		)
		(zone
			(layer "F.Cu")
			(hatch none 0.5)
			(connect_pads
				(clearance 0)
			)
			(min_thickness 0.25)
			(keepout
				(tracks allowed)
				(vias not_allowed)
				(pads allowed)
				(copperpour not_allowed)
				(footprints allowed)
			)
			(placement
				(enabled no)
				(sheetname "")
			)
			(fill
				(thermal_gap 0.5)
				(thermal_bridge_width 0.5)
				(island_removal_mode 0)
			)
			(polygon
				(pts
					(arc
						(start 233.98099 -51.999896)
						(mid 233.21899 -51.999896)
						(end 233.98099 -51.999896)
					)
				)
			)
		)
		(zone
			(layer "F.Cu")
			(hatch none 0.5)
			(connect_pads
				(clearance 0)
			)
			(min_thickness 0.25)
			(keepout
				(tracks allowed)
				(vias not_allowed)
				(pads allowed)
				(copperpour not_allowed)
				(footprints allowed)
			)
			(placement
				(enabled no)
				(sheetname "")
			)
			(fill
				(thermal_gap 0.5)
				(thermal_bridge_width 0.5)
				(island_removal_mode 0)
			)
			(polygon
				(pts
					(arc
						(start 233.98099 -50.999898)
						(mid 233.21899 -50.999898)
						(end 233.98099 -50.999898)
					)
				)
			)
		)
		(zone
			(layer "F.Cu")
			(hatch none 0.5)
			(connect_pads
				(clearance 0)
			)
			(min_thickness 0.25)
			(keepout
				(tracks allowed)
				(vias not_allowed)
				(pads allowed)
				(copperpour not_allowed)
				(footprints allowed)
			)
			(placement
				(enabled no)
				(sheetname "")
			)
			(fill
				(thermal_gap 0.5)
				(thermal_bridge_width 0.5)
				(island_removal_mode 0)
			)
			(polygon
				(pts
					(arc
						(start 233.98099 -49.9999)
						(mid 233.21899 -49.9999)
						(end 233.98099 -49.9999)
					)
				)
			)
		)
		(zone
			(layer "F.Cu")
			(hatch none 0.5)
			(connect_pads
				(clearance 0)
			)
			(min_thickness 0.25)
			(keepout
				(tracks allowed)
				(vias not_allowed)
				(pads allowed)
				(copperpour not_allowed)
				(footprints allowed)
			)
			(placement
				(enabled no)
				(sheetname "")
			)
			(fill
				(thermal_gap 0.5)
				(thermal_bridge_width 0.5)
				(island_removal_mode 0)
			)
			(polygon
				(pts
					(arc
						(start 233.98099 -48.999902)
						(mid 233.21899 -48.999902)
						(end 233.98099 -48.999902)
					)
				)
			)
		)
		(zone
			(layer "F.Cu")
			(hatch none 0.5)
			(connect_pads
				(clearance 0)
			)
			(min_thickness 0.25)
			(keepout
				(tracks allowed)
				(vias not_allowed)
				(pads allowed)
				(copperpour not_allowed)
				(footprints allowed)
			)
			(placement
				(enabled no)
				(sheetname "")
			)
			(fill
				(thermal_gap 0.5)
				(thermal_bridge_width 0.5)
				(island_removal_mode 0)
			)
			(polygon
				(pts
					(arc
						(start 233.98099 -47.999904)
						(mid 233.21899 -47.999904)
						(end 233.98099 -47.999904)
					)
				)
			)
		)
		(zone
			(layer "F.Cu")
			(hatch none 0.5)
			(connect_pads
				(clearance 0)
			)
			(min_thickness 0.25)
			(keepout
				(tracks allowed)
				(vias not_allowed)
				(pads allowed)
				(copperpour not_allowed)
				(footprints allowed)
			)
			(placement
				(enabled no)
				(sheetname "")
			)
			(fill
				(thermal_gap 0.5)
				(thermal_bridge_width 0.5)
				(island_removal_mode 0)
			)
			(polygon
				(pts
					(arc
						(start 233.98099 -46.999906)
						(mid 233.21899 -46.999906)
						(end 233.98099 -46.999906)
					)
				)
			)
		)
		(zone
			(layer "F.Cu")
			(hatch none 0.5)
			(connect_pads
				(clearance 0)
			)
			(min_thickness 0.25)
			(keepout
				(tracks allowed)
				(vias not_allowed)
				(pads allowed)
				(copperpour not_allowed)
				(footprints allowed)
			)
			(placement
				(enabled no)
				(sheetname "")
			)
			(fill
				(thermal_gap 0.5)
				(thermal_bridge_width 0.5)
				(island_removal_mode 0)
			)
			(polygon
				(pts
					(arc
						(start 233.98099 -45.999908)
						(mid 233.21899 -45.999908)
						(end 233.98099 -45.999908)
					)
				)
			)
		)
		(zone
			(layer "F.Cu")
			(hatch none 0.5)
			(connect_pads
				(clearance 0)
			)
			(min_thickness 0.25)
			(keepout
				(tracks allowed)
				(vias not_allowed)
				(pads allowed)
				(copperpour not_allowed)
				(footprints allowed)
			)
			(placement
				(enabled no)
				(sheetname "")
			)
			(fill
				(thermal_gap 0.5)
				(thermal_bridge_width 0.5)
				(island_removal_mode 0)
			)
			(polygon
				(pts
					(arc
						(start 233.98099 -44.99991)
						(mid 233.21899 -44.99991)
						(end 233.98099 -44.99991)
					)
				)
			)
		)
		(zone
			(layer "F.Cu")
			(hatch none 0.5)
			(connect_pads
				(clearance 0)
			)
			(min_thickness 0.25)
			(keepout
				(tracks allowed)
				(vias not_allowed)
				(pads allowed)
				(copperpour not_allowed)
				(footprints allowed)
			)
			(placement
				(enabled no)
				(sheetname "")
			)
			(fill
				(thermal_gap 0.5)
				(thermal_bridge_width 0.5)
				(island_removal_mode 0)
			)
			(polygon
				(pts
					(arc
						(start 233.98099 -43.999912)
						(mid 233.21899 -43.999912)
						(end 233.98099 -43.999912)
					)
				)
			)
		)
		(zone
			(layer "F.Cu")
			(hatch none 0.5)
			(connect_pads
				(clearance 0)
			)
			(min_thickness 0.25)
			(keepout
				(tracks allowed)
				(vias not_allowed)
				(pads allowed)
				(copperpour not_allowed)
				(footprints allowed)
			)
			(placement
				(enabled no)
				(sheetname "")
			)
			(fill
				(thermal_gap 0.5)
				(thermal_bridge_width 0.5)
				(island_removal_mode 0)
			)
			(polygon
				(pts
					(arc
						(start 233.98099 -42.999914)
						(mid 233.21899 -42.999914)
						(end 233.98099 -42.999914)
					)
				)
			)
		)
		(zone
			(layer "F.Cu")
			(hatch none 0.5)
			(connect_pads
				(clearance 0)
			)
			(min_thickness 0.25)
			(keepout
				(tracks allowed)
				(vias not_allowed)
				(pads allowed)
				(copperpour not_allowed)
				(footprints allowed)
			)
			(placement
				(enabled no)
				(sheetname "")
			)
			(fill
				(thermal_gap 0.5)
				(thermal_bridge_width 0.5)
				(island_removal_mode 0)
			)
			(polygon
				(pts
					(arc
						(start 233.98099 -41.999916)
						(mid 233.21899 -41.999916)
						(end 233.98099 -41.999916)
					)
				)
			)
		)
		(zone
			(layer "F.Cu")
			(hatch none 0.5)
			(connect_pads
				(clearance 0)
			)
			(min_thickness 0.25)
			(keepout
				(tracks allowed)
				(vias not_allowed)
				(pads allowed)
				(copperpour not_allowed)
				(footprints allowed)
			)
			(placement
				(enabled no)
				(sheetname "")
			)
			(fill
				(thermal_gap 0.5)
				(thermal_bridge_width 0.5)
				(island_removal_mode 0)
			)
			(polygon
				(pts
					(arc
						(start 233.98099 -40.999918)
						(mid 233.21899 -40.999918)
						(end 233.98099 -40.999918)
					)
				)
			)
		)
		(zone
			(layer "F.Cu")
			(hatch none 0.5)
			(connect_pads
				(clearance 0)
			)
			(min_thickness 0.25)
			(keepout
				(tracks allowed)
				(vias not_allowed)
				(pads allowed)
				(copperpour not_allowed)
				(footprints allowed)
			)
			(placement
				(enabled no)
				(sheetname "")
			)
			(fill
				(thermal_gap 0.5)
				(thermal_bridge_width 0.5)
				(island_removal_mode 0)
			)
			(polygon
				(pts
					(arc
						(start 233.98099 -39.99992)
						(mid 233.21899 -39.99992)
						(end 233.98099 -39.99992)
					)
				)
			)
		)
		(zone
			(layer "F.Cu")
			(hatch none 0.5)
			(connect_pads
				(clearance 0)
			)
			(min_thickness 0.25)
			(keepout
				(tracks allowed)
				(vias not_allowed)
				(pads allowed)
				(copperpour not_allowed)
				(footprints allowed)
			)
			(placement
				(enabled no)
				(sheetname "")
			)
			(fill
				(thermal_gap 0.5)
				(thermal_bridge_width 0.5)
				(island_removal_mode 0)
			)
			(polygon
				(pts
					(arc
						(start 233.98099 -38.999922)
						(mid 233.21899 -38.999922)
						(end 233.98099 -38.999922)
					)
				)
			)
		)
		(zone
			(layer "F.Cu")
			(hatch none 0.5)
			(connect_pads
				(clearance 0)
			)
			(min_thickness 0.25)
			(keepout
				(tracks allowed)
				(vias not_allowed)
				(pads allowed)
				(copperpour not_allowed)
				(footprints allowed)
			)
			(placement
				(enabled no)
				(sheetname "")
			)
			(fill
				(thermal_gap 0.5)
				(thermal_bridge_width 0.5)
				(island_removal_mode 0)
			)
			(polygon
				(pts
					(arc
						(start 233.98099 -37.999924)
						(mid 233.21899 -37.999924)
						(end 233.98099 -37.999924)
					)
				)
			)
		)
		(zone
			(layer "F.Cu")
			(hatch none 0.5)
			(connect_pads
				(clearance 0)
			)
			(min_thickness 0.25)
			(keepout
				(tracks allowed)
				(vias not_allowed)
				(pads allowed)
				(copperpour not_allowed)
				(footprints allowed)
			)
			(placement
				(enabled no)
				(sheetname "")
			)
			(fill
				(thermal_gap 0.5)
				(thermal_bridge_width 0.5)
				(island_removal_mode 0)
			)
			(polygon
				(pts
					(arc
						(start 233.98099 -36.999926)
						(mid 233.21899 -36.999926)
						(end 233.98099 -36.999926)
					)
				)
			)
		)
		(zone
			(layer "F.Cu")
			(hatch none 0.5)
			(connect_pads
				(clearance 0)
			)
			(min_thickness 0.25)
			(keepout
				(tracks allowed)
				(vias not_allowed)
				(pads allowed)
				(copperpour not_allowed)
				(footprints allowed)
			)
			(placement
				(enabled no)
				(sheetname "")
			)
			(fill
				(thermal_gap 0.5)
				(thermal_bridge_width 0.5)
				(island_removal_mode 0)
			)
			(polygon
				(pts
					(arc
						(start 233.98099 -35.999928)
						(mid 233.21899 -35.999928)
						(end 233.98099 -35.999928)
					)
				)
			)
		)
		(zone
			(layer "F.Cu")
			(hatch none 0.5)
			(connect_pads
				(clearance 0)
			)
			(min_thickness 0.25)
			(keepout
				(tracks allowed)
				(vias not_allowed)
				(pads allowed)
				(copperpour not_allowed)
				(footprints allowed)
			)
			(placement
				(enabled no)
				(sheetname "")
			)
			(fill
				(thermal_gap 0.5)
				(thermal_bridge_width 0.5)
				(island_removal_mode 0)
			)
			(polygon
				(pts
					(arc
						(start 233.98099 -34.99993)
						(mid 233.21899 -34.99993)
						(end 233.98099 -34.99993)
					)
				)
			)
		)
		(zone
			(layer "F.Cu")
			(hatch none 0.5)
			(connect_pads
				(clearance 0)
			)
			(min_thickness 0.25)
			(keepout
				(tracks allowed)
				(vias not_allowed)
				(pads allowed)
				(copperpour not_allowed)
				(footprints allowed)
			)
			(placement
				(enabled no)
				(sheetname "")
			)
			(fill
				(thermal_gap 0.5)
				(thermal_bridge_width 0.5)
				(island_removal_mode 0)
			)
			(polygon
				(pts
					(arc
						(start 233.98099 -33.999932)
						(mid 233.21899 -33.999932)
						(end 233.98099 -33.999932)
					)
				)
			)
		)
		(zone
			(layer "F.Cu")
			(hatch none 0.5)
			(connect_pads
				(clearance 0)
			)
			(min_thickness 0.25)
			(keepout
				(tracks allowed)
				(vias not_allowed)
				(pads allowed)
				(copperpour not_allowed)
				(footprints allowed)
			)
			(placement
				(enabled no)
				(sheetname "")
			)
			(fill
				(thermal_gap 0.5)
				(thermal_bridge_width 0.5)
				(island_removal_mode 0)
			)
			(polygon
				(pts
					(arc
						(start 233.98099 -32.999934)
						(mid 233.21899 -32.999934)
						(end 233.98099 -32.999934)
					)
				)
			)
		)
		(zone
			(layer "F.Cu")
			(hatch none 0.5)
			(connect_pads
				(clearance 0)
			)
			(min_thickness 0.25)
			(keepout
				(tracks allowed)
				(vias not_allowed)
				(pads allowed)
				(copperpour not_allowed)
				(footprints allowed)
			)
			(placement
				(enabled no)
				(sheetname "")
			)
			(fill
				(thermal_gap 0.5)
				(thermal_bridge_width 0.5)
				(island_removal_mode 0)
			)
			(polygon
				(pts
					(arc
						(start 233.98099 -31.999936)
						(mid 233.21899 -31.999936)
						(end 233.98099 -31.999936)
					)
				)
			)
		)
		(zone
			(layer "F.Cu")
			(hatch none 0.5)
			(connect_pads
				(clearance 0)
			)
			(min_thickness 0.25)
			(keepout
				(tracks allowed)
				(vias not_allowed)
				(pads allowed)
				(copperpour not_allowed)
				(footprints allowed)
			)
			(placement
				(enabled no)
				(sheetname "")
			)
			(fill
				(thermal_gap 0.5)
				(thermal_bridge_width 0.5)
				(island_removal_mode 0)
			)
			(polygon
				(pts
					(arc
						(start 233.98099 -30.999938)
						(mid 233.21899 -30.999938)
						(end 233.98099 -30.999938)
					)
				)
			)
		)
		(zone
			(layer "F.Cu")
			(hatch none 0.5)
			(connect_pads
				(clearance 0)
			)
			(min_thickness 0.25)
			(keepout
				(tracks allowed)
				(vias not_allowed)
				(pads allowed)
				(copperpour not_allowed)
				(footprints allowed)
			)
			(placement
				(enabled no)
				(sheetname "")
			)
			(fill
				(thermal_gap 0.5)
				(thermal_bridge_width 0.5)
				(island_removal_mode 0)
			)
			(polygon
				(pts
					(arc
						(start 234.980988 -65.999868)
						(mid 234.218988 -65.999868)
						(end 234.980988 -65.999868)
					)
				)
			)
		)
		(zone
			(layer "F.Cu")
			(hatch none 0.5)
			(connect_pads
				(clearance 0)
			)
			(min_thickness 0.25)
			(keepout
				(tracks allowed)
				(vias not_allowed)
				(pads allowed)
				(copperpour not_allowed)
				(footprints allowed)
			)
			(placement
				(enabled no)
				(sheetname "")
			)
			(fill
				(thermal_gap 0.5)
				(thermal_bridge_width 0.5)
				(island_removal_mode 0)
			)
			(polygon
				(pts
					(arc
						(start 234.980988 -64.99987)
						(mid 234.218988 -64.99987)
						(end 234.980988 -64.99987)
					)
				)
			)
		)
		(zone
			(layer "F.Cu")
			(hatch none 0.5)
			(connect_pads
				(clearance 0)
			)
			(min_thickness 0.25)
			(keepout
				(tracks allowed)
				(vias not_allowed)
				(pads allowed)
				(copperpour not_allowed)
				(footprints allowed)
			)
			(placement
				(enabled no)
				(sheetname "")
			)
			(fill
				(thermal_gap 0.5)
				(thermal_bridge_width 0.5)
				(island_removal_mode 0)
			)
			(polygon
				(pts
					(arc
						(start 234.980988 -63.999872)
						(mid 234.218988 -63.999872)
						(end 234.980988 -63.999872)
					)
				)
			)
		)
		(zone
			(layer "F.Cu")
			(hatch none 0.5)
			(connect_pads
				(clearance 0)
			)
			(min_thickness 0.25)
			(keepout
				(tracks allowed)
				(vias not_allowed)
				(pads allowed)
				(copperpour not_allowed)
				(footprints allowed)
			)
			(placement
				(enabled no)
				(sheetname "")
			)
			(fill
				(thermal_gap 0.5)
				(thermal_bridge_width 0.5)
				(island_removal_mode 0)
			)
			(polygon
				(pts
					(arc
						(start 234.980988 -62.999874)
						(mid 234.218988 -62.999874)
						(end 234.980988 -62.999874)
					)
				)
			)
		)
		(zone
			(layer "F.Cu")
			(hatch none 0.5)
			(connect_pads
				(clearance 0)
			)
			(min_thickness 0.25)
			(keepout
				(tracks allowed)
				(vias not_allowed)
				(pads allowed)
				(copperpour not_allowed)
				(footprints allowed)
			)
			(placement
				(enabled no)
				(sheetname "")
			)
			(fill
				(thermal_gap 0.5)
				(thermal_bridge_width 0.5)
				(island_removal_mode 0)
			)
			(polygon
				(pts
					(arc
						(start 234.980988 -61.999876)
						(mid 234.218988 -61.999876)
						(end 234.980988 -61.999876)
					)
				)
			)
		)
		(zone
			(layer "F.Cu")
			(hatch none 0.5)
			(connect_pads
				(clearance 0)
			)
			(min_thickness 0.25)
			(keepout
				(tracks allowed)
				(vias not_allowed)
				(pads allowed)
				(copperpour not_allowed)
				(footprints allowed)
			)
			(placement
				(enabled no)
				(sheetname "")
			)
			(fill
				(thermal_gap 0.5)
				(thermal_bridge_width 0.5)
				(island_removal_mode 0)
			)
			(polygon
				(pts
					(arc
						(start 234.980988 -60.999878)
						(mid 234.218988 -60.999878)
						(end 234.980988 -60.999878)
					)
				)
			)
		)
		(zone
			(layer "F.Cu")
			(hatch none 0.5)
			(connect_pads
				(clearance 0)
			)
			(min_thickness 0.25)
			(keepout
				(tracks allowed)
				(vias not_allowed)
				(pads allowed)
				(copperpour not_allowed)
				(footprints allowed)
			)
			(placement
				(enabled no)
				(sheetname "")
			)
			(fill
				(thermal_gap 0.5)
				(thermal_bridge_width 0.5)
				(island_removal_mode 0)
			)
			(polygon
				(pts
					(arc
						(start 234.980988 -59.99988)
						(mid 234.218988 -59.99988)
						(end 234.980988 -59.99988)
					)
				)
			)
		)
		(zone
			(layer "F.Cu")
			(hatch none 0.5)
			(connect_pads
				(clearance 0)
			)
			(min_thickness 0.25)
			(keepout
				(tracks allowed)
				(vias not_allowed)
				(pads allowed)
				(copperpour not_allowed)
				(footprints allowed)
			)
			(placement
				(enabled no)
				(sheetname "")
			)
			(fill
				(thermal_gap 0.5)
				(thermal_bridge_width 0.5)
				(island_removal_mode 0)
			)
			(polygon
				(pts
					(arc
						(start 234.980988 -58.999882)
						(mid 234.218988 -58.999882)
						(end 234.980988 -58.999882)
					)
				)
			)
		)
		(zone
			(layer "F.Cu")
			(hatch none 0.5)
			(connect_pads
				(clearance 0)
			)
			(min_thickness 0.25)
			(keepout
				(tracks allowed)
				(vias not_allowed)
				(pads allowed)
				(copperpour not_allowed)
				(footprints allowed)
			)
			(placement
				(enabled no)
				(sheetname "")
			)
			(fill
				(thermal_gap 0.5)
				(thermal_bridge_width 0.5)
				(island_removal_mode 0)
			)
			(polygon
				(pts
					(arc
						(start 234.980988 -57.999884)
						(mid 234.218988 -57.999884)
						(end 234.980988 -57.999884)
					)
				)
			)
		)
		(zone
			(layer "F.Cu")
			(hatch none 0.5)
			(connect_pads
				(clearance 0)
			)
			(min_thickness 0.25)
			(keepout
				(tracks allowed)
				(vias not_allowed)
				(pads allowed)
				(copperpour not_allowed)
				(footprints allowed)
			)
			(placement
				(enabled no)
				(sheetname "")
			)
			(fill
				(thermal_gap 0.5)
				(thermal_bridge_width 0.5)
				(island_removal_mode 0)
			)
			(polygon
				(pts
					(arc
						(start 234.980988 -56.999886)
						(mid 234.218988 -56.999886)
						(end 234.980988 -56.999886)
					)
				)
			)
		)
		(zone
			(layer "F.Cu")
			(hatch none 0.5)
			(connect_pads
				(clearance 0)
			)
			(min_thickness 0.25)
			(keepout
				(tracks allowed)
				(vias not_allowed)
				(pads allowed)
				(copperpour not_allowed)
				(footprints allowed)
			)
			(placement
				(enabled no)
				(sheetname "")
			)
			(fill
				(thermal_gap 0.5)
				(thermal_bridge_width 0.5)
				(island_removal_mode 0)
			)
			(polygon
				(pts
					(arc
						(start 234.980988 -55.999888)
						(mid 234.218988 -55.999888)
						(end 234.980988 -55.999888)
					)
				)
			)
		)
		(zone
			(layer "F.Cu")
			(hatch none 0.5)
			(connect_pads
				(clearance 0)
			)
			(min_thickness 0.25)
			(keepout
				(tracks allowed)
				(vias not_allowed)
				(pads allowed)
				(copperpour not_allowed)
				(footprints allowed)
			)
			(placement
				(enabled no)
				(sheetname "")
			)
			(fill
				(thermal_gap 0.5)
				(thermal_bridge_width 0.5)
				(island_removal_mode 0)
			)
			(polygon
				(pts
					(arc
						(start 234.980988 -54.99989)
						(mid 234.218988 -54.99989)
						(end 234.980988 -54.99989)
					)
				)
			)
		)
		(zone
			(layer "F.Cu")
			(hatch none 0.5)
			(connect_pads
				(clearance 0)
			)
			(min_thickness 0.25)
			(keepout
				(tracks allowed)
				(vias not_allowed)
				(pads allowed)
				(copperpour not_allowed)
				(footprints allowed)
			)
			(placement
				(enabled no)
				(sheetname "")
			)
			(fill
				(thermal_gap 0.5)
				(thermal_bridge_width 0.5)
				(island_removal_mode 0)
			)
			(polygon
				(pts
					(arc
						(start 234.980988 -53.999892)
						(mid 234.218988 -53.999892)
						(end 234.980988 -53.999892)
					)
				)
			)
		)
		(zone
			(layer "F.Cu")
			(hatch none 0.5)
			(connect_pads
				(clearance 0)
			)
			(min_thickness 0.25)
			(keepout
				(tracks allowed)
				(vias not_allowed)
				(pads allowed)
				(copperpour not_allowed)
				(footprints allowed)
			)
			(placement
				(enabled no)
				(sheetname "")
			)
			(fill
				(thermal_gap 0.5)
				(thermal_bridge_width 0.5)
				(island_removal_mode 0)
			)
			(polygon
				(pts
					(arc
						(start 234.980988 -52.999894)
						(mid 234.218988 -52.999894)
						(end 234.980988 -52.999894)
					)
				)
			)
		)
		(zone
			(layer "F.Cu")
			(hatch none 0.5)
			(connect_pads
				(clearance 0)
			)
			(min_thickness 0.25)
			(keepout
				(tracks allowed)
				(vias not_allowed)
				(pads allowed)
				(copperpour not_allowed)
				(footprints allowed)
			)
			(placement
				(enabled no)
				(sheetname "")
			)
			(fill
				(thermal_gap 0.5)
				(thermal_bridge_width 0.5)
				(island_removal_mode 0)
			)
			(polygon
				(pts
					(arc
						(start 234.980988 -51.999896)
						(mid 234.218988 -51.999896)
						(end 234.980988 -51.999896)
					)
				)
			)
		)
		(zone
			(layer "F.Cu")
			(hatch none 0.5)
			(connect_pads
				(clearance 0)
			)
			(min_thickness 0.25)
			(keepout
				(tracks allowed)
				(vias not_allowed)
				(pads allowed)
				(copperpour not_allowed)
				(footprints allowed)
			)
			(placement
				(enabled no)
				(sheetname "")
			)
			(fill
				(thermal_gap 0.5)
				(thermal_bridge_width 0.5)
				(island_removal_mode 0)
			)
			(polygon
				(pts
					(arc
						(start 234.980988 -50.999898)
						(mid 234.218988 -50.999898)
						(end 234.980988 -50.999898)
					)
				)
			)
		)
		(zone
			(layer "F.Cu")
			(hatch none 0.5)
			(connect_pads
				(clearance 0)
			)
			(min_thickness 0.25)
			(keepout
				(tracks allowed)
				(vias not_allowed)
				(pads allowed)
				(copperpour not_allowed)
				(footprints allowed)
			)
			(placement
				(enabled no)
				(sheetname "")
			)
			(fill
				(thermal_gap 0.5)
				(thermal_bridge_width 0.5)
				(island_removal_mode 0)
			)
			(polygon
				(pts
					(arc
						(start 234.980988 -49.9999)
						(mid 234.218988 -49.9999)
						(end 234.980988 -49.9999)
					)
				)
			)
		)
		(zone
			(layer "F.Cu")
			(hatch none 0.5)
			(connect_pads
				(clearance 0)
			)
			(min_thickness 0.25)
			(keepout
				(tracks allowed)
				(vias not_allowed)
				(pads allowed)
				(copperpour not_allowed)
				(footprints allowed)
			)
			(placement
				(enabled no)
				(sheetname "")
			)
			(fill
				(thermal_gap 0.5)
				(thermal_bridge_width 0.5)
				(island_removal_mode 0)
			)
			(polygon
				(pts
					(arc
						(start 234.980988 -48.999902)
						(mid 234.218988 -48.999902)
						(end 234.980988 -48.999902)
					)
				)
			)
		)
		(zone
			(layer "F.Cu")
			(hatch none 0.5)
			(connect_pads
				(clearance 0)
			)
			(min_thickness 0.25)
			(keepout
				(tracks allowed)
				(vias not_allowed)
				(pads allowed)
				(copperpour not_allowed)
				(footprints allowed)
			)
			(placement
				(enabled no)
				(sheetname "")
			)
			(fill
				(thermal_gap 0.5)
				(thermal_bridge_width 0.5)
				(island_removal_mode 0)
			)
			(polygon
				(pts
					(arc
						(start 234.980988 -47.999904)
						(mid 234.218988 -47.999904)
						(end 234.980988 -47.999904)
					)
				)
			)
		)
		(zone
			(layer "F.Cu")
			(hatch none 0.5)
			(connect_pads
				(clearance 0)
			)
			(min_thickness 0.25)
			(keepout
				(tracks allowed)
				(vias not_allowed)
				(pads allowed)
				(copperpour not_allowed)
				(footprints allowed)
			)
			(placement
				(enabled no)
				(sheetname "")
			)
			(fill
				(thermal_gap 0.5)
				(thermal_bridge_width 0.5)
				(island_removal_mode 0)
			)
			(polygon
				(pts
					(arc
						(start 234.980988 -46.999906)
						(mid 234.218988 -46.999906)
						(end 234.980988 -46.999906)
					)
				)
			)
		)
		(zone
			(layer "F.Cu")
			(hatch none 0.5)
			(connect_pads
				(clearance 0)
			)
			(min_thickness 0.25)
			(keepout
				(tracks allowed)
				(vias not_allowed)
				(pads allowed)
				(copperpour not_allowed)
				(footprints allowed)
			)
			(placement
				(enabled no)
				(sheetname "")
			)
			(fill
				(thermal_gap 0.5)
				(thermal_bridge_width 0.5)
				(island_removal_mode 0)
			)
			(polygon
				(pts
					(arc
						(start 234.980988 -45.999908)
						(mid 234.218988 -45.999908)
						(end 234.980988 -45.999908)
					)
				)
			)
		)
		(zone
			(layer "F.Cu")
			(hatch none 0.5)
			(connect_pads
				(clearance 0)
			)
			(min_thickness 0.25)
			(keepout
				(tracks allowed)
				(vias not_allowed)
				(pads allowed)
				(copperpour not_allowed)
				(footprints allowed)
			)
			(placement
				(enabled no)
				(sheetname "")
			)
			(fill
				(thermal_gap 0.5)
				(thermal_bridge_width 0.5)
				(island_removal_mode 0)
			)
			(polygon
				(pts
					(arc
						(start 234.980988 -44.99991)
						(mid 234.218988 -44.99991)
						(end 234.980988 -44.99991)
					)
				)
			)
		)
		(zone
			(layer "F.Cu")
			(hatch none 0.5)
			(connect_pads
				(clearance 0)
			)
			(min_thickness 0.25)
			(keepout
				(tracks allowed)
				(vias not_allowed)
				(pads allowed)
				(copperpour not_allowed)
				(footprints allowed)
			)
			(placement
				(enabled no)
				(sheetname "")
			)
			(fill
				(thermal_gap 0.5)
				(thermal_bridge_width 0.5)
				(island_removal_mode 0)
			)
			(polygon
				(pts
					(arc
						(start 234.980988 -43.999912)
						(mid 234.218988 -43.999912)
						(end 234.980988 -43.999912)
					)
				)
			)
		)
		(zone
			(layer "F.Cu")
			(hatch none 0.5)
			(connect_pads
				(clearance 0)
			)
			(min_thickness 0.25)
			(keepout
				(tracks allowed)
				(vias not_allowed)
				(pads allowed)
				(copperpour not_allowed)
				(footprints allowed)
			)
			(placement
				(enabled no)
				(sheetname "")
			)
			(fill
				(thermal_gap 0.5)
				(thermal_bridge_width 0.5)
				(island_removal_mode 0)
			)
			(polygon
				(pts
					(arc
						(start 234.980988 -42.999914)
						(mid 234.218988 -42.999914)
						(end 234.980988 -42.999914)
					)
				)
			)
		)
		(zone
			(layer "F.Cu")
			(hatch none 0.5)
			(connect_pads
				(clearance 0)
			)
			(min_thickness 0.25)
			(keepout
				(tracks allowed)
				(vias not_allowed)
				(pads allowed)
				(copperpour not_allowed)
				(footprints allowed)
			)
			(placement
				(enabled no)
				(sheetname "")
			)
			(fill
				(thermal_gap 0.5)
				(thermal_bridge_width 0.5)
				(island_removal_mode 0)
			)
			(polygon
				(pts
					(arc
						(start 234.980988 -41.999916)
						(mid 234.218988 -41.999916)
						(end 234.980988 -41.999916)
					)
				)
			)
		)
		(zone
			(layer "F.Cu")
			(hatch none 0.5)
			(connect_pads
				(clearance 0)
			)
			(min_thickness 0.25)
			(keepout
				(tracks allowed)
				(vias not_allowed)
				(pads allowed)
				(copperpour not_allowed)
				(footprints allowed)
			)
			(placement
				(enabled no)
				(sheetname "")
			)
			(fill
				(thermal_gap 0.5)
				(thermal_bridge_width 0.5)
				(island_removal_mode 0)
			)
			(polygon
				(pts
					(arc
						(start 234.980988 -40.999918)
						(mid 234.218988 -40.999918)
						(end 234.980988 -40.999918)
					)
				)
			)
		)
		(zone
			(layer "F.Cu")
			(hatch none 0.5)
			(connect_pads
				(clearance 0)
			)
			(min_thickness 0.25)
			(keepout
				(tracks allowed)
				(vias not_allowed)
				(pads allowed)
				(copperpour not_allowed)
				(footprints allowed)
			)
			(placement
				(enabled no)
				(sheetname "")
			)
			(fill
				(thermal_gap 0.5)
				(thermal_bridge_width 0.5)
				(island_removal_mode 0)
			)
			(polygon
				(pts
					(arc
						(start 234.980988 -39.99992)
						(mid 234.218988 -39.99992)
						(end 234.980988 -39.99992)
					)
				)
			)
		)
		(zone
			(layer "F.Cu")
			(hatch none 0.5)
			(connect_pads
				(clearance 0)
			)
			(min_thickness 0.25)
			(keepout
				(tracks allowed)
				(vias not_allowed)
				(pads allowed)
				(copperpour not_allowed)
				(footprints allowed)
			)
			(placement
				(enabled no)
				(sheetname "")
			)
			(fill
				(thermal_gap 0.5)
				(thermal_bridge_width 0.5)
				(island_removal_mode 0)
			)
			(polygon
				(pts
					(arc
						(start 234.980988 -38.999922)
						(mid 234.218988 -38.999922)
						(end 234.980988 -38.999922)
					)
				)
			)
		)
		(zone
			(layer "F.Cu")
			(hatch none 0.5)
			(connect_pads
				(clearance 0)
			)
			(min_thickness 0.25)
			(keepout
				(tracks allowed)
				(vias not_allowed)
				(pads allowed)
				(copperpour not_allowed)
				(footprints allowed)
			)
			(placement
				(enabled no)
				(sheetname "")
			)
			(fill
				(thermal_gap 0.5)
				(thermal_bridge_width 0.5)
				(island_removal_mode 0)
			)
			(polygon
				(pts
					(arc
						(start 234.980988 -37.999924)
						(mid 234.218988 -37.999924)
						(end 234.980988 -37.999924)
					)
				)
			)
		)
		(zone
			(layer "F.Cu")
			(hatch none 0.5)
			(connect_pads
				(clearance 0)
			)
			(min_thickness 0.25)
			(keepout
				(tracks allowed)
				(vias not_allowed)
				(pads allowed)
				(copperpour not_allowed)
				(footprints allowed)
			)
			(placement
				(enabled no)
				(sheetname "")
			)
			(fill
				(thermal_gap 0.5)
				(thermal_bridge_width 0.5)
				(island_removal_mode 0)
			)
			(polygon
				(pts
					(arc
						(start 234.980988 -36.999926)
						(mid 234.218988 -36.999926)
						(end 234.980988 -36.999926)
					)
				)
			)
		)
		(zone
			(layer "F.Cu")
			(hatch none 0.5)
			(connect_pads
				(clearance 0)
			)
			(min_thickness 0.25)
			(keepout
				(tracks allowed)
				(vias not_allowed)
				(pads allowed)
				(copperpour not_allowed)
				(footprints allowed)
			)
			(placement
				(enabled no)
				(sheetname "")
			)
			(fill
				(thermal_gap 0.5)
				(thermal_bridge_width 0.5)
				(island_removal_mode 0)
			)
			(polygon
				(pts
					(arc
						(start 234.980988 -35.999928)
						(mid 234.218988 -35.999928)
						(end 234.980988 -35.999928)
					)
				)
			)
		)
		(zone
			(layer "F.Cu")
			(hatch none 0.5)
			(connect_pads
				(clearance 0)
			)
			(min_thickness 0.25)
			(keepout
				(tracks allowed)
				(vias not_allowed)
				(pads allowed)
				(copperpour not_allowed)
				(footprints allowed)
			)
			(placement
				(enabled no)
				(sheetname "")
			)
			(fill
				(thermal_gap 0.5)
				(thermal_bridge_width 0.5)
				(island_removal_mode 0)
			)
			(polygon
				(pts
					(arc
						(start 234.980988 -34.99993)
						(mid 234.218988 -34.99993)
						(end 234.980988 -34.99993)
					)
				)
			)
		)
		(zone
			(layer "F.Cu")
			(hatch none 0.5)
			(connect_pads
				(clearance 0)
			)
			(min_thickness 0.25)
			(keepout
				(tracks allowed)
				(vias not_allowed)
				(pads allowed)
				(copperpour not_allowed)
				(footprints allowed)
			)
			(placement
				(enabled no)
				(sheetname "")
			)
			(fill
				(thermal_gap 0.5)
				(thermal_bridge_width 0.5)
				(island_removal_mode 0)
			)
			(polygon
				(pts
					(arc
						(start 234.980988 -33.999932)
						(mid 234.218988 -33.999932)
						(end 234.980988 -33.999932)
					)
				)
			)
		)
		(zone
			(layer "F.Cu")
			(hatch none 0.5)
			(connect_pads
				(clearance 0)
			)
			(min_thickness 0.25)
			(keepout
				(tracks allowed)
				(vias not_allowed)
				(pads allowed)
				(copperpour not_allowed)
				(footprints allowed)
			)
			(placement
				(enabled no)
				(sheetname "")
			)
			(fill
				(thermal_gap 0.5)
				(thermal_bridge_width 0.5)
				(island_removal_mode 0)
			)
			(polygon
				(pts
					(arc
						(start 234.980988 -32.999934)
						(mid 234.218988 -32.999934)
						(end 234.980988 -32.999934)
					)
				)
			)
		)
		(zone
			(layer "F.Cu")
			(hatch none 0.5)
			(connect_pads
				(clearance 0)
			)
			(min_thickness 0.25)
			(keepout
				(tracks allowed)
				(vias not_allowed)
				(pads allowed)
				(copperpour not_allowed)
				(footprints allowed)
			)
			(placement
				(enabled no)
				(sheetname "")
			)
			(fill
				(thermal_gap 0.5)
				(thermal_bridge_width 0.5)
				(island_removal_mode 0)
			)
			(polygon
				(pts
					(arc
						(start 234.980988 -31.999936)
						(mid 234.218988 -31.999936)
						(end 234.980988 -31.999936)
					)
				)
			)
		)
		(zone
			(layer "F.Cu")
			(hatch none 0.5)
			(connect_pads
				(clearance 0)
			)
			(min_thickness 0.25)
			(keepout
				(tracks allowed)
				(vias not_allowed)
				(pads allowed)
				(copperpour not_allowed)
				(footprints allowed)
			)
			(placement
				(enabled no)
				(sheetname "")
			)
			(fill
				(thermal_gap 0.5)
				(thermal_bridge_width 0.5)
				(island_removal_mode 0)
			)
			(polygon
				(pts
					(arc
						(start 234.980988 -30.999938)
						(mid 234.218988 -30.999938)
						(end 234.980988 -30.999938)
					)
				)
			)
		)
		(zone
			(layer "F.Cu")
			(hatch none 0.5)
			(connect_pads
				(clearance 0)
			)
			(min_thickness 0.25)
			(keepout
				(tracks allowed)
				(vias not_allowed)
				(pads allowed)
				(copperpour not_allowed)
				(footprints allowed)
			)
			(placement
				(enabled no)
				(sheetname "")
			)
			(fill
				(thermal_gap 0.5)
				(thermal_bridge_width 0.5)
				(island_removal_mode 0)
			)
			(polygon
				(pts
					(arc
						(start 234.980988 -29.99994)
						(mid 234.218988 -29.99994)
						(end 234.980988 -29.99994)
					)
				)
			)
		)
		(zone
			(layer "F.Cu")
			(hatch none 0.5)
			(connect_pads
				(clearance 0)
			)
			(min_thickness 0.25)
			(keepout
				(tracks allowed)
				(vias not_allowed)
				(pads allowed)
				(copperpour not_allowed)
				(footprints allowed)
			)
			(placement
				(enabled no)
				(sheetname "")
			)
			(fill
				(thermal_gap 0.5)
				(thermal_bridge_width 0.5)
				(island_removal_mode 0)
			)
			(polygon
				(pts
					(arc
						(start 235.980986 -64.99987)
						(mid 235.218986 -64.99987)
						(end 235.980986 -64.99987)
					)
				)
			)
		)
		(zone
			(layer "F.Cu")
			(hatch none 0.5)
			(connect_pads
				(clearance 0)
			)
			(min_thickness 0.25)
			(keepout
				(tracks allowed)
				(vias not_allowed)
				(pads allowed)
				(copperpour not_allowed)
				(footprints allowed)
			)
			(placement
				(enabled no)
				(sheetname "")
			)
			(fill
				(thermal_gap 0.5)
				(thermal_bridge_width 0.5)
				(island_removal_mode 0)
			)
			(polygon
				(pts
					(arc
						(start 235.980986 -63.999872)
						(mid 235.218986 -63.999872)
						(end 235.980986 -63.999872)
					)
				)
			)
		)
		(zone
			(layer "F.Cu")
			(hatch none 0.5)
			(connect_pads
				(clearance 0)
			)
			(min_thickness 0.25)
			(keepout
				(tracks allowed)
				(vias not_allowed)
				(pads allowed)
				(copperpour not_allowed)
				(footprints allowed)
			)
			(placement
				(enabled no)
				(sheetname "")
			)
			(fill
				(thermal_gap 0.5)
				(thermal_bridge_width 0.5)
				(island_removal_mode 0)
			)
			(polygon
				(pts
					(arc
						(start 235.980986 -62.999874)
						(mid 235.218986 -62.999874)
						(end 235.980986 -62.999874)
					)
				)
			)
		)
		(zone
			(layer "F.Cu")
			(hatch none 0.5)
			(connect_pads
				(clearance 0)
			)
			(min_thickness 0.25)
			(keepout
				(tracks allowed)
				(vias not_allowed)
				(pads allowed)
				(copperpour not_allowed)
				(footprints allowed)
			)
			(placement
				(enabled no)
				(sheetname "")
			)
			(fill
				(thermal_gap 0.5)
				(thermal_bridge_width 0.5)
				(island_removal_mode 0)
			)
			(polygon
				(pts
					(arc
						(start 235.980986 -61.999876)
						(mid 235.218986 -61.999876)
						(end 235.980986 -61.999876)
					)
				)
			)
		)
		(zone
			(layer "F.Cu")
			(hatch none 0.5)
			(connect_pads
				(clearance 0)
			)
			(min_thickness 0.25)
			(keepout
				(tracks allowed)
				(vias not_allowed)
				(pads allowed)
				(copperpour not_allowed)
				(footprints allowed)
			)
			(placement
				(enabled no)
				(sheetname "")
			)
			(fill
				(thermal_gap 0.5)
				(thermal_bridge_width 0.5)
				(island_removal_mode 0)
			)
			(polygon
				(pts
					(arc
						(start 235.980986 -60.999878)
						(mid 235.218986 -60.999878)
						(end 235.980986 -60.999878)
					)
				)
			)
		)
		(zone
			(layer "F.Cu")
			(hatch none 0.5)
			(connect_pads
				(clearance 0)
			)
			(min_thickness 0.25)
			(keepout
				(tracks allowed)
				(vias not_allowed)
				(pads allowed)
				(copperpour not_allowed)
				(footprints allowed)
			)
			(placement
				(enabled no)
				(sheetname "")
			)
			(fill
				(thermal_gap 0.5)
				(thermal_bridge_width 0.5)
				(island_removal_mode 0)
			)
			(polygon
				(pts
					(arc
						(start 235.980986 -59.99988)
						(mid 235.218986 -59.99988)
						(end 235.980986 -59.99988)
					)
				)
			)
		)
		(zone
			(layer "F.Cu")
			(hatch none 0.5)
			(connect_pads
				(clearance 0)
			)
			(min_thickness 0.25)
			(keepout
				(tracks allowed)
				(vias not_allowed)
				(pads allowed)
				(copperpour not_allowed)
				(footprints allowed)
			)
			(placement
				(enabled no)
				(sheetname "")
			)
			(fill
				(thermal_gap 0.5)
				(thermal_bridge_width 0.5)
				(island_removal_mode 0)
			)
			(polygon
				(pts
					(arc
						(start 235.980986 -58.999882)
						(mid 235.218986 -58.999882)
						(end 235.980986 -58.999882)
					)
				)
			)
		)
		(zone
			(layer "F.Cu")
			(hatch none 0.5)
			(connect_pads
				(clearance 0)
			)
			(min_thickness 0.25)
			(keepout
				(tracks allowed)
				(vias not_allowed)
				(pads allowed)
				(copperpour not_allowed)
				(footprints allowed)
			)
			(placement
				(enabled no)
				(sheetname "")
			)
			(fill
				(thermal_gap 0.5)
				(thermal_bridge_width 0.5)
				(island_removal_mode 0)
			)
			(polygon
				(pts
					(arc
						(start 235.980986 -57.999884)
						(mid 235.218986 -57.999884)
						(end 235.980986 -57.999884)
					)
				)
			)
		)
		(zone
			(layer "F.Cu")
			(hatch none 0.5)
			(connect_pads
				(clearance 0)
			)
			(min_thickness 0.25)
			(keepout
				(tracks allowed)
				(vias not_allowed)
				(pads allowed)
				(copperpour not_allowed)
				(footprints allowed)
			)
			(placement
				(enabled no)
				(sheetname "")
			)
			(fill
				(thermal_gap 0.5)
				(thermal_bridge_width 0.5)
				(island_removal_mode 0)
			)
			(polygon
				(pts
					(arc
						(start 235.980986 -56.999886)
						(mid 235.218986 -56.999886)
						(end 235.980986 -56.999886)
					)
				)
			)
		)
		(zone
			(layer "F.Cu")
			(hatch none 0.5)
			(connect_pads
				(clearance 0)
			)
			(min_thickness 0.25)
			(keepout
				(tracks allowed)
				(vias not_allowed)
				(pads allowed)
				(copperpour not_allowed)
				(footprints allowed)
			)
			(placement
				(enabled no)
				(sheetname "")
			)
			(fill
				(thermal_gap 0.5)
				(thermal_bridge_width 0.5)
				(island_removal_mode 0)
			)
			(polygon
				(pts
					(arc
						(start 235.980986 -55.999888)
						(mid 235.218986 -55.999888)
						(end 235.980986 -55.999888)
					)
				)
			)
		)
		(zone
			(layer "F.Cu")
			(hatch none 0.5)
			(connect_pads
				(clearance 0)
			)
			(min_thickness 0.25)
			(keepout
				(tracks allowed)
				(vias not_allowed)
				(pads allowed)
				(copperpour not_allowed)
				(footprints allowed)
			)
			(placement
				(enabled no)
				(sheetname "")
			)
			(fill
				(thermal_gap 0.5)
				(thermal_bridge_width 0.5)
				(island_removal_mode 0)
			)
			(polygon
				(pts
					(arc
						(start 235.980986 -54.99989)
						(mid 235.218986 -54.99989)
						(end 235.980986 -54.99989)
					)
				)
			)
		)
		(zone
			(layer "F.Cu")
			(hatch none 0.5)
			(connect_pads
				(clearance 0)
			)
			(min_thickness 0.25)
			(keepout
				(tracks allowed)
				(vias not_allowed)
				(pads allowed)
				(copperpour not_allowed)
				(footprints allowed)
			)
			(placement
				(enabled no)
				(sheetname "")
			)
			(fill
				(thermal_gap 0.5)
				(thermal_bridge_width 0.5)
				(island_removal_mode 0)
			)
			(polygon
				(pts
					(arc
						(start 235.980986 -53.999892)
						(mid 235.218986 -53.999892)
						(end 235.980986 -53.999892)
					)
				)
			)
		)
		(zone
			(layer "F.Cu")
			(hatch none 0.5)
			(connect_pads
				(clearance 0)
			)
			(min_thickness 0.25)
			(keepout
				(tracks allowed)
				(vias not_allowed)
				(pads allowed)
				(copperpour not_allowed)
				(footprints allowed)
			)
			(placement
				(enabled no)
				(sheetname "")
			)
			(fill
				(thermal_gap 0.5)
				(thermal_bridge_width 0.5)
				(island_removal_mode 0)
			)
			(polygon
				(pts
					(arc
						(start 235.980986 -52.999894)
						(mid 235.218986 -52.999894)
						(end 235.980986 -52.999894)
					)
				)
			)
		)
		(zone
			(layer "F.Cu")
			(hatch none 0.5)
			(connect_pads
				(clearance 0)
			)
			(min_thickness 0.25)
			(keepout
				(tracks allowed)
				(vias not_allowed)
				(pads allowed)
				(copperpour not_allowed)
				(footprints allowed)
			)
			(placement
				(enabled no)
				(sheetname "")
			)
			(fill
				(thermal_gap 0.5)
				(thermal_bridge_width 0.5)
				(island_removal_mode 0)
			)
			(polygon
				(pts
					(arc
						(start 235.980986 -51.999896)
						(mid 235.218986 -51.999896)
						(end 235.980986 -51.999896)
					)
				)
			)
		)
		(zone
			(layer "F.Cu")
			(hatch none 0.5)
			(connect_pads
				(clearance 0)
			)
			(min_thickness 0.25)
			(keepout
				(tracks allowed)
				(vias not_allowed)
				(pads allowed)
				(copperpour not_allowed)
				(footprints allowed)
			)
			(placement
				(enabled no)
				(sheetname "")
			)
			(fill
				(thermal_gap 0.5)
				(thermal_bridge_width 0.5)
				(island_removal_mode 0)
			)
			(polygon
				(pts
					(arc
						(start 235.980986 -50.999898)
						(mid 235.218986 -50.999898)
						(end 235.980986 -50.999898)
					)
				)
			)
		)
		(zone
			(layer "F.Cu")
			(hatch none 0.5)
			(connect_pads
				(clearance 0)
			)
			(min_thickness 0.25)
			(keepout
				(tracks allowed)
				(vias not_allowed)
				(pads allowed)
				(copperpour not_allowed)
				(footprints allowed)
			)
			(placement
				(enabled no)
				(sheetname "")
			)
			(fill
				(thermal_gap 0.5)
				(thermal_bridge_width 0.5)
				(island_removal_mode 0)
			)
			(polygon
				(pts
					(arc
						(start 235.980986 -49.9999)
						(mid 235.218986 -49.9999)
						(end 235.980986 -49.9999)
					)
				)
			)
		)
		(zone
			(layer "F.Cu")
			(hatch none 0.5)
			(connect_pads
				(clearance 0)
			)
			(min_thickness 0.25)
			(keepout
				(tracks allowed)
				(vias not_allowed)
				(pads allowed)
				(copperpour not_allowed)
				(footprints allowed)
			)
			(placement
				(enabled no)
				(sheetname "")
			)
			(fill
				(thermal_gap 0.5)
				(thermal_bridge_width 0.5)
				(island_removal_mode 0)
			)
			(polygon
				(pts
					(arc
						(start 235.980986 -48.999902)
						(mid 235.218986 -48.999902)
						(end 235.980986 -48.999902)
					)
				)
			)
		)
		(zone
			(layer "F.Cu")
			(hatch none 0.5)
			(connect_pads
				(clearance 0)
			)
			(min_thickness 0.25)
			(keepout
				(tracks allowed)
				(vias not_allowed)
				(pads allowed)
				(copperpour not_allowed)
				(footprints allowed)
			)
			(placement
				(enabled no)
				(sheetname "")
			)
			(fill
				(thermal_gap 0.5)
				(thermal_bridge_width 0.5)
				(island_removal_mode 0)
			)
			(polygon
				(pts
					(arc
						(start 235.980986 -47.999904)
						(mid 235.218986 -47.999904)
						(end 235.980986 -47.999904)
					)
				)
			)
		)
		(zone
			(layer "F.Cu")
			(hatch none 0.5)
			(connect_pads
				(clearance 0)
			)
			(min_thickness 0.25)
			(keepout
				(tracks allowed)
				(vias not_allowed)
				(pads allowed)
				(copperpour not_allowed)
				(footprints allowed)
			)
			(placement
				(enabled no)
				(sheetname "")
			)
			(fill
				(thermal_gap 0.5)
				(thermal_bridge_width 0.5)
				(island_removal_mode 0)
			)
			(polygon
				(pts
					(arc
						(start 235.980986 -46.999906)
						(mid 235.218986 -46.999906)
						(end 235.980986 -46.999906)
					)
				)
			)
		)
		(zone
			(layer "F.Cu")
			(hatch none 0.5)
			(connect_pads
				(clearance 0)
			)
			(min_thickness 0.25)
			(keepout
				(tracks allowed)
				(vias not_allowed)
				(pads allowed)
				(copperpour not_allowed)
				(footprints allowed)
			)
			(placement
				(enabled no)
				(sheetname "")
			)
			(fill
				(thermal_gap 0.5)
				(thermal_bridge_width 0.5)
				(island_removal_mode 0)
			)
			(polygon
				(pts
					(arc
						(start 235.980986 -45.999908)
						(mid 235.218986 -45.999908)
						(end 235.980986 -45.999908)
					)
				)
			)
		)
		(zone
			(layer "F.Cu")
			(hatch none 0.5)
			(connect_pads
				(clearance 0)
			)
			(min_thickness 0.25)
			(keepout
				(tracks allowed)
				(vias not_allowed)
				(pads allowed)
				(copperpour not_allowed)
				(footprints allowed)
			)
			(placement
				(enabled no)
				(sheetname "")
			)
			(fill
				(thermal_gap 0.5)
				(thermal_bridge_width 0.5)
				(island_removal_mode 0)
			)
			(polygon
				(pts
					(arc
						(start 235.980986 -44.99991)
						(mid 235.218986 -44.99991)
						(end 235.980986 -44.99991)
					)
				)
			)
		)
		(zone
			(layer "F.Cu")
			(hatch none 0.5)
			(connect_pads
				(clearance 0)
			)
			(min_thickness 0.25)
			(keepout
				(tracks allowed)
				(vias not_allowed)
				(pads allowed)
				(copperpour not_allowed)
				(footprints allowed)
			)
			(placement
				(enabled no)
				(sheetname "")
			)
			(fill
				(thermal_gap 0.5)
				(thermal_bridge_width 0.5)
				(island_removal_mode 0)
			)
			(polygon
				(pts
					(arc
						(start 235.980986 -43.999912)
						(mid 235.218986 -43.999912)
						(end 235.980986 -43.999912)
					)
				)
			)
		)
		(zone
			(layer "F.Cu")
			(hatch none 0.5)
			(connect_pads
				(clearance 0)
			)
			(min_thickness 0.25)
			(keepout
				(tracks allowed)
				(vias not_allowed)
				(pads allowed)
				(copperpour not_allowed)
				(footprints allowed)
			)
			(placement
				(enabled no)
				(sheetname "")
			)
			(fill
				(thermal_gap 0.5)
				(thermal_bridge_width 0.5)
				(island_removal_mode 0)
			)
			(polygon
				(pts
					(arc
						(start 235.980986 -42.999914)
						(mid 235.218986 -42.999914)
						(end 235.980986 -42.999914)
					)
				)
			)
		)
		(zone
			(layer "F.Cu")
			(hatch none 0.5)
			(connect_pads
				(clearance 0)
			)
			(min_thickness 0.25)
			(keepout
				(tracks allowed)
				(vias not_allowed)
				(pads allowed)
				(copperpour not_allowed)
				(footprints allowed)
			)
			(placement
				(enabled no)
				(sheetname "")
			)
			(fill
				(thermal_gap 0.5)
				(thermal_bridge_width 0.5)
				(island_removal_mode 0)
			)
			(polygon
				(pts
					(arc
						(start 235.980986 -41.999916)
						(mid 235.218986 -41.999916)
						(end 235.980986 -41.999916)
					)
				)
			)
		)
		(zone
			(layer "F.Cu")
			(hatch none 0.5)
			(connect_pads
				(clearance 0)
			)
			(min_thickness 0.25)
			(keepout
				(tracks allowed)
				(vias not_allowed)
				(pads allowed)
				(copperpour not_allowed)
				(footprints allowed)
			)
			(placement
				(enabled no)
				(sheetname "")
			)
			(fill
				(thermal_gap 0.5)
				(thermal_bridge_width 0.5)
				(island_removal_mode 0)
			)
			(polygon
				(pts
					(arc
						(start 235.980986 -40.999918)
						(mid 235.218986 -40.999918)
						(end 235.980986 -40.999918)
					)
				)
			)
		)
		(zone
			(layer "F.Cu")
			(hatch none 0.5)
			(connect_pads
				(clearance 0)
			)
			(min_thickness 0.25)
			(keepout
				(tracks allowed)
				(vias not_allowed)
				(pads allowed)
				(copperpour not_allowed)
				(footprints allowed)
			)
			(placement
				(enabled no)
				(sheetname "")
			)
			(fill
				(thermal_gap 0.5)
				(thermal_bridge_width 0.5)
				(island_removal_mode 0)
			)
			(polygon
				(pts
					(arc
						(start 235.980986 -39.99992)
						(mid 235.218986 -39.99992)
						(end 235.980986 -39.99992)
					)
				)
			)
		)
		(zone
			(layer "F.Cu")
			(hatch none 0.5)
			(connect_pads
				(clearance 0)
			)
			(min_thickness 0.25)
			(keepout
				(tracks allowed)
				(vias not_allowed)
				(pads allowed)
				(copperpour not_allowed)
				(footprints allowed)
			)
			(placement
				(enabled no)
				(sheetname "")
			)
			(fill
				(thermal_gap 0.5)
				(thermal_bridge_width 0.5)
				(island_removal_mode 0)
			)
			(polygon
				(pts
					(arc
						(start 235.980986 -38.999922)
						(mid 235.218986 -38.999922)
						(end 235.980986 -38.999922)
					)
				)
			)
		)
		(zone
			(layer "F.Cu")
			(hatch none 0.5)
			(connect_pads
				(clearance 0)
			)
			(min_thickness 0.25)
			(keepout
				(tracks allowed)
				(vias not_allowed)
				(pads allowed)
				(copperpour not_allowed)
				(footprints allowed)
			)
			(placement
				(enabled no)
				(sheetname "")
			)
			(fill
				(thermal_gap 0.5)
				(thermal_bridge_width 0.5)
				(island_removal_mode 0)
			)
			(polygon
				(pts
					(arc
						(start 235.980986 -37.999924)
						(mid 235.218986 -37.999924)
						(end 235.980986 -37.999924)
					)
				)
			)
		)
		(zone
			(layer "F.Cu")
			(hatch none 0.5)
			(connect_pads
				(clearance 0)
			)
			(min_thickness 0.25)
			(keepout
				(tracks allowed)
				(vias not_allowed)
				(pads allowed)
				(copperpour not_allowed)
				(footprints allowed)
			)
			(placement
				(enabled no)
				(sheetname "")
			)
			(fill
				(thermal_gap 0.5)
				(thermal_bridge_width 0.5)
				(island_removal_mode 0)
			)
			(polygon
				(pts
					(arc
						(start 235.980986 -36.999926)
						(mid 235.218986 -36.999926)
						(end 235.980986 -36.999926)
					)
				)
			)
		)
		(zone
			(layer "F.Cu")
			(hatch none 0.5)
			(connect_pads
				(clearance 0)
			)
			(min_thickness 0.25)
			(keepout
				(tracks allowed)
				(vias not_allowed)
				(pads allowed)
				(copperpour not_allowed)
				(footprints allowed)
			)
			(placement
				(enabled no)
				(sheetname "")
			)
			(fill
				(thermal_gap 0.5)
				(thermal_bridge_width 0.5)
				(island_removal_mode 0)
			)
			(polygon
				(pts
					(arc
						(start 235.980986 -35.999928)
						(mid 235.218986 -35.999928)
						(end 235.980986 -35.999928)
					)
				)
			)
		)
		(zone
			(layer "F.Cu")
			(hatch none 0.5)
			(connect_pads
				(clearance 0)
			)
			(min_thickness 0.25)
			(keepout
				(tracks allowed)
				(vias not_allowed)
				(pads allowed)
				(copperpour not_allowed)
				(footprints allowed)
			)
			(placement
				(enabled no)
				(sheetname "")
			)
			(fill
				(thermal_gap 0.5)
				(thermal_bridge_width 0.5)
				(island_removal_mode 0)
			)
			(polygon
				(pts
					(arc
						(start 235.980986 -34.99993)
						(mid 235.218986 -34.99993)
						(end 235.980986 -34.99993)
					)
				)
			)
		)
		(zone
			(layer "F.Cu")
			(hatch none 0.5)
			(connect_pads
				(clearance 0)
			)
			(min_thickness 0.25)
			(keepout
				(tracks allowed)
				(vias not_allowed)
				(pads allowed)
				(copperpour not_allowed)
				(footprints allowed)
			)
			(placement
				(enabled no)
				(sheetname "")
			)
			(fill
				(thermal_gap 0.5)
				(thermal_bridge_width 0.5)
				(island_removal_mode 0)
			)
			(polygon
				(pts
					(arc
						(start 235.980986 -33.999932)
						(mid 235.218986 -33.999932)
						(end 235.980986 -33.999932)
					)
				)
			)
		)
		(zone
			(layer "F.Cu")
			(hatch none 0.5)
			(connect_pads
				(clearance 0)
			)
			(min_thickness 0.25)
			(keepout
				(tracks allowed)
				(vias not_allowed)
				(pads allowed)
				(copperpour not_allowed)
				(footprints allowed)
			)
			(placement
				(enabled no)
				(sheetname "")
			)
			(fill
				(thermal_gap 0.5)
				(thermal_bridge_width 0.5)
				(island_removal_mode 0)
			)
			(polygon
				(pts
					(arc
						(start 235.980986 -32.999934)
						(mid 235.218986 -32.999934)
						(end 235.980986 -32.999934)
					)
				)
			)
		)
		(zone
			(layer "F.Cu")
			(hatch none 0.5)
			(connect_pads
				(clearance 0)
			)
			(min_thickness 0.25)
			(keepout
				(tracks allowed)
				(vias not_allowed)
				(pads allowed)
				(copperpour not_allowed)
				(footprints allowed)
			)
			(placement
				(enabled no)
				(sheetname "")
			)
			(fill
				(thermal_gap 0.5)
				(thermal_bridge_width 0.5)
				(island_removal_mode 0)
			)
			(polygon
				(pts
					(arc
						(start 235.980986 -31.999936)
						(mid 235.218986 -31.999936)
						(end 235.980986 -31.999936)
					)
				)
			)
		)
		(zone
			(layer "F.Cu")
			(hatch none 0.5)
			(connect_pads
				(clearance 0)
			)
			(min_thickness 0.25)
			(keepout
				(tracks allowed)
				(vias not_allowed)
				(pads allowed)
				(copperpour not_allowed)
				(footprints allowed)
			)
			(placement
				(enabled no)
				(sheetname "")
			)
			(fill
				(thermal_gap 0.5)
				(thermal_bridge_width 0.5)
				(island_removal_mode 0)
			)
			(polygon
				(pts
					(arc
						(start 235.980986 -30.999938)
						(mid 235.218986 -30.999938)
						(end 235.980986 -30.999938)
					)
				)
			)
		)
		(zone
			(layer "F.Cu")
			(hatch none 0.5)
			(connect_pads
				(clearance 0)
			)
			(min_thickness 0.25)
			(keepout
				(tracks allowed)
				(vias not_allowed)
				(pads allowed)
				(copperpour not_allowed)
				(footprints allowed)
			)
			(placement
				(enabled no)
				(sheetname "")
			)
			(fill
				(thermal_gap 0.5)
				(thermal_bridge_width 0.5)
				(island_removal_mode 0)
			)
			(polygon
				(pts
					(arc
						(start 236.980984 -65.999868)
						(mid 236.218984 -65.999868)
						(end 236.980984 -65.999868)
					)
				)
			)
		)
		(zone
			(layer "F.Cu")
			(hatch none 0.5)
			(connect_pads
				(clearance 0)
			)
			(min_thickness 0.25)
			(keepout
				(tracks allowed)
				(vias not_allowed)
				(pads allowed)
				(copperpour not_allowed)
				(footprints allowed)
			)
			(placement
				(enabled no)
				(sheetname "")
			)
			(fill
				(thermal_gap 0.5)
				(thermal_bridge_width 0.5)
				(island_removal_mode 0)
			)
			(polygon
				(pts
					(arc
						(start 236.980984 -64.99987)
						(mid 236.218984 -64.99987)
						(end 236.980984 -64.99987)
					)
				)
			)
		)
		(zone
			(layer "F.Cu")
			(hatch none 0.5)
			(connect_pads
				(clearance 0)
			)
			(min_thickness 0.25)
			(keepout
				(tracks allowed)
				(vias not_allowed)
				(pads allowed)
				(copperpour not_allowed)
				(footprints allowed)
			)
			(placement
				(enabled no)
				(sheetname "")
			)
			(fill
				(thermal_gap 0.5)
				(thermal_bridge_width 0.5)
				(island_removal_mode 0)
			)
			(polygon
				(pts
					(arc
						(start 236.980984 -63.999872)
						(mid 236.218984 -63.999872)
						(end 236.980984 -63.999872)
					)
				)
			)
		)
		(zone
			(layer "F.Cu")
			(hatch none 0.5)
			(connect_pads
				(clearance 0)
			)
			(min_thickness 0.25)
			(keepout
				(tracks allowed)
				(vias not_allowed)
				(pads allowed)
				(copperpour not_allowed)
				(footprints allowed)
			)
			(placement
				(enabled no)
				(sheetname "")
			)
			(fill
				(thermal_gap 0.5)
				(thermal_bridge_width 0.5)
				(island_removal_mode 0)
			)
			(polygon
				(pts
					(arc
						(start 236.980984 -62.999874)
						(mid 236.218984 -62.999874)
						(end 236.980984 -62.999874)
					)
				)
			)
		)
		(zone
			(layer "F.Cu")
			(hatch none 0.5)
			(connect_pads
				(clearance 0)
			)
			(min_thickness 0.25)
			(keepout
				(tracks allowed)
				(vias not_allowed)
				(pads allowed)
				(copperpour not_allowed)
				(footprints allowed)
			)
			(placement
				(enabled no)
				(sheetname "")
			)
			(fill
				(thermal_gap 0.5)
				(thermal_bridge_width 0.5)
				(island_removal_mode 0)
			)
			(polygon
				(pts
					(arc
						(start 236.980984 -61.999876)
						(mid 236.218984 -61.999876)
						(end 236.980984 -61.999876)
					)
				)
			)
		)
		(zone
			(layer "F.Cu")
			(hatch none 0.5)
			(connect_pads
				(clearance 0)
			)
			(min_thickness 0.25)
			(keepout
				(tracks allowed)
				(vias not_allowed)
				(pads allowed)
				(copperpour not_allowed)
				(footprints allowed)
			)
			(placement
				(enabled no)
				(sheetname "")
			)
			(fill
				(thermal_gap 0.5)
				(thermal_bridge_width 0.5)
				(island_removal_mode 0)
			)
			(polygon
				(pts
					(arc
						(start 236.980984 -60.999878)
						(mid 236.218984 -60.999878)
						(end 236.980984 -60.999878)
					)
				)
			)
		)
		(zone
			(layer "F.Cu")
			(hatch none 0.5)
			(connect_pads
				(clearance 0)
			)
			(min_thickness 0.25)
			(keepout
				(tracks allowed)
				(vias not_allowed)
				(pads allowed)
				(copperpour not_allowed)
				(footprints allowed)
			)
			(placement
				(enabled no)
				(sheetname "")
			)
			(fill
				(thermal_gap 0.5)
				(thermal_bridge_width 0.5)
				(island_removal_mode 0)
			)
			(polygon
				(pts
					(arc
						(start 236.980984 -59.99988)
						(mid 236.218984 -59.99988)
						(end 236.980984 -59.99988)
					)
				)
			)
		)
		(zone
			(layer "F.Cu")
			(hatch none 0.5)
			(connect_pads
				(clearance 0)
			)
			(min_thickness 0.25)
			(keepout
				(tracks allowed)
				(vias not_allowed)
				(pads allowed)
				(copperpour not_allowed)
				(footprints allowed)
			)
			(placement
				(enabled no)
				(sheetname "")
			)
			(fill
				(thermal_gap 0.5)
				(thermal_bridge_width 0.5)
				(island_removal_mode 0)
			)
			(polygon
				(pts
					(arc
						(start 236.980984 -58.999882)
						(mid 236.218984 -58.999882)
						(end 236.980984 -58.999882)
					)
				)
			)
		)
		(zone
			(layer "F.Cu")
			(hatch none 0.5)
			(connect_pads
				(clearance 0)
			)
			(min_thickness 0.25)
			(keepout
				(tracks allowed)
				(vias not_allowed)
				(pads allowed)
				(copperpour not_allowed)
				(footprints allowed)
			)
			(placement
				(enabled no)
				(sheetname "")
			)
			(fill
				(thermal_gap 0.5)
				(thermal_bridge_width 0.5)
				(island_removal_mode 0)
			)
			(polygon
				(pts
					(arc
						(start 236.980984 -57.999884)
						(mid 236.218984 -57.999884)
						(end 236.980984 -57.999884)
					)
				)
			)
		)
		(zone
			(layer "F.Cu")
			(hatch none 0.5)
			(connect_pads
				(clearance 0)
			)
			(min_thickness 0.25)
			(keepout
				(tracks allowed)
				(vias not_allowed)
				(pads allowed)
				(copperpour not_allowed)
				(footprints allowed)
			)
			(placement
				(enabled no)
				(sheetname "")
			)
			(fill
				(thermal_gap 0.5)
				(thermal_bridge_width 0.5)
				(island_removal_mode 0)
			)
			(polygon
				(pts
					(arc
						(start 236.980984 -56.999886)
						(mid 236.218984 -56.999886)
						(end 236.980984 -56.999886)
					)
				)
			)
		)
		(zone
			(layer "F.Cu")
			(hatch none 0.5)
			(connect_pads
				(clearance 0)
			)
			(min_thickness 0.25)
			(keepout
				(tracks allowed)
				(vias not_allowed)
				(pads allowed)
				(copperpour not_allowed)
				(footprints allowed)
			)
			(placement
				(enabled no)
				(sheetname "")
			)
			(fill
				(thermal_gap 0.5)
				(thermal_bridge_width 0.5)
				(island_removal_mode 0)
			)
			(polygon
				(pts
					(arc
						(start 236.980984 -55.999888)
						(mid 236.218984 -55.999888)
						(end 236.980984 -55.999888)
					)
				)
			)
		)
		(zone
			(layer "F.Cu")
			(hatch none 0.5)
			(connect_pads
				(clearance 0)
			)
			(min_thickness 0.25)
			(keepout
				(tracks allowed)
				(vias not_allowed)
				(pads allowed)
				(copperpour not_allowed)
				(footprints allowed)
			)
			(placement
				(enabled no)
				(sheetname "")
			)
			(fill
				(thermal_gap 0.5)
				(thermal_bridge_width 0.5)
				(island_removal_mode 0)
			)
			(polygon
				(pts
					(arc
						(start 236.980984 -54.99989)
						(mid 236.218984 -54.99989)
						(end 236.980984 -54.99989)
					)
				)
			)
		)
		(zone
			(layer "F.Cu")
			(hatch none 0.5)
			(connect_pads
				(clearance 0)
			)
			(min_thickness 0.25)
			(keepout
				(tracks allowed)
				(vias not_allowed)
				(pads allowed)
				(copperpour not_allowed)
				(footprints allowed)
			)
			(placement
				(enabled no)
				(sheetname "")
			)
			(fill
				(thermal_gap 0.5)
				(thermal_bridge_width 0.5)
				(island_removal_mode 0)
			)
			(polygon
				(pts
					(arc
						(start 236.980984 -53.999892)
						(mid 236.218984 -53.999892)
						(end 236.980984 -53.999892)
					)
				)
			)
		)
		(zone
			(layer "F.Cu")
			(hatch none 0.5)
			(connect_pads
				(clearance 0)
			)
			(min_thickness 0.25)
			(keepout
				(tracks allowed)
				(vias not_allowed)
				(pads allowed)
				(copperpour not_allowed)
				(footprints allowed)
			)
			(placement
				(enabled no)
				(sheetname "")
			)
			(fill
				(thermal_gap 0.5)
				(thermal_bridge_width 0.5)
				(island_removal_mode 0)
			)
			(polygon
				(pts
					(arc
						(start 236.980984 -52.999894)
						(mid 236.218984 -52.999894)
						(end 236.980984 -52.999894)
					)
				)
			)
		)
		(zone
			(layer "F.Cu")
			(hatch none 0.5)
			(connect_pads
				(clearance 0)
			)
			(min_thickness 0.25)
			(keepout
				(tracks allowed)
				(vias not_allowed)
				(pads allowed)
				(copperpour not_allowed)
				(footprints allowed)
			)
			(placement
				(enabled no)
				(sheetname "")
			)
			(fill
				(thermal_gap 0.5)
				(thermal_bridge_width 0.5)
				(island_removal_mode 0)
			)
			(polygon
				(pts
					(arc
						(start 236.980984 -51.999896)
						(mid 236.218984 -51.999896)
						(end 236.980984 -51.999896)
					)
				)
			)
		)
		(zone
			(layer "F.Cu")
			(hatch none 0.5)
			(connect_pads
				(clearance 0)
			)
			(min_thickness 0.25)
			(keepout
				(tracks allowed)
				(vias not_allowed)
				(pads allowed)
				(copperpour not_allowed)
				(footprints allowed)
			)
			(placement
				(enabled no)
				(sheetname "")
			)
			(fill
				(thermal_gap 0.5)
				(thermal_bridge_width 0.5)
				(island_removal_mode 0)
			)
			(polygon
				(pts
					(arc
						(start 236.980984 -50.999898)
						(mid 236.218984 -50.999898)
						(end 236.980984 -50.999898)
					)
				)
			)
		)
		(zone
			(layer "F.Cu")
			(hatch none 0.5)
			(connect_pads
				(clearance 0)
			)
			(min_thickness 0.25)
			(keepout
				(tracks allowed)
				(vias not_allowed)
				(pads allowed)
				(copperpour not_allowed)
				(footprints allowed)
			)
			(placement
				(enabled no)
				(sheetname "")
			)
			(fill
				(thermal_gap 0.5)
				(thermal_bridge_width 0.5)
				(island_removal_mode 0)
			)
			(polygon
				(pts
					(arc
						(start 236.980984 -49.9999)
						(mid 236.218984 -49.9999)
						(end 236.980984 -49.9999)
					)
				)
			)
		)
		(zone
			(layer "F.Cu")
			(hatch none 0.5)
			(connect_pads
				(clearance 0)
			)
			(min_thickness 0.25)
			(keepout
				(tracks allowed)
				(vias not_allowed)
				(pads allowed)
				(copperpour not_allowed)
				(footprints allowed)
			)
			(placement
				(enabled no)
				(sheetname "")
			)
			(fill
				(thermal_gap 0.5)
				(thermal_bridge_width 0.5)
				(island_removal_mode 0)
			)
			(polygon
				(pts
					(arc
						(start 236.980984 -48.999902)
						(mid 236.218984 -48.999902)
						(end 236.980984 -48.999902)
					)
				)
			)
		)
		(zone
			(layer "F.Cu")
			(hatch none 0.5)
			(connect_pads
				(clearance 0)
			)
			(min_thickness 0.25)
			(keepout
				(tracks allowed)
				(vias not_allowed)
				(pads allowed)
				(copperpour not_allowed)
				(footprints allowed)
			)
			(placement
				(enabled no)
				(sheetname "")
			)
			(fill
				(thermal_gap 0.5)
				(thermal_bridge_width 0.5)
				(island_removal_mode 0)
			)
			(polygon
				(pts
					(arc
						(start 236.980984 -47.999904)
						(mid 236.218984 -47.999904)
						(end 236.980984 -47.999904)
					)
				)
			)
		)
		(zone
			(layer "F.Cu")
			(hatch none 0.5)
			(connect_pads
				(clearance 0)
			)
			(min_thickness 0.25)
			(keepout
				(tracks allowed)
				(vias not_allowed)
				(pads allowed)
				(copperpour not_allowed)
				(footprints allowed)
			)
			(placement
				(enabled no)
				(sheetname "")
			)
			(fill
				(thermal_gap 0.5)
				(thermal_bridge_width 0.5)
				(island_removal_mode 0)
			)
			(polygon
				(pts
					(arc
						(start 236.980984 -46.999906)
						(mid 236.218984 -46.999906)
						(end 236.980984 -46.999906)
					)
				)
			)
		)
		(zone
			(layer "F.Cu")
			(hatch none 0.5)
			(connect_pads
				(clearance 0)
			)
			(min_thickness 0.25)
			(keepout
				(tracks allowed)
				(vias not_allowed)
				(pads allowed)
				(copperpour not_allowed)
				(footprints allowed)
			)
			(placement
				(enabled no)
				(sheetname "")
			)
			(fill
				(thermal_gap 0.5)
				(thermal_bridge_width 0.5)
				(island_removal_mode 0)
			)
			(polygon
				(pts
					(arc
						(start 236.980984 -45.999908)
						(mid 236.218984 -45.999908)
						(end 236.980984 -45.999908)
					)
				)
			)
		)
		(zone
			(layer "F.Cu")
			(hatch none 0.5)
			(connect_pads
				(clearance 0)
			)
			(min_thickness 0.25)
			(keepout
				(tracks allowed)
				(vias not_allowed)
				(pads allowed)
				(copperpour not_allowed)
				(footprints allowed)
			)
			(placement
				(enabled no)
				(sheetname "")
			)
			(fill
				(thermal_gap 0.5)
				(thermal_bridge_width 0.5)
				(island_removal_mode 0)
			)
			(polygon
				(pts
					(arc
						(start 236.980984 -44.99991)
						(mid 236.218984 -44.99991)
						(end 236.980984 -44.99991)
					)
				)
			)
		)
		(zone
			(layer "F.Cu")
			(hatch none 0.5)
			(connect_pads
				(clearance 0)
			)
			(min_thickness 0.25)
			(keepout
				(tracks allowed)
				(vias not_allowed)
				(pads allowed)
				(copperpour not_allowed)
				(footprints allowed)
			)
			(placement
				(enabled no)
				(sheetname "")
			)
			(fill
				(thermal_gap 0.5)
				(thermal_bridge_width 0.5)
				(island_removal_mode 0)
			)
			(polygon
				(pts
					(arc
						(start 236.980984 -43.999912)
						(mid 236.218984 -43.999912)
						(end 236.980984 -43.999912)
					)
				)
			)
		)
		(zone
			(layer "F.Cu")
			(hatch none 0.5)
			(connect_pads
				(clearance 0)
			)
			(min_thickness 0.25)
			(keepout
				(tracks allowed)
				(vias not_allowed)
				(pads allowed)
				(copperpour not_allowed)
				(footprints allowed)
			)
			(placement
				(enabled no)
				(sheetname "")
			)
			(fill
				(thermal_gap 0.5)
				(thermal_bridge_width 0.5)
				(island_removal_mode 0)
			)
			(polygon
				(pts
					(arc
						(start 236.980984 -42.999914)
						(mid 236.218984 -42.999914)
						(end 236.980984 -42.999914)
					)
				)
			)
		)
		(zone
			(layer "F.Cu")
			(hatch none 0.5)
			(connect_pads
				(clearance 0)
			)
			(min_thickness 0.25)
			(keepout
				(tracks allowed)
				(vias not_allowed)
				(pads allowed)
				(copperpour not_allowed)
				(footprints allowed)
			)
			(placement
				(enabled no)
				(sheetname "")
			)
			(fill
				(thermal_gap 0.5)
				(thermal_bridge_width 0.5)
				(island_removal_mode 0)
			)
			(polygon
				(pts
					(arc
						(start 236.980984 -41.999916)
						(mid 236.218984 -41.999916)
						(end 236.980984 -41.999916)
					)
				)
			)
		)
		(zone
			(layer "F.Cu")
			(hatch none 0.5)
			(connect_pads
				(clearance 0)
			)
			(min_thickness 0.25)
			(keepout
				(tracks allowed)
				(vias not_allowed)
				(pads allowed)
				(copperpour not_allowed)
				(footprints allowed)
			)
			(placement
				(enabled no)
				(sheetname "")
			)
			(fill
				(thermal_gap 0.5)
				(thermal_bridge_width 0.5)
				(island_removal_mode 0)
			)
			(polygon
				(pts
					(arc
						(start 236.980984 -40.999918)
						(mid 236.218984 -40.999918)
						(end 236.980984 -40.999918)
					)
				)
			)
		)
		(zone
			(layer "F.Cu")
			(hatch none 0.5)
			(connect_pads
				(clearance 0)
			)
			(min_thickness 0.25)
			(keepout
				(tracks allowed)
				(vias not_allowed)
				(pads allowed)
				(copperpour not_allowed)
				(footprints allowed)
			)
			(placement
				(enabled no)
				(sheetname "")
			)
			(fill
				(thermal_gap 0.5)
				(thermal_bridge_width 0.5)
				(island_removal_mode 0)
			)
			(polygon
				(pts
					(arc
						(start 236.980984 -39.99992)
						(mid 236.218984 -39.99992)
						(end 236.980984 -39.99992)
					)
				)
			)
		)
		(zone
			(layer "F.Cu")
			(hatch none 0.5)
			(connect_pads
				(clearance 0)
			)
			(min_thickness 0.25)
			(keepout
				(tracks allowed)
				(vias not_allowed)
				(pads allowed)
				(copperpour not_allowed)
				(footprints allowed)
			)
			(placement
				(enabled no)
				(sheetname "")
			)
			(fill
				(thermal_gap 0.5)
				(thermal_bridge_width 0.5)
				(island_removal_mode 0)
			)
			(polygon
				(pts
					(arc
						(start 236.980984 -38.999922)
						(mid 236.218984 -38.999922)
						(end 236.980984 -38.999922)
					)
				)
			)
		)
		(zone
			(layer "F.Cu")
			(hatch none 0.5)
			(connect_pads
				(clearance 0)
			)
			(min_thickness 0.25)
			(keepout
				(tracks allowed)
				(vias not_allowed)
				(pads allowed)
				(copperpour not_allowed)
				(footprints allowed)
			)
			(placement
				(enabled no)
				(sheetname "")
			)
			(fill
				(thermal_gap 0.5)
				(thermal_bridge_width 0.5)
				(island_removal_mode 0)
			)
			(polygon
				(pts
					(arc
						(start 236.980984 -37.999924)
						(mid 236.218984 -37.999924)
						(end 236.980984 -37.999924)
					)
				)
			)
		)
		(zone
			(layer "F.Cu")
			(hatch none 0.5)
			(connect_pads
				(clearance 0)
			)
			(min_thickness 0.25)
			(keepout
				(tracks allowed)
				(vias not_allowed)
				(pads allowed)
				(copperpour not_allowed)
				(footprints allowed)
			)
			(placement
				(enabled no)
				(sheetname "")
			)
			(fill
				(thermal_gap 0.5)
				(thermal_bridge_width 0.5)
				(island_removal_mode 0)
			)
			(polygon
				(pts
					(arc
						(start 236.980984 -36.999926)
						(mid 236.218984 -36.999926)
						(end 236.980984 -36.999926)
					)
				)
			)
		)
		(zone
			(layer "F.Cu")
			(hatch none 0.5)
			(connect_pads
				(clearance 0)
			)
			(min_thickness 0.25)
			(keepout
				(tracks allowed)
				(vias not_allowed)
				(pads allowed)
				(copperpour not_allowed)
				(footprints allowed)
			)
			(placement
				(enabled no)
				(sheetname "")
			)
			(fill
				(thermal_gap 0.5)
				(thermal_bridge_width 0.5)
				(island_removal_mode 0)
			)
			(polygon
				(pts
					(arc
						(start 236.980984 -35.999928)
						(mid 236.218984 -35.999928)
						(end 236.980984 -35.999928)
					)
				)
			)
		)
		(zone
			(layer "F.Cu")
			(hatch none 0.5)
			(connect_pads
				(clearance 0)
			)
			(min_thickness 0.25)
			(keepout
				(tracks allowed)
				(vias not_allowed)
				(pads allowed)
				(copperpour not_allowed)
				(footprints allowed)
			)
			(placement
				(enabled no)
				(sheetname "")
			)
			(fill
				(thermal_gap 0.5)
				(thermal_bridge_width 0.5)
				(island_removal_mode 0)
			)
			(polygon
				(pts
					(arc
						(start 236.980984 -34.99993)
						(mid 236.218984 -34.99993)
						(end 236.980984 -34.99993)
					)
				)
			)
		)
		(zone
			(layer "F.Cu")
			(hatch none 0.5)
			(connect_pads
				(clearance 0)
			)
			(min_thickness 0.25)
			(keepout
				(tracks allowed)
				(vias not_allowed)
				(pads allowed)
				(copperpour not_allowed)
				(footprints allowed)
			)
			(placement
				(enabled no)
				(sheetname "")
			)
			(fill
				(thermal_gap 0.5)
				(thermal_bridge_width 0.5)
				(island_removal_mode 0)
			)
			(polygon
				(pts
					(arc
						(start 236.980984 -33.999932)
						(mid 236.218984 -33.999932)
						(end 236.980984 -33.999932)
					)
				)
			)
		)
		(zone
			(layer "F.Cu")
			(hatch none 0.5)
			(connect_pads
				(clearance 0)
			)
			(min_thickness 0.25)
			(keepout
				(tracks allowed)
				(vias not_allowed)
				(pads allowed)
				(copperpour not_allowed)
				(footprints allowed)
			)
			(placement
				(enabled no)
				(sheetname "")
			)
			(fill
				(thermal_gap 0.5)
				(thermal_bridge_width 0.5)
				(island_removal_mode 0)
			)
			(polygon
				(pts
					(arc
						(start 236.980984 -32.999934)
						(mid 236.218984 -32.999934)
						(end 236.980984 -32.999934)
					)
				)
			)
		)
		(zone
			(layer "F.Cu")
			(hatch none 0.5)
			(connect_pads
				(clearance 0)
			)
			(min_thickness 0.25)
			(keepout
				(tracks allowed)
				(vias not_allowed)
				(pads allowed)
				(copperpour not_allowed)
				(footprints allowed)
			)
			(placement
				(enabled no)
				(sheetname "")
			)
			(fill
				(thermal_gap 0.5)
				(thermal_bridge_width 0.5)
				(island_removal_mode 0)
			)
			(polygon
				(pts
					(arc
						(start 236.980984 -31.999936)
						(mid 236.218984 -31.999936)
						(end 236.980984 -31.999936)
					)
				)
			)
		)
		(zone
			(layer "F.Cu")
			(hatch none 0.5)
			(connect_pads
				(clearance 0)
			)
			(min_thickness 0.25)
			(keepout
				(tracks allowed)
				(vias not_allowed)
				(pads allowed)
				(copperpour not_allowed)
				(footprints allowed)
			)
			(placement
				(enabled no)
				(sheetname "")
			)
			(fill
				(thermal_gap 0.5)
				(thermal_bridge_width 0.5)
				(island_removal_mode 0)
			)
			(polygon
				(pts
					(arc
						(start 236.980984 -30.999938)
						(mid 236.218984 -30.999938)
						(end 236.980984 -30.999938)
					)
				)
			)
		)
		(zone
			(layer "F.Cu")
			(hatch none 0.5)
			(connect_pads
				(clearance 0)
			)
			(min_thickness 0.25)
			(keepout
				(tracks allowed)
				(vias not_allowed)
				(pads allowed)
				(copperpour not_allowed)
				(footprints allowed)
			)
			(placement
				(enabled no)
				(sheetname "")
			)
			(fill
				(thermal_gap 0.5)
				(thermal_bridge_width 0.5)
				(island_removal_mode 0)
			)
			(polygon
				(pts
					(arc
						(start 236.980984 -29.99994)
						(mid 236.218984 -29.99994)
						(end 236.980984 -29.99994)
					)
				)
			)
		)
		(zone
			(layer "F.Cu")
			(hatch none 0.5)
			(connect_pads
				(clearance 0)
			)
			(min_thickness 0.25)
			(keepout
				(tracks allowed)
				(vias not_allowed)
				(pads allowed)
				(copperpour not_allowed)
				(footprints allowed)
			)
			(placement
				(enabled no)
				(sheetname "")
			)
			(fill
				(thermal_gap 0.5)
				(thermal_bridge_width 0.5)
				(island_removal_mode 0)
			)
			(polygon
				(pts
					(arc
						(start 237.980982 -64.99987)
						(mid 237.218982 -64.99987)
						(end 237.980982 -64.99987)
					)
				)
			)
		)
		(zone
			(layer "F.Cu")
			(hatch none 0.5)
			(connect_pads
				(clearance 0)
			)
			(min_thickness 0.25)
			(keepout
				(tracks allowed)
				(vias not_allowed)
				(pads allowed)
				(copperpour not_allowed)
				(footprints allowed)
			)
			(placement
				(enabled no)
				(sheetname "")
			)
			(fill
				(thermal_gap 0.5)
				(thermal_bridge_width 0.5)
				(island_removal_mode 0)
			)
			(polygon
				(pts
					(arc
						(start 237.980982 -63.999872)
						(mid 237.218982 -63.999872)
						(end 237.980982 -63.999872)
					)
				)
			)
		)
		(zone
			(layer "F.Cu")
			(hatch none 0.5)
			(connect_pads
				(clearance 0)
			)
			(min_thickness 0.25)
			(keepout
				(tracks allowed)
				(vias not_allowed)
				(pads allowed)
				(copperpour not_allowed)
				(footprints allowed)
			)
			(placement
				(enabled no)
				(sheetname "")
			)
			(fill
				(thermal_gap 0.5)
				(thermal_bridge_width 0.5)
				(island_removal_mode 0)
			)
			(polygon
				(pts
					(arc
						(start 237.980982 -62.999874)
						(mid 237.218982 -62.999874)
						(end 237.980982 -62.999874)
					)
				)
			)
		)
		(zone
			(layer "F.Cu")
			(hatch none 0.5)
			(connect_pads
				(clearance 0)
			)
			(min_thickness 0.25)
			(keepout
				(tracks allowed)
				(vias not_allowed)
				(pads allowed)
				(copperpour not_allowed)
				(footprints allowed)
			)
			(placement
				(enabled no)
				(sheetname "")
			)
			(fill
				(thermal_gap 0.5)
				(thermal_bridge_width 0.5)
				(island_removal_mode 0)
			)
			(polygon
				(pts
					(arc
						(start 237.980982 -61.999876)
						(mid 237.218982 -61.999876)
						(end 237.980982 -61.999876)
					)
				)
			)
		)
		(zone
			(layer "F.Cu")
			(hatch none 0.5)
			(connect_pads
				(clearance 0)
			)
			(min_thickness 0.25)
			(keepout
				(tracks allowed)
				(vias not_allowed)
				(pads allowed)
				(copperpour not_allowed)
				(footprints allowed)
			)
			(placement
				(enabled no)
				(sheetname "")
			)
			(fill
				(thermal_gap 0.5)
				(thermal_bridge_width 0.5)
				(island_removal_mode 0)
			)
			(polygon
				(pts
					(arc
						(start 237.980982 -60.999878)
						(mid 237.218982 -60.999878)
						(end 237.980982 -60.999878)
					)
				)
			)
		)
		(zone
			(layer "F.Cu")
			(hatch none 0.5)
			(connect_pads
				(clearance 0)
			)
			(min_thickness 0.25)
			(keepout
				(tracks allowed)
				(vias not_allowed)
				(pads allowed)
				(copperpour not_allowed)
				(footprints allowed)
			)
			(placement
				(enabled no)
				(sheetname "")
			)
			(fill
				(thermal_gap 0.5)
				(thermal_bridge_width 0.5)
				(island_removal_mode 0)
			)
			(polygon
				(pts
					(arc
						(start 237.980982 -59.99988)
						(mid 237.218982 -59.99988)
						(end 237.980982 -59.99988)
					)
				)
			)
		)
		(zone
			(layer "F.Cu")
			(hatch none 0.5)
			(connect_pads
				(clearance 0)
			)
			(min_thickness 0.25)
			(keepout
				(tracks allowed)
				(vias not_allowed)
				(pads allowed)
				(copperpour not_allowed)
				(footprints allowed)
			)
			(placement
				(enabled no)
				(sheetname "")
			)
			(fill
				(thermal_gap 0.5)
				(thermal_bridge_width 0.5)
				(island_removal_mode 0)
			)
			(polygon
				(pts
					(arc
						(start 237.980982 -58.999882)
						(mid 237.218982 -58.999882)
						(end 237.980982 -58.999882)
					)
				)
			)
		)
		(zone
			(layer "F.Cu")
			(hatch none 0.5)
			(connect_pads
				(clearance 0)
			)
			(min_thickness 0.25)
			(keepout
				(tracks allowed)
				(vias not_allowed)
				(pads allowed)
				(copperpour not_allowed)
				(footprints allowed)
			)
			(placement
				(enabled no)
				(sheetname "")
			)
			(fill
				(thermal_gap 0.5)
				(thermal_bridge_width 0.5)
				(island_removal_mode 0)
			)
			(polygon
				(pts
					(arc
						(start 237.980982 -57.999884)
						(mid 237.218982 -57.999884)
						(end 237.980982 -57.999884)
					)
				)
			)
		)
		(zone
			(layer "F.Cu")
			(hatch none 0.5)
			(connect_pads
				(clearance 0)
			)
			(min_thickness 0.25)
			(keepout
				(tracks allowed)
				(vias not_allowed)
				(pads allowed)
				(copperpour not_allowed)
				(footprints allowed)
			)
			(placement
				(enabled no)
				(sheetname "")
			)
			(fill
				(thermal_gap 0.5)
				(thermal_bridge_width 0.5)
				(island_removal_mode 0)
			)
			(polygon
				(pts
					(arc
						(start 237.980982 -56.999886)
						(mid 237.218982 -56.999886)
						(end 237.980982 -56.999886)
					)
				)
			)
		)
		(zone
			(layer "F.Cu")
			(hatch none 0.5)
			(connect_pads
				(clearance 0)
			)
			(min_thickness 0.25)
			(keepout
				(tracks allowed)
				(vias not_allowed)
				(pads allowed)
				(copperpour not_allowed)
				(footprints allowed)
			)
			(placement
				(enabled no)
				(sheetname "")
			)
			(fill
				(thermal_gap 0.5)
				(thermal_bridge_width 0.5)
				(island_removal_mode 0)
			)
			(polygon
				(pts
					(arc
						(start 237.980982 -55.999888)
						(mid 237.218982 -55.999888)
						(end 237.980982 -55.999888)
					)
				)
			)
		)
		(zone
			(layer "F.Cu")
			(hatch none 0.5)
			(connect_pads
				(clearance 0)
			)
			(min_thickness 0.25)
			(keepout
				(tracks allowed)
				(vias not_allowed)
				(pads allowed)
				(copperpour not_allowed)
				(footprints allowed)
			)
			(placement
				(enabled no)
				(sheetname "")
			)
			(fill
				(thermal_gap 0.5)
				(thermal_bridge_width 0.5)
				(island_removal_mode 0)
			)
			(polygon
				(pts
					(arc
						(start 237.980982 -54.99989)
						(mid 237.218982 -54.99989)
						(end 237.980982 -54.99989)
					)
				)
			)
		)
		(zone
			(layer "F.Cu")
			(hatch none 0.5)
			(connect_pads
				(clearance 0)
			)
			(min_thickness 0.25)
			(keepout
				(tracks allowed)
				(vias not_allowed)
				(pads allowed)
				(copperpour not_allowed)
				(footprints allowed)
			)
			(placement
				(enabled no)
				(sheetname "")
			)
			(fill
				(thermal_gap 0.5)
				(thermal_bridge_width 0.5)
				(island_removal_mode 0)
			)
			(polygon
				(pts
					(arc
						(start 237.980982 -53.999892)
						(mid 237.218982 -53.999892)
						(end 237.980982 -53.999892)
					)
				)
			)
		)
		(zone
			(layer "F.Cu")
			(hatch none 0.5)
			(connect_pads
				(clearance 0)
			)
			(min_thickness 0.25)
			(keepout
				(tracks allowed)
				(vias not_allowed)
				(pads allowed)
				(copperpour not_allowed)
				(footprints allowed)
			)
			(placement
				(enabled no)
				(sheetname "")
			)
			(fill
				(thermal_gap 0.5)
				(thermal_bridge_width 0.5)
				(island_removal_mode 0)
			)
			(polygon
				(pts
					(arc
						(start 237.980982 -52.999894)
						(mid 237.218982 -52.999894)
						(end 237.980982 -52.999894)
					)
				)
			)
		)
		(zone
			(layer "F.Cu")
			(hatch none 0.5)
			(connect_pads
				(clearance 0)
			)
			(min_thickness 0.25)
			(keepout
				(tracks allowed)
				(vias not_allowed)
				(pads allowed)
				(copperpour not_allowed)
				(footprints allowed)
			)
			(placement
				(enabled no)
				(sheetname "")
			)
			(fill
				(thermal_gap 0.5)
				(thermal_bridge_width 0.5)
				(island_removal_mode 0)
			)
			(polygon
				(pts
					(arc
						(start 237.980982 -51.999896)
						(mid 237.218982 -51.999896)
						(end 237.980982 -51.999896)
					)
				)
			)
		)
		(zone
			(layer "F.Cu")
			(hatch none 0.5)
			(connect_pads
				(clearance 0)
			)
			(min_thickness 0.25)
			(keepout
				(tracks allowed)
				(vias not_allowed)
				(pads allowed)
				(copperpour not_allowed)
				(footprints allowed)
			)
			(placement
				(enabled no)
				(sheetname "")
			)
			(fill
				(thermal_gap 0.5)
				(thermal_bridge_width 0.5)
				(island_removal_mode 0)
			)
			(polygon
				(pts
					(arc
						(start 237.980982 -50.999898)
						(mid 237.218982 -50.999898)
						(end 237.980982 -50.999898)
					)
				)
			)
		)
		(zone
			(layer "F.Cu")
			(hatch none 0.5)
			(connect_pads
				(clearance 0)
			)
			(min_thickness 0.25)
			(keepout
				(tracks allowed)
				(vias not_allowed)
				(pads allowed)
				(copperpour not_allowed)
				(footprints allowed)
			)
			(placement
				(enabled no)
				(sheetname "")
			)
			(fill
				(thermal_gap 0.5)
				(thermal_bridge_width 0.5)
				(island_removal_mode 0)
			)
			(polygon
				(pts
					(arc
						(start 237.980982 -49.9999)
						(mid 237.218982 -49.9999)
						(end 237.980982 -49.9999)
					)
				)
			)
		)
		(zone
			(layer "F.Cu")
			(hatch none 0.5)
			(connect_pads
				(clearance 0)
			)
			(min_thickness 0.25)
			(keepout
				(tracks allowed)
				(vias not_allowed)
				(pads allowed)
				(copperpour not_allowed)
				(footprints allowed)
			)
			(placement
				(enabled no)
				(sheetname "")
			)
			(fill
				(thermal_gap 0.5)
				(thermal_bridge_width 0.5)
				(island_removal_mode 0)
			)
			(polygon
				(pts
					(arc
						(start 237.980982 -48.999902)
						(mid 237.218982 -48.999902)
						(end 237.980982 -48.999902)
					)
				)
			)
		)
		(zone
			(layer "F.Cu")
			(hatch none 0.5)
			(connect_pads
				(clearance 0)
			)
			(min_thickness 0.25)
			(keepout
				(tracks allowed)
				(vias not_allowed)
				(pads allowed)
				(copperpour not_allowed)
				(footprints allowed)
			)
			(placement
				(enabled no)
				(sheetname "")
			)
			(fill
				(thermal_gap 0.5)
				(thermal_bridge_width 0.5)
				(island_removal_mode 0)
			)
			(polygon
				(pts
					(arc
						(start 237.980982 -47.999904)
						(mid 237.218982 -47.999904)
						(end 237.980982 -47.999904)
					)
				)
			)
		)
		(zone
			(layer "F.Cu")
			(hatch none 0.5)
			(connect_pads
				(clearance 0)
			)
			(min_thickness 0.25)
			(keepout
				(tracks allowed)
				(vias not_allowed)
				(pads allowed)
				(copperpour not_allowed)
				(footprints allowed)
			)
			(placement
				(enabled no)
				(sheetname "")
			)
			(fill
				(thermal_gap 0.5)
				(thermal_bridge_width 0.5)
				(island_removal_mode 0)
			)
			(polygon
				(pts
					(arc
						(start 237.980982 -46.999906)
						(mid 237.218982 -46.999906)
						(end 237.980982 -46.999906)
					)
				)
			)
		)
		(zone
			(layer "F.Cu")
			(hatch none 0.5)
			(connect_pads
				(clearance 0)
			)
			(min_thickness 0.25)
			(keepout
				(tracks allowed)
				(vias not_allowed)
				(pads allowed)
				(copperpour not_allowed)
				(footprints allowed)
			)
			(placement
				(enabled no)
				(sheetname "")
			)
			(fill
				(thermal_gap 0.5)
				(thermal_bridge_width 0.5)
				(island_removal_mode 0)
			)
			(polygon
				(pts
					(arc
						(start 237.980982 -45.999908)
						(mid 237.218982 -45.999908)
						(end 237.980982 -45.999908)
					)
				)
			)
		)
		(zone
			(layer "F.Cu")
			(hatch none 0.5)
			(connect_pads
				(clearance 0)
			)
			(min_thickness 0.25)
			(keepout
				(tracks allowed)
				(vias not_allowed)
				(pads allowed)
				(copperpour not_allowed)
				(footprints allowed)
			)
			(placement
				(enabled no)
				(sheetname "")
			)
			(fill
				(thermal_gap 0.5)
				(thermal_bridge_width 0.5)
				(island_removal_mode 0)
			)
			(polygon
				(pts
					(arc
						(start 237.980982 -44.99991)
						(mid 237.218982 -44.99991)
						(end 237.980982 -44.99991)
					)
				)
			)
		)
		(zone
			(layer "F.Cu")
			(hatch none 0.5)
			(connect_pads
				(clearance 0)
			)
			(min_thickness 0.25)
			(keepout
				(tracks allowed)
				(vias not_allowed)
				(pads allowed)
				(copperpour not_allowed)
				(footprints allowed)
			)
			(placement
				(enabled no)
				(sheetname "")
			)
			(fill
				(thermal_gap 0.5)
				(thermal_bridge_width 0.5)
				(island_removal_mode 0)
			)
			(polygon
				(pts
					(arc
						(start 237.980982 -43.999912)
						(mid 237.218982 -43.999912)
						(end 237.980982 -43.999912)
					)
				)
			)
		)
		(zone
			(layer "F.Cu")
			(hatch none 0.5)
			(connect_pads
				(clearance 0)
			)
			(min_thickness 0.25)
			(keepout
				(tracks allowed)
				(vias not_allowed)
				(pads allowed)
				(copperpour not_allowed)
				(footprints allowed)
			)
			(placement
				(enabled no)
				(sheetname "")
			)
			(fill
				(thermal_gap 0.5)
				(thermal_bridge_width 0.5)
				(island_removal_mode 0)
			)
			(polygon
				(pts
					(arc
						(start 237.980982 -42.999914)
						(mid 237.218982 -42.999914)
						(end 237.980982 -42.999914)
					)
				)
			)
		)
		(zone
			(layer "F.Cu")
			(hatch none 0.5)
			(connect_pads
				(clearance 0)
			)
			(min_thickness 0.25)
			(keepout
				(tracks allowed)
				(vias not_allowed)
				(pads allowed)
				(copperpour not_allowed)
				(footprints allowed)
			)
			(placement
				(enabled no)
				(sheetname "")
			)
			(fill
				(thermal_gap 0.5)
				(thermal_bridge_width 0.5)
				(island_removal_mode 0)
			)
			(polygon
				(pts
					(arc
						(start 237.980982 -41.999916)
						(mid 237.218982 -41.999916)
						(end 237.980982 -41.999916)
					)
				)
			)
		)
		(zone
			(layer "F.Cu")
			(hatch none 0.5)
			(connect_pads
				(clearance 0)
			)
			(min_thickness 0.25)
			(keepout
				(tracks allowed)
				(vias not_allowed)
				(pads allowed)
				(copperpour not_allowed)
				(footprints allowed)
			)
			(placement
				(enabled no)
				(sheetname "")
			)
			(fill
				(thermal_gap 0.5)
				(thermal_bridge_width 0.5)
				(island_removal_mode 0)
			)
			(polygon
				(pts
					(arc
						(start 237.980982 -40.999918)
						(mid 237.218982 -40.999918)
						(end 237.980982 -40.999918)
					)
				)
			)
		)
		(zone
			(layer "F.Cu")
			(hatch none 0.5)
			(connect_pads
				(clearance 0)
			)
			(min_thickness 0.25)
			(keepout
				(tracks allowed)
				(vias not_allowed)
				(pads allowed)
				(copperpour not_allowed)
				(footprints allowed)
			)
			(placement
				(enabled no)
				(sheetname "")
			)
			(fill
				(thermal_gap 0.5)
				(thermal_bridge_width 0.5)
				(island_removal_mode 0)
			)
			(polygon
				(pts
					(arc
						(start 237.980982 -39.99992)
						(mid 237.218982 -39.99992)
						(end 237.980982 -39.99992)
					)
				)
			)
		)
		(zone
			(layer "F.Cu")
			(hatch none 0.5)
			(connect_pads
				(clearance 0)
			)
			(min_thickness 0.25)
			(keepout
				(tracks allowed)
				(vias not_allowed)
				(pads allowed)
				(copperpour not_allowed)
				(footprints allowed)
			)
			(placement
				(enabled no)
				(sheetname "")
			)
			(fill
				(thermal_gap 0.5)
				(thermal_bridge_width 0.5)
				(island_removal_mode 0)
			)
			(polygon
				(pts
					(arc
						(start 237.980982 -38.999922)
						(mid 237.218982 -38.999922)
						(end 237.980982 -38.999922)
					)
				)
			)
		)
		(zone
			(layer "F.Cu")
			(hatch none 0.5)
			(connect_pads
				(clearance 0)
			)
			(min_thickness 0.25)
			(keepout
				(tracks allowed)
				(vias not_allowed)
				(pads allowed)
				(copperpour not_allowed)
				(footprints allowed)
			)
			(placement
				(enabled no)
				(sheetname "")
			)
			(fill
				(thermal_gap 0.5)
				(thermal_bridge_width 0.5)
				(island_removal_mode 0)
			)
			(polygon
				(pts
					(arc
						(start 237.980982 -37.999924)
						(mid 237.218982 -37.999924)
						(end 237.980982 -37.999924)
					)
				)
			)
		)
		(zone
			(layer "F.Cu")
			(hatch none 0.5)
			(connect_pads
				(clearance 0)
			)
			(min_thickness 0.25)
			(keepout
				(tracks allowed)
				(vias not_allowed)
				(pads allowed)
				(copperpour not_allowed)
				(footprints allowed)
			)
			(placement
				(enabled no)
				(sheetname "")
			)
			(fill
				(thermal_gap 0.5)
				(thermal_bridge_width 0.5)
				(island_removal_mode 0)
			)
			(polygon
				(pts
					(arc
						(start 237.980982 -36.999926)
						(mid 237.218982 -36.999926)
						(end 237.980982 -36.999926)
					)
				)
			)
		)
		(zone
			(layer "F.Cu")
			(hatch none 0.5)
			(connect_pads
				(clearance 0)
			)
			(min_thickness 0.25)
			(keepout
				(tracks allowed)
				(vias not_allowed)
				(pads allowed)
				(copperpour not_allowed)
				(footprints allowed)
			)
			(placement
				(enabled no)
				(sheetname "")
			)
			(fill
				(thermal_gap 0.5)
				(thermal_bridge_width 0.5)
				(island_removal_mode 0)
			)
			(polygon
				(pts
					(arc
						(start 237.980982 -35.999928)
						(mid 237.218982 -35.999928)
						(end 237.980982 -35.999928)
					)
				)
			)
		)
		(zone
			(layer "F.Cu")
			(hatch none 0.5)
			(connect_pads
				(clearance 0)
			)
			(min_thickness 0.25)
			(keepout
				(tracks allowed)
				(vias not_allowed)
				(pads allowed)
				(copperpour not_allowed)
				(footprints allowed)
			)
			(placement
				(enabled no)
				(sheetname "")
			)
			(fill
				(thermal_gap 0.5)
				(thermal_bridge_width 0.5)
				(island_removal_mode 0)
			)
			(polygon
				(pts
					(arc
						(start 237.980982 -34.99993)
						(mid 237.218982 -34.99993)
						(end 237.980982 -34.99993)
					)
				)
			)
		)
		(zone
			(layer "F.Cu")
			(hatch none 0.5)
			(connect_pads
				(clearance 0)
			)
			(min_thickness 0.25)
			(keepout
				(tracks allowed)
				(vias not_allowed)
				(pads allowed)
				(copperpour not_allowed)
				(footprints allowed)
			)
			(placement
				(enabled no)
				(sheetname "")
			)
			(fill
				(thermal_gap 0.5)
				(thermal_bridge_width 0.5)
				(island_removal_mode 0)
			)
			(polygon
				(pts
					(arc
						(start 237.980982 -33.999932)
						(mid 237.218982 -33.999932)
						(end 237.980982 -33.999932)
					)
				)
			)
		)
		(zone
			(layer "F.Cu")
			(hatch none 0.5)
			(connect_pads
				(clearance 0)
			)
			(min_thickness 0.25)
			(keepout
				(tracks allowed)
				(vias not_allowed)
				(pads allowed)
				(copperpour not_allowed)
				(footprints allowed)
			)
			(placement
				(enabled no)
				(sheetname "")
			)
			(fill
				(thermal_gap 0.5)
				(thermal_bridge_width 0.5)
				(island_removal_mode 0)
			)
			(polygon
				(pts
					(arc
						(start 237.980982 -32.999934)
						(mid 237.218982 -32.999934)
						(end 237.980982 -32.999934)
					)
				)
			)
		)
		(zone
			(layer "F.Cu")
			(hatch none 0.5)
			(connect_pads
				(clearance 0)
			)
			(min_thickness 0.25)
			(keepout
				(tracks allowed)
				(vias not_allowed)
				(pads allowed)
				(copperpour not_allowed)
				(footprints allowed)
			)
			(placement
				(enabled no)
				(sheetname "")
			)
			(fill
				(thermal_gap 0.5)
				(thermal_bridge_width 0.5)
				(island_removal_mode 0)
			)
			(polygon
				(pts
					(arc
						(start 237.980982 -31.999936)
						(mid 237.218982 -31.999936)
						(end 237.980982 -31.999936)
					)
				)
			)
		)
		(zone
			(layer "F.Cu")
			(hatch none 0.5)
			(connect_pads
				(clearance 0)
			)
			(min_thickness 0.25)
			(keepout
				(tracks allowed)
				(vias not_allowed)
				(pads allowed)
				(copperpour not_allowed)
				(footprints allowed)
			)
			(placement
				(enabled no)
				(sheetname "")
			)
			(fill
				(thermal_gap 0.5)
				(thermal_bridge_width 0.5)
				(island_removal_mode 0)
			)
			(polygon
				(pts
					(arc
						(start 237.980982 -30.999938)
						(mid 237.218982 -30.999938)
						(end 237.980982 -30.999938)
					)
				)
			)
		)
		(zone
			(layer "F.Cu")
			(hatch none 0.5)
			(connect_pads
				(clearance 0)
			)
			(min_thickness 0.25)
			(keepout
				(tracks allowed)
				(vias not_allowed)
				(pads allowed)
				(copperpour not_allowed)
				(footprints allowed)
			)
			(placement
				(enabled no)
				(sheetname "")
			)
			(fill
				(thermal_gap 0.5)
				(thermal_bridge_width 0.5)
				(island_removal_mode 0)
			)
			(polygon
				(pts
					(arc
						(start 238.98098 -65.999868)
						(mid 238.21898 -65.999868)
						(end 238.98098 -65.999868)
					)
				)
			)
		)
		(zone
			(layer "F.Cu")
			(hatch none 0.5)
			(connect_pads
				(clearance 0)
			)
			(min_thickness 0.25)
			(keepout
				(tracks allowed)
				(vias not_allowed)
				(pads allowed)
				(copperpour not_allowed)
				(footprints allowed)
			)
			(placement
				(enabled no)
				(sheetname "")
			)
			(fill
				(thermal_gap 0.5)
				(thermal_bridge_width 0.5)
				(island_removal_mode 0)
			)
			(polygon
				(pts
					(arc
						(start 238.98098 -64.99987)
						(mid 238.21898 -64.99987)
						(end 238.98098 -64.99987)
					)
				)
			)
		)
		(zone
			(layer "F.Cu")
			(hatch none 0.5)
			(connect_pads
				(clearance 0)
			)
			(min_thickness 0.25)
			(keepout
				(tracks allowed)
				(vias not_allowed)
				(pads allowed)
				(copperpour not_allowed)
				(footprints allowed)
			)
			(placement
				(enabled no)
				(sheetname "")
			)
			(fill
				(thermal_gap 0.5)
				(thermal_bridge_width 0.5)
				(island_removal_mode 0)
			)
			(polygon
				(pts
					(arc
						(start 238.98098 -63.999872)
						(mid 238.21898 -63.999872)
						(end 238.98098 -63.999872)
					)
				)
			)
		)
		(zone
			(layer "F.Cu")
			(hatch none 0.5)
			(connect_pads
				(clearance 0)
			)
			(min_thickness 0.25)
			(keepout
				(tracks allowed)
				(vias not_allowed)
				(pads allowed)
				(copperpour not_allowed)
				(footprints allowed)
			)
			(placement
				(enabled no)
				(sheetname "")
			)
			(fill
				(thermal_gap 0.5)
				(thermal_bridge_width 0.5)
				(island_removal_mode 0)
			)
			(polygon
				(pts
					(arc
						(start 238.98098 -62.999874)
						(mid 238.21898 -62.999874)
						(end 238.98098 -62.999874)
					)
				)
			)
		)
		(zone
			(layer "F.Cu")
			(hatch none 0.5)
			(connect_pads
				(clearance 0)
			)
			(min_thickness 0.25)
			(keepout
				(tracks allowed)
				(vias not_allowed)
				(pads allowed)
				(copperpour not_allowed)
				(footprints allowed)
			)
			(placement
				(enabled no)
				(sheetname "")
			)
			(fill
				(thermal_gap 0.5)
				(thermal_bridge_width 0.5)
				(island_removal_mode 0)
			)
			(polygon
				(pts
					(arc
						(start 238.98098 -61.999876)
						(mid 238.21898 -61.999876)
						(end 238.98098 -61.999876)
					)
				)
			)
		)
		(zone
			(layer "F.Cu")
			(hatch none 0.5)
			(connect_pads
				(clearance 0)
			)
			(min_thickness 0.25)
			(keepout
				(tracks allowed)
				(vias not_allowed)
				(pads allowed)
				(copperpour not_allowed)
				(footprints allowed)
			)
			(placement
				(enabled no)
				(sheetname "")
			)
			(fill
				(thermal_gap 0.5)
				(thermal_bridge_width 0.5)
				(island_removal_mode 0)
			)
			(polygon
				(pts
					(arc
						(start 238.98098 -60.999878)
						(mid 238.21898 -60.999878)
						(end 238.98098 -60.999878)
					)
				)
			)
		)
		(zone
			(layer "F.Cu")
			(hatch none 0.5)
			(connect_pads
				(clearance 0)
			)
			(min_thickness 0.25)
			(keepout
				(tracks allowed)
				(vias not_allowed)
				(pads allowed)
				(copperpour not_allowed)
				(footprints allowed)
			)
			(placement
				(enabled no)
				(sheetname "")
			)
			(fill
				(thermal_gap 0.5)
				(thermal_bridge_width 0.5)
				(island_removal_mode 0)
			)
			(polygon
				(pts
					(arc
						(start 238.98098 -59.99988)
						(mid 238.21898 -59.99988)
						(end 238.98098 -59.99988)
					)
				)
			)
		)
		(zone
			(layer "F.Cu")
			(hatch none 0.5)
			(connect_pads
				(clearance 0)
			)
			(min_thickness 0.25)
			(keepout
				(tracks allowed)
				(vias not_allowed)
				(pads allowed)
				(copperpour not_allowed)
				(footprints allowed)
			)
			(placement
				(enabled no)
				(sheetname "")
			)
			(fill
				(thermal_gap 0.5)
				(thermal_bridge_width 0.5)
				(island_removal_mode 0)
			)
			(polygon
				(pts
					(arc
						(start 238.98098 -58.999882)
						(mid 238.21898 -58.999882)
						(end 238.98098 -58.999882)
					)
				)
			)
		)
		(zone
			(layer "F.Cu")
			(hatch none 0.5)
			(connect_pads
				(clearance 0)
			)
			(min_thickness 0.25)
			(keepout
				(tracks allowed)
				(vias not_allowed)
				(pads allowed)
				(copperpour not_allowed)
				(footprints allowed)
			)
			(placement
				(enabled no)
				(sheetname "")
			)
			(fill
				(thermal_gap 0.5)
				(thermal_bridge_width 0.5)
				(island_removal_mode 0)
			)
			(polygon
				(pts
					(arc
						(start 238.98098 -57.999884)
						(mid 238.21898 -57.999884)
						(end 238.98098 -57.999884)
					)
				)
			)
		)
		(zone
			(layer "F.Cu")
			(hatch none 0.5)
			(connect_pads
				(clearance 0)
			)
			(min_thickness 0.25)
			(keepout
				(tracks allowed)
				(vias not_allowed)
				(pads allowed)
				(copperpour not_allowed)
				(footprints allowed)
			)
			(placement
				(enabled no)
				(sheetname "")
			)
			(fill
				(thermal_gap 0.5)
				(thermal_bridge_width 0.5)
				(island_removal_mode 0)
			)
			(polygon
				(pts
					(arc
						(start 238.98098 -56.999886)
						(mid 238.21898 -56.999886)
						(end 238.98098 -56.999886)
					)
				)
			)
		)
		(zone
			(layer "F.Cu")
			(hatch none 0.5)
			(connect_pads
				(clearance 0)
			)
			(min_thickness 0.25)
			(keepout
				(tracks allowed)
				(vias not_allowed)
				(pads allowed)
				(copperpour not_allowed)
				(footprints allowed)
			)
			(placement
				(enabled no)
				(sheetname "")
			)
			(fill
				(thermal_gap 0.5)
				(thermal_bridge_width 0.5)
				(island_removal_mode 0)
			)
			(polygon
				(pts
					(arc
						(start 238.98098 -55.999888)
						(mid 238.21898 -55.999888)
						(end 238.98098 -55.999888)
					)
				)
			)
		)
		(zone
			(layer "F.Cu")
			(hatch none 0.5)
			(connect_pads
				(clearance 0)
			)
			(min_thickness 0.25)
			(keepout
				(tracks allowed)
				(vias not_allowed)
				(pads allowed)
				(copperpour not_allowed)
				(footprints allowed)
			)
			(placement
				(enabled no)
				(sheetname "")
			)
			(fill
				(thermal_gap 0.5)
				(thermal_bridge_width 0.5)
				(island_removal_mode 0)
			)
			(polygon
				(pts
					(arc
						(start 238.98098 -54.99989)
						(mid 238.21898 -54.99989)
						(end 238.98098 -54.99989)
					)
				)
			)
		)
		(zone
			(layer "F.Cu")
			(hatch none 0.5)
			(connect_pads
				(clearance 0)
			)
			(min_thickness 0.25)
			(keepout
				(tracks allowed)
				(vias not_allowed)
				(pads allowed)
				(copperpour not_allowed)
				(footprints allowed)
			)
			(placement
				(enabled no)
				(sheetname "")
			)
			(fill
				(thermal_gap 0.5)
				(thermal_bridge_width 0.5)
				(island_removal_mode 0)
			)
			(polygon
				(pts
					(arc
						(start 238.98098 -53.999892)
						(mid 238.21898 -53.999892)
						(end 238.98098 -53.999892)
					)
				)
			)
		)
		(zone
			(layer "F.Cu")
			(hatch none 0.5)
			(connect_pads
				(clearance 0)
			)
			(min_thickness 0.25)
			(keepout
				(tracks allowed)
				(vias not_allowed)
				(pads allowed)
				(copperpour not_allowed)
				(footprints allowed)
			)
			(placement
				(enabled no)
				(sheetname "")
			)
			(fill
				(thermal_gap 0.5)
				(thermal_bridge_width 0.5)
				(island_removal_mode 0)
			)
			(polygon
				(pts
					(arc
						(start 238.98098 -52.999894)
						(mid 238.21898 -52.999894)
						(end 238.98098 -52.999894)
					)
				)
			)
		)
		(zone
			(layer "F.Cu")
			(hatch none 0.5)
			(connect_pads
				(clearance 0)
			)
			(min_thickness 0.25)
			(keepout
				(tracks allowed)
				(vias not_allowed)
				(pads allowed)
				(copperpour not_allowed)
				(footprints allowed)
			)
			(placement
				(enabled no)
				(sheetname "")
			)
			(fill
				(thermal_gap 0.5)
				(thermal_bridge_width 0.5)
				(island_removal_mode 0)
			)
			(polygon
				(pts
					(arc
						(start 238.98098 -51.999896)
						(mid 238.21898 -51.999896)
						(end 238.98098 -51.999896)
					)
				)
			)
		)
		(zone
			(layer "F.Cu")
			(hatch none 0.5)
			(connect_pads
				(clearance 0)
			)
			(min_thickness 0.25)
			(keepout
				(tracks allowed)
				(vias not_allowed)
				(pads allowed)
				(copperpour not_allowed)
				(footprints allowed)
			)
			(placement
				(enabled no)
				(sheetname "")
			)
			(fill
				(thermal_gap 0.5)
				(thermal_bridge_width 0.5)
				(island_removal_mode 0)
			)
			(polygon
				(pts
					(arc
						(start 238.98098 -50.999898)
						(mid 238.21898 -50.999898)
						(end 238.98098 -50.999898)
					)
				)
			)
		)
		(zone
			(layer "F.Cu")
			(hatch none 0.5)
			(connect_pads
				(clearance 0)
			)
			(min_thickness 0.25)
			(keepout
				(tracks allowed)
				(vias not_allowed)
				(pads allowed)
				(copperpour not_allowed)
				(footprints allowed)
			)
			(placement
				(enabled no)
				(sheetname "")
			)
			(fill
				(thermal_gap 0.5)
				(thermal_bridge_width 0.5)
				(island_removal_mode 0)
			)
			(polygon
				(pts
					(arc
						(start 238.98098 -49.9999)
						(mid 238.21898 -49.9999)
						(end 238.98098 -49.9999)
					)
				)
			)
		)
		(zone
			(layer "F.Cu")
			(hatch none 0.5)
			(connect_pads
				(clearance 0)
			)
			(min_thickness 0.25)
			(keepout
				(tracks allowed)
				(vias not_allowed)
				(pads allowed)
				(copperpour not_allowed)
				(footprints allowed)
			)
			(placement
				(enabled no)
				(sheetname "")
			)
			(fill
				(thermal_gap 0.5)
				(thermal_bridge_width 0.5)
				(island_removal_mode 0)
			)
			(polygon
				(pts
					(arc
						(start 238.98098 -48.999902)
						(mid 238.21898 -48.999902)
						(end 238.98098 -48.999902)
					)
				)
			)
		)
		(zone
			(layer "F.Cu")
			(hatch none 0.5)
			(connect_pads
				(clearance 0)
			)
			(min_thickness 0.25)
			(keepout
				(tracks allowed)
				(vias not_allowed)
				(pads allowed)
				(copperpour not_allowed)
				(footprints allowed)
			)
			(placement
				(enabled no)
				(sheetname "")
			)
			(fill
				(thermal_gap 0.5)
				(thermal_bridge_width 0.5)
				(island_removal_mode 0)
			)
			(polygon
				(pts
					(arc
						(start 238.98098 -47.999904)
						(mid 238.21898 -47.999904)
						(end 238.98098 -47.999904)
					)
				)
			)
		)
		(zone
			(layer "F.Cu")
			(hatch none 0.5)
			(connect_pads
				(clearance 0)
			)
			(min_thickness 0.25)
			(keepout
				(tracks allowed)
				(vias not_allowed)
				(pads allowed)
				(copperpour not_allowed)
				(footprints allowed)
			)
			(placement
				(enabled no)
				(sheetname "")
			)
			(fill
				(thermal_gap 0.5)
				(thermal_bridge_width 0.5)
				(island_removal_mode 0)
			)
			(polygon
				(pts
					(arc
						(start 238.98098 -46.999906)
						(mid 238.21898 -46.999906)
						(end 238.98098 -46.999906)
					)
				)
			)
		)
		(zone
			(layer "F.Cu")
			(hatch none 0.5)
			(connect_pads
				(clearance 0)
			)
			(min_thickness 0.25)
			(keepout
				(tracks allowed)
				(vias not_allowed)
				(pads allowed)
				(copperpour not_allowed)
				(footprints allowed)
			)
			(placement
				(enabled no)
				(sheetname "")
			)
			(fill
				(thermal_gap 0.5)
				(thermal_bridge_width 0.5)
				(island_removal_mode 0)
			)
			(polygon
				(pts
					(arc
						(start 238.98098 -45.999908)
						(mid 238.21898 -45.999908)
						(end 238.98098 -45.999908)
					)
				)
			)
		)
		(zone
			(layer "F.Cu")
			(hatch none 0.5)
			(connect_pads
				(clearance 0)
			)
			(min_thickness 0.25)
			(keepout
				(tracks allowed)
				(vias not_allowed)
				(pads allowed)
				(copperpour not_allowed)
				(footprints allowed)
			)
			(placement
				(enabled no)
				(sheetname "")
			)
			(fill
				(thermal_gap 0.5)
				(thermal_bridge_width 0.5)
				(island_removal_mode 0)
			)
			(polygon
				(pts
					(arc
						(start 238.98098 -44.99991)
						(mid 238.21898 -44.99991)
						(end 238.98098 -44.99991)
					)
				)
			)
		)
		(zone
			(layer "F.Cu")
			(hatch none 0.5)
			(connect_pads
				(clearance 0)
			)
			(min_thickness 0.25)
			(keepout
				(tracks allowed)
				(vias not_allowed)
				(pads allowed)
				(copperpour not_allowed)
				(footprints allowed)
			)
			(placement
				(enabled no)
				(sheetname "")
			)
			(fill
				(thermal_gap 0.5)
				(thermal_bridge_width 0.5)
				(island_removal_mode 0)
			)
			(polygon
				(pts
					(arc
						(start 238.98098 -43.999912)
						(mid 238.21898 -43.999912)
						(end 238.98098 -43.999912)
					)
				)
			)
		)
		(zone
			(layer "F.Cu")
			(hatch none 0.5)
			(connect_pads
				(clearance 0)
			)
			(min_thickness 0.25)
			(keepout
				(tracks allowed)
				(vias not_allowed)
				(pads allowed)
				(copperpour not_allowed)
				(footprints allowed)
			)
			(placement
				(enabled no)
				(sheetname "")
			)
			(fill
				(thermal_gap 0.5)
				(thermal_bridge_width 0.5)
				(island_removal_mode 0)
			)
			(polygon
				(pts
					(arc
						(start 238.98098 -42.999914)
						(mid 238.21898 -42.999914)
						(end 238.98098 -42.999914)
					)
				)
			)
		)
		(zone
			(layer "F.Cu")
			(hatch none 0.5)
			(connect_pads
				(clearance 0)
			)
			(min_thickness 0.25)
			(keepout
				(tracks allowed)
				(vias not_allowed)
				(pads allowed)
				(copperpour not_allowed)
				(footprints allowed)
			)
			(placement
				(enabled no)
				(sheetname "")
			)
			(fill
				(thermal_gap 0.5)
				(thermal_bridge_width 0.5)
				(island_removal_mode 0)
			)
			(polygon
				(pts
					(arc
						(start 238.98098 -41.999916)
						(mid 238.21898 -41.999916)
						(end 238.98098 -41.999916)
					)
				)
			)
		)
		(zone
			(layer "F.Cu")
			(hatch none 0.5)
			(connect_pads
				(clearance 0)
			)
			(min_thickness 0.25)
			(keepout
				(tracks allowed)
				(vias not_allowed)
				(pads allowed)
				(copperpour not_allowed)
				(footprints allowed)
			)
			(placement
				(enabled no)
				(sheetname "")
			)
			(fill
				(thermal_gap 0.5)
				(thermal_bridge_width 0.5)
				(island_removal_mode 0)
			)
			(polygon
				(pts
					(arc
						(start 238.98098 -40.999918)
						(mid 238.21898 -40.999918)
						(end 238.98098 -40.999918)
					)
				)
			)
		)
		(zone
			(layer "F.Cu")
			(hatch none 0.5)
			(connect_pads
				(clearance 0)
			)
			(min_thickness 0.25)
			(keepout
				(tracks allowed)
				(vias not_allowed)
				(pads allowed)
				(copperpour not_allowed)
				(footprints allowed)
			)
			(placement
				(enabled no)
				(sheetname "")
			)
			(fill
				(thermal_gap 0.5)
				(thermal_bridge_width 0.5)
				(island_removal_mode 0)
			)
			(polygon
				(pts
					(arc
						(start 238.98098 -39.99992)
						(mid 238.21898 -39.99992)
						(end 238.98098 -39.99992)
					)
				)
			)
		)
		(zone
			(layer "F.Cu")
			(hatch none 0.5)
			(connect_pads
				(clearance 0)
			)
			(min_thickness 0.25)
			(keepout
				(tracks allowed)
				(vias not_allowed)
				(pads allowed)
				(copperpour not_allowed)
				(footprints allowed)
			)
			(placement
				(enabled no)
				(sheetname "")
			)
			(fill
				(thermal_gap 0.5)
				(thermal_bridge_width 0.5)
				(island_removal_mode 0)
			)
			(polygon
				(pts
					(arc
						(start 238.98098 -38.999922)
						(mid 238.21898 -38.999922)
						(end 238.98098 -38.999922)
					)
				)
			)
		)
		(zone
			(layer "F.Cu")
			(hatch none 0.5)
			(connect_pads
				(clearance 0)
			)
			(min_thickness 0.25)
			(keepout
				(tracks allowed)
				(vias not_allowed)
				(pads allowed)
				(copperpour not_allowed)
				(footprints allowed)
			)
			(placement
				(enabled no)
				(sheetname "")
			)
			(fill
				(thermal_gap 0.5)
				(thermal_bridge_width 0.5)
				(island_removal_mode 0)
			)
			(polygon
				(pts
					(arc
						(start 238.98098 -37.999924)
						(mid 238.21898 -37.999924)
						(end 238.98098 -37.999924)
					)
				)
			)
		)
		(zone
			(layer "F.Cu")
			(hatch none 0.5)
			(connect_pads
				(clearance 0)
			)
			(min_thickness 0.25)
			(keepout
				(tracks allowed)
				(vias not_allowed)
				(pads allowed)
				(copperpour not_allowed)
				(footprints allowed)
			)
			(placement
				(enabled no)
				(sheetname "")
			)
			(fill
				(thermal_gap 0.5)
				(thermal_bridge_width 0.5)
				(island_removal_mode 0)
			)
			(polygon
				(pts
					(arc
						(start 238.98098 -36.999926)
						(mid 238.21898 -36.999926)
						(end 238.98098 -36.999926)
					)
				)
			)
		)
		(zone
			(layer "F.Cu")
			(hatch none 0.5)
			(connect_pads
				(clearance 0)
			)
			(min_thickness 0.25)
			(keepout
				(tracks allowed)
				(vias not_allowed)
				(pads allowed)
				(copperpour not_allowed)
				(footprints allowed)
			)
			(placement
				(enabled no)
				(sheetname "")
			)
			(fill
				(thermal_gap 0.5)
				(thermal_bridge_width 0.5)
				(island_removal_mode 0)
			)
			(polygon
				(pts
					(arc
						(start 238.98098 -35.999928)
						(mid 238.21898 -35.999928)
						(end 238.98098 -35.999928)
					)
				)
			)
		)
		(zone
			(layer "F.Cu")
			(hatch none 0.5)
			(connect_pads
				(clearance 0)
			)
			(min_thickness 0.25)
			(keepout
				(tracks allowed)
				(vias not_allowed)
				(pads allowed)
				(copperpour not_allowed)
				(footprints allowed)
			)
			(placement
				(enabled no)
				(sheetname "")
			)
			(fill
				(thermal_gap 0.5)
				(thermal_bridge_width 0.5)
				(island_removal_mode 0)
			)
			(polygon
				(pts
					(arc
						(start 238.98098 -34.99993)
						(mid 238.21898 -34.99993)
						(end 238.98098 -34.99993)
					)
				)
			)
		)
		(zone
			(layer "F.Cu")
			(hatch none 0.5)
			(connect_pads
				(clearance 0)
			)
			(min_thickness 0.25)
			(keepout
				(tracks allowed)
				(vias not_allowed)
				(pads allowed)
				(copperpour not_allowed)
				(footprints allowed)
			)
			(placement
				(enabled no)
				(sheetname "")
			)
			(fill
				(thermal_gap 0.5)
				(thermal_bridge_width 0.5)
				(island_removal_mode 0)
			)
			(polygon
				(pts
					(arc
						(start 238.98098 -33.999932)
						(mid 238.21898 -33.999932)
						(end 238.98098 -33.999932)
					)
				)
			)
		)
		(zone
			(layer "F.Cu")
			(hatch none 0.5)
			(connect_pads
				(clearance 0)
			)
			(min_thickness 0.25)
			(keepout
				(tracks allowed)
				(vias not_allowed)
				(pads allowed)
				(copperpour not_allowed)
				(footprints allowed)
			)
			(placement
				(enabled no)
				(sheetname "")
			)
			(fill
				(thermal_gap 0.5)
				(thermal_bridge_width 0.5)
				(island_removal_mode 0)
			)
			(polygon
				(pts
					(arc
						(start 238.98098 -32.999934)
						(mid 238.21898 -32.999934)
						(end 238.98098 -32.999934)
					)
				)
			)
		)
		(zone
			(layer "F.Cu")
			(hatch none 0.5)
			(connect_pads
				(clearance 0)
			)
			(min_thickness 0.25)
			(keepout
				(tracks allowed)
				(vias not_allowed)
				(pads allowed)
				(copperpour not_allowed)
				(footprints allowed)
			)
			(placement
				(enabled no)
				(sheetname "")
			)
			(fill
				(thermal_gap 0.5)
				(thermal_bridge_width 0.5)
				(island_removal_mode 0)
			)
			(polygon
				(pts
					(arc
						(start 238.98098 -31.999936)
						(mid 238.21898 -31.999936)
						(end 238.98098 -31.999936)
					)
				)
			)
		)
		(zone
			(layer "F.Cu")
			(hatch none 0.5)
			(connect_pads
				(clearance 0)
			)
			(min_thickness 0.25)
			(keepout
				(tracks allowed)
				(vias not_allowed)
				(pads allowed)
				(copperpour not_allowed)
				(footprints allowed)
			)
			(placement
				(enabled no)
				(sheetname "")
			)
			(fill
				(thermal_gap 0.5)
				(thermal_bridge_width 0.5)
				(island_removal_mode 0)
			)
			(polygon
				(pts
					(arc
						(start 238.98098 -30.999938)
						(mid 238.21898 -30.999938)
						(end 238.98098 -30.999938)
					)
				)
			)
		)
		(zone
			(layer "F.Cu")
			(hatch none 0.5)
			(connect_pads
				(clearance 0)
			)
			(min_thickness 0.25)
			(keepout
				(tracks allowed)
				(vias not_allowed)
				(pads allowed)
				(copperpour not_allowed)
				(footprints allowed)
			)
			(placement
				(enabled no)
				(sheetname "")
			)
			(fill
				(thermal_gap 0.5)
				(thermal_bridge_width 0.5)
				(island_removal_mode 0)
			)
			(polygon
				(pts
					(arc
						(start 238.98098 -29.99994)
						(mid 238.21898 -29.99994)
						(end 238.98098 -29.99994)
					)
				)
			)
		)
		(zone
			(layer "F.Cu")
			(hatch none 0.5)
			(connect_pads
				(clearance 0)
			)
			(min_thickness 0.25)
			(keepout
				(tracks allowed)
				(vias not_allowed)
				(pads allowed)
				(copperpour not_allowed)
				(footprints allowed)
			)
			(placement
				(enabled no)
				(sheetname "")
			)
			(fill
				(thermal_gap 0.5)
				(thermal_bridge_width 0.5)
				(island_removal_mode 0)
			)
			(polygon
				(pts
					(arc
						(start 239.980978 -64.99987)
						(mid 239.218978 -64.99987)
						(end 239.980978 -64.99987)
					)
				)
			)
		)
		(zone
			(layer "F.Cu")
			(hatch none 0.5)
			(connect_pads
				(clearance 0)
			)
			(min_thickness 0.25)
			(keepout
				(tracks allowed)
				(vias not_allowed)
				(pads allowed)
				(copperpour not_allowed)
				(footprints allowed)
			)
			(placement
				(enabled no)
				(sheetname "")
			)
			(fill
				(thermal_gap 0.5)
				(thermal_bridge_width 0.5)
				(island_removal_mode 0)
			)
			(polygon
				(pts
					(arc
						(start 239.980978 -63.999872)
						(mid 239.218978 -63.999872)
						(end 239.980978 -63.999872)
					)
				)
			)
		)
		(zone
			(layer "F.Cu")
			(hatch none 0.5)
			(connect_pads
				(clearance 0)
			)
			(min_thickness 0.25)
			(keepout
				(tracks allowed)
				(vias not_allowed)
				(pads allowed)
				(copperpour not_allowed)
				(footprints allowed)
			)
			(placement
				(enabled no)
				(sheetname "")
			)
			(fill
				(thermal_gap 0.5)
				(thermal_bridge_width 0.5)
				(island_removal_mode 0)
			)
			(polygon
				(pts
					(arc
						(start 239.980978 -62.999874)
						(mid 239.218978 -62.999874)
						(end 239.980978 -62.999874)
					)
				)
			)
		)
		(zone
			(layer "F.Cu")
			(hatch none 0.5)
			(connect_pads
				(clearance 0)
			)
			(min_thickness 0.25)
			(keepout
				(tracks allowed)
				(vias not_allowed)
				(pads allowed)
				(copperpour not_allowed)
				(footprints allowed)
			)
			(placement
				(enabled no)
				(sheetname "")
			)
			(fill
				(thermal_gap 0.5)
				(thermal_bridge_width 0.5)
				(island_removal_mode 0)
			)
			(polygon
				(pts
					(arc
						(start 239.980978 -61.999876)
						(mid 239.218978 -61.999876)
						(end 239.980978 -61.999876)
					)
				)
			)
		)
		(zone
			(layer "F.Cu")
			(hatch none 0.5)
			(connect_pads
				(clearance 0)
			)
			(min_thickness 0.25)
			(keepout
				(tracks allowed)
				(vias not_allowed)
				(pads allowed)
				(copperpour not_allowed)
				(footprints allowed)
			)
			(placement
				(enabled no)
				(sheetname "")
			)
			(fill
				(thermal_gap 0.5)
				(thermal_bridge_width 0.5)
				(island_removal_mode 0)
			)
			(polygon
				(pts
					(arc
						(start 239.980978 -60.999878)
						(mid 239.218978 -60.999878)
						(end 239.980978 -60.999878)
					)
				)
			)
		)
		(zone
			(layer "F.Cu")
			(hatch none 0.5)
			(connect_pads
				(clearance 0)
			)
			(min_thickness 0.25)
			(keepout
				(tracks allowed)
				(vias not_allowed)
				(pads allowed)
				(copperpour not_allowed)
				(footprints allowed)
			)
			(placement
				(enabled no)
				(sheetname "")
			)
			(fill
				(thermal_gap 0.5)
				(thermal_bridge_width 0.5)
				(island_removal_mode 0)
			)
			(polygon
				(pts
					(arc
						(start 239.980978 -59.99988)
						(mid 239.218978 -59.99988)
						(end 239.980978 -59.99988)
					)
				)
			)
		)
		(zone
			(layer "F.Cu")
			(hatch none 0.5)
			(connect_pads
				(clearance 0)
			)
			(min_thickness 0.25)
			(keepout
				(tracks allowed)
				(vias not_allowed)
				(pads allowed)
				(copperpour not_allowed)
				(footprints allowed)
			)
			(placement
				(enabled no)
				(sheetname "")
			)
			(fill
				(thermal_gap 0.5)
				(thermal_bridge_width 0.5)
				(island_removal_mode 0)
			)
			(polygon
				(pts
					(arc
						(start 239.980978 -58.999882)
						(mid 239.218978 -58.999882)
						(end 239.980978 -58.999882)
					)
				)
			)
		)
		(zone
			(layer "F.Cu")
			(hatch none 0.5)
			(connect_pads
				(clearance 0)
			)
			(min_thickness 0.25)
			(keepout
				(tracks allowed)
				(vias not_allowed)
				(pads allowed)
				(copperpour not_allowed)
				(footprints allowed)
			)
			(placement
				(enabled no)
				(sheetname "")
			)
			(fill
				(thermal_gap 0.5)
				(thermal_bridge_width 0.5)
				(island_removal_mode 0)
			)
			(polygon
				(pts
					(arc
						(start 239.980978 -57.999884)
						(mid 239.218978 -57.999884)
						(end 239.980978 -57.999884)
					)
				)
			)
		)
		(zone
			(layer "F.Cu")
			(hatch none 0.5)
			(connect_pads
				(clearance 0)
			)
			(min_thickness 0.25)
			(keepout
				(tracks allowed)
				(vias not_allowed)
				(pads allowed)
				(copperpour not_allowed)
				(footprints allowed)
			)
			(placement
				(enabled no)
				(sheetname "")
			)
			(fill
				(thermal_gap 0.5)
				(thermal_bridge_width 0.5)
				(island_removal_mode 0)
			)
			(polygon
				(pts
					(arc
						(start 239.980978 -56.999886)
						(mid 239.218978 -56.999886)
						(end 239.980978 -56.999886)
					)
				)
			)
		)
		(zone
			(layer "F.Cu")
			(hatch none 0.5)
			(connect_pads
				(clearance 0)
			)
			(min_thickness 0.25)
			(keepout
				(tracks allowed)
				(vias not_allowed)
				(pads allowed)
				(copperpour not_allowed)
				(footprints allowed)
			)
			(placement
				(enabled no)
				(sheetname "")
			)
			(fill
				(thermal_gap 0.5)
				(thermal_bridge_width 0.5)
				(island_removal_mode 0)
			)
			(polygon
				(pts
					(arc
						(start 239.980978 -55.999888)
						(mid 239.218978 -55.999888)
						(end 239.980978 -55.999888)
					)
				)
			)
		)
		(zone
			(layer "F.Cu")
			(hatch none 0.5)
			(connect_pads
				(clearance 0)
			)
			(min_thickness 0.25)
			(keepout
				(tracks allowed)
				(vias not_allowed)
				(pads allowed)
				(copperpour not_allowed)
				(footprints allowed)
			)
			(placement
				(enabled no)
				(sheetname "")
			)
			(fill
				(thermal_gap 0.5)
				(thermal_bridge_width 0.5)
				(island_removal_mode 0)
			)
			(polygon
				(pts
					(arc
						(start 239.980978 -54.99989)
						(mid 239.218978 -54.99989)
						(end 239.980978 -54.99989)
					)
				)
			)
		)
		(zone
			(layer "F.Cu")
			(hatch none 0.5)
			(connect_pads
				(clearance 0)
			)
			(min_thickness 0.25)
			(keepout
				(tracks allowed)
				(vias not_allowed)
				(pads allowed)
				(copperpour not_allowed)
				(footprints allowed)
			)
			(placement
				(enabled no)
				(sheetname "")
			)
			(fill
				(thermal_gap 0.5)
				(thermal_bridge_width 0.5)
				(island_removal_mode 0)
			)
			(polygon
				(pts
					(arc
						(start 239.980978 -53.999892)
						(mid 239.218978 -53.999892)
						(end 239.980978 -53.999892)
					)
				)
			)
		)
		(zone
			(layer "F.Cu")
			(hatch none 0.5)
			(connect_pads
				(clearance 0)
			)
			(min_thickness 0.25)
			(keepout
				(tracks allowed)
				(vias not_allowed)
				(pads allowed)
				(copperpour not_allowed)
				(footprints allowed)
			)
			(placement
				(enabled no)
				(sheetname "")
			)
			(fill
				(thermal_gap 0.5)
				(thermal_bridge_width 0.5)
				(island_removal_mode 0)
			)
			(polygon
				(pts
					(arc
						(start 239.980978 -52.999894)
						(mid 239.218978 -52.999894)
						(end 239.980978 -52.999894)
					)
				)
			)
		)
		(zone
			(layer "F.Cu")
			(hatch none 0.5)
			(connect_pads
				(clearance 0)
			)
			(min_thickness 0.25)
			(keepout
				(tracks allowed)
				(vias not_allowed)
				(pads allowed)
				(copperpour not_allowed)
				(footprints allowed)
			)
			(placement
				(enabled no)
				(sheetname "")
			)
			(fill
				(thermal_gap 0.5)
				(thermal_bridge_width 0.5)
				(island_removal_mode 0)
			)
			(polygon
				(pts
					(arc
						(start 239.980978 -51.999896)
						(mid 239.218978 -51.999896)
						(end 239.980978 -51.999896)
					)
				)
			)
		)
		(zone
			(layer "F.Cu")
			(hatch none 0.5)
			(connect_pads
				(clearance 0)
			)
			(min_thickness 0.25)
			(keepout
				(tracks allowed)
				(vias not_allowed)
				(pads allowed)
				(copperpour not_allowed)
				(footprints allowed)
			)
			(placement
				(enabled no)
				(sheetname "")
			)
			(fill
				(thermal_gap 0.5)
				(thermal_bridge_width 0.5)
				(island_removal_mode 0)
			)
			(polygon
				(pts
					(arc
						(start 239.980978 -50.999898)
						(mid 239.218978 -50.999898)
						(end 239.980978 -50.999898)
					)
				)
			)
		)
		(zone
			(layer "F.Cu")
			(hatch none 0.5)
			(connect_pads
				(clearance 0)
			)
			(min_thickness 0.25)
			(keepout
				(tracks allowed)
				(vias not_allowed)
				(pads allowed)
				(copperpour not_allowed)
				(footprints allowed)
			)
			(placement
				(enabled no)
				(sheetname "")
			)
			(fill
				(thermal_gap 0.5)
				(thermal_bridge_width 0.5)
				(island_removal_mode 0)
			)
			(polygon
				(pts
					(arc
						(start 239.980978 -49.9999)
						(mid 239.218978 -49.9999)
						(end 239.980978 -49.9999)
					)
				)
			)
		)
		(zone
			(layer "F.Cu")
			(hatch none 0.5)
			(connect_pads
				(clearance 0)
			)
			(min_thickness 0.25)
			(keepout
				(tracks allowed)
				(vias not_allowed)
				(pads allowed)
				(copperpour not_allowed)
				(footprints allowed)
			)
			(placement
				(enabled no)
				(sheetname "")
			)
			(fill
				(thermal_gap 0.5)
				(thermal_bridge_width 0.5)
				(island_removal_mode 0)
			)
			(polygon
				(pts
					(arc
						(start 239.980978 -48.999902)
						(mid 239.218978 -48.999902)
						(end 239.980978 -48.999902)
					)
				)
			)
		)
		(zone
			(layer "F.Cu")
			(hatch none 0.5)
			(connect_pads
				(clearance 0)
			)
			(min_thickness 0.25)
			(keepout
				(tracks allowed)
				(vias not_allowed)
				(pads allowed)
				(copperpour not_allowed)
				(footprints allowed)
			)
			(placement
				(enabled no)
				(sheetname "")
			)
			(fill
				(thermal_gap 0.5)
				(thermal_bridge_width 0.5)
				(island_removal_mode 0)
			)
			(polygon
				(pts
					(arc
						(start 239.980978 -47.999904)
						(mid 239.218978 -47.999904)
						(end 239.980978 -47.999904)
					)
				)
			)
		)
		(zone
			(layer "F.Cu")
			(hatch none 0.5)
			(connect_pads
				(clearance 0)
			)
			(min_thickness 0.25)
			(keepout
				(tracks allowed)
				(vias not_allowed)
				(pads allowed)
				(copperpour not_allowed)
				(footprints allowed)
			)
			(placement
				(enabled no)
				(sheetname "")
			)
			(fill
				(thermal_gap 0.5)
				(thermal_bridge_width 0.5)
				(island_removal_mode 0)
			)
			(polygon
				(pts
					(arc
						(start 239.980978 -46.999906)
						(mid 239.218978 -46.999906)
						(end 239.980978 -46.999906)
					)
				)
			)
		)
		(zone
			(layer "F.Cu")
			(hatch none 0.5)
			(connect_pads
				(clearance 0)
			)
			(min_thickness 0.25)
			(keepout
				(tracks allowed)
				(vias not_allowed)
				(pads allowed)
				(copperpour not_allowed)
				(footprints allowed)
			)
			(placement
				(enabled no)
				(sheetname "")
			)
			(fill
				(thermal_gap 0.5)
				(thermal_bridge_width 0.5)
				(island_removal_mode 0)
			)
			(polygon
				(pts
					(arc
						(start 239.980978 -45.999908)
						(mid 239.218978 -45.999908)
						(end 239.980978 -45.999908)
					)
				)
			)
		)
		(zone
			(layer "F.Cu")
			(hatch none 0.5)
			(connect_pads
				(clearance 0)
			)
			(min_thickness 0.25)
			(keepout
				(tracks allowed)
				(vias not_allowed)
				(pads allowed)
				(copperpour not_allowed)
				(footprints allowed)
			)
			(placement
				(enabled no)
				(sheetname "")
			)
			(fill
				(thermal_gap 0.5)
				(thermal_bridge_width 0.5)
				(island_removal_mode 0)
			)
			(polygon
				(pts
					(arc
						(start 239.980978 -44.99991)
						(mid 239.218978 -44.99991)
						(end 239.980978 -44.99991)
					)
				)
			)
		)
		(zone
			(layer "F.Cu")
			(hatch none 0.5)
			(connect_pads
				(clearance 0)
			)
			(min_thickness 0.25)
			(keepout
				(tracks allowed)
				(vias not_allowed)
				(pads allowed)
				(copperpour not_allowed)
				(footprints allowed)
			)
			(placement
				(enabled no)
				(sheetname "")
			)
			(fill
				(thermal_gap 0.5)
				(thermal_bridge_width 0.5)
				(island_removal_mode 0)
			)
			(polygon
				(pts
					(arc
						(start 239.980978 -43.999912)
						(mid 239.218978 -43.999912)
						(end 239.980978 -43.999912)
					)
				)
			)
		)
		(zone
			(layer "F.Cu")
			(hatch none 0.5)
			(connect_pads
				(clearance 0)
			)
			(min_thickness 0.25)
			(keepout
				(tracks allowed)
				(vias not_allowed)
				(pads allowed)
				(copperpour not_allowed)
				(footprints allowed)
			)
			(placement
				(enabled no)
				(sheetname "")
			)
			(fill
				(thermal_gap 0.5)
				(thermal_bridge_width 0.5)
				(island_removal_mode 0)
			)
			(polygon
				(pts
					(arc
						(start 239.980978 -42.999914)
						(mid 239.218978 -42.999914)
						(end 239.980978 -42.999914)
					)
				)
			)
		)
		(zone
			(layer "F.Cu")
			(hatch none 0.5)
			(connect_pads
				(clearance 0)
			)
			(min_thickness 0.25)
			(keepout
				(tracks allowed)
				(vias not_allowed)
				(pads allowed)
				(copperpour not_allowed)
				(footprints allowed)
			)
			(placement
				(enabled no)
				(sheetname "")
			)
			(fill
				(thermal_gap 0.5)
				(thermal_bridge_width 0.5)
				(island_removal_mode 0)
			)
			(polygon
				(pts
					(arc
						(start 239.980978 -41.999916)
						(mid 239.218978 -41.999916)
						(end 239.980978 -41.999916)
					)
				)
			)
		)
		(zone
			(layer "F.Cu")
			(hatch none 0.5)
			(connect_pads
				(clearance 0)
			)
			(min_thickness 0.25)
			(keepout
				(tracks allowed)
				(vias not_allowed)
				(pads allowed)
				(copperpour not_allowed)
				(footprints allowed)
			)
			(placement
				(enabled no)
				(sheetname "")
			)
			(fill
				(thermal_gap 0.5)
				(thermal_bridge_width 0.5)
				(island_removal_mode 0)
			)
			(polygon
				(pts
					(arc
						(start 239.980978 -40.999918)
						(mid 239.218978 -40.999918)
						(end 239.980978 -40.999918)
					)
				)
			)
		)
		(zone
			(layer "F.Cu")
			(hatch none 0.5)
			(connect_pads
				(clearance 0)
			)
			(min_thickness 0.25)
			(keepout
				(tracks allowed)
				(vias not_allowed)
				(pads allowed)
				(copperpour not_allowed)
				(footprints allowed)
			)
			(placement
				(enabled no)
				(sheetname "")
			)
			(fill
				(thermal_gap 0.5)
				(thermal_bridge_width 0.5)
				(island_removal_mode 0)
			)
			(polygon
				(pts
					(arc
						(start 239.980978 -39.99992)
						(mid 239.218978 -39.99992)
						(end 239.980978 -39.99992)
					)
				)
			)
		)
		(zone
			(layer "F.Cu")
			(hatch none 0.5)
			(connect_pads
				(clearance 0)
			)
			(min_thickness 0.25)
			(keepout
				(tracks allowed)
				(vias not_allowed)
				(pads allowed)
				(copperpour not_allowed)
				(footprints allowed)
			)
			(placement
				(enabled no)
				(sheetname "")
			)
			(fill
				(thermal_gap 0.5)
				(thermal_bridge_width 0.5)
				(island_removal_mode 0)
			)
			(polygon
				(pts
					(arc
						(start 239.980978 -38.999922)
						(mid 239.218978 -38.999922)
						(end 239.980978 -38.999922)
					)
				)
			)
		)
		(zone
			(layer "F.Cu")
			(hatch none 0.5)
			(connect_pads
				(clearance 0)
			)
			(min_thickness 0.25)
			(keepout
				(tracks allowed)
				(vias not_allowed)
				(pads allowed)
				(copperpour not_allowed)
				(footprints allowed)
			)
			(placement
				(enabled no)
				(sheetname "")
			)
			(fill
				(thermal_gap 0.5)
				(thermal_bridge_width 0.5)
				(island_removal_mode 0)
			)
			(polygon
				(pts
					(arc
						(start 239.980978 -37.999924)
						(mid 239.218978 -37.999924)
						(end 239.980978 -37.999924)
					)
				)
			)
		)
		(zone
			(layer "F.Cu")
			(hatch none 0.5)
			(connect_pads
				(clearance 0)
			)
			(min_thickness 0.25)
			(keepout
				(tracks allowed)
				(vias not_allowed)
				(pads allowed)
				(copperpour not_allowed)
				(footprints allowed)
			)
			(placement
				(enabled no)
				(sheetname "")
			)
			(fill
				(thermal_gap 0.5)
				(thermal_bridge_width 0.5)
				(island_removal_mode 0)
			)
			(polygon
				(pts
					(arc
						(start 239.980978 -36.999926)
						(mid 239.218978 -36.999926)
						(end 239.980978 -36.999926)
					)
				)
			)
		)
		(zone
			(layer "F.Cu")
			(hatch none 0.5)
			(connect_pads
				(clearance 0)
			)
			(min_thickness 0.25)
			(keepout
				(tracks allowed)
				(vias not_allowed)
				(pads allowed)
				(copperpour not_allowed)
				(footprints allowed)
			)
			(placement
				(enabled no)
				(sheetname "")
			)
			(fill
				(thermal_gap 0.5)
				(thermal_bridge_width 0.5)
				(island_removal_mode 0)
			)
			(polygon
				(pts
					(arc
						(start 239.980978 -35.999928)
						(mid 239.218978 -35.999928)
						(end 239.980978 -35.999928)
					)
				)
			)
		)
		(zone
			(layer "F.Cu")
			(hatch none 0.5)
			(connect_pads
				(clearance 0)
			)
			(min_thickness 0.25)
			(keepout
				(tracks allowed)
				(vias not_allowed)
				(pads allowed)
				(copperpour not_allowed)
				(footprints allowed)
			)
			(placement
				(enabled no)
				(sheetname "")
			)
			(fill
				(thermal_gap 0.5)
				(thermal_bridge_width 0.5)
				(island_removal_mode 0)
			)
			(polygon
				(pts
					(arc
						(start 239.980978 -34.99993)
						(mid 239.218978 -34.99993)
						(end 239.980978 -34.99993)
					)
				)
			)
		)
		(zone
			(layer "F.Cu")
			(hatch none 0.5)
			(connect_pads
				(clearance 0)
			)
			(min_thickness 0.25)
			(keepout
				(tracks allowed)
				(vias not_allowed)
				(pads allowed)
				(copperpour not_allowed)
				(footprints allowed)
			)
			(placement
				(enabled no)
				(sheetname "")
			)
			(fill
				(thermal_gap 0.5)
				(thermal_bridge_width 0.5)
				(island_removal_mode 0)
			)
			(polygon
				(pts
					(arc
						(start 239.980978 -33.999932)
						(mid 239.218978 -33.999932)
						(end 239.980978 -33.999932)
					)
				)
			)
		)
		(zone
			(layer "F.Cu")
			(hatch none 0.5)
			(connect_pads
				(clearance 0)
			)
			(min_thickness 0.25)
			(keepout
				(tracks allowed)
				(vias not_allowed)
				(pads allowed)
				(copperpour not_allowed)
				(footprints allowed)
			)
			(placement
				(enabled no)
				(sheetname "")
			)
			(fill
				(thermal_gap 0.5)
				(thermal_bridge_width 0.5)
				(island_removal_mode 0)
			)
			(polygon
				(pts
					(arc
						(start 239.980978 -32.999934)
						(mid 239.218978 -32.999934)
						(end 239.980978 -32.999934)
					)
				)
			)
		)
		(zone
			(layer "F.Cu")
			(hatch none 0.5)
			(connect_pads
				(clearance 0)
			)
			(min_thickness 0.25)
			(keepout
				(tracks allowed)
				(vias not_allowed)
				(pads allowed)
				(copperpour not_allowed)
				(footprints allowed)
			)
			(placement
				(enabled no)
				(sheetname "")
			)
			(fill
				(thermal_gap 0.5)
				(thermal_bridge_width 0.5)
				(island_removal_mode 0)
			)
			(polygon
				(pts
					(arc
						(start 239.980978 -31.999936)
						(mid 239.218978 -31.999936)
						(end 239.980978 -31.999936)
					)
				)
			)
		)
		(zone
			(layer "F.Cu")
			(hatch none 0.5)
			(connect_pads
				(clearance 0)
			)
			(min_thickness 0.25)
			(keepout
				(tracks allowed)
				(vias not_allowed)
				(pads allowed)
				(copperpour not_allowed)
				(footprints allowed)
			)
			(placement
				(enabled no)
				(sheetname "")
			)
			(fill
				(thermal_gap 0.5)
				(thermal_bridge_width 0.5)
				(island_removal_mode 0)
			)
			(polygon
				(pts
					(arc
						(start 239.980978 -30.999938)
						(mid 239.218978 -30.999938)
						(end 239.980978 -30.999938)
					)
				)
			)
		)
		(zone
			(layer "F.Cu")
			(hatch none 0.5)
			(connect_pads
				(clearance 0)
			)
			(min_thickness 0.25)
			(keepout
				(tracks allowed)
				(vias not_allowed)
				(pads allowed)
				(copperpour not_allowed)
				(footprints allowed)
			)
			(placement
				(enabled no)
				(sheetname "")
			)
			(fill
				(thermal_gap 0.5)
				(thermal_bridge_width 0.5)
				(island_removal_mode 0)
			)
			(polygon
				(pts
					(arc
						(start 239.980978 -29.99994)
						(mid 239.218978 -29.99994)
						(end 239.980978 -29.99994)
					)
				)
			)
		)
		(zone
			(layer "F.Cu")
			(hatch none 0.5)
			(connect_pads
				(clearance 0)
			)
			(min_thickness 0.25)
			(keepout
				(tracks allowed)
				(vias not_allowed)
				(pads allowed)
				(copperpour not_allowed)
				(footprints allowed)
			)
			(placement
				(enabled no)
				(sheetname "")
			)
			(fill
				(thermal_gap 0.5)
				(thermal_bridge_width 0.5)
				(island_removal_mode 0)
			)
			(polygon
				(pts
					(arc
						(start 240.980976 -65.999868)
						(mid 240.218976 -65.999868)
						(end 240.980976 -65.999868)
					)
				)
			)
		)
		(zone
			(layer "F.Cu")
			(hatch none 0.5)
			(connect_pads
				(clearance 0)
			)
			(min_thickness 0.25)
			(keepout
				(tracks allowed)
				(vias not_allowed)
				(pads allowed)
				(copperpour not_allowed)
				(footprints allowed)
			)
			(placement
				(enabled no)
				(sheetname "")
			)
			(fill
				(thermal_gap 0.5)
				(thermal_bridge_width 0.5)
				(island_removal_mode 0)
			)
			(polygon
				(pts
					(arc
						(start 240.980976 -64.99987)
						(mid 240.218976 -64.99987)
						(end 240.980976 -64.99987)
					)
				)
			)
		)
		(zone
			(layer "F.Cu")
			(hatch none 0.5)
			(connect_pads
				(clearance 0)
			)
			(min_thickness 0.25)
			(keepout
				(tracks allowed)
				(vias not_allowed)
				(pads allowed)
				(copperpour not_allowed)
				(footprints allowed)
			)
			(placement
				(enabled no)
				(sheetname "")
			)
			(fill
				(thermal_gap 0.5)
				(thermal_bridge_width 0.5)
				(island_removal_mode 0)
			)
			(polygon
				(pts
					(arc
						(start 240.980976 -63.999872)
						(mid 240.218976 -63.999872)
						(end 240.980976 -63.999872)
					)
				)
			)
		)
		(zone
			(layer "F.Cu")
			(hatch none 0.5)
			(connect_pads
				(clearance 0)
			)
			(min_thickness 0.25)
			(keepout
				(tracks allowed)
				(vias not_allowed)
				(pads allowed)
				(copperpour not_allowed)
				(footprints allowed)
			)
			(placement
				(enabled no)
				(sheetname "")
			)
			(fill
				(thermal_gap 0.5)
				(thermal_bridge_width 0.5)
				(island_removal_mode 0)
			)
			(polygon
				(pts
					(arc
						(start 240.980976 -62.999874)
						(mid 240.218976 -62.999874)
						(end 240.980976 -62.999874)
					)
				)
			)
		)
		(zone
			(layer "F.Cu")
			(hatch none 0.5)
			(connect_pads
				(clearance 0)
			)
			(min_thickness 0.25)
			(keepout
				(tracks allowed)
				(vias not_allowed)
				(pads allowed)
				(copperpour not_allowed)
				(footprints allowed)
			)
			(placement
				(enabled no)
				(sheetname "")
			)
			(fill
				(thermal_gap 0.5)
				(thermal_bridge_width 0.5)
				(island_removal_mode 0)
			)
			(polygon
				(pts
					(arc
						(start 240.980976 -61.999876)
						(mid 240.218976 -61.999876)
						(end 240.980976 -61.999876)
					)
				)
			)
		)
		(zone
			(layer "F.Cu")
			(hatch none 0.5)
			(connect_pads
				(clearance 0)
			)
			(min_thickness 0.25)
			(keepout
				(tracks allowed)
				(vias not_allowed)
				(pads allowed)
				(copperpour not_allowed)
				(footprints allowed)
			)
			(placement
				(enabled no)
				(sheetname "")
			)
			(fill
				(thermal_gap 0.5)
				(thermal_bridge_width 0.5)
				(island_removal_mode 0)
			)
			(polygon
				(pts
					(arc
						(start 240.980976 -60.999878)
						(mid 240.218976 -60.999878)
						(end 240.980976 -60.999878)
					)
				)
			)
		)
		(zone
			(layer "F.Cu")
			(hatch none 0.5)
			(connect_pads
				(clearance 0)
			)
			(min_thickness 0.25)
			(keepout
				(tracks allowed)
				(vias not_allowed)
				(pads allowed)
				(copperpour not_allowed)
				(footprints allowed)
			)
			(placement
				(enabled no)
				(sheetname "")
			)
			(fill
				(thermal_gap 0.5)
				(thermal_bridge_width 0.5)
				(island_removal_mode 0)
			)
			(polygon
				(pts
					(arc
						(start 240.980976 -59.99988)
						(mid 240.218976 -59.99988)
						(end 240.980976 -59.99988)
					)
				)
			)
		)
		(zone
			(layer "F.Cu")
			(hatch none 0.5)
			(connect_pads
				(clearance 0)
			)
			(min_thickness 0.25)
			(keepout
				(tracks allowed)
				(vias not_allowed)
				(pads allowed)
				(copperpour not_allowed)
				(footprints allowed)
			)
			(placement
				(enabled no)
				(sheetname "")
			)
			(fill
				(thermal_gap 0.5)
				(thermal_bridge_width 0.5)
				(island_removal_mode 0)
			)
			(polygon
				(pts
					(arc
						(start 240.980976 -58.999882)
						(mid 240.218976 -58.999882)
						(end 240.980976 -58.999882)
					)
				)
			)
		)
		(zone
			(layer "F.Cu")
			(hatch none 0.5)
			(connect_pads
				(clearance 0)
			)
			(min_thickness 0.25)
			(keepout
				(tracks allowed)
				(vias not_allowed)
				(pads allowed)
				(copperpour not_allowed)
				(footprints allowed)
			)
			(placement
				(enabled no)
				(sheetname "")
			)
			(fill
				(thermal_gap 0.5)
				(thermal_bridge_width 0.5)
				(island_removal_mode 0)
			)
			(polygon
				(pts
					(arc
						(start 240.980976 -57.999884)
						(mid 240.218976 -57.999884)
						(end 240.980976 -57.999884)
					)
				)
			)
		)
		(zone
			(layer "F.Cu")
			(hatch none 0.5)
			(connect_pads
				(clearance 0)
			)
			(min_thickness 0.25)
			(keepout
				(tracks allowed)
				(vias not_allowed)
				(pads allowed)
				(copperpour not_allowed)
				(footprints allowed)
			)
			(placement
				(enabled no)
				(sheetname "")
			)
			(fill
				(thermal_gap 0.5)
				(thermal_bridge_width 0.5)
				(island_removal_mode 0)
			)
			(polygon
				(pts
					(arc
						(start 240.980976 -56.999886)
						(mid 240.218976 -56.999886)
						(end 240.980976 -56.999886)
					)
				)
			)
		)
		(zone
			(layer "F.Cu")
			(hatch none 0.5)
			(connect_pads
				(clearance 0)
			)
			(min_thickness 0.25)
			(keepout
				(tracks allowed)
				(vias not_allowed)
				(pads allowed)
				(copperpour not_allowed)
				(footprints allowed)
			)
			(placement
				(enabled no)
				(sheetname "")
			)
			(fill
				(thermal_gap 0.5)
				(thermal_bridge_width 0.5)
				(island_removal_mode 0)
			)
			(polygon
				(pts
					(arc
						(start 240.980976 -55.999888)
						(mid 240.218976 -55.999888)
						(end 240.980976 -55.999888)
					)
				)
			)
		)
		(zone
			(layer "F.Cu")
			(hatch none 0.5)
			(connect_pads
				(clearance 0)
			)
			(min_thickness 0.25)
			(keepout
				(tracks allowed)
				(vias not_allowed)
				(pads allowed)
				(copperpour not_allowed)
				(footprints allowed)
			)
			(placement
				(enabled no)
				(sheetname "")
			)
			(fill
				(thermal_gap 0.5)
				(thermal_bridge_width 0.5)
				(island_removal_mode 0)
			)
			(polygon
				(pts
					(arc
						(start 240.980976 -54.99989)
						(mid 240.218976 -54.99989)
						(end 240.980976 -54.99989)
					)
				)
			)
		)
		(zone
			(layer "F.Cu")
			(hatch none 0.5)
			(connect_pads
				(clearance 0)
			)
			(min_thickness 0.25)
			(keepout
				(tracks allowed)
				(vias not_allowed)
				(pads allowed)
				(copperpour not_allowed)
				(footprints allowed)
			)
			(placement
				(enabled no)
				(sheetname "")
			)
			(fill
				(thermal_gap 0.5)
				(thermal_bridge_width 0.5)
				(island_removal_mode 0)
			)
			(polygon
				(pts
					(arc
						(start 240.980976 -53.999892)
						(mid 240.218976 -53.999892)
						(end 240.980976 -53.999892)
					)
				)
			)
		)
		(zone
			(layer "F.Cu")
			(hatch none 0.5)
			(connect_pads
				(clearance 0)
			)
			(min_thickness 0.25)
			(keepout
				(tracks allowed)
				(vias not_allowed)
				(pads allowed)
				(copperpour not_allowed)
				(footprints allowed)
			)
			(placement
				(enabled no)
				(sheetname "")
			)
			(fill
				(thermal_gap 0.5)
				(thermal_bridge_width 0.5)
				(island_removal_mode 0)
			)
			(polygon
				(pts
					(arc
						(start 240.980976 -52.999894)
						(mid 240.218976 -52.999894)
						(end 240.980976 -52.999894)
					)
				)
			)
		)
		(zone
			(layer "F.Cu")
			(hatch none 0.5)
			(connect_pads
				(clearance 0)
			)
			(min_thickness 0.25)
			(keepout
				(tracks allowed)
				(vias not_allowed)
				(pads allowed)
				(copperpour not_allowed)
				(footprints allowed)
			)
			(placement
				(enabled no)
				(sheetname "")
			)
			(fill
				(thermal_gap 0.5)
				(thermal_bridge_width 0.5)
				(island_removal_mode 0)
			)
			(polygon
				(pts
					(arc
						(start 240.980976 -51.999896)
						(mid 240.218976 -51.999896)
						(end 240.980976 -51.999896)
					)
				)
			)
		)
		(zone
			(layer "F.Cu")
			(hatch none 0.5)
			(connect_pads
				(clearance 0)
			)
			(min_thickness 0.25)
			(keepout
				(tracks allowed)
				(vias not_allowed)
				(pads allowed)
				(copperpour not_allowed)
				(footprints allowed)
			)
			(placement
				(enabled no)
				(sheetname "")
			)
			(fill
				(thermal_gap 0.5)
				(thermal_bridge_width 0.5)
				(island_removal_mode 0)
			)
			(polygon
				(pts
					(arc
						(start 240.980976 -50.999898)
						(mid 240.218976 -50.999898)
						(end 240.980976 -50.999898)
					)
				)
			)
		)
		(zone
			(layer "F.Cu")
			(hatch none 0.5)
			(connect_pads
				(clearance 0)
			)
			(min_thickness 0.25)
			(keepout
				(tracks allowed)
				(vias not_allowed)
				(pads allowed)
				(copperpour not_allowed)
				(footprints allowed)
			)
			(placement
				(enabled no)
				(sheetname "")
			)
			(fill
				(thermal_gap 0.5)
				(thermal_bridge_width 0.5)
				(island_removal_mode 0)
			)
			(polygon
				(pts
					(arc
						(start 240.980976 -49.9999)
						(mid 240.218976 -49.9999)
						(end 240.980976 -49.9999)
					)
				)
			)
		)
		(zone
			(layer "F.Cu")
			(hatch none 0.5)
			(connect_pads
				(clearance 0)
			)
			(min_thickness 0.25)
			(keepout
				(tracks allowed)
				(vias not_allowed)
				(pads allowed)
				(copperpour not_allowed)
				(footprints allowed)
			)
			(placement
				(enabled no)
				(sheetname "")
			)
			(fill
				(thermal_gap 0.5)
				(thermal_bridge_width 0.5)
				(island_removal_mode 0)
			)
			(polygon
				(pts
					(arc
						(start 240.980976 -48.999902)
						(mid 240.218976 -48.999902)
						(end 240.980976 -48.999902)
					)
				)
			)
		)
		(zone
			(layer "F.Cu")
			(hatch none 0.5)
			(connect_pads
				(clearance 0)
			)
			(min_thickness 0.25)
			(keepout
				(tracks allowed)
				(vias not_allowed)
				(pads allowed)
				(copperpour not_allowed)
				(footprints allowed)
			)
			(placement
				(enabled no)
				(sheetname "")
			)
			(fill
				(thermal_gap 0.5)
				(thermal_bridge_width 0.5)
				(island_removal_mode 0)
			)
			(polygon
				(pts
					(arc
						(start 240.980976 -47.999904)
						(mid 240.218976 -47.999904)
						(end 240.980976 -47.999904)
					)
				)
			)
		)
		(zone
			(layer "F.Cu")
			(hatch none 0.5)
			(connect_pads
				(clearance 0)
			)
			(min_thickness 0.25)
			(keepout
				(tracks allowed)
				(vias not_allowed)
				(pads allowed)
				(copperpour not_allowed)
				(footprints allowed)
			)
			(placement
				(enabled no)
				(sheetname "")
			)
			(fill
				(thermal_gap 0.5)
				(thermal_bridge_width 0.5)
				(island_removal_mode 0)
			)
			(polygon
				(pts
					(arc
						(start 240.980976 -46.999906)
						(mid 240.218976 -46.999906)
						(end 240.980976 -46.999906)
					)
				)
			)
		)
		(zone
			(layer "F.Cu")
			(hatch none 0.5)
			(connect_pads
				(clearance 0)
			)
			(min_thickness 0.25)
			(keepout
				(tracks allowed)
				(vias not_allowed)
				(pads allowed)
				(copperpour not_allowed)
				(footprints allowed)
			)
			(placement
				(enabled no)
				(sheetname "")
			)
			(fill
				(thermal_gap 0.5)
				(thermal_bridge_width 0.5)
				(island_removal_mode 0)
			)
			(polygon
				(pts
					(arc
						(start 240.980976 -45.999908)
						(mid 240.218976 -45.999908)
						(end 240.980976 -45.999908)
					)
				)
			)
		)
		(zone
			(layer "F.Cu")
			(hatch none 0.5)
			(connect_pads
				(clearance 0)
			)
			(min_thickness 0.25)
			(keepout
				(tracks allowed)
				(vias not_allowed)
				(pads allowed)
				(copperpour not_allowed)
				(footprints allowed)
			)
			(placement
				(enabled no)
				(sheetname "")
			)
			(fill
				(thermal_gap 0.5)
				(thermal_bridge_width 0.5)
				(island_removal_mode 0)
			)
			(polygon
				(pts
					(arc
						(start 240.980976 -44.99991)
						(mid 240.218976 -44.99991)
						(end 240.980976 -44.99991)
					)
				)
			)
		)
		(zone
			(layer "F.Cu")
			(hatch none 0.5)
			(connect_pads
				(clearance 0)
			)
			(min_thickness 0.25)
			(keepout
				(tracks allowed)
				(vias not_allowed)
				(pads allowed)
				(copperpour not_allowed)
				(footprints allowed)
			)
			(placement
				(enabled no)
				(sheetname "")
			)
			(fill
				(thermal_gap 0.5)
				(thermal_bridge_width 0.5)
				(island_removal_mode 0)
			)
			(polygon
				(pts
					(arc
						(start 240.980976 -43.999912)
						(mid 240.218976 -43.999912)
						(end 240.980976 -43.999912)
					)
				)
			)
		)
		(zone
			(layer "F.Cu")
			(hatch none 0.5)
			(connect_pads
				(clearance 0)
			)
			(min_thickness 0.25)
			(keepout
				(tracks allowed)
				(vias not_allowed)
				(pads allowed)
				(copperpour not_allowed)
				(footprints allowed)
			)
			(placement
				(enabled no)
				(sheetname "")
			)
			(fill
				(thermal_gap 0.5)
				(thermal_bridge_width 0.5)
				(island_removal_mode 0)
			)
			(polygon
				(pts
					(arc
						(start 240.980976 -42.999914)
						(mid 240.218976 -42.999914)
						(end 240.980976 -42.999914)
					)
				)
			)
		)
		(zone
			(layer "F.Cu")
			(hatch none 0.5)
			(connect_pads
				(clearance 0)
			)
			(min_thickness 0.25)
			(keepout
				(tracks allowed)
				(vias not_allowed)
				(pads allowed)
				(copperpour not_allowed)
				(footprints allowed)
			)
			(placement
				(enabled no)
				(sheetname "")
			)
			(fill
				(thermal_gap 0.5)
				(thermal_bridge_width 0.5)
				(island_removal_mode 0)
			)
			(polygon
				(pts
					(arc
						(start 240.980976 -41.999916)
						(mid 240.218976 -41.999916)
						(end 240.980976 -41.999916)
					)
				)
			)
		)
		(zone
			(layer "F.Cu")
			(hatch none 0.5)
			(connect_pads
				(clearance 0)
			)
			(min_thickness 0.25)
			(keepout
				(tracks allowed)
				(vias not_allowed)
				(pads allowed)
				(copperpour not_allowed)
				(footprints allowed)
			)
			(placement
				(enabled no)
				(sheetname "")
			)
			(fill
				(thermal_gap 0.5)
				(thermal_bridge_width 0.5)
				(island_removal_mode 0)
			)
			(polygon
				(pts
					(arc
						(start 240.980976 -40.999918)
						(mid 240.218976 -40.999918)
						(end 240.980976 -40.999918)
					)
				)
			)
		)
		(zone
			(layer "F.Cu")
			(hatch none 0.5)
			(connect_pads
				(clearance 0)
			)
			(min_thickness 0.25)
			(keepout
				(tracks allowed)
				(vias not_allowed)
				(pads allowed)
				(copperpour not_allowed)
				(footprints allowed)
			)
			(placement
				(enabled no)
				(sheetname "")
			)
			(fill
				(thermal_gap 0.5)
				(thermal_bridge_width 0.5)
				(island_removal_mode 0)
			)
			(polygon
				(pts
					(arc
						(start 240.980976 -39.99992)
						(mid 240.218976 -39.99992)
						(end 240.980976 -39.99992)
					)
				)
			)
		)
		(zone
			(layer "F.Cu")
			(hatch none 0.5)
			(connect_pads
				(clearance 0)
			)
			(min_thickness 0.25)
			(keepout
				(tracks allowed)
				(vias not_allowed)
				(pads allowed)
				(copperpour not_allowed)
				(footprints allowed)
			)
			(placement
				(enabled no)
				(sheetname "")
			)
			(fill
				(thermal_gap 0.5)
				(thermal_bridge_width 0.5)
				(island_removal_mode 0)
			)
			(polygon
				(pts
					(arc
						(start 240.980976 -38.999922)
						(mid 240.218976 -38.999922)
						(end 240.980976 -38.999922)
					)
				)
			)
		)
		(zone
			(layer "F.Cu")
			(hatch none 0.5)
			(connect_pads
				(clearance 0)
			)
			(min_thickness 0.25)
			(keepout
				(tracks allowed)
				(vias not_allowed)
				(pads allowed)
				(copperpour not_allowed)
				(footprints allowed)
			)
			(placement
				(enabled no)
				(sheetname "")
			)
			(fill
				(thermal_gap 0.5)
				(thermal_bridge_width 0.5)
				(island_removal_mode 0)
			)
			(polygon
				(pts
					(arc
						(start 240.980976 -37.999924)
						(mid 240.218976 -37.999924)
						(end 240.980976 -37.999924)
					)
				)
			)
		)
		(zone
			(layer "F.Cu")
			(hatch none 0.5)
			(connect_pads
				(clearance 0)
			)
			(min_thickness 0.25)
			(keepout
				(tracks allowed)
				(vias not_allowed)
				(pads allowed)
				(copperpour not_allowed)
				(footprints allowed)
			)
			(placement
				(enabled no)
				(sheetname "")
			)
			(fill
				(thermal_gap 0.5)
				(thermal_bridge_width 0.5)
				(island_removal_mode 0)
			)
			(polygon
				(pts
					(arc
						(start 240.980976 -36.999926)
						(mid 240.218976 -36.999926)
						(end 240.980976 -36.999926)
					)
				)
			)
		)
		(zone
			(layer "F.Cu")
			(hatch none 0.5)
			(connect_pads
				(clearance 0)
			)
			(min_thickness 0.25)
			(keepout
				(tracks allowed)
				(vias not_allowed)
				(pads allowed)
				(copperpour not_allowed)
				(footprints allowed)
			)
			(placement
				(enabled no)
				(sheetname "")
			)
			(fill
				(thermal_gap 0.5)
				(thermal_bridge_width 0.5)
				(island_removal_mode 0)
			)
			(polygon
				(pts
					(arc
						(start 240.980976 -35.999928)
						(mid 240.218976 -35.999928)
						(end 240.980976 -35.999928)
					)
				)
			)
		)
		(zone
			(layer "F.Cu")
			(hatch none 0.5)
			(connect_pads
				(clearance 0)
			)
			(min_thickness 0.25)
			(keepout
				(tracks allowed)
				(vias not_allowed)
				(pads allowed)
				(copperpour not_allowed)
				(footprints allowed)
			)
			(placement
				(enabled no)
				(sheetname "")
			)
			(fill
				(thermal_gap 0.5)
				(thermal_bridge_width 0.5)
				(island_removal_mode 0)
			)
			(polygon
				(pts
					(arc
						(start 240.980976 -34.99993)
						(mid 240.218976 -34.99993)
						(end 240.980976 -34.99993)
					)
				)
			)
		)
		(zone
			(layer "F.Cu")
			(hatch none 0.5)
			(connect_pads
				(clearance 0)
			)
			(min_thickness 0.25)
			(keepout
				(tracks allowed)
				(vias not_allowed)
				(pads allowed)
				(copperpour not_allowed)
				(footprints allowed)
			)
			(placement
				(enabled no)
				(sheetname "")
			)
			(fill
				(thermal_gap 0.5)
				(thermal_bridge_width 0.5)
				(island_removal_mode 0)
			)
			(polygon
				(pts
					(arc
						(start 240.980976 -33.999932)
						(mid 240.218976 -33.999932)
						(end 240.980976 -33.999932)
					)
				)
			)
		)
		(zone
			(layer "F.Cu")
			(hatch none 0.5)
			(connect_pads
				(clearance 0)
			)
			(min_thickness 0.25)
			(keepout
				(tracks allowed)
				(vias not_allowed)
				(pads allowed)
				(copperpour not_allowed)
				(footprints allowed)
			)
			(placement
				(enabled no)
				(sheetname "")
			)
			(fill
				(thermal_gap 0.5)
				(thermal_bridge_width 0.5)
				(island_removal_mode 0)
			)
			(polygon
				(pts
					(arc
						(start 240.980976 -32.999934)
						(mid 240.218976 -32.999934)
						(end 240.980976 -32.999934)
					)
				)
			)
		)
		(zone
			(layer "F.Cu")
			(hatch none 0.5)
			(connect_pads
				(clearance 0)
			)
			(min_thickness 0.25)
			(keepout
				(tracks allowed)
				(vias not_allowed)
				(pads allowed)
				(copperpour not_allowed)
				(footprints allowed)
			)
			(placement
				(enabled no)
				(sheetname "")
			)
			(fill
				(thermal_gap 0.5)
				(thermal_bridge_width 0.5)
				(island_removal_mode 0)
			)
			(polygon
				(pts
					(arc
						(start 240.980976 -31.999936)
						(mid 240.218976 -31.999936)
						(end 240.980976 -31.999936)
					)
				)
			)
		)
		(zone
			(layer "F.Cu")
			(hatch none 0.5)
			(connect_pads
				(clearance 0)
			)
			(min_thickness 0.25)
			(keepout
				(tracks allowed)
				(vias not_allowed)
				(pads allowed)
				(copperpour not_allowed)
				(footprints allowed)
			)
			(placement
				(enabled no)
				(sheetname "")
			)
			(fill
				(thermal_gap 0.5)
				(thermal_bridge_width 0.5)
				(island_removal_mode 0)
			)
			(polygon
				(pts
					(arc
						(start 240.980976 -30.999938)
						(mid 240.218976 -30.999938)
						(end 240.980976 -30.999938)
					)
				)
			)
		)
		(zone
			(layer "F.Cu")
			(hatch none 0.5)
			(connect_pads
				(clearance 0)
			)
			(min_thickness 0.25)
			(keepout
				(tracks allowed)
				(vias not_allowed)
				(pads allowed)
				(copperpour not_allowed)
				(footprints allowed)
			)
			(placement
				(enabled no)
				(sheetname "")
			)
			(fill
				(thermal_gap 0.5)
				(thermal_bridge_width 0.5)
				(island_removal_mode 0)
			)
			(polygon
				(pts
					(arc
						(start 240.980976 -29.99994)
						(mid 240.218976 -29.99994)
						(end 240.980976 -29.99994)
					)
				)
			)
		)
		(zone
			(layer "F.Cu")
			(hatch none 0.5)
			(connect_pads
				(clearance 0)
			)
			(min_thickness 0.25)
			(keepout
				(tracks allowed)
				(vias not_allowed)
				(pads allowed)
				(copperpour not_allowed)
				(footprints allowed)
			)
			(placement
				(enabled no)
				(sheetname "")
			)
			(fill
				(thermal_gap 0.5)
				(thermal_bridge_width 0.5)
				(island_removal_mode 0)
			)
			(polygon
				(pts
					(arc
						(start 241.980974 -64.99987)
						(mid 241.218974 -64.99987)
						(end 241.980974 -64.99987)
					)
				)
			)
		)
		(zone
			(layer "F.Cu")
			(hatch none 0.5)
			(connect_pads
				(clearance 0)
			)
			(min_thickness 0.25)
			(keepout
				(tracks allowed)
				(vias not_allowed)
				(pads allowed)
				(copperpour not_allowed)
				(footprints allowed)
			)
			(placement
				(enabled no)
				(sheetname "")
			)
			(fill
				(thermal_gap 0.5)
				(thermal_bridge_width 0.5)
				(island_removal_mode 0)
			)
			(polygon
				(pts
					(arc
						(start 241.980974 -63.999872)
						(mid 241.218974 -63.999872)
						(end 241.980974 -63.999872)
					)
				)
			)
		)
		(zone
			(layer "F.Cu")
			(hatch none 0.5)
			(connect_pads
				(clearance 0)
			)
			(min_thickness 0.25)
			(keepout
				(tracks allowed)
				(vias not_allowed)
				(pads allowed)
				(copperpour not_allowed)
				(footprints allowed)
			)
			(placement
				(enabled no)
				(sheetname "")
			)
			(fill
				(thermal_gap 0.5)
				(thermal_bridge_width 0.5)
				(island_removal_mode 0)
			)
			(polygon
				(pts
					(arc
						(start 241.980974 -62.999874)
						(mid 241.218974 -62.999874)
						(end 241.980974 -62.999874)
					)
				)
			)
		)
		(zone
			(layer "F.Cu")
			(hatch none 0.5)
			(connect_pads
				(clearance 0)
			)
			(min_thickness 0.25)
			(keepout
				(tracks allowed)
				(vias not_allowed)
				(pads allowed)
				(copperpour not_allowed)
				(footprints allowed)
			)
			(placement
				(enabled no)
				(sheetname "")
			)
			(fill
				(thermal_gap 0.5)
				(thermal_bridge_width 0.5)
				(island_removal_mode 0)
			)
			(polygon
				(pts
					(arc
						(start 241.980974 -61.999876)
						(mid 241.218974 -61.999876)
						(end 241.980974 -61.999876)
					)
				)
			)
		)
		(zone
			(layer "F.Cu")
			(hatch none 0.5)
			(connect_pads
				(clearance 0)
			)
			(min_thickness 0.25)
			(keepout
				(tracks allowed)
				(vias not_allowed)
				(pads allowed)
				(copperpour not_allowed)
				(footprints allowed)
			)
			(placement
				(enabled no)
				(sheetname "")
			)
			(fill
				(thermal_gap 0.5)
				(thermal_bridge_width 0.5)
				(island_removal_mode 0)
			)
			(polygon
				(pts
					(arc
						(start 241.980974 -60.999878)
						(mid 241.218974 -60.999878)
						(end 241.980974 -60.999878)
					)
				)
			)
		)
		(zone
			(layer "F.Cu")
			(hatch none 0.5)
			(connect_pads
				(clearance 0)
			)
			(min_thickness 0.25)
			(keepout
				(tracks allowed)
				(vias not_allowed)
				(pads allowed)
				(copperpour not_allowed)
				(footprints allowed)
			)
			(placement
				(enabled no)
				(sheetname "")
			)
			(fill
				(thermal_gap 0.5)
				(thermal_bridge_width 0.5)
				(island_removal_mode 0)
			)
			(polygon
				(pts
					(arc
						(start 241.980974 -59.99988)
						(mid 241.218974 -59.99988)
						(end 241.980974 -59.99988)
					)
				)
			)
		)
		(zone
			(layer "F.Cu")
			(hatch none 0.5)
			(connect_pads
				(clearance 0)
			)
			(min_thickness 0.25)
			(keepout
				(tracks allowed)
				(vias not_allowed)
				(pads allowed)
				(copperpour not_allowed)
				(footprints allowed)
			)
			(placement
				(enabled no)
				(sheetname "")
			)
			(fill
				(thermal_gap 0.5)
				(thermal_bridge_width 0.5)
				(island_removal_mode 0)
			)
			(polygon
				(pts
					(arc
						(start 241.980974 -58.999882)
						(mid 241.218974 -58.999882)
						(end 241.980974 -58.999882)
					)
				)
			)
		)
		(zone
			(layer "F.Cu")
			(hatch none 0.5)
			(connect_pads
				(clearance 0)
			)
			(min_thickness 0.25)
			(keepout
				(tracks allowed)
				(vias not_allowed)
				(pads allowed)
				(copperpour not_allowed)
				(footprints allowed)
			)
			(placement
				(enabled no)
				(sheetname "")
			)
			(fill
				(thermal_gap 0.5)
				(thermal_bridge_width 0.5)
				(island_removal_mode 0)
			)
			(polygon
				(pts
					(arc
						(start 241.980974 -57.999884)
						(mid 241.218974 -57.999884)
						(end 241.980974 -57.999884)
					)
				)
			)
		)
		(zone
			(layer "F.Cu")
			(hatch none 0.5)
			(connect_pads
				(clearance 0)
			)
			(min_thickness 0.25)
			(keepout
				(tracks allowed)
				(vias not_allowed)
				(pads allowed)
				(copperpour not_allowed)
				(footprints allowed)
			)
			(placement
				(enabled no)
				(sheetname "")
			)
			(fill
				(thermal_gap 0.5)
				(thermal_bridge_width 0.5)
				(island_removal_mode 0)
			)
			(polygon
				(pts
					(arc
						(start 241.980974 -56.999886)
						(mid 241.218974 -56.999886)
						(end 241.980974 -56.999886)
					)
				)
			)
		)
		(zone
			(layer "F.Cu")
			(hatch none 0.5)
			(connect_pads
				(clearance 0)
			)
			(min_thickness 0.25)
			(keepout
				(tracks allowed)
				(vias not_allowed)
				(pads allowed)
				(copperpour not_allowed)
				(footprints allowed)
			)
			(placement
				(enabled no)
				(sheetname "")
			)
			(fill
				(thermal_gap 0.5)
				(thermal_bridge_width 0.5)
				(island_removal_mode 0)
			)
			(polygon
				(pts
					(arc
						(start 241.980974 -55.999888)
						(mid 241.218974 -55.999888)
						(end 241.980974 -55.999888)
					)
				)
			)
		)
		(zone
			(layer "F.Cu")
			(hatch none 0.5)
			(connect_pads
				(clearance 0)
			)
			(min_thickness 0.25)
			(keepout
				(tracks allowed)
				(vias not_allowed)
				(pads allowed)
				(copperpour not_allowed)
				(footprints allowed)
			)
			(placement
				(enabled no)
				(sheetname "")
			)
			(fill
				(thermal_gap 0.5)
				(thermal_bridge_width 0.5)
				(island_removal_mode 0)
			)
			(polygon
				(pts
					(arc
						(start 241.980974 -54.99989)
						(mid 241.218974 -54.99989)
						(end 241.980974 -54.99989)
					)
				)
			)
		)
		(zone
			(layer "F.Cu")
			(hatch none 0.5)
			(connect_pads
				(clearance 0)
			)
			(min_thickness 0.25)
			(keepout
				(tracks allowed)
				(vias not_allowed)
				(pads allowed)
				(copperpour not_allowed)
				(footprints allowed)
			)
			(placement
				(enabled no)
				(sheetname "")
			)
			(fill
				(thermal_gap 0.5)
				(thermal_bridge_width 0.5)
				(island_removal_mode 0)
			)
			(polygon
				(pts
					(arc
						(start 241.980974 -53.999892)
						(mid 241.218974 -53.999892)
						(end 241.980974 -53.999892)
					)
				)
			)
		)
		(zone
			(layer "F.Cu")
			(hatch none 0.5)
			(connect_pads
				(clearance 0)
			)
			(min_thickness 0.25)
			(keepout
				(tracks allowed)
				(vias not_allowed)
				(pads allowed)
				(copperpour not_allowed)
				(footprints allowed)
			)
			(placement
				(enabled no)
				(sheetname "")
			)
			(fill
				(thermal_gap 0.5)
				(thermal_bridge_width 0.5)
				(island_removal_mode 0)
			)
			(polygon
				(pts
					(arc
						(start 241.980974 -52.999894)
						(mid 241.218974 -52.999894)
						(end 241.980974 -52.999894)
					)
				)
			)
		)
		(zone
			(layer "F.Cu")
			(hatch none 0.5)
			(connect_pads
				(clearance 0)
			)
			(min_thickness 0.25)
			(keepout
				(tracks allowed)
				(vias not_allowed)
				(pads allowed)
				(copperpour not_allowed)
				(footprints allowed)
			)
			(placement
				(enabled no)
				(sheetname "")
			)
			(fill
				(thermal_gap 0.5)
				(thermal_bridge_width 0.5)
				(island_removal_mode 0)
			)
			(polygon
				(pts
					(arc
						(start 241.980974 -51.999896)
						(mid 241.218974 -51.999896)
						(end 241.980974 -51.999896)
					)
				)
			)
		)
		(zone
			(layer "F.Cu")
			(hatch none 0.5)
			(connect_pads
				(clearance 0)
			)
			(min_thickness 0.25)
			(keepout
				(tracks allowed)
				(vias not_allowed)
				(pads allowed)
				(copperpour not_allowed)
				(footprints allowed)
			)
			(placement
				(enabled no)
				(sheetname "")
			)
			(fill
				(thermal_gap 0.5)
				(thermal_bridge_width 0.5)
				(island_removal_mode 0)
			)
			(polygon
				(pts
					(arc
						(start 241.980974 -50.999898)
						(mid 241.218974 -50.999898)
						(end 241.980974 -50.999898)
					)
				)
			)
		)
		(zone
			(layer "F.Cu")
			(hatch none 0.5)
			(connect_pads
				(clearance 0)
			)
			(min_thickness 0.25)
			(keepout
				(tracks allowed)
				(vias not_allowed)
				(pads allowed)
				(copperpour not_allowed)
				(footprints allowed)
			)
			(placement
				(enabled no)
				(sheetname "")
			)
			(fill
				(thermal_gap 0.5)
				(thermal_bridge_width 0.5)
				(island_removal_mode 0)
			)
			(polygon
				(pts
					(arc
						(start 241.980974 -49.9999)
						(mid 241.218974 -49.9999)
						(end 241.980974 -49.9999)
					)
				)
			)
		)
		(zone
			(layer "F.Cu")
			(hatch none 0.5)
			(connect_pads
				(clearance 0)
			)
			(min_thickness 0.25)
			(keepout
				(tracks allowed)
				(vias not_allowed)
				(pads allowed)
				(copperpour not_allowed)
				(footprints allowed)
			)
			(placement
				(enabled no)
				(sheetname "")
			)
			(fill
				(thermal_gap 0.5)
				(thermal_bridge_width 0.5)
				(island_removal_mode 0)
			)
			(polygon
				(pts
					(arc
						(start 241.980974 -48.999902)
						(mid 241.218974 -48.999902)
						(end 241.980974 -48.999902)
					)
				)
			)
		)
		(zone
			(layer "F.Cu")
			(hatch none 0.5)
			(connect_pads
				(clearance 0)
			)
			(min_thickness 0.25)
			(keepout
				(tracks allowed)
				(vias not_allowed)
				(pads allowed)
				(copperpour not_allowed)
				(footprints allowed)
			)
			(placement
				(enabled no)
				(sheetname "")
			)
			(fill
				(thermal_gap 0.5)
				(thermal_bridge_width 0.5)
				(island_removal_mode 0)
			)
			(polygon
				(pts
					(arc
						(start 241.980974 -47.999904)
						(mid 241.218974 -47.999904)
						(end 241.980974 -47.999904)
					)
				)
			)
		)
		(zone
			(layer "F.Cu")
			(hatch none 0.5)
			(connect_pads
				(clearance 0)
			)
			(min_thickness 0.25)
			(keepout
				(tracks allowed)
				(vias not_allowed)
				(pads allowed)
				(copperpour not_allowed)
				(footprints allowed)
			)
			(placement
				(enabled no)
				(sheetname "")
			)
			(fill
				(thermal_gap 0.5)
				(thermal_bridge_width 0.5)
				(island_removal_mode 0)
			)
			(polygon
				(pts
					(arc
						(start 241.980974 -46.999906)
						(mid 241.218974 -46.999906)
						(end 241.980974 -46.999906)
					)
				)
			)
		)
		(zone
			(layer "F.Cu")
			(hatch none 0.5)
			(connect_pads
				(clearance 0)
			)
			(min_thickness 0.25)
			(keepout
				(tracks allowed)
				(vias not_allowed)
				(pads allowed)
				(copperpour not_allowed)
				(footprints allowed)
			)
			(placement
				(enabled no)
				(sheetname "")
			)
			(fill
				(thermal_gap 0.5)
				(thermal_bridge_width 0.5)
				(island_removal_mode 0)
			)
			(polygon
				(pts
					(arc
						(start 241.980974 -45.999908)
						(mid 241.218974 -45.999908)
						(end 241.980974 -45.999908)
					)
				)
			)
		)
		(zone
			(layer "F.Cu")
			(hatch none 0.5)
			(connect_pads
				(clearance 0)
			)
			(min_thickness 0.25)
			(keepout
				(tracks allowed)
				(vias not_allowed)
				(pads allowed)
				(copperpour not_allowed)
				(footprints allowed)
			)
			(placement
				(enabled no)
				(sheetname "")
			)
			(fill
				(thermal_gap 0.5)
				(thermal_bridge_width 0.5)
				(island_removal_mode 0)
			)
			(polygon
				(pts
					(arc
						(start 241.980974 -44.99991)
						(mid 241.218974 -44.99991)
						(end 241.980974 -44.99991)
					)
				)
			)
		)
		(zone
			(layer "F.Cu")
			(hatch none 0.5)
			(connect_pads
				(clearance 0)
			)
			(min_thickness 0.25)
			(keepout
				(tracks allowed)
				(vias not_allowed)
				(pads allowed)
				(copperpour not_allowed)
				(footprints allowed)
			)
			(placement
				(enabled no)
				(sheetname "")
			)
			(fill
				(thermal_gap 0.5)
				(thermal_bridge_width 0.5)
				(island_removal_mode 0)
			)
			(polygon
				(pts
					(arc
						(start 241.980974 -43.999912)
						(mid 241.218974 -43.999912)
						(end 241.980974 -43.999912)
					)
				)
			)
		)
		(zone
			(layer "F.Cu")
			(hatch none 0.5)
			(connect_pads
				(clearance 0)
			)
			(min_thickness 0.25)
			(keepout
				(tracks allowed)
				(vias not_allowed)
				(pads allowed)
				(copperpour not_allowed)
				(footprints allowed)
			)
			(placement
				(enabled no)
				(sheetname "")
			)
			(fill
				(thermal_gap 0.5)
				(thermal_bridge_width 0.5)
				(island_removal_mode 0)
			)
			(polygon
				(pts
					(arc
						(start 241.980974 -42.999914)
						(mid 241.218974 -42.999914)
						(end 241.980974 -42.999914)
					)
				)
			)
		)
		(zone
			(layer "F.Cu")
			(hatch none 0.5)
			(connect_pads
				(clearance 0)
			)
			(min_thickness 0.25)
			(keepout
				(tracks allowed)
				(vias not_allowed)
				(pads allowed)
				(copperpour not_allowed)
				(footprints allowed)
			)
			(placement
				(enabled no)
				(sheetname "")
			)
			(fill
				(thermal_gap 0.5)
				(thermal_bridge_width 0.5)
				(island_removal_mode 0)
			)
			(polygon
				(pts
					(arc
						(start 241.980974 -41.999916)
						(mid 241.218974 -41.999916)
						(end 241.980974 -41.999916)
					)
				)
			)
		)
		(zone
			(layer "F.Cu")
			(hatch none 0.5)
			(connect_pads
				(clearance 0)
			)
			(min_thickness 0.25)
			(keepout
				(tracks allowed)
				(vias not_allowed)
				(pads allowed)
				(copperpour not_allowed)
				(footprints allowed)
			)
			(placement
				(enabled no)
				(sheetname "")
			)
			(fill
				(thermal_gap 0.5)
				(thermal_bridge_width 0.5)
				(island_removal_mode 0)
			)
			(polygon
				(pts
					(arc
						(start 241.980974 -40.999918)
						(mid 241.218974 -40.999918)
						(end 241.980974 -40.999918)
					)
				)
			)
		)
		(zone
			(layer "F.Cu")
			(hatch none 0.5)
			(connect_pads
				(clearance 0)
			)
			(min_thickness 0.25)
			(keepout
				(tracks allowed)
				(vias not_allowed)
				(pads allowed)
				(copperpour not_allowed)
				(footprints allowed)
			)
			(placement
				(enabled no)
				(sheetname "")
			)
			(fill
				(thermal_gap 0.5)
				(thermal_bridge_width 0.5)
				(island_removal_mode 0)
			)
			(polygon
				(pts
					(arc
						(start 241.980974 -39.99992)
						(mid 241.218974 -39.99992)
						(end 241.980974 -39.99992)
					)
				)
			)
		)
		(zone
			(layer "F.Cu")
			(hatch none 0.5)
			(connect_pads
				(clearance 0)
			)
			(min_thickness 0.25)
			(keepout
				(tracks allowed)
				(vias not_allowed)
				(pads allowed)
				(copperpour not_allowed)
				(footprints allowed)
			)
			(placement
				(enabled no)
				(sheetname "")
			)
			(fill
				(thermal_gap 0.5)
				(thermal_bridge_width 0.5)
				(island_removal_mode 0)
			)
			(polygon
				(pts
					(arc
						(start 241.980974 -38.999922)
						(mid 241.218974 -38.999922)
						(end 241.980974 -38.999922)
					)
				)
			)
		)
		(zone
			(layer "F.Cu")
			(hatch none 0.5)
			(connect_pads
				(clearance 0)
			)
			(min_thickness 0.25)
			(keepout
				(tracks allowed)
				(vias not_allowed)
				(pads allowed)
				(copperpour not_allowed)
				(footprints allowed)
			)
			(placement
				(enabled no)
				(sheetname "")
			)
			(fill
				(thermal_gap 0.5)
				(thermal_bridge_width 0.5)
				(island_removal_mode 0)
			)
			(polygon
				(pts
					(arc
						(start 241.980974 -37.999924)
						(mid 241.218974 -37.999924)
						(end 241.980974 -37.999924)
					)
				)
			)
		)
		(zone
			(layer "F.Cu")
			(hatch none 0.5)
			(connect_pads
				(clearance 0)
			)
			(min_thickness 0.25)
			(keepout
				(tracks allowed)
				(vias not_allowed)
				(pads allowed)
				(copperpour not_allowed)
				(footprints allowed)
			)
			(placement
				(enabled no)
				(sheetname "")
			)
			(fill
				(thermal_gap 0.5)
				(thermal_bridge_width 0.5)
				(island_removal_mode 0)
			)
			(polygon
				(pts
					(arc
						(start 241.980974 -36.999926)
						(mid 241.218974 -36.999926)
						(end 241.980974 -36.999926)
					)
				)
			)
		)
		(zone
			(layer "F.Cu")
			(hatch none 0.5)
			(connect_pads
				(clearance 0)
			)
			(min_thickness 0.25)
			(keepout
				(tracks allowed)
				(vias not_allowed)
				(pads allowed)
				(copperpour not_allowed)
				(footprints allowed)
			)
			(placement
				(enabled no)
				(sheetname "")
			)
			(fill
				(thermal_gap 0.5)
				(thermal_bridge_width 0.5)
				(island_removal_mode 0)
			)
			(polygon
				(pts
					(arc
						(start 241.980974 -35.999928)
						(mid 241.218974 -35.999928)
						(end 241.980974 -35.999928)
					)
				)
			)
		)
		(zone
			(layer "F.Cu")
			(hatch none 0.5)
			(connect_pads
				(clearance 0)
			)
			(min_thickness 0.25)
			(keepout
				(tracks allowed)
				(vias not_allowed)
				(pads allowed)
				(copperpour not_allowed)
				(footprints allowed)
			)
			(placement
				(enabled no)
				(sheetname "")
			)
			(fill
				(thermal_gap 0.5)
				(thermal_bridge_width 0.5)
				(island_removal_mode 0)
			)
			(polygon
				(pts
					(arc
						(start 241.980974 -34.99993)
						(mid 241.218974 -34.99993)
						(end 241.980974 -34.99993)
					)
				)
			)
		)
		(zone
			(layer "F.Cu")
			(hatch none 0.5)
			(connect_pads
				(clearance 0)
			)
			(min_thickness 0.25)
			(keepout
				(tracks allowed)
				(vias not_allowed)
				(pads allowed)
				(copperpour not_allowed)
				(footprints allowed)
			)
			(placement
				(enabled no)
				(sheetname "")
			)
			(fill
				(thermal_gap 0.5)
				(thermal_bridge_width 0.5)
				(island_removal_mode 0)
			)
			(polygon
				(pts
					(arc
						(start 241.980974 -33.999932)
						(mid 241.218974 -33.999932)
						(end 241.980974 -33.999932)
					)
				)
			)
		)
		(zone
			(layer "F.Cu")
			(hatch none 0.5)
			(connect_pads
				(clearance 0)
			)
			(min_thickness 0.25)
			(keepout
				(tracks allowed)
				(vias not_allowed)
				(pads allowed)
				(copperpour not_allowed)
				(footprints allowed)
			)
			(placement
				(enabled no)
				(sheetname "")
			)
			(fill
				(thermal_gap 0.5)
				(thermal_bridge_width 0.5)
				(island_removal_mode 0)
			)
			(polygon
				(pts
					(arc
						(start 241.980974 -32.999934)
						(mid 241.218974 -32.999934)
						(end 241.980974 -32.999934)
					)
				)
			)
		)
		(zone
			(layer "F.Cu")
			(hatch none 0.5)
			(connect_pads
				(clearance 0)
			)
			(min_thickness 0.25)
			(keepout
				(tracks allowed)
				(vias not_allowed)
				(pads allowed)
				(copperpour not_allowed)
				(footprints allowed)
			)
			(placement
				(enabled no)
				(sheetname "")
			)
			(fill
				(thermal_gap 0.5)
				(thermal_bridge_width 0.5)
				(island_removal_mode 0)
			)
			(polygon
				(pts
					(arc
						(start 241.980974 -31.999936)
						(mid 241.218974 -31.999936)
						(end 241.980974 -31.999936)
					)
				)
			)
		)
		(zone
			(layer "F.Cu")
			(hatch none 0.5)
			(connect_pads
				(clearance 0)
			)
			(min_thickness 0.25)
			(keepout
				(tracks allowed)
				(vias not_allowed)
				(pads allowed)
				(copperpour not_allowed)
				(footprints allowed)
			)
			(placement
				(enabled no)
				(sheetname "")
			)
			(fill
				(thermal_gap 0.5)
				(thermal_bridge_width 0.5)
				(island_removal_mode 0)
			)
			(polygon
				(pts
					(arc
						(start 241.980974 -30.999938)
						(mid 241.218974 -30.999938)
						(end 241.980974 -30.999938)
					)
				)
			)
		)
		(zone
			(layer "F.Cu")
			(hatch none 0.5)
			(connect_pads
				(clearance 0)
			)
			(min_thickness 0.25)
			(keepout
				(tracks allowed)
				(vias not_allowed)
				(pads allowed)
				(copperpour not_allowed)
				(footprints allowed)
			)
			(placement
				(enabled no)
				(sheetname "")
			)
			(fill
				(thermal_gap 0.5)
				(thermal_bridge_width 0.5)
				(island_removal_mode 0)
			)
			(polygon
				(pts
					(arc
						(start 241.980974 -29.99994)
						(mid 241.218974 -29.99994)
						(end 241.980974 -29.99994)
					)
				)
			)
		)
		(zone
			(layer "F.Cu")
			(hatch none 0.5)
			(connect_pads
				(clearance 0)
			)
			(min_thickness 0.25)
			(keepout
				(tracks allowed)
				(vias not_allowed)
				(pads allowed)
				(copperpour not_allowed)
				(footprints allowed)
			)
			(placement
				(enabled no)
				(sheetname "")
			)
			(fill
				(thermal_gap 0.5)
				(thermal_bridge_width 0.5)
				(island_removal_mode 0)
			)
			(polygon
				(pts
					(arc
						(start 242.980972 -65.999868)
						(mid 242.218972 -65.999868)
						(end 242.980972 -65.999868)
					)
				)
			)
		)
		(zone
			(layer "F.Cu")
			(hatch none 0.5)
			(connect_pads
				(clearance 0)
			)
			(min_thickness 0.25)
			(keepout
				(tracks allowed)
				(vias not_allowed)
				(pads allowed)
				(copperpour not_allowed)
				(footprints allowed)
			)
			(placement
				(enabled no)
				(sheetname "")
			)
			(fill
				(thermal_gap 0.5)
				(thermal_bridge_width 0.5)
				(island_removal_mode 0)
			)
			(polygon
				(pts
					(arc
						(start 242.980972 -64.99987)
						(mid 242.218972 -64.99987)
						(end 242.980972 -64.99987)
					)
				)
			)
		)
		(zone
			(layer "F.Cu")
			(hatch none 0.5)
			(connect_pads
				(clearance 0)
			)
			(min_thickness 0.25)
			(keepout
				(tracks allowed)
				(vias not_allowed)
				(pads allowed)
				(copperpour not_allowed)
				(footprints allowed)
			)
			(placement
				(enabled no)
				(sheetname "")
			)
			(fill
				(thermal_gap 0.5)
				(thermal_bridge_width 0.5)
				(island_removal_mode 0)
			)
			(polygon
				(pts
					(arc
						(start 242.980972 -63.999872)
						(mid 242.218972 -63.999872)
						(end 242.980972 -63.999872)
					)
				)
			)
		)
		(zone
			(layer "F.Cu")
			(hatch none 0.5)
			(connect_pads
				(clearance 0)
			)
			(min_thickness 0.25)
			(keepout
				(tracks allowed)
				(vias not_allowed)
				(pads allowed)
				(copperpour not_allowed)
				(footprints allowed)
			)
			(placement
				(enabled no)
				(sheetname "")
			)
			(fill
				(thermal_gap 0.5)
				(thermal_bridge_width 0.5)
				(island_removal_mode 0)
			)
			(polygon
				(pts
					(arc
						(start 242.980972 -62.999874)
						(mid 242.218972 -62.999874)
						(end 242.980972 -62.999874)
					)
				)
			)
		)
		(zone
			(layer "F.Cu")
			(hatch none 0.5)
			(connect_pads
				(clearance 0)
			)
			(min_thickness 0.25)
			(keepout
				(tracks allowed)
				(vias not_allowed)
				(pads allowed)
				(copperpour not_allowed)
				(footprints allowed)
			)
			(placement
				(enabled no)
				(sheetname "")
			)
			(fill
				(thermal_gap 0.5)
				(thermal_bridge_width 0.5)
				(island_removal_mode 0)
			)
			(polygon
				(pts
					(arc
						(start 242.980972 -61.999876)
						(mid 242.218972 -61.999876)
						(end 242.980972 -61.999876)
					)
				)
			)
		)
		(zone
			(layer "F.Cu")
			(hatch none 0.5)
			(connect_pads
				(clearance 0)
			)
			(min_thickness 0.25)
			(keepout
				(tracks allowed)
				(vias not_allowed)
				(pads allowed)
				(copperpour not_allowed)
				(footprints allowed)
			)
			(placement
				(enabled no)
				(sheetname "")
			)
			(fill
				(thermal_gap 0.5)
				(thermal_bridge_width 0.5)
				(island_removal_mode 0)
			)
			(polygon
				(pts
					(arc
						(start 242.980972 -60.999878)
						(mid 242.218972 -60.999878)
						(end 242.980972 -60.999878)
					)
				)
			)
		)
		(zone
			(layer "F.Cu")
			(hatch none 0.5)
			(connect_pads
				(clearance 0)
			)
			(min_thickness 0.25)
			(keepout
				(tracks allowed)
				(vias not_allowed)
				(pads allowed)
				(copperpour not_allowed)
				(footprints allowed)
			)
			(placement
				(enabled no)
				(sheetname "")
			)
			(fill
				(thermal_gap 0.5)
				(thermal_bridge_width 0.5)
				(island_removal_mode 0)
			)
			(polygon
				(pts
					(arc
						(start 242.980972 -59.99988)
						(mid 242.218972 -59.99988)
						(end 242.980972 -59.99988)
					)
				)
			)
		)
		(zone
			(layer "F.Cu")
			(hatch none 0.5)
			(connect_pads
				(clearance 0)
			)
			(min_thickness 0.25)
			(keepout
				(tracks allowed)
				(vias not_allowed)
				(pads allowed)
				(copperpour not_allowed)
				(footprints allowed)
			)
			(placement
				(enabled no)
				(sheetname "")
			)
			(fill
				(thermal_gap 0.5)
				(thermal_bridge_width 0.5)
				(island_removal_mode 0)
			)
			(polygon
				(pts
					(arc
						(start 242.980972 -58.999882)
						(mid 242.218972 -58.999882)
						(end 242.980972 -58.999882)
					)
				)
			)
		)
		(zone
			(layer "F.Cu")
			(hatch none 0.5)
			(connect_pads
				(clearance 0)
			)
			(min_thickness 0.25)
			(keepout
				(tracks allowed)
				(vias not_allowed)
				(pads allowed)
				(copperpour not_allowed)
				(footprints allowed)
			)
			(placement
				(enabled no)
				(sheetname "")
			)
			(fill
				(thermal_gap 0.5)
				(thermal_bridge_width 0.5)
				(island_removal_mode 0)
			)
			(polygon
				(pts
					(arc
						(start 242.980972 -57.999884)
						(mid 242.218972 -57.999884)
						(end 242.980972 -57.999884)
					)
				)
			)
		)
		(zone
			(layer "F.Cu")
			(hatch none 0.5)
			(connect_pads
				(clearance 0)
			)
			(min_thickness 0.25)
			(keepout
				(tracks allowed)
				(vias not_allowed)
				(pads allowed)
				(copperpour not_allowed)
				(footprints allowed)
			)
			(placement
				(enabled no)
				(sheetname "")
			)
			(fill
				(thermal_gap 0.5)
				(thermal_bridge_width 0.5)
				(island_removal_mode 0)
			)
			(polygon
				(pts
					(arc
						(start 242.980972 -56.999886)
						(mid 242.218972 -56.999886)
						(end 242.980972 -56.999886)
					)
				)
			)
		)
		(zone
			(layer "F.Cu")
			(hatch none 0.5)
			(connect_pads
				(clearance 0)
			)
			(min_thickness 0.25)
			(keepout
				(tracks allowed)
				(vias not_allowed)
				(pads allowed)
				(copperpour not_allowed)
				(footprints allowed)
			)
			(placement
				(enabled no)
				(sheetname "")
			)
			(fill
				(thermal_gap 0.5)
				(thermal_bridge_width 0.5)
				(island_removal_mode 0)
			)
			(polygon
				(pts
					(arc
						(start 242.980972 -55.999888)
						(mid 242.218972 -55.999888)
						(end 242.980972 -55.999888)
					)
				)
			)
		)
		(zone
			(layer "F.Cu")
			(hatch none 0.5)
			(connect_pads
				(clearance 0)
			)
			(min_thickness 0.25)
			(keepout
				(tracks allowed)
				(vias not_allowed)
				(pads allowed)
				(copperpour not_allowed)
				(footprints allowed)
			)
			(placement
				(enabled no)
				(sheetname "")
			)
			(fill
				(thermal_gap 0.5)
				(thermal_bridge_width 0.5)
				(island_removal_mode 0)
			)
			(polygon
				(pts
					(arc
						(start 242.980972 -54.99989)
						(mid 242.218972 -54.99989)
						(end 242.980972 -54.99989)
					)
				)
			)
		)
		(zone
			(layer "F.Cu")
			(hatch none 0.5)
			(connect_pads
				(clearance 0)
			)
			(min_thickness 0.25)
			(keepout
				(tracks allowed)
				(vias not_allowed)
				(pads allowed)
				(copperpour not_allowed)
				(footprints allowed)
			)
			(placement
				(enabled no)
				(sheetname "")
			)
			(fill
				(thermal_gap 0.5)
				(thermal_bridge_width 0.5)
				(island_removal_mode 0)
			)
			(polygon
				(pts
					(arc
						(start 242.980972 -53.999892)
						(mid 242.218972 -53.999892)
						(end 242.980972 -53.999892)
					)
				)
			)
		)
		(zone
			(layer "F.Cu")
			(hatch none 0.5)
			(connect_pads
				(clearance 0)
			)
			(min_thickness 0.25)
			(keepout
				(tracks allowed)
				(vias not_allowed)
				(pads allowed)
				(copperpour not_allowed)
				(footprints allowed)
			)
			(placement
				(enabled no)
				(sheetname "")
			)
			(fill
				(thermal_gap 0.5)
				(thermal_bridge_width 0.5)
				(island_removal_mode 0)
			)
			(polygon
				(pts
					(arc
						(start 242.980972 -52.999894)
						(mid 242.218972 -52.999894)
						(end 242.980972 -52.999894)
					)
				)
			)
		)
		(zone
			(layer "F.Cu")
			(hatch none 0.5)
			(connect_pads
				(clearance 0)
			)
			(min_thickness 0.25)
			(keepout
				(tracks allowed)
				(vias not_allowed)
				(pads allowed)
				(copperpour not_allowed)
				(footprints allowed)
			)
			(placement
				(enabled no)
				(sheetname "")
			)
			(fill
				(thermal_gap 0.5)
				(thermal_bridge_width 0.5)
				(island_removal_mode 0)
			)
			(polygon
				(pts
					(arc
						(start 242.980972 -51.999896)
						(mid 242.218972 -51.999896)
						(end 242.980972 -51.999896)
					)
				)
			)
		)
		(zone
			(layer "F.Cu")
			(hatch none 0.5)
			(connect_pads
				(clearance 0)
			)
			(min_thickness 0.25)
			(keepout
				(tracks allowed)
				(vias not_allowed)
				(pads allowed)
				(copperpour not_allowed)
				(footprints allowed)
			)
			(placement
				(enabled no)
				(sheetname "")
			)
			(fill
				(thermal_gap 0.5)
				(thermal_bridge_width 0.5)
				(island_removal_mode 0)
			)
			(polygon
				(pts
					(arc
						(start 242.980972 -50.999898)
						(mid 242.218972 -50.999898)
						(end 242.980972 -50.999898)
					)
				)
			)
		)
		(zone
			(layer "F.Cu")
			(hatch none 0.5)
			(connect_pads
				(clearance 0)
			)
			(min_thickness 0.25)
			(keepout
				(tracks allowed)
				(vias not_allowed)
				(pads allowed)
				(copperpour not_allowed)
				(footprints allowed)
			)
			(placement
				(enabled no)
				(sheetname "")
			)
			(fill
				(thermal_gap 0.5)
				(thermal_bridge_width 0.5)
				(island_removal_mode 0)
			)
			(polygon
				(pts
					(arc
						(start 242.980972 -49.9999)
						(mid 242.218972 -49.9999)
						(end 242.980972 -49.9999)
					)
				)
			)
		)
		(zone
			(layer "F.Cu")
			(hatch none 0.5)
			(connect_pads
				(clearance 0)
			)
			(min_thickness 0.25)
			(keepout
				(tracks allowed)
				(vias not_allowed)
				(pads allowed)
				(copperpour not_allowed)
				(footprints allowed)
			)
			(placement
				(enabled no)
				(sheetname "")
			)
			(fill
				(thermal_gap 0.5)
				(thermal_bridge_width 0.5)
				(island_removal_mode 0)
			)
			(polygon
				(pts
					(arc
						(start 242.980972 -48.999902)
						(mid 242.218972 -48.999902)
						(end 242.980972 -48.999902)
					)
				)
			)
		)
		(zone
			(layer "F.Cu")
			(hatch none 0.5)
			(connect_pads
				(clearance 0)
			)
			(min_thickness 0.25)
			(keepout
				(tracks allowed)
				(vias not_allowed)
				(pads allowed)
				(copperpour not_allowed)
				(footprints allowed)
			)
			(placement
				(enabled no)
				(sheetname "")
			)
			(fill
				(thermal_gap 0.5)
				(thermal_bridge_width 0.5)
				(island_removal_mode 0)
			)
			(polygon
				(pts
					(arc
						(start 242.980972 -47.999904)
						(mid 242.218972 -47.999904)
						(end 242.980972 -47.999904)
					)
				)
			)
		)
		(zone
			(layer "F.Cu")
			(hatch none 0.5)
			(connect_pads
				(clearance 0)
			)
			(min_thickness 0.25)
			(keepout
				(tracks allowed)
				(vias not_allowed)
				(pads allowed)
				(copperpour not_allowed)
				(footprints allowed)
			)
			(placement
				(enabled no)
				(sheetname "")
			)
			(fill
				(thermal_gap 0.5)
				(thermal_bridge_width 0.5)
				(island_removal_mode 0)
			)
			(polygon
				(pts
					(arc
						(start 242.980972 -46.999906)
						(mid 242.218972 -46.999906)
						(end 242.980972 -46.999906)
					)
				)
			)
		)
		(zone
			(layer "F.Cu")
			(hatch none 0.5)
			(connect_pads
				(clearance 0)
			)
			(min_thickness 0.25)
			(keepout
				(tracks allowed)
				(vias not_allowed)
				(pads allowed)
				(copperpour not_allowed)
				(footprints allowed)
			)
			(placement
				(enabled no)
				(sheetname "")
			)
			(fill
				(thermal_gap 0.5)
				(thermal_bridge_width 0.5)
				(island_removal_mode 0)
			)
			(polygon
				(pts
					(arc
						(start 242.980972 -45.999908)
						(mid 242.218972 -45.999908)
						(end 242.980972 -45.999908)
					)
				)
			)
		)
		(zone
			(layer "F.Cu")
			(hatch none 0.5)
			(connect_pads
				(clearance 0)
			)
			(min_thickness 0.25)
			(keepout
				(tracks allowed)
				(vias not_allowed)
				(pads allowed)
				(copperpour not_allowed)
				(footprints allowed)
			)
			(placement
				(enabled no)
				(sheetname "")
			)
			(fill
				(thermal_gap 0.5)
				(thermal_bridge_width 0.5)
				(island_removal_mode 0)
			)
			(polygon
				(pts
					(arc
						(start 242.980972 -44.99991)
						(mid 242.218972 -44.99991)
						(end 242.980972 -44.99991)
					)
				)
			)
		)
		(zone
			(layer "F.Cu")
			(hatch none 0.5)
			(connect_pads
				(clearance 0)
			)
			(min_thickness 0.25)
			(keepout
				(tracks allowed)
				(vias not_allowed)
				(pads allowed)
				(copperpour not_allowed)
				(footprints allowed)
			)
			(placement
				(enabled no)
				(sheetname "")
			)
			(fill
				(thermal_gap 0.5)
				(thermal_bridge_width 0.5)
				(island_removal_mode 0)
			)
			(polygon
				(pts
					(arc
						(start 242.980972 -43.999912)
						(mid 242.218972 -43.999912)
						(end 242.980972 -43.999912)
					)
				)
			)
		)
		(zone
			(layer "F.Cu")
			(hatch none 0.5)
			(connect_pads
				(clearance 0)
			)
			(min_thickness 0.25)
			(keepout
				(tracks allowed)
				(vias not_allowed)
				(pads allowed)
				(copperpour not_allowed)
				(footprints allowed)
			)
			(placement
				(enabled no)
				(sheetname "")
			)
			(fill
				(thermal_gap 0.5)
				(thermal_bridge_width 0.5)
				(island_removal_mode 0)
			)
			(polygon
				(pts
					(arc
						(start 242.980972 -42.999914)
						(mid 242.218972 -42.999914)
						(end 242.980972 -42.999914)
					)
				)
			)
		)
		(zone
			(layer "F.Cu")
			(hatch none 0.5)
			(connect_pads
				(clearance 0)
			)
			(min_thickness 0.25)
			(keepout
				(tracks allowed)
				(vias not_allowed)
				(pads allowed)
				(copperpour not_allowed)
				(footprints allowed)
			)
			(placement
				(enabled no)
				(sheetname "")
			)
			(fill
				(thermal_gap 0.5)
				(thermal_bridge_width 0.5)
				(island_removal_mode 0)
			)
			(polygon
				(pts
					(arc
						(start 242.980972 -41.999916)
						(mid 242.218972 -41.999916)
						(end 242.980972 -41.999916)
					)
				)
			)
		)
		(zone
			(layer "F.Cu")
			(hatch none 0.5)
			(connect_pads
				(clearance 0)
			)
			(min_thickness 0.25)
			(keepout
				(tracks allowed)
				(vias not_allowed)
				(pads allowed)
				(copperpour not_allowed)
				(footprints allowed)
			)
			(placement
				(enabled no)
				(sheetname "")
			)
			(fill
				(thermal_gap 0.5)
				(thermal_bridge_width 0.5)
				(island_removal_mode 0)
			)
			(polygon
				(pts
					(arc
						(start 242.980972 -40.999918)
						(mid 242.218972 -40.999918)
						(end 242.980972 -40.999918)
					)
				)
			)
		)
		(zone
			(layer "F.Cu")
			(hatch none 0.5)
			(connect_pads
				(clearance 0)
			)
			(min_thickness 0.25)
			(keepout
				(tracks allowed)
				(vias not_allowed)
				(pads allowed)
				(copperpour not_allowed)
				(footprints allowed)
			)
			(placement
				(enabled no)
				(sheetname "")
			)
			(fill
				(thermal_gap 0.5)
				(thermal_bridge_width 0.5)
				(island_removal_mode 0)
			)
			(polygon
				(pts
					(arc
						(start 242.980972 -39.99992)
						(mid 242.218972 -39.99992)
						(end 242.980972 -39.99992)
					)
				)
			)
		)
		(zone
			(layer "F.Cu")
			(hatch none 0.5)
			(connect_pads
				(clearance 0)
			)
			(min_thickness 0.25)
			(keepout
				(tracks allowed)
				(vias not_allowed)
				(pads allowed)
				(copperpour not_allowed)
				(footprints allowed)
			)
			(placement
				(enabled no)
				(sheetname "")
			)
			(fill
				(thermal_gap 0.5)
				(thermal_bridge_width 0.5)
				(island_removal_mode 0)
			)
			(polygon
				(pts
					(arc
						(start 242.980972 -38.999922)
						(mid 242.218972 -38.999922)
						(end 242.980972 -38.999922)
					)
				)
			)
		)
		(zone
			(layer "F.Cu")
			(hatch none 0.5)
			(connect_pads
				(clearance 0)
			)
			(min_thickness 0.25)
			(keepout
				(tracks allowed)
				(vias not_allowed)
				(pads allowed)
				(copperpour not_allowed)
				(footprints allowed)
			)
			(placement
				(enabled no)
				(sheetname "")
			)
			(fill
				(thermal_gap 0.5)
				(thermal_bridge_width 0.5)
				(island_removal_mode 0)
			)
			(polygon
				(pts
					(arc
						(start 242.980972 -37.999924)
						(mid 242.218972 -37.999924)
						(end 242.980972 -37.999924)
					)
				)
			)
		)
		(zone
			(layer "F.Cu")
			(hatch none 0.5)
			(connect_pads
				(clearance 0)
			)
			(min_thickness 0.25)
			(keepout
				(tracks allowed)
				(vias not_allowed)
				(pads allowed)
				(copperpour not_allowed)
				(footprints allowed)
			)
			(placement
				(enabled no)
				(sheetname "")
			)
			(fill
				(thermal_gap 0.5)
				(thermal_bridge_width 0.5)
				(island_removal_mode 0)
			)
			(polygon
				(pts
					(arc
						(start 242.980972 -36.999926)
						(mid 242.218972 -36.999926)
						(end 242.980972 -36.999926)
					)
				)
			)
		)
		(zone
			(layer "F.Cu")
			(hatch none 0.5)
			(connect_pads
				(clearance 0)
			)
			(min_thickness 0.25)
			(keepout
				(tracks allowed)
				(vias not_allowed)
				(pads allowed)
				(copperpour not_allowed)
				(footprints allowed)
			)
			(placement
				(enabled no)
				(sheetname "")
			)
			(fill
				(thermal_gap 0.5)
				(thermal_bridge_width 0.5)
				(island_removal_mode 0)
			)
			(polygon
				(pts
					(arc
						(start 242.980972 -35.999928)
						(mid 242.218972 -35.999928)
						(end 242.980972 -35.999928)
					)
				)
			)
		)
		(zone
			(layer "F.Cu")
			(hatch none 0.5)
			(connect_pads
				(clearance 0)
			)
			(min_thickness 0.25)
			(keepout
				(tracks allowed)
				(vias not_allowed)
				(pads allowed)
				(copperpour not_allowed)
				(footprints allowed)
			)
			(placement
				(enabled no)
				(sheetname "")
			)
			(fill
				(thermal_gap 0.5)
				(thermal_bridge_width 0.5)
				(island_removal_mode 0)
			)
			(polygon
				(pts
					(arc
						(start 242.980972 -34.99993)
						(mid 242.218972 -34.99993)
						(end 242.980972 -34.99993)
					)
				)
			)
		)
		(zone
			(layer "F.Cu")
			(hatch none 0.5)
			(connect_pads
				(clearance 0)
			)
			(min_thickness 0.25)
			(keepout
				(tracks allowed)
				(vias not_allowed)
				(pads allowed)
				(copperpour not_allowed)
				(footprints allowed)
			)
			(placement
				(enabled no)
				(sheetname "")
			)
			(fill
				(thermal_gap 0.5)
				(thermal_bridge_width 0.5)
				(island_removal_mode 0)
			)
			(polygon
				(pts
					(arc
						(start 242.980972 -33.999932)
						(mid 242.218972 -33.999932)
						(end 242.980972 -33.999932)
					)
				)
			)
		)
		(zone
			(layer "F.Cu")
			(hatch none 0.5)
			(connect_pads
				(clearance 0)
			)
			(min_thickness 0.25)
			(keepout
				(tracks allowed)
				(vias not_allowed)
				(pads allowed)
				(copperpour not_allowed)
				(footprints allowed)
			)
			(placement
				(enabled no)
				(sheetname "")
			)
			(fill
				(thermal_gap 0.5)
				(thermal_bridge_width 0.5)
				(island_removal_mode 0)
			)
			(polygon
				(pts
					(arc
						(start 242.980972 -32.999934)
						(mid 242.218972 -32.999934)
						(end 242.980972 -32.999934)
					)
				)
			)
		)
		(zone
			(layer "F.Cu")
			(hatch none 0.5)
			(connect_pads
				(clearance 0)
			)
			(min_thickness 0.25)
			(keepout
				(tracks allowed)
				(vias not_allowed)
				(pads allowed)
				(copperpour not_allowed)
				(footprints allowed)
			)
			(placement
				(enabled no)
				(sheetname "")
			)
			(fill
				(thermal_gap 0.5)
				(thermal_bridge_width 0.5)
				(island_removal_mode 0)
			)
			(polygon
				(pts
					(arc
						(start 242.980972 -31.999936)
						(mid 242.218972 -31.999936)
						(end 242.980972 -31.999936)
					)
				)
			)
		)
		(zone
			(layer "F.Cu")
			(hatch none 0.5)
			(connect_pads
				(clearance 0)
			)
			(min_thickness 0.25)
			(keepout
				(tracks allowed)
				(vias not_allowed)
				(pads allowed)
				(copperpour not_allowed)
				(footprints allowed)
			)
			(placement
				(enabled no)
				(sheetname "")
			)
			(fill
				(thermal_gap 0.5)
				(thermal_bridge_width 0.5)
				(island_removal_mode 0)
			)
			(polygon
				(pts
					(arc
						(start 242.980972 -30.999938)
						(mid 242.218972 -30.999938)
						(end 242.980972 -30.999938)
					)
				)
			)
		)
		(zone
			(layer "F.Cu")
			(hatch none 0.5)
			(connect_pads
				(clearance 0)
			)
			(min_thickness 0.25)
			(keepout
				(tracks allowed)
				(vias not_allowed)
				(pads allowed)
				(copperpour not_allowed)
				(footprints allowed)
			)
			(placement
				(enabled no)
				(sheetname "")
			)
			(fill
				(thermal_gap 0.5)
				(thermal_bridge_width 0.5)
				(island_removal_mode 0)
			)
			(polygon
				(pts
					(arc
						(start 242.980972 -29.99994)
						(mid 242.218972 -29.99994)
						(end 242.980972 -29.99994)
					)
				)
			)
		)
		(zone
			(layer "F.Cu")
			(hatch none 0.5)
			(connect_pads
				(clearance 0)
			)
			(min_thickness 0.25)
			(keepout
				(tracks allowed)
				(vias not_allowed)
				(pads allowed)
				(copperpour not_allowed)
				(footprints allowed)
			)
			(placement
				(enabled no)
				(sheetname "")
			)
			(fill
				(thermal_gap 0.5)
				(thermal_bridge_width 0.5)
				(island_removal_mode 0)
			)
			(polygon
				(pts
					(arc
						(start 243.98097 -64.99987)
						(mid 243.21897 -64.99987)
						(end 243.98097 -64.99987)
					)
				)
			)
		)
		(zone
			(layer "F.Cu")
			(hatch none 0.5)
			(connect_pads
				(clearance 0)
			)
			(min_thickness 0.25)
			(keepout
				(tracks allowed)
				(vias not_allowed)
				(pads allowed)
				(copperpour not_allowed)
				(footprints allowed)
			)
			(placement
				(enabled no)
				(sheetname "")
			)
			(fill
				(thermal_gap 0.5)
				(thermal_bridge_width 0.5)
				(island_removal_mode 0)
			)
			(polygon
				(pts
					(arc
						(start 243.98097 -63.999872)
						(mid 243.21897 -63.999872)
						(end 243.98097 -63.999872)
					)
				)
			)
		)
		(zone
			(layer "F.Cu")
			(hatch none 0.5)
			(connect_pads
				(clearance 0)
			)
			(min_thickness 0.25)
			(keepout
				(tracks allowed)
				(vias not_allowed)
				(pads allowed)
				(copperpour not_allowed)
				(footprints allowed)
			)
			(placement
				(enabled no)
				(sheetname "")
			)
			(fill
				(thermal_gap 0.5)
				(thermal_bridge_width 0.5)
				(island_removal_mode 0)
			)
			(polygon
				(pts
					(arc
						(start 243.98097 -62.999874)
						(mid 243.21897 -62.999874)
						(end 243.98097 -62.999874)
					)
				)
			)
		)
		(zone
			(layer "F.Cu")
			(hatch none 0.5)
			(connect_pads
				(clearance 0)
			)
			(min_thickness 0.25)
			(keepout
				(tracks allowed)
				(vias not_allowed)
				(pads allowed)
				(copperpour not_allowed)
				(footprints allowed)
			)
			(placement
				(enabled no)
				(sheetname "")
			)
			(fill
				(thermal_gap 0.5)
				(thermal_bridge_width 0.5)
				(island_removal_mode 0)
			)
			(polygon
				(pts
					(arc
						(start 243.98097 -61.999876)
						(mid 243.21897 -61.999876)
						(end 243.98097 -61.999876)
					)
				)
			)
		)
		(zone
			(layer "F.Cu")
			(hatch none 0.5)
			(connect_pads
				(clearance 0)
			)
			(min_thickness 0.25)
			(keepout
				(tracks allowed)
				(vias not_allowed)
				(pads allowed)
				(copperpour not_allowed)
				(footprints allowed)
			)
			(placement
				(enabled no)
				(sheetname "")
			)
			(fill
				(thermal_gap 0.5)
				(thermal_bridge_width 0.5)
				(island_removal_mode 0)
			)
			(polygon
				(pts
					(arc
						(start 243.98097 -60.999878)
						(mid 243.21897 -60.999878)
						(end 243.98097 -60.999878)
					)
				)
			)
		)
		(zone
			(layer "F.Cu")
			(hatch none 0.5)
			(connect_pads
				(clearance 0)
			)
			(min_thickness 0.25)
			(keepout
				(tracks allowed)
				(vias not_allowed)
				(pads allowed)
				(copperpour not_allowed)
				(footprints allowed)
			)
			(placement
				(enabled no)
				(sheetname "")
			)
			(fill
				(thermal_gap 0.5)
				(thermal_bridge_width 0.5)
				(island_removal_mode 0)
			)
			(polygon
				(pts
					(arc
						(start 243.98097 -59.99988)
						(mid 243.21897 -59.99988)
						(end 243.98097 -59.99988)
					)
				)
			)
		)
		(zone
			(layer "F.Cu")
			(hatch none 0.5)
			(connect_pads
				(clearance 0)
			)
			(min_thickness 0.25)
			(keepout
				(tracks allowed)
				(vias not_allowed)
				(pads allowed)
				(copperpour not_allowed)
				(footprints allowed)
			)
			(placement
				(enabled no)
				(sheetname "")
			)
			(fill
				(thermal_gap 0.5)
				(thermal_bridge_width 0.5)
				(island_removal_mode 0)
			)
			(polygon
				(pts
					(arc
						(start 243.98097 -58.999882)
						(mid 243.21897 -58.999882)
						(end 243.98097 -58.999882)
					)
				)
			)
		)
		(zone
			(layer "F.Cu")
			(hatch none 0.5)
			(connect_pads
				(clearance 0)
			)
			(min_thickness 0.25)
			(keepout
				(tracks allowed)
				(vias not_allowed)
				(pads allowed)
				(copperpour not_allowed)
				(footprints allowed)
			)
			(placement
				(enabled no)
				(sheetname "")
			)
			(fill
				(thermal_gap 0.5)
				(thermal_bridge_width 0.5)
				(island_removal_mode 0)
			)
			(polygon
				(pts
					(arc
						(start 243.98097 -57.999884)
						(mid 243.21897 -57.999884)
						(end 243.98097 -57.999884)
					)
				)
			)
		)
		(zone
			(layer "F.Cu")
			(hatch none 0.5)
			(connect_pads
				(clearance 0)
			)
			(min_thickness 0.25)
			(keepout
				(tracks allowed)
				(vias not_allowed)
				(pads allowed)
				(copperpour not_allowed)
				(footprints allowed)
			)
			(placement
				(enabled no)
				(sheetname "")
			)
			(fill
				(thermal_gap 0.5)
				(thermal_bridge_width 0.5)
				(island_removal_mode 0)
			)
			(polygon
				(pts
					(arc
						(start 243.98097 -56.999886)
						(mid 243.21897 -56.999886)
						(end 243.98097 -56.999886)
					)
				)
			)
		)
		(zone
			(layer "F.Cu")
			(hatch none 0.5)
			(connect_pads
				(clearance 0)
			)
			(min_thickness 0.25)
			(keepout
				(tracks allowed)
				(vias not_allowed)
				(pads allowed)
				(copperpour not_allowed)
				(footprints allowed)
			)
			(placement
				(enabled no)
				(sheetname "")
			)
			(fill
				(thermal_gap 0.5)
				(thermal_bridge_width 0.5)
				(island_removal_mode 0)
			)
			(polygon
				(pts
					(arc
						(start 243.98097 -55.999888)
						(mid 243.21897 -55.999888)
						(end 243.98097 -55.999888)
					)
				)
			)
		)
		(zone
			(layer "F.Cu")
			(hatch none 0.5)
			(connect_pads
				(clearance 0)
			)
			(min_thickness 0.25)
			(keepout
				(tracks allowed)
				(vias not_allowed)
				(pads allowed)
				(copperpour not_allowed)
				(footprints allowed)
			)
			(placement
				(enabled no)
				(sheetname "")
			)
			(fill
				(thermal_gap 0.5)
				(thermal_bridge_width 0.5)
				(island_removal_mode 0)
			)
			(polygon
				(pts
					(arc
						(start 243.98097 -54.99989)
						(mid 243.21897 -54.99989)
						(end 243.98097 -54.99989)
					)
				)
			)
		)
		(zone
			(layer "F.Cu")
			(hatch none 0.5)
			(connect_pads
				(clearance 0)
			)
			(min_thickness 0.25)
			(keepout
				(tracks allowed)
				(vias not_allowed)
				(pads allowed)
				(copperpour not_allowed)
				(footprints allowed)
			)
			(placement
				(enabled no)
				(sheetname "")
			)
			(fill
				(thermal_gap 0.5)
				(thermal_bridge_width 0.5)
				(island_removal_mode 0)
			)
			(polygon
				(pts
					(arc
						(start 243.98097 -53.999892)
						(mid 243.21897 -53.999892)
						(end 243.98097 -53.999892)
					)
				)
			)
		)
		(zone
			(layer "F.Cu")
			(hatch none 0.5)
			(connect_pads
				(clearance 0)
			)
			(min_thickness 0.25)
			(keepout
				(tracks allowed)
				(vias not_allowed)
				(pads allowed)
				(copperpour not_allowed)
				(footprints allowed)
			)
			(placement
				(enabled no)
				(sheetname "")
			)
			(fill
				(thermal_gap 0.5)
				(thermal_bridge_width 0.5)
				(island_removal_mode 0)
			)
			(polygon
				(pts
					(arc
						(start 243.98097 -52.999894)
						(mid 243.21897 -52.999894)
						(end 243.98097 -52.999894)
					)
				)
			)
		)
		(zone
			(layer "F.Cu")
			(hatch none 0.5)
			(connect_pads
				(clearance 0)
			)
			(min_thickness 0.25)
			(keepout
				(tracks allowed)
				(vias not_allowed)
				(pads allowed)
				(copperpour not_allowed)
				(footprints allowed)
			)
			(placement
				(enabled no)
				(sheetname "")
			)
			(fill
				(thermal_gap 0.5)
				(thermal_bridge_width 0.5)
				(island_removal_mode 0)
			)
			(polygon
				(pts
					(arc
						(start 243.98097 -51.999896)
						(mid 243.21897 -51.999896)
						(end 243.98097 -51.999896)
					)
				)
			)
		)
		(zone
			(layer "F.Cu")
			(hatch none 0.5)
			(connect_pads
				(clearance 0)
			)
			(min_thickness 0.25)
			(keepout
				(tracks allowed)
				(vias not_allowed)
				(pads allowed)
				(copperpour not_allowed)
				(footprints allowed)
			)
			(placement
				(enabled no)
				(sheetname "")
			)
			(fill
				(thermal_gap 0.5)
				(thermal_bridge_width 0.5)
				(island_removal_mode 0)
			)
			(polygon
				(pts
					(arc
						(start 243.98097 -50.999898)
						(mid 243.21897 -50.999898)
						(end 243.98097 -50.999898)
					)
				)
			)
		)
		(zone
			(layer "F.Cu")
			(hatch none 0.5)
			(connect_pads
				(clearance 0)
			)
			(min_thickness 0.25)
			(keepout
				(tracks allowed)
				(vias not_allowed)
				(pads allowed)
				(copperpour not_allowed)
				(footprints allowed)
			)
			(placement
				(enabled no)
				(sheetname "")
			)
			(fill
				(thermal_gap 0.5)
				(thermal_bridge_width 0.5)
				(island_removal_mode 0)
			)
			(polygon
				(pts
					(arc
						(start 243.98097 -49.9999)
						(mid 243.21897 -49.9999)
						(end 243.98097 -49.9999)
					)
				)
			)
		)
		(zone
			(layer "F.Cu")
			(hatch none 0.5)
			(connect_pads
				(clearance 0)
			)
			(min_thickness 0.25)
			(keepout
				(tracks allowed)
				(vias not_allowed)
				(pads allowed)
				(copperpour not_allowed)
				(footprints allowed)
			)
			(placement
				(enabled no)
				(sheetname "")
			)
			(fill
				(thermal_gap 0.5)
				(thermal_bridge_width 0.5)
				(island_removal_mode 0)
			)
			(polygon
				(pts
					(arc
						(start 243.98097 -48.999902)
						(mid 243.21897 -48.999902)
						(end 243.98097 -48.999902)
					)
				)
			)
		)
		(zone
			(layer "F.Cu")
			(hatch none 0.5)
			(connect_pads
				(clearance 0)
			)
			(min_thickness 0.25)
			(keepout
				(tracks allowed)
				(vias not_allowed)
				(pads allowed)
				(copperpour not_allowed)
				(footprints allowed)
			)
			(placement
				(enabled no)
				(sheetname "")
			)
			(fill
				(thermal_gap 0.5)
				(thermal_bridge_width 0.5)
				(island_removal_mode 0)
			)
			(polygon
				(pts
					(arc
						(start 243.98097 -47.999904)
						(mid 243.21897 -47.999904)
						(end 243.98097 -47.999904)
					)
				)
			)
		)
		(zone
			(layer "F.Cu")
			(hatch none 0.5)
			(connect_pads
				(clearance 0)
			)
			(min_thickness 0.25)
			(keepout
				(tracks allowed)
				(vias not_allowed)
				(pads allowed)
				(copperpour not_allowed)
				(footprints allowed)
			)
			(placement
				(enabled no)
				(sheetname "")
			)
			(fill
				(thermal_gap 0.5)
				(thermal_bridge_width 0.5)
				(island_removal_mode 0)
			)
			(polygon
				(pts
					(arc
						(start 243.98097 -46.999906)
						(mid 243.21897 -46.999906)
						(end 243.98097 -46.999906)
					)
				)
			)
		)
		(zone
			(layer "F.Cu")
			(hatch none 0.5)
			(connect_pads
				(clearance 0)
			)
			(min_thickness 0.25)
			(keepout
				(tracks allowed)
				(vias not_allowed)
				(pads allowed)
				(copperpour not_allowed)
				(footprints allowed)
			)
			(placement
				(enabled no)
				(sheetname "")
			)
			(fill
				(thermal_gap 0.5)
				(thermal_bridge_width 0.5)
				(island_removal_mode 0)
			)
			(polygon
				(pts
					(arc
						(start 243.98097 -45.999908)
						(mid 243.21897 -45.999908)
						(end 243.98097 -45.999908)
					)
				)
			)
		)
		(zone
			(layer "F.Cu")
			(hatch none 0.5)
			(connect_pads
				(clearance 0)
			)
			(min_thickness 0.25)
			(keepout
				(tracks allowed)
				(vias not_allowed)
				(pads allowed)
				(copperpour not_allowed)
				(footprints allowed)
			)
			(placement
				(enabled no)
				(sheetname "")
			)
			(fill
				(thermal_gap 0.5)
				(thermal_bridge_width 0.5)
				(island_removal_mode 0)
			)
			(polygon
				(pts
					(arc
						(start 243.98097 -44.99991)
						(mid 243.21897 -44.99991)
						(end 243.98097 -44.99991)
					)
				)
			)
		)
		(zone
			(layer "F.Cu")
			(hatch none 0.5)
			(connect_pads
				(clearance 0)
			)
			(min_thickness 0.25)
			(keepout
				(tracks allowed)
				(vias not_allowed)
				(pads allowed)
				(copperpour not_allowed)
				(footprints allowed)
			)
			(placement
				(enabled no)
				(sheetname "")
			)
			(fill
				(thermal_gap 0.5)
				(thermal_bridge_width 0.5)
				(island_removal_mode 0)
			)
			(polygon
				(pts
					(arc
						(start 243.98097 -43.999912)
						(mid 243.21897 -43.999912)
						(end 243.98097 -43.999912)
					)
				)
			)
		)
		(zone
			(layer "F.Cu")
			(hatch none 0.5)
			(connect_pads
				(clearance 0)
			)
			(min_thickness 0.25)
			(keepout
				(tracks allowed)
				(vias not_allowed)
				(pads allowed)
				(copperpour not_allowed)
				(footprints allowed)
			)
			(placement
				(enabled no)
				(sheetname "")
			)
			(fill
				(thermal_gap 0.5)
				(thermal_bridge_width 0.5)
				(island_removal_mode 0)
			)
			(polygon
				(pts
					(arc
						(start 243.98097 -42.999914)
						(mid 243.21897 -42.999914)
						(end 243.98097 -42.999914)
					)
				)
			)
		)
		(zone
			(layer "F.Cu")
			(hatch none 0.5)
			(connect_pads
				(clearance 0)
			)
			(min_thickness 0.25)
			(keepout
				(tracks allowed)
				(vias not_allowed)
				(pads allowed)
				(copperpour not_allowed)
				(footprints allowed)
			)
			(placement
				(enabled no)
				(sheetname "")
			)
			(fill
				(thermal_gap 0.5)
				(thermal_bridge_width 0.5)
				(island_removal_mode 0)
			)
			(polygon
				(pts
					(arc
						(start 243.98097 -41.999916)
						(mid 243.21897 -41.999916)
						(end 243.98097 -41.999916)
					)
				)
			)
		)
		(zone
			(layer "F.Cu")
			(hatch none 0.5)
			(connect_pads
				(clearance 0)
			)
			(min_thickness 0.25)
			(keepout
				(tracks allowed)
				(vias not_allowed)
				(pads allowed)
				(copperpour not_allowed)
				(footprints allowed)
			)
			(placement
				(enabled no)
				(sheetname "")
			)
			(fill
				(thermal_gap 0.5)
				(thermal_bridge_width 0.5)
				(island_removal_mode 0)
			)
			(polygon
				(pts
					(arc
						(start 243.98097 -40.999918)
						(mid 243.21897 -40.999918)
						(end 243.98097 -40.999918)
					)
				)
			)
		)
		(zone
			(layer "F.Cu")
			(hatch none 0.5)
			(connect_pads
				(clearance 0)
			)
			(min_thickness 0.25)
			(keepout
				(tracks allowed)
				(vias not_allowed)
				(pads allowed)
				(copperpour not_allowed)
				(footprints allowed)
			)
			(placement
				(enabled no)
				(sheetname "")
			)
			(fill
				(thermal_gap 0.5)
				(thermal_bridge_width 0.5)
				(island_removal_mode 0)
			)
			(polygon
				(pts
					(arc
						(start 243.98097 -39.99992)
						(mid 243.21897 -39.99992)
						(end 243.98097 -39.99992)
					)
				)
			)
		)
		(zone
			(layer "F.Cu")
			(hatch none 0.5)
			(connect_pads
				(clearance 0)
			)
			(min_thickness 0.25)
			(keepout
				(tracks allowed)
				(vias not_allowed)
				(pads allowed)
				(copperpour not_allowed)
				(footprints allowed)
			)
			(placement
				(enabled no)
				(sheetname "")
			)
			(fill
				(thermal_gap 0.5)
				(thermal_bridge_width 0.5)
				(island_removal_mode 0)
			)
			(polygon
				(pts
					(arc
						(start 243.98097 -38.999922)
						(mid 243.21897 -38.999922)
						(end 243.98097 -38.999922)
					)
				)
			)
		)
		(zone
			(layer "F.Cu")
			(hatch none 0.5)
			(connect_pads
				(clearance 0)
			)
			(min_thickness 0.25)
			(keepout
				(tracks allowed)
				(vias not_allowed)
				(pads allowed)
				(copperpour not_allowed)
				(footprints allowed)
			)
			(placement
				(enabled no)
				(sheetname "")
			)
			(fill
				(thermal_gap 0.5)
				(thermal_bridge_width 0.5)
				(island_removal_mode 0)
			)
			(polygon
				(pts
					(arc
						(start 243.98097 -37.999924)
						(mid 243.21897 -37.999924)
						(end 243.98097 -37.999924)
					)
				)
			)
		)
		(zone
			(layer "F.Cu")
			(hatch none 0.5)
			(connect_pads
				(clearance 0)
			)
			(min_thickness 0.25)
			(keepout
				(tracks allowed)
				(vias not_allowed)
				(pads allowed)
				(copperpour not_allowed)
				(footprints allowed)
			)
			(placement
				(enabled no)
				(sheetname "")
			)
			(fill
				(thermal_gap 0.5)
				(thermal_bridge_width 0.5)
				(island_removal_mode 0)
			)
			(polygon
				(pts
					(arc
						(start 243.98097 -36.999926)
						(mid 243.21897 -36.999926)
						(end 243.98097 -36.999926)
					)
				)
			)
		)
		(zone
			(layer "F.Cu")
			(hatch none 0.5)
			(connect_pads
				(clearance 0)
			)
			(min_thickness 0.25)
			(keepout
				(tracks allowed)
				(vias not_allowed)
				(pads allowed)
				(copperpour not_allowed)
				(footprints allowed)
			)
			(placement
				(enabled no)
				(sheetname "")
			)
			(fill
				(thermal_gap 0.5)
				(thermal_bridge_width 0.5)
				(island_removal_mode 0)
			)
			(polygon
				(pts
					(arc
						(start 243.98097 -35.999928)
						(mid 243.21897 -35.999928)
						(end 243.98097 -35.999928)
					)
				)
			)
		)
		(zone
			(layer "F.Cu")
			(hatch none 0.5)
			(connect_pads
				(clearance 0)
			)
			(min_thickness 0.25)
			(keepout
				(tracks allowed)
				(vias not_allowed)
				(pads allowed)
				(copperpour not_allowed)
				(footprints allowed)
			)
			(placement
				(enabled no)
				(sheetname "")
			)
			(fill
				(thermal_gap 0.5)
				(thermal_bridge_width 0.5)
				(island_removal_mode 0)
			)
			(polygon
				(pts
					(arc
						(start 243.98097 -34.99993)
						(mid 243.21897 -34.99993)
						(end 243.98097 -34.99993)
					)
				)
			)
		)
		(zone
			(layer "F.Cu")
			(hatch none 0.5)
			(connect_pads
				(clearance 0)
			)
			(min_thickness 0.25)
			(keepout
				(tracks allowed)
				(vias not_allowed)
				(pads allowed)
				(copperpour not_allowed)
				(footprints allowed)
			)
			(placement
				(enabled no)
				(sheetname "")
			)
			(fill
				(thermal_gap 0.5)
				(thermal_bridge_width 0.5)
				(island_removal_mode 0)
			)
			(polygon
				(pts
					(arc
						(start 243.98097 -33.999932)
						(mid 243.21897 -33.999932)
						(end 243.98097 -33.999932)
					)
				)
			)
		)
		(zone
			(layer "F.Cu")
			(hatch none 0.5)
			(connect_pads
				(clearance 0)
			)
			(min_thickness 0.25)
			(keepout
				(tracks allowed)
				(vias not_allowed)
				(pads allowed)
				(copperpour not_allowed)
				(footprints allowed)
			)
			(placement
				(enabled no)
				(sheetname "")
			)
			(fill
				(thermal_gap 0.5)
				(thermal_bridge_width 0.5)
				(island_removal_mode 0)
			)
			(polygon
				(pts
					(arc
						(start 243.98097 -32.999934)
						(mid 243.21897 -32.999934)
						(end 243.98097 -32.999934)
					)
				)
			)
		)
		(zone
			(layer "F.Cu")
			(hatch none 0.5)
			(connect_pads
				(clearance 0)
			)
			(min_thickness 0.25)
			(keepout
				(tracks allowed)
				(vias not_allowed)
				(pads allowed)
				(copperpour not_allowed)
				(footprints allowed)
			)
			(placement
				(enabled no)
				(sheetname "")
			)
			(fill
				(thermal_gap 0.5)
				(thermal_bridge_width 0.5)
				(island_removal_mode 0)
			)
			(polygon
				(pts
					(arc
						(start 243.98097 -31.999936)
						(mid 243.21897 -31.999936)
						(end 243.98097 -31.999936)
					)
				)
			)
		)
		(zone
			(layer "F.Cu")
			(hatch none 0.5)
			(connect_pads
				(clearance 0)
			)
			(min_thickness 0.25)
			(keepout
				(tracks allowed)
				(vias not_allowed)
				(pads allowed)
				(copperpour not_allowed)
				(footprints allowed)
			)
			(placement
				(enabled no)
				(sheetname "")
			)
			(fill
				(thermal_gap 0.5)
				(thermal_bridge_width 0.5)
				(island_removal_mode 0)
			)
			(polygon
				(pts
					(arc
						(start 243.98097 -30.999938)
						(mid 243.21897 -30.999938)
						(end 243.98097 -30.999938)
					)
				)
			)
		)
		(zone
			(layer "F.Cu")
			(hatch none 0.5)
			(connect_pads
				(clearance 0)
			)
			(min_thickness 0.25)
			(keepout
				(tracks allowed)
				(vias not_allowed)
				(pads allowed)
				(copperpour not_allowed)
				(footprints allowed)
			)
			(placement
				(enabled no)
				(sheetname "")
			)
			(fill
				(thermal_gap 0.5)
				(thermal_bridge_width 0.5)
				(island_removal_mode 0)
			)
			(polygon
				(pts
					(arc
						(start 244.980968 -65.999868)
						(mid 244.218968 -65.999868)
						(end 244.980968 -65.999868)
					)
				)
			)
		)
		(zone
			(layer "F.Cu")
			(hatch none 0.5)
			(connect_pads
				(clearance 0)
			)
			(min_thickness 0.25)
			(keepout
				(tracks allowed)
				(vias not_allowed)
				(pads allowed)
				(copperpour not_allowed)
				(footprints allowed)
			)
			(placement
				(enabled no)
				(sheetname "")
			)
			(fill
				(thermal_gap 0.5)
				(thermal_bridge_width 0.5)
				(island_removal_mode 0)
			)
			(polygon
				(pts
					(arc
						(start 244.980968 -64.99987)
						(mid 244.218968 -64.99987)
						(end 244.980968 -64.99987)
					)
				)
			)
		)
		(zone
			(layer "F.Cu")
			(hatch none 0.5)
			(connect_pads
				(clearance 0)
			)
			(min_thickness 0.25)
			(keepout
				(tracks allowed)
				(vias not_allowed)
				(pads allowed)
				(copperpour not_allowed)
				(footprints allowed)
			)
			(placement
				(enabled no)
				(sheetname "")
			)
			(fill
				(thermal_gap 0.5)
				(thermal_bridge_width 0.5)
				(island_removal_mode 0)
			)
			(polygon
				(pts
					(arc
						(start 244.980968 -63.999872)
						(mid 244.218968 -63.999872)
						(end 244.980968 -63.999872)
					)
				)
			)
		)
		(zone
			(layer "F.Cu")
			(hatch none 0.5)
			(connect_pads
				(clearance 0)
			)
			(min_thickness 0.25)
			(keepout
				(tracks allowed)
				(vias not_allowed)
				(pads allowed)
				(copperpour not_allowed)
				(footprints allowed)
			)
			(placement
				(enabled no)
				(sheetname "")
			)
			(fill
				(thermal_gap 0.5)
				(thermal_bridge_width 0.5)
				(island_removal_mode 0)
			)
			(polygon
				(pts
					(arc
						(start 244.980968 -62.999874)
						(mid 244.218968 -62.999874)
						(end 244.980968 -62.999874)
					)
				)
			)
		)
		(zone
			(layer "F.Cu")
			(hatch none 0.5)
			(connect_pads
				(clearance 0)
			)
			(min_thickness 0.25)
			(keepout
				(tracks allowed)
				(vias not_allowed)
				(pads allowed)
				(copperpour not_allowed)
				(footprints allowed)
			)
			(placement
				(enabled no)
				(sheetname "")
			)
			(fill
				(thermal_gap 0.5)
				(thermal_bridge_width 0.5)
				(island_removal_mode 0)
			)
			(polygon
				(pts
					(arc
						(start 244.980968 -61.999876)
						(mid 244.218968 -61.999876)
						(end 244.980968 -61.999876)
					)
				)
			)
		)
		(zone
			(layer "F.Cu")
			(hatch none 0.5)
			(connect_pads
				(clearance 0)
			)
			(min_thickness 0.25)
			(keepout
				(tracks allowed)
				(vias not_allowed)
				(pads allowed)
				(copperpour not_allowed)
				(footprints allowed)
			)
			(placement
				(enabled no)
				(sheetname "")
			)
			(fill
				(thermal_gap 0.5)
				(thermal_bridge_width 0.5)
				(island_removal_mode 0)
			)
			(polygon
				(pts
					(arc
						(start 244.980968 -60.999878)
						(mid 244.218968 -60.999878)
						(end 244.980968 -60.999878)
					)
				)
			)
		)
		(zone
			(layer "F.Cu")
			(hatch none 0.5)
			(connect_pads
				(clearance 0)
			)
			(min_thickness 0.25)
			(keepout
				(tracks allowed)
				(vias not_allowed)
				(pads allowed)
				(copperpour not_allowed)
				(footprints allowed)
			)
			(placement
				(enabled no)
				(sheetname "")
			)
			(fill
				(thermal_gap 0.5)
				(thermal_bridge_width 0.5)
				(island_removal_mode 0)
			)
			(polygon
				(pts
					(arc
						(start 244.980968 -59.99988)
						(mid 244.218968 -59.99988)
						(end 244.980968 -59.99988)
					)
				)
			)
		)
		(zone
			(layer "F.Cu")
			(hatch none 0.5)
			(connect_pads
				(clearance 0)
			)
			(min_thickness 0.25)
			(keepout
				(tracks allowed)
				(vias not_allowed)
				(pads allowed)
				(copperpour not_allowed)
				(footprints allowed)
			)
			(placement
				(enabled no)
				(sheetname "")
			)
			(fill
				(thermal_gap 0.5)
				(thermal_bridge_width 0.5)
				(island_removal_mode 0)
			)
			(polygon
				(pts
					(arc
						(start 244.980968 -58.999882)
						(mid 244.218968 -58.999882)
						(end 244.980968 -58.999882)
					)
				)
			)
		)
		(zone
			(layer "F.Cu")
			(hatch none 0.5)
			(connect_pads
				(clearance 0)
			)
			(min_thickness 0.25)
			(keepout
				(tracks allowed)
				(vias not_allowed)
				(pads allowed)
				(copperpour not_allowed)
				(footprints allowed)
			)
			(placement
				(enabled no)
				(sheetname "")
			)
			(fill
				(thermal_gap 0.5)
				(thermal_bridge_width 0.5)
				(island_removal_mode 0)
			)
			(polygon
				(pts
					(arc
						(start 244.980968 -57.999884)
						(mid 244.218968 -57.999884)
						(end 244.980968 -57.999884)
					)
				)
			)
		)
		(zone
			(layer "F.Cu")
			(hatch none 0.5)
			(connect_pads
				(clearance 0)
			)
			(min_thickness 0.25)
			(keepout
				(tracks allowed)
				(vias not_allowed)
				(pads allowed)
				(copperpour not_allowed)
				(footprints allowed)
			)
			(placement
				(enabled no)
				(sheetname "")
			)
			(fill
				(thermal_gap 0.5)
				(thermal_bridge_width 0.5)
				(island_removal_mode 0)
			)
			(polygon
				(pts
					(arc
						(start 244.980968 -56.999886)
						(mid 244.218968 -56.999886)
						(end 244.980968 -56.999886)
					)
				)
			)
		)
		(zone
			(layer "F.Cu")
			(hatch none 0.5)
			(connect_pads
				(clearance 0)
			)
			(min_thickness 0.25)
			(keepout
				(tracks allowed)
				(vias not_allowed)
				(pads allowed)
				(copperpour not_allowed)
				(footprints allowed)
			)
			(placement
				(enabled no)
				(sheetname "")
			)
			(fill
				(thermal_gap 0.5)
				(thermal_bridge_width 0.5)
				(island_removal_mode 0)
			)
			(polygon
				(pts
					(arc
						(start 244.980968 -55.999888)
						(mid 244.218968 -55.999888)
						(end 244.980968 -55.999888)
					)
				)
			)
		)
		(zone
			(layer "F.Cu")
			(hatch none 0.5)
			(connect_pads
				(clearance 0)
			)
			(min_thickness 0.25)
			(keepout
				(tracks allowed)
				(vias not_allowed)
				(pads allowed)
				(copperpour not_allowed)
				(footprints allowed)
			)
			(placement
				(enabled no)
				(sheetname "")
			)
			(fill
				(thermal_gap 0.5)
				(thermal_bridge_width 0.5)
				(island_removal_mode 0)
			)
			(polygon
				(pts
					(arc
						(start 244.980968 -54.99989)
						(mid 244.218968 -54.99989)
						(end 244.980968 -54.99989)
					)
				)
			)
		)
		(zone
			(layer "F.Cu")
			(hatch none 0.5)
			(connect_pads
				(clearance 0)
			)
			(min_thickness 0.25)
			(keepout
				(tracks allowed)
				(vias not_allowed)
				(pads allowed)
				(copperpour not_allowed)
				(footprints allowed)
			)
			(placement
				(enabled no)
				(sheetname "")
			)
			(fill
				(thermal_gap 0.5)
				(thermal_bridge_width 0.5)
				(island_removal_mode 0)
			)
			(polygon
				(pts
					(arc
						(start 244.980968 -53.999892)
						(mid 244.218968 -53.999892)
						(end 244.980968 -53.999892)
					)
				)
			)
		)
		(zone
			(layer "F.Cu")
			(hatch none 0.5)
			(connect_pads
				(clearance 0)
			)
			(min_thickness 0.25)
			(keepout
				(tracks allowed)
				(vias not_allowed)
				(pads allowed)
				(copperpour not_allowed)
				(footprints allowed)
			)
			(placement
				(enabled no)
				(sheetname "")
			)
			(fill
				(thermal_gap 0.5)
				(thermal_bridge_width 0.5)
				(island_removal_mode 0)
			)
			(polygon
				(pts
					(arc
						(start 244.980968 -52.999894)
						(mid 244.218968 -52.999894)
						(end 244.980968 -52.999894)
					)
				)
			)
		)
		(zone
			(layer "F.Cu")
			(hatch none 0.5)
			(connect_pads
				(clearance 0)
			)
			(min_thickness 0.25)
			(keepout
				(tracks allowed)
				(vias not_allowed)
				(pads allowed)
				(copperpour not_allowed)
				(footprints allowed)
			)
			(placement
				(enabled no)
				(sheetname "")
			)
			(fill
				(thermal_gap 0.5)
				(thermal_bridge_width 0.5)
				(island_removal_mode 0)
			)
			(polygon
				(pts
					(arc
						(start 244.980968 -51.999896)
						(mid 244.218968 -51.999896)
						(end 244.980968 -51.999896)
					)
				)
			)
		)
		(zone
			(layer "F.Cu")
			(hatch none 0.5)
			(connect_pads
				(clearance 0)
			)
			(min_thickness 0.25)
			(keepout
				(tracks allowed)
				(vias not_allowed)
				(pads allowed)
				(copperpour not_allowed)
				(footprints allowed)
			)
			(placement
				(enabled no)
				(sheetname "")
			)
			(fill
				(thermal_gap 0.5)
				(thermal_bridge_width 0.5)
				(island_removal_mode 0)
			)
			(polygon
				(pts
					(arc
						(start 244.980968 -50.999898)
						(mid 244.218968 -50.999898)
						(end 244.980968 -50.999898)
					)
				)
			)
		)
		(zone
			(layer "F.Cu")
			(hatch none 0.5)
			(connect_pads
				(clearance 0)
			)
			(min_thickness 0.25)
			(keepout
				(tracks allowed)
				(vias not_allowed)
				(pads allowed)
				(copperpour not_allowed)
				(footprints allowed)
			)
			(placement
				(enabled no)
				(sheetname "")
			)
			(fill
				(thermal_gap 0.5)
				(thermal_bridge_width 0.5)
				(island_removal_mode 0)
			)
			(polygon
				(pts
					(arc
						(start 244.980968 -49.9999)
						(mid 244.218968 -49.9999)
						(end 244.980968 -49.9999)
					)
				)
			)
		)
		(zone
			(layer "F.Cu")
			(hatch none 0.5)
			(connect_pads
				(clearance 0)
			)
			(min_thickness 0.25)
			(keepout
				(tracks allowed)
				(vias not_allowed)
				(pads allowed)
				(copperpour not_allowed)
				(footprints allowed)
			)
			(placement
				(enabled no)
				(sheetname "")
			)
			(fill
				(thermal_gap 0.5)
				(thermal_bridge_width 0.5)
				(island_removal_mode 0)
			)
			(polygon
				(pts
					(arc
						(start 244.980968 -48.999902)
						(mid 244.218968 -48.999902)
						(end 244.980968 -48.999902)
					)
				)
			)
		)
		(zone
			(layer "F.Cu")
			(hatch none 0.5)
			(connect_pads
				(clearance 0)
			)
			(min_thickness 0.25)
			(keepout
				(tracks allowed)
				(vias not_allowed)
				(pads allowed)
				(copperpour not_allowed)
				(footprints allowed)
			)
			(placement
				(enabled no)
				(sheetname "")
			)
			(fill
				(thermal_gap 0.5)
				(thermal_bridge_width 0.5)
				(island_removal_mode 0)
			)
			(polygon
				(pts
					(arc
						(start 244.980968 -47.999904)
						(mid 244.218968 -47.999904)
						(end 244.980968 -47.999904)
					)
				)
			)
		)
		(zone
			(layer "F.Cu")
			(hatch none 0.5)
			(connect_pads
				(clearance 0)
			)
			(min_thickness 0.25)
			(keepout
				(tracks allowed)
				(vias not_allowed)
				(pads allowed)
				(copperpour not_allowed)
				(footprints allowed)
			)
			(placement
				(enabled no)
				(sheetname "")
			)
			(fill
				(thermal_gap 0.5)
				(thermal_bridge_width 0.5)
				(island_removal_mode 0)
			)
			(polygon
				(pts
					(arc
						(start 244.980968 -46.999906)
						(mid 244.218968 -46.999906)
						(end 244.980968 -46.999906)
					)
				)
			)
		)
		(zone
			(layer "F.Cu")
			(hatch none 0.5)
			(connect_pads
				(clearance 0)
			)
			(min_thickness 0.25)
			(keepout
				(tracks allowed)
				(vias not_allowed)
				(pads allowed)
				(copperpour not_allowed)
				(footprints allowed)
			)
			(placement
				(enabled no)
				(sheetname "")
			)
			(fill
				(thermal_gap 0.5)
				(thermal_bridge_width 0.5)
				(island_removal_mode 0)
			)
			(polygon
				(pts
					(arc
						(start 244.980968 -45.999908)
						(mid 244.218968 -45.999908)
						(end 244.980968 -45.999908)
					)
				)
			)
		)
		(zone
			(layer "F.Cu")
			(hatch none 0.5)
			(connect_pads
				(clearance 0)
			)
			(min_thickness 0.25)
			(keepout
				(tracks allowed)
				(vias not_allowed)
				(pads allowed)
				(copperpour not_allowed)
				(footprints allowed)
			)
			(placement
				(enabled no)
				(sheetname "")
			)
			(fill
				(thermal_gap 0.5)
				(thermal_bridge_width 0.5)
				(island_removal_mode 0)
			)
			(polygon
				(pts
					(arc
						(start 244.980968 -44.99991)
						(mid 244.218968 -44.99991)
						(end 244.980968 -44.99991)
					)
				)
			)
		)
		(zone
			(layer "F.Cu")
			(hatch none 0.5)
			(connect_pads
				(clearance 0)
			)
			(min_thickness 0.25)
			(keepout
				(tracks allowed)
				(vias not_allowed)
				(pads allowed)
				(copperpour not_allowed)
				(footprints allowed)
			)
			(placement
				(enabled no)
				(sheetname "")
			)
			(fill
				(thermal_gap 0.5)
				(thermal_bridge_width 0.5)
				(island_removal_mode 0)
			)
			(polygon
				(pts
					(arc
						(start 244.980968 -43.999912)
						(mid 244.218968 -43.999912)
						(end 244.980968 -43.999912)
					)
				)
			)
		)
		(zone
			(layer "F.Cu")
			(hatch none 0.5)
			(connect_pads
				(clearance 0)
			)
			(min_thickness 0.25)
			(keepout
				(tracks allowed)
				(vias not_allowed)
				(pads allowed)
				(copperpour not_allowed)
				(footprints allowed)
			)
			(placement
				(enabled no)
				(sheetname "")
			)
			(fill
				(thermal_gap 0.5)
				(thermal_bridge_width 0.5)
				(island_removal_mode 0)
			)
			(polygon
				(pts
					(arc
						(start 244.980968 -42.999914)
						(mid 244.218968 -42.999914)
						(end 244.980968 -42.999914)
					)
				)
			)
		)
		(zone
			(layer "F.Cu")
			(hatch none 0.5)
			(connect_pads
				(clearance 0)
			)
			(min_thickness 0.25)
			(keepout
				(tracks allowed)
				(vias not_allowed)
				(pads allowed)
				(copperpour not_allowed)
				(footprints allowed)
			)
			(placement
				(enabled no)
				(sheetname "")
			)
			(fill
				(thermal_gap 0.5)
				(thermal_bridge_width 0.5)
				(island_removal_mode 0)
			)
			(polygon
				(pts
					(arc
						(start 244.980968 -41.999916)
						(mid 244.218968 -41.999916)
						(end 244.980968 -41.999916)
					)
				)
			)
		)
		(zone
			(layer "F.Cu")
			(hatch none 0.5)
			(connect_pads
				(clearance 0)
			)
			(min_thickness 0.25)
			(keepout
				(tracks allowed)
				(vias not_allowed)
				(pads allowed)
				(copperpour not_allowed)
				(footprints allowed)
			)
			(placement
				(enabled no)
				(sheetname "")
			)
			(fill
				(thermal_gap 0.5)
				(thermal_bridge_width 0.5)
				(island_removal_mode 0)
			)
			(polygon
				(pts
					(arc
						(start 244.980968 -40.999918)
						(mid 244.218968 -40.999918)
						(end 244.980968 -40.999918)
					)
				)
			)
		)
		(zone
			(layer "F.Cu")
			(hatch none 0.5)
			(connect_pads
				(clearance 0)
			)
			(min_thickness 0.25)
			(keepout
				(tracks allowed)
				(vias not_allowed)
				(pads allowed)
				(copperpour not_allowed)
				(footprints allowed)
			)
			(placement
				(enabled no)
				(sheetname "")
			)
			(fill
				(thermal_gap 0.5)
				(thermal_bridge_width 0.5)
				(island_removal_mode 0)
			)
			(polygon
				(pts
					(arc
						(start 244.980968 -39.99992)
						(mid 244.218968 -39.99992)
						(end 244.980968 -39.99992)
					)
				)
			)
		)
		(zone
			(layer "F.Cu")
			(hatch none 0.5)
			(connect_pads
				(clearance 0)
			)
			(min_thickness 0.25)
			(keepout
				(tracks allowed)
				(vias not_allowed)
				(pads allowed)
				(copperpour not_allowed)
				(footprints allowed)
			)
			(placement
				(enabled no)
				(sheetname "")
			)
			(fill
				(thermal_gap 0.5)
				(thermal_bridge_width 0.5)
				(island_removal_mode 0)
			)
			(polygon
				(pts
					(arc
						(start 244.980968 -38.999922)
						(mid 244.218968 -38.999922)
						(end 244.980968 -38.999922)
					)
				)
			)
		)
		(zone
			(layer "F.Cu")
			(hatch none 0.5)
			(connect_pads
				(clearance 0)
			)
			(min_thickness 0.25)
			(keepout
				(tracks allowed)
				(vias not_allowed)
				(pads allowed)
				(copperpour not_allowed)
				(footprints allowed)
			)
			(placement
				(enabled no)
				(sheetname "")
			)
			(fill
				(thermal_gap 0.5)
				(thermal_bridge_width 0.5)
				(island_removal_mode 0)
			)
			(polygon
				(pts
					(arc
						(start 244.980968 -37.999924)
						(mid 244.218968 -37.999924)
						(end 244.980968 -37.999924)
					)
				)
			)
		)
		(zone
			(layer "F.Cu")
			(hatch none 0.5)
			(connect_pads
				(clearance 0)
			)
			(min_thickness 0.25)
			(keepout
				(tracks allowed)
				(vias not_allowed)
				(pads allowed)
				(copperpour not_allowed)
				(footprints allowed)
			)
			(placement
				(enabled no)
				(sheetname "")
			)
			(fill
				(thermal_gap 0.5)
				(thermal_bridge_width 0.5)
				(island_removal_mode 0)
			)
			(polygon
				(pts
					(arc
						(start 244.980968 -36.999926)
						(mid 244.218968 -36.999926)
						(end 244.980968 -36.999926)
					)
				)
			)
		)
		(zone
			(layer "F.Cu")
			(hatch none 0.5)
			(connect_pads
				(clearance 0)
			)
			(min_thickness 0.25)
			(keepout
				(tracks allowed)
				(vias not_allowed)
				(pads allowed)
				(copperpour not_allowed)
				(footprints allowed)
			)
			(placement
				(enabled no)
				(sheetname "")
			)
			(fill
				(thermal_gap 0.5)
				(thermal_bridge_width 0.5)
				(island_removal_mode 0)
			)
			(polygon
				(pts
					(arc
						(start 244.980968 -35.999928)
						(mid 244.218968 -35.999928)
						(end 244.980968 -35.999928)
					)
				)
			)
		)
		(zone
			(layer "F.Cu")
			(hatch none 0.5)
			(connect_pads
				(clearance 0)
			)
			(min_thickness 0.25)
			(keepout
				(tracks allowed)
				(vias not_allowed)
				(pads allowed)
				(copperpour not_allowed)
				(footprints allowed)
			)
			(placement
				(enabled no)
				(sheetname "")
			)
			(fill
				(thermal_gap 0.5)
				(thermal_bridge_width 0.5)
				(island_removal_mode 0)
			)
			(polygon
				(pts
					(arc
						(start 244.980968 -34.99993)
						(mid 244.218968 -34.99993)
						(end 244.980968 -34.99993)
					)
				)
			)
		)
		(zone
			(layer "F.Cu")
			(hatch none 0.5)
			(connect_pads
				(clearance 0)
			)
			(min_thickness 0.25)
			(keepout
				(tracks allowed)
				(vias not_allowed)
				(pads allowed)
				(copperpour not_allowed)
				(footprints allowed)
			)
			(placement
				(enabled no)
				(sheetname "")
			)
			(fill
				(thermal_gap 0.5)
				(thermal_bridge_width 0.5)
				(island_removal_mode 0)
			)
			(polygon
				(pts
					(arc
						(start 244.980968 -33.999932)
						(mid 244.218968 -33.999932)
						(end 244.980968 -33.999932)
					)
				)
			)
		)
		(zone
			(layer "F.Cu")
			(hatch none 0.5)
			(connect_pads
				(clearance 0)
			)
			(min_thickness 0.25)
			(keepout
				(tracks allowed)
				(vias not_allowed)
				(pads allowed)
				(copperpour not_allowed)
				(footprints allowed)
			)
			(placement
				(enabled no)
				(sheetname "")
			)
			(fill
				(thermal_gap 0.5)
				(thermal_bridge_width 0.5)
				(island_removal_mode 0)
			)
			(polygon
				(pts
					(arc
						(start 244.980968 -32.999934)
						(mid 244.218968 -32.999934)
						(end 244.980968 -32.999934)
					)
				)
			)
		)
		(zone
			(layer "F.Cu")
			(hatch none 0.5)
			(connect_pads
				(clearance 0)
			)
			(min_thickness 0.25)
			(keepout
				(tracks allowed)
				(vias not_allowed)
				(pads allowed)
				(copperpour not_allowed)
				(footprints allowed)
			)
			(placement
				(enabled no)
				(sheetname "")
			)
			(fill
				(thermal_gap 0.5)
				(thermal_bridge_width 0.5)
				(island_removal_mode 0)
			)
			(polygon
				(pts
					(arc
						(start 244.980968 -31.999936)
						(mid 244.218968 -31.999936)
						(end 244.980968 -31.999936)
					)
				)
			)
		)
		(zone
			(layer "F.Cu")
			(hatch none 0.5)
			(connect_pads
				(clearance 0)
			)
			(min_thickness 0.25)
			(keepout
				(tracks allowed)
				(vias not_allowed)
				(pads allowed)
				(copperpour not_allowed)
				(footprints allowed)
			)
			(placement
				(enabled no)
				(sheetname "")
			)
			(fill
				(thermal_gap 0.5)
				(thermal_bridge_width 0.5)
				(island_removal_mode 0)
			)
			(polygon
				(pts
					(arc
						(start 244.980968 -30.999938)
						(mid 244.218968 -30.999938)
						(end 244.980968 -30.999938)
					)
				)
			)
		)
		(zone
			(layer "F.Cu")
			(hatch none 0.5)
			(connect_pads
				(clearance 0)
			)
			(min_thickness 0.25)
			(keepout
				(tracks allowed)
				(vias not_allowed)
				(pads allowed)
				(copperpour not_allowed)
				(footprints allowed)
			)
			(placement
				(enabled no)
				(sheetname "")
			)
			(fill
				(thermal_gap 0.5)
				(thermal_bridge_width 0.5)
				(island_removal_mode 0)
			)
			(polygon
				(pts
					(arc
						(start 244.980968 -29.99994)
						(mid 244.218968 -29.99994)
						(end 244.980968 -29.99994)
					)
				)
			)
		)
		(zone
			(layer "F.Cu")
			(hatch none 0.5)
			(connect_pads
				(clearance 0)
			)
			(min_thickness 0.25)
			(keepout
				(tracks allowed)
				(vias not_allowed)
				(pads allowed)
				(copperpour not_allowed)
				(footprints allowed)
			)
			(placement
				(enabled no)
				(sheetname "")
			)
			(fill
				(thermal_gap 0.5)
				(thermal_bridge_width 0.5)
				(island_removal_mode 0)
			)
			(polygon
				(pts
					(arc
						(start 245.980966 -64.99987)
						(mid 245.218966 -64.99987)
						(end 245.980966 -64.99987)
					)
				)
			)
		)
		(zone
			(layer "F.Cu")
			(hatch none 0.5)
			(connect_pads
				(clearance 0)
			)
			(min_thickness 0.25)
			(keepout
				(tracks allowed)
				(vias not_allowed)
				(pads allowed)
				(copperpour not_allowed)
				(footprints allowed)
			)
			(placement
				(enabled no)
				(sheetname "")
			)
			(fill
				(thermal_gap 0.5)
				(thermal_bridge_width 0.5)
				(island_removal_mode 0)
			)
			(polygon
				(pts
					(arc
						(start 245.980966 -63.999872)
						(mid 245.218966 -63.999872)
						(end 245.980966 -63.999872)
					)
				)
			)
		)
		(zone
			(layer "F.Cu")
			(hatch none 0.5)
			(connect_pads
				(clearance 0)
			)
			(min_thickness 0.25)
			(keepout
				(tracks allowed)
				(vias not_allowed)
				(pads allowed)
				(copperpour not_allowed)
				(footprints allowed)
			)
			(placement
				(enabled no)
				(sheetname "")
			)
			(fill
				(thermal_gap 0.5)
				(thermal_bridge_width 0.5)
				(island_removal_mode 0)
			)
			(polygon
				(pts
					(arc
						(start 245.980966 -62.999874)
						(mid 245.218966 -62.999874)
						(end 245.980966 -62.999874)
					)
				)
			)
		)
		(zone
			(layer "F.Cu")
			(hatch none 0.5)
			(connect_pads
				(clearance 0)
			)
			(min_thickness 0.25)
			(keepout
				(tracks allowed)
				(vias not_allowed)
				(pads allowed)
				(copperpour not_allowed)
				(footprints allowed)
			)
			(placement
				(enabled no)
				(sheetname "")
			)
			(fill
				(thermal_gap 0.5)
				(thermal_bridge_width 0.5)
				(island_removal_mode 0)
			)
			(polygon
				(pts
					(arc
						(start 245.980966 -61.999876)
						(mid 245.218966 -61.999876)
						(end 245.980966 -61.999876)
					)
				)
			)
		)
		(zone
			(layer "F.Cu")
			(hatch none 0.5)
			(connect_pads
				(clearance 0)
			)
			(min_thickness 0.25)
			(keepout
				(tracks allowed)
				(vias not_allowed)
				(pads allowed)
				(copperpour not_allowed)
				(footprints allowed)
			)
			(placement
				(enabled no)
				(sheetname "")
			)
			(fill
				(thermal_gap 0.5)
				(thermal_bridge_width 0.5)
				(island_removal_mode 0)
			)
			(polygon
				(pts
					(arc
						(start 245.980966 -60.999878)
						(mid 245.218966 -60.999878)
						(end 245.980966 -60.999878)
					)
				)
			)
		)
		(zone
			(layer "F.Cu")
			(hatch none 0.5)
			(connect_pads
				(clearance 0)
			)
			(min_thickness 0.25)
			(keepout
				(tracks allowed)
				(vias not_allowed)
				(pads allowed)
				(copperpour not_allowed)
				(footprints allowed)
			)
			(placement
				(enabled no)
				(sheetname "")
			)
			(fill
				(thermal_gap 0.5)
				(thermal_bridge_width 0.5)
				(island_removal_mode 0)
			)
			(polygon
				(pts
					(arc
						(start 245.980966 -59.99988)
						(mid 245.218966 -59.99988)
						(end 245.980966 -59.99988)
					)
				)
			)
		)
		(zone
			(layer "F.Cu")
			(hatch none 0.5)
			(connect_pads
				(clearance 0)
			)
			(min_thickness 0.25)
			(keepout
				(tracks allowed)
				(vias not_allowed)
				(pads allowed)
				(copperpour not_allowed)
				(footprints allowed)
			)
			(placement
				(enabled no)
				(sheetname "")
			)
			(fill
				(thermal_gap 0.5)
				(thermal_bridge_width 0.5)
				(island_removal_mode 0)
			)
			(polygon
				(pts
					(arc
						(start 245.980966 -58.999882)
						(mid 245.218966 -58.999882)
						(end 245.980966 -58.999882)
					)
				)
			)
		)
		(zone
			(layer "F.Cu")
			(hatch none 0.5)
			(connect_pads
				(clearance 0)
			)
			(min_thickness 0.25)
			(keepout
				(tracks allowed)
				(vias not_allowed)
				(pads allowed)
				(copperpour not_allowed)
				(footprints allowed)
			)
			(placement
				(enabled no)
				(sheetname "")
			)
			(fill
				(thermal_gap 0.5)
				(thermal_bridge_width 0.5)
				(island_removal_mode 0)
			)
			(polygon
				(pts
					(arc
						(start 245.980966 -57.999884)
						(mid 245.218966 -57.999884)
						(end 245.980966 -57.999884)
					)
				)
			)
		)
		(zone
			(layer "F.Cu")
			(hatch none 0.5)
			(connect_pads
				(clearance 0)
			)
			(min_thickness 0.25)
			(keepout
				(tracks allowed)
				(vias not_allowed)
				(pads allowed)
				(copperpour not_allowed)
				(footprints allowed)
			)
			(placement
				(enabled no)
				(sheetname "")
			)
			(fill
				(thermal_gap 0.5)
				(thermal_bridge_width 0.5)
				(island_removal_mode 0)
			)
			(polygon
				(pts
					(arc
						(start 245.980966 -56.999886)
						(mid 245.218966 -56.999886)
						(end 245.980966 -56.999886)
					)
				)
			)
		)
		(zone
			(layer "F.Cu")
			(hatch none 0.5)
			(connect_pads
				(clearance 0)
			)
			(min_thickness 0.25)
			(keepout
				(tracks allowed)
				(vias not_allowed)
				(pads allowed)
				(copperpour not_allowed)
				(footprints allowed)
			)
			(placement
				(enabled no)
				(sheetname "")
			)
			(fill
				(thermal_gap 0.5)
				(thermal_bridge_width 0.5)
				(island_removal_mode 0)
			)
			(polygon
				(pts
					(arc
						(start 245.980966 -55.999888)
						(mid 245.218966 -55.999888)
						(end 245.980966 -55.999888)
					)
				)
			)
		)
		(zone
			(layer "F.Cu")
			(hatch none 0.5)
			(connect_pads
				(clearance 0)
			)
			(min_thickness 0.25)
			(keepout
				(tracks allowed)
				(vias not_allowed)
				(pads allowed)
				(copperpour not_allowed)
				(footprints allowed)
			)
			(placement
				(enabled no)
				(sheetname "")
			)
			(fill
				(thermal_gap 0.5)
				(thermal_bridge_width 0.5)
				(island_removal_mode 0)
			)
			(polygon
				(pts
					(arc
						(start 245.980966 -54.99989)
						(mid 245.218966 -54.99989)
						(end 245.980966 -54.99989)
					)
				)
			)
		)
		(zone
			(layer "F.Cu")
			(hatch none 0.5)
			(connect_pads
				(clearance 0)
			)
			(min_thickness 0.25)
			(keepout
				(tracks allowed)
				(vias not_allowed)
				(pads allowed)
				(copperpour not_allowed)
				(footprints allowed)
			)
			(placement
				(enabled no)
				(sheetname "")
			)
			(fill
				(thermal_gap 0.5)
				(thermal_bridge_width 0.5)
				(island_removal_mode 0)
			)
			(polygon
				(pts
					(arc
						(start 245.980966 -53.999892)
						(mid 245.218966 -53.999892)
						(end 245.980966 -53.999892)
					)
				)
			)
		)
		(zone
			(layer "F.Cu")
			(hatch none 0.5)
			(connect_pads
				(clearance 0)
			)
			(min_thickness 0.25)
			(keepout
				(tracks allowed)
				(vias not_allowed)
				(pads allowed)
				(copperpour not_allowed)
				(footprints allowed)
			)
			(placement
				(enabled no)
				(sheetname "")
			)
			(fill
				(thermal_gap 0.5)
				(thermal_bridge_width 0.5)
				(island_removal_mode 0)
			)
			(polygon
				(pts
					(arc
						(start 245.980966 -52.999894)
						(mid 245.218966 -52.999894)
						(end 245.980966 -52.999894)
					)
				)
			)
		)
		(zone
			(layer "F.Cu")
			(hatch none 0.5)
			(connect_pads
				(clearance 0)
			)
			(min_thickness 0.25)
			(keepout
				(tracks allowed)
				(vias not_allowed)
				(pads allowed)
				(copperpour not_allowed)
				(footprints allowed)
			)
			(placement
				(enabled no)
				(sheetname "")
			)
			(fill
				(thermal_gap 0.5)
				(thermal_bridge_width 0.5)
				(island_removal_mode 0)
			)
			(polygon
				(pts
					(arc
						(start 245.980966 -51.999896)
						(mid 245.218966 -51.999896)
						(end 245.980966 -51.999896)
					)
				)
			)
		)
		(zone
			(layer "F.Cu")
			(hatch none 0.5)
			(connect_pads
				(clearance 0)
			)
			(min_thickness 0.25)
			(keepout
				(tracks allowed)
				(vias not_allowed)
				(pads allowed)
				(copperpour not_allowed)
				(footprints allowed)
			)
			(placement
				(enabled no)
				(sheetname "")
			)
			(fill
				(thermal_gap 0.5)
				(thermal_bridge_width 0.5)
				(island_removal_mode 0)
			)
			(polygon
				(pts
					(arc
						(start 245.980966 -50.999898)
						(mid 245.218966 -50.999898)
						(end 245.980966 -50.999898)
					)
				)
			)
		)
		(zone
			(layer "F.Cu")
			(hatch none 0.5)
			(connect_pads
				(clearance 0)
			)
			(min_thickness 0.25)
			(keepout
				(tracks allowed)
				(vias not_allowed)
				(pads allowed)
				(copperpour not_allowed)
				(footprints allowed)
			)
			(placement
				(enabled no)
				(sheetname "")
			)
			(fill
				(thermal_gap 0.5)
				(thermal_bridge_width 0.5)
				(island_removal_mode 0)
			)
			(polygon
				(pts
					(arc
						(start 245.980966 -49.9999)
						(mid 245.218966 -49.9999)
						(end 245.980966 -49.9999)
					)
				)
			)
		)
		(zone
			(layer "F.Cu")
			(hatch none 0.5)
			(connect_pads
				(clearance 0)
			)
			(min_thickness 0.25)
			(keepout
				(tracks allowed)
				(vias not_allowed)
				(pads allowed)
				(copperpour not_allowed)
				(footprints allowed)
			)
			(placement
				(enabled no)
				(sheetname "")
			)
			(fill
				(thermal_gap 0.5)
				(thermal_bridge_width 0.5)
				(island_removal_mode 0)
			)
			(polygon
				(pts
					(arc
						(start 245.980966 -48.999902)
						(mid 245.218966 -48.999902)
						(end 245.980966 -48.999902)
					)
				)
			)
		)
		(zone
			(layer "F.Cu")
			(hatch none 0.5)
			(connect_pads
				(clearance 0)
			)
			(min_thickness 0.25)
			(keepout
				(tracks allowed)
				(vias not_allowed)
				(pads allowed)
				(copperpour not_allowed)
				(footprints allowed)
			)
			(placement
				(enabled no)
				(sheetname "")
			)
			(fill
				(thermal_gap 0.5)
				(thermal_bridge_width 0.5)
				(island_removal_mode 0)
			)
			(polygon
				(pts
					(arc
						(start 245.980966 -47.999904)
						(mid 245.218966 -47.999904)
						(end 245.980966 -47.999904)
					)
				)
			)
		)
		(zone
			(layer "F.Cu")
			(hatch none 0.5)
			(connect_pads
				(clearance 0)
			)
			(min_thickness 0.25)
			(keepout
				(tracks allowed)
				(vias not_allowed)
				(pads allowed)
				(copperpour not_allowed)
				(footprints allowed)
			)
			(placement
				(enabled no)
				(sheetname "")
			)
			(fill
				(thermal_gap 0.5)
				(thermal_bridge_width 0.5)
				(island_removal_mode 0)
			)
			(polygon
				(pts
					(arc
						(start 245.980966 -46.999906)
						(mid 245.218966 -46.999906)
						(end 245.980966 -46.999906)
					)
				)
			)
		)
		(zone
			(layer "F.Cu")
			(hatch none 0.5)
			(connect_pads
				(clearance 0)
			)
			(min_thickness 0.25)
			(keepout
				(tracks allowed)
				(vias not_allowed)
				(pads allowed)
				(copperpour not_allowed)
				(footprints allowed)
			)
			(placement
				(enabled no)
				(sheetname "")
			)
			(fill
				(thermal_gap 0.5)
				(thermal_bridge_width 0.5)
				(island_removal_mode 0)
			)
			(polygon
				(pts
					(arc
						(start 245.980966 -45.999908)
						(mid 245.218966 -45.999908)
						(end 245.980966 -45.999908)
					)
				)
			)
		)
		(zone
			(layer "F.Cu")
			(hatch none 0.5)
			(connect_pads
				(clearance 0)
			)
			(min_thickness 0.25)
			(keepout
				(tracks allowed)
				(vias not_allowed)
				(pads allowed)
				(copperpour not_allowed)
				(footprints allowed)
			)
			(placement
				(enabled no)
				(sheetname "")
			)
			(fill
				(thermal_gap 0.5)
				(thermal_bridge_width 0.5)
				(island_removal_mode 0)
			)
			(polygon
				(pts
					(arc
						(start 245.980966 -44.99991)
						(mid 245.218966 -44.99991)
						(end 245.980966 -44.99991)
					)
				)
			)
		)
		(zone
			(layer "F.Cu")
			(hatch none 0.5)
			(connect_pads
				(clearance 0)
			)
			(min_thickness 0.25)
			(keepout
				(tracks allowed)
				(vias not_allowed)
				(pads allowed)
				(copperpour not_allowed)
				(footprints allowed)
			)
			(placement
				(enabled no)
				(sheetname "")
			)
			(fill
				(thermal_gap 0.5)
				(thermal_bridge_width 0.5)
				(island_removal_mode 0)
			)
			(polygon
				(pts
					(arc
						(start 245.980966 -43.999912)
						(mid 245.218966 -43.999912)
						(end 245.980966 -43.999912)
					)
				)
			)
		)
		(zone
			(layer "F.Cu")
			(hatch none 0.5)
			(connect_pads
				(clearance 0)
			)
			(min_thickness 0.25)
			(keepout
				(tracks allowed)
				(vias not_allowed)
				(pads allowed)
				(copperpour not_allowed)
				(footprints allowed)
			)
			(placement
				(enabled no)
				(sheetname "")
			)
			(fill
				(thermal_gap 0.5)
				(thermal_bridge_width 0.5)
				(island_removal_mode 0)
			)
			(polygon
				(pts
					(arc
						(start 245.980966 -42.999914)
						(mid 245.218966 -42.999914)
						(end 245.980966 -42.999914)
					)
				)
			)
		)
		(zone
			(layer "F.Cu")
			(hatch none 0.5)
			(connect_pads
				(clearance 0)
			)
			(min_thickness 0.25)
			(keepout
				(tracks allowed)
				(vias not_allowed)
				(pads allowed)
				(copperpour not_allowed)
				(footprints allowed)
			)
			(placement
				(enabled no)
				(sheetname "")
			)
			(fill
				(thermal_gap 0.5)
				(thermal_bridge_width 0.5)
				(island_removal_mode 0)
			)
			(polygon
				(pts
					(arc
						(start 245.980966 -41.999916)
						(mid 245.218966 -41.999916)
						(end 245.980966 -41.999916)
					)
				)
			)
		)
		(zone
			(layer "F.Cu")
			(hatch none 0.5)
			(connect_pads
				(clearance 0)
			)
			(min_thickness 0.25)
			(keepout
				(tracks allowed)
				(vias not_allowed)
				(pads allowed)
				(copperpour not_allowed)
				(footprints allowed)
			)
			(placement
				(enabled no)
				(sheetname "")
			)
			(fill
				(thermal_gap 0.5)
				(thermal_bridge_width 0.5)
				(island_removal_mode 0)
			)
			(polygon
				(pts
					(arc
						(start 245.980966 -40.999918)
						(mid 245.218966 -40.999918)
						(end 245.980966 -40.999918)
					)
				)
			)
		)
		(zone
			(layer "F.Cu")
			(hatch none 0.5)
			(connect_pads
				(clearance 0)
			)
			(min_thickness 0.25)
			(keepout
				(tracks allowed)
				(vias not_allowed)
				(pads allowed)
				(copperpour not_allowed)
				(footprints allowed)
			)
			(placement
				(enabled no)
				(sheetname "")
			)
			(fill
				(thermal_gap 0.5)
				(thermal_bridge_width 0.5)
				(island_removal_mode 0)
			)
			(polygon
				(pts
					(arc
						(start 245.980966 -39.99992)
						(mid 245.218966 -39.99992)
						(end 245.980966 -39.99992)
					)
				)
			)
		)
		(zone
			(layer "F.Cu")
			(hatch none 0.5)
			(connect_pads
				(clearance 0)
			)
			(min_thickness 0.25)
			(keepout
				(tracks allowed)
				(vias not_allowed)
				(pads allowed)
				(copperpour not_allowed)
				(footprints allowed)
			)
			(placement
				(enabled no)
				(sheetname "")
			)
			(fill
				(thermal_gap 0.5)
				(thermal_bridge_width 0.5)
				(island_removal_mode 0)
			)
			(polygon
				(pts
					(arc
						(start 245.980966 -38.999922)
						(mid 245.218966 -38.999922)
						(end 245.980966 -38.999922)
					)
				)
			)
		)
		(zone
			(layer "F.Cu")
			(hatch none 0.5)
			(connect_pads
				(clearance 0)
			)
			(min_thickness 0.25)
			(keepout
				(tracks allowed)
				(vias not_allowed)
				(pads allowed)
				(copperpour not_allowed)
				(footprints allowed)
			)
			(placement
				(enabled no)
				(sheetname "")
			)
			(fill
				(thermal_gap 0.5)
				(thermal_bridge_width 0.5)
				(island_removal_mode 0)
			)
			(polygon
				(pts
					(arc
						(start 245.980966 -37.999924)
						(mid 245.218966 -37.999924)
						(end 245.980966 -37.999924)
					)
				)
			)
		)
		(zone
			(layer "F.Cu")
			(hatch none 0.5)
			(connect_pads
				(clearance 0)
			)
			(min_thickness 0.25)
			(keepout
				(tracks allowed)
				(vias not_allowed)
				(pads allowed)
				(copperpour not_allowed)
				(footprints allowed)
			)
			(placement
				(enabled no)
				(sheetname "")
			)
			(fill
				(thermal_gap 0.5)
				(thermal_bridge_width 0.5)
				(island_removal_mode 0)
			)
			(polygon
				(pts
					(arc
						(start 245.980966 -36.999926)
						(mid 245.218966 -36.999926)
						(end 245.980966 -36.999926)
					)
				)
			)
		)
		(zone
			(layer "F.Cu")
			(hatch none 0.5)
			(connect_pads
				(clearance 0)
			)
			(min_thickness 0.25)
			(keepout
				(tracks allowed)
				(vias not_allowed)
				(pads allowed)
				(copperpour not_allowed)
				(footprints allowed)
			)
			(placement
				(enabled no)
				(sheetname "")
			)
			(fill
				(thermal_gap 0.5)
				(thermal_bridge_width 0.5)
				(island_removal_mode 0)
			)
			(polygon
				(pts
					(arc
						(start 245.980966 -35.999928)
						(mid 245.218966 -35.999928)
						(end 245.980966 -35.999928)
					)
				)
			)
		)
		(zone
			(layer "F.Cu")
			(hatch none 0.5)
			(connect_pads
				(clearance 0)
			)
			(min_thickness 0.25)
			(keepout
				(tracks allowed)
				(vias not_allowed)
				(pads allowed)
				(copperpour not_allowed)
				(footprints allowed)
			)
			(placement
				(enabled no)
				(sheetname "")
			)
			(fill
				(thermal_gap 0.5)
				(thermal_bridge_width 0.5)
				(island_removal_mode 0)
			)
			(polygon
				(pts
					(arc
						(start 245.980966 -34.99993)
						(mid 245.218966 -34.99993)
						(end 245.980966 -34.99993)
					)
				)
			)
		)
		(zone
			(layer "F.Cu")
			(hatch none 0.5)
			(connect_pads
				(clearance 0)
			)
			(min_thickness 0.25)
			(keepout
				(tracks allowed)
				(vias not_allowed)
				(pads allowed)
				(copperpour not_allowed)
				(footprints allowed)
			)
			(placement
				(enabled no)
				(sheetname "")
			)
			(fill
				(thermal_gap 0.5)
				(thermal_bridge_width 0.5)
				(island_removal_mode 0)
			)
			(polygon
				(pts
					(arc
						(start 245.980966 -33.999932)
						(mid 245.218966 -33.999932)
						(end 245.980966 -33.999932)
					)
				)
			)
		)
		(zone
			(layer "F.Cu")
			(hatch none 0.5)
			(connect_pads
				(clearance 0)
			)
			(min_thickness 0.25)
			(keepout
				(tracks allowed)
				(vias not_allowed)
				(pads allowed)
				(copperpour not_allowed)
				(footprints allowed)
			)
			(placement
				(enabled no)
				(sheetname "")
			)
			(fill
				(thermal_gap 0.5)
				(thermal_bridge_width 0.5)
				(island_removal_mode 0)
			)
			(polygon
				(pts
					(arc
						(start 245.980966 -32.999934)
						(mid 245.218966 -32.999934)
						(end 245.980966 -32.999934)
					)
				)
			)
		)
		(zone
			(layer "F.Cu")
			(hatch none 0.5)
			(connect_pads
				(clearance 0)
			)
			(min_thickness 0.25)
			(keepout
				(tracks allowed)
				(vias not_allowed)
				(pads allowed)
				(copperpour not_allowed)
				(footprints allowed)
			)
			(placement
				(enabled no)
				(sheetname "")
			)
			(fill
				(thermal_gap 0.5)
				(thermal_bridge_width 0.5)
				(island_removal_mode 0)
			)
			(polygon
				(pts
					(arc
						(start 245.980966 -31.999936)
						(mid 245.218966 -31.999936)
						(end 245.980966 -31.999936)
					)
				)
			)
		)
		(zone
			(layer "F.Cu")
			(hatch none 0.5)
			(connect_pads
				(clearance 0)
			)
			(min_thickness 0.25)
			(keepout
				(tracks allowed)
				(vias not_allowed)
				(pads allowed)
				(copperpour not_allowed)
				(footprints allowed)
			)
			(placement
				(enabled no)
				(sheetname "")
			)
			(fill
				(thermal_gap 0.5)
				(thermal_bridge_width 0.5)
				(island_removal_mode 0)
			)
			(polygon
				(pts
					(arc
						(start 245.980966 -30.999938)
						(mid 245.218966 -30.999938)
						(end 245.980966 -30.999938)
					)
				)
			)
		)
		(zone
			(layer "F.Cu")
			(hatch none 0.5)
			(connect_pads
				(clearance 0)
			)
			(min_thickness 0.25)
			(keepout
				(tracks allowed)
				(vias not_allowed)
				(pads allowed)
				(copperpour not_allowed)
				(footprints allowed)
			)
			(placement
				(enabled no)
				(sheetname "")
			)
			(fill
				(thermal_gap 0.5)
				(thermal_bridge_width 0.5)
				(island_removal_mode 0)
			)
			(polygon
				(pts
					(arc
						(start 246.980964 -65.999868)
						(mid 246.218964 -65.999868)
						(end 246.980964 -65.999868)
					)
				)
			)
		)
		(zone
			(layer "F.Cu")
			(hatch none 0.5)
			(connect_pads
				(clearance 0)
			)
			(min_thickness 0.25)
			(keepout
				(tracks allowed)
				(vias not_allowed)
				(pads allowed)
				(copperpour not_allowed)
				(footprints allowed)
			)
			(placement
				(enabled no)
				(sheetname "")
			)
			(fill
				(thermal_gap 0.5)
				(thermal_bridge_width 0.5)
				(island_removal_mode 0)
			)
			(polygon
				(pts
					(arc
						(start 246.980964 -64.99987)
						(mid 246.218964 -64.99987)
						(end 246.980964 -64.99987)
					)
				)
			)
		)
		(zone
			(layer "F.Cu")
			(hatch none 0.5)
			(connect_pads
				(clearance 0)
			)
			(min_thickness 0.25)
			(keepout
				(tracks allowed)
				(vias not_allowed)
				(pads allowed)
				(copperpour not_allowed)
				(footprints allowed)
			)
			(placement
				(enabled no)
				(sheetname "")
			)
			(fill
				(thermal_gap 0.5)
				(thermal_bridge_width 0.5)
				(island_removal_mode 0)
			)
			(polygon
				(pts
					(arc
						(start 246.980964 -63.999872)
						(mid 246.218964 -63.999872)
						(end 246.980964 -63.999872)
					)
				)
			)
		)
		(zone
			(layer "F.Cu")
			(hatch none 0.5)
			(connect_pads
				(clearance 0)
			)
			(min_thickness 0.25)
			(keepout
				(tracks allowed)
				(vias not_allowed)
				(pads allowed)
				(copperpour not_allowed)
				(footprints allowed)
			)
			(placement
				(enabled no)
				(sheetname "")
			)
			(fill
				(thermal_gap 0.5)
				(thermal_bridge_width 0.5)
				(island_removal_mode 0)
			)
			(polygon
				(pts
					(arc
						(start 246.980964 -62.999874)
						(mid 246.218964 -62.999874)
						(end 246.980964 -62.999874)
					)
				)
			)
		)
		(zone
			(layer "F.Cu")
			(hatch none 0.5)
			(connect_pads
				(clearance 0)
			)
			(min_thickness 0.25)
			(keepout
				(tracks allowed)
				(vias not_allowed)
				(pads allowed)
				(copperpour not_allowed)
				(footprints allowed)
			)
			(placement
				(enabled no)
				(sheetname "")
			)
			(fill
				(thermal_gap 0.5)
				(thermal_bridge_width 0.5)
				(island_removal_mode 0)
			)
			(polygon
				(pts
					(arc
						(start 246.980964 -61.999876)
						(mid 246.218964 -61.999876)
						(end 246.980964 -61.999876)
					)
				)
			)
		)
		(zone
			(layer "F.Cu")
			(hatch none 0.5)
			(connect_pads
				(clearance 0)
			)
			(min_thickness 0.25)
			(keepout
				(tracks allowed)
				(vias not_allowed)
				(pads allowed)
				(copperpour not_allowed)
				(footprints allowed)
			)
			(placement
				(enabled no)
				(sheetname "")
			)
			(fill
				(thermal_gap 0.5)
				(thermal_bridge_width 0.5)
				(island_removal_mode 0)
			)
			(polygon
				(pts
					(arc
						(start 246.980964 -60.999878)
						(mid 246.218964 -60.999878)
						(end 246.980964 -60.999878)
					)
				)
			)
		)
		(zone
			(layer "F.Cu")
			(hatch none 0.5)
			(connect_pads
				(clearance 0)
			)
			(min_thickness 0.25)
			(keepout
				(tracks allowed)
				(vias not_allowed)
				(pads allowed)
				(copperpour not_allowed)
				(footprints allowed)
			)
			(placement
				(enabled no)
				(sheetname "")
			)
			(fill
				(thermal_gap 0.5)
				(thermal_bridge_width 0.5)
				(island_removal_mode 0)
			)
			(polygon
				(pts
					(arc
						(start 246.980964 -59.99988)
						(mid 246.218964 -59.99988)
						(end 246.980964 -59.99988)
					)
				)
			)
		)
		(zone
			(layer "F.Cu")
			(hatch none 0.5)
			(connect_pads
				(clearance 0)
			)
			(min_thickness 0.25)
			(keepout
				(tracks allowed)
				(vias not_allowed)
				(pads allowed)
				(copperpour not_allowed)
				(footprints allowed)
			)
			(placement
				(enabled no)
				(sheetname "")
			)
			(fill
				(thermal_gap 0.5)
				(thermal_bridge_width 0.5)
				(island_removal_mode 0)
			)
			(polygon
				(pts
					(arc
						(start 246.980964 -58.999882)
						(mid 246.218964 -58.999882)
						(end 246.980964 -58.999882)
					)
				)
			)
		)
		(zone
			(layer "F.Cu")
			(hatch none 0.5)
			(connect_pads
				(clearance 0)
			)
			(min_thickness 0.25)
			(keepout
				(tracks allowed)
				(vias not_allowed)
				(pads allowed)
				(copperpour not_allowed)
				(footprints allowed)
			)
			(placement
				(enabled no)
				(sheetname "")
			)
			(fill
				(thermal_gap 0.5)
				(thermal_bridge_width 0.5)
				(island_removal_mode 0)
			)
			(polygon
				(pts
					(arc
						(start 246.980964 -57.999884)
						(mid 246.218964 -57.999884)
						(end 246.980964 -57.999884)
					)
				)
			)
		)
		(zone
			(layer "F.Cu")
			(hatch none 0.5)
			(connect_pads
				(clearance 0)
			)
			(min_thickness 0.25)
			(keepout
				(tracks allowed)
				(vias not_allowed)
				(pads allowed)
				(copperpour not_allowed)
				(footprints allowed)
			)
			(placement
				(enabled no)
				(sheetname "")
			)
			(fill
				(thermal_gap 0.5)
				(thermal_bridge_width 0.5)
				(island_removal_mode 0)
			)
			(polygon
				(pts
					(arc
						(start 246.980964 -56.999886)
						(mid 246.218964 -56.999886)
						(end 246.980964 -56.999886)
					)
				)
			)
		)
		(zone
			(layer "F.Cu")
			(hatch none 0.5)
			(connect_pads
				(clearance 0)
			)
			(min_thickness 0.25)
			(keepout
				(tracks allowed)
				(vias not_allowed)
				(pads allowed)
				(copperpour not_allowed)
				(footprints allowed)
			)
			(placement
				(enabled no)
				(sheetname "")
			)
			(fill
				(thermal_gap 0.5)
				(thermal_bridge_width 0.5)
				(island_removal_mode 0)
			)
			(polygon
				(pts
					(arc
						(start 246.980964 -55.999888)
						(mid 246.218964 -55.999888)
						(end 246.980964 -55.999888)
					)
				)
			)
		)
		(zone
			(layer "F.Cu")
			(hatch none 0.5)
			(connect_pads
				(clearance 0)
			)
			(min_thickness 0.25)
			(keepout
				(tracks allowed)
				(vias not_allowed)
				(pads allowed)
				(copperpour not_allowed)
				(footprints allowed)
			)
			(placement
				(enabled no)
				(sheetname "")
			)
			(fill
				(thermal_gap 0.5)
				(thermal_bridge_width 0.5)
				(island_removal_mode 0)
			)
			(polygon
				(pts
					(arc
						(start 246.980964 -54.99989)
						(mid 246.218964 -54.99989)
						(end 246.980964 -54.99989)
					)
				)
			)
		)
		(zone
			(layer "F.Cu")
			(hatch none 0.5)
			(connect_pads
				(clearance 0)
			)
			(min_thickness 0.25)
			(keepout
				(tracks allowed)
				(vias not_allowed)
				(pads allowed)
				(copperpour not_allowed)
				(footprints allowed)
			)
			(placement
				(enabled no)
				(sheetname "")
			)
			(fill
				(thermal_gap 0.5)
				(thermal_bridge_width 0.5)
				(island_removal_mode 0)
			)
			(polygon
				(pts
					(arc
						(start 246.980964 -53.999892)
						(mid 246.218964 -53.999892)
						(end 246.980964 -53.999892)
					)
				)
			)
		)
		(zone
			(layer "F.Cu")
			(hatch none 0.5)
			(connect_pads
				(clearance 0)
			)
			(min_thickness 0.25)
			(keepout
				(tracks allowed)
				(vias not_allowed)
				(pads allowed)
				(copperpour not_allowed)
				(footprints allowed)
			)
			(placement
				(enabled no)
				(sheetname "")
			)
			(fill
				(thermal_gap 0.5)
				(thermal_bridge_width 0.5)
				(island_removal_mode 0)
			)
			(polygon
				(pts
					(arc
						(start 246.980964 -52.999894)
						(mid 246.218964 -52.999894)
						(end 246.980964 -52.999894)
					)
				)
			)
		)
		(zone
			(layer "F.Cu")
			(hatch none 0.5)
			(connect_pads
				(clearance 0)
			)
			(min_thickness 0.25)
			(keepout
				(tracks allowed)
				(vias not_allowed)
				(pads allowed)
				(copperpour not_allowed)
				(footprints allowed)
			)
			(placement
				(enabled no)
				(sheetname "")
			)
			(fill
				(thermal_gap 0.5)
				(thermal_bridge_width 0.5)
				(island_removal_mode 0)
			)
			(polygon
				(pts
					(arc
						(start 246.980964 -51.999896)
						(mid 246.218964 -51.999896)
						(end 246.980964 -51.999896)
					)
				)
			)
		)
		(zone
			(layer "F.Cu")
			(hatch none 0.5)
			(connect_pads
				(clearance 0)
			)
			(min_thickness 0.25)
			(keepout
				(tracks allowed)
				(vias not_allowed)
				(pads allowed)
				(copperpour not_allowed)
				(footprints allowed)
			)
			(placement
				(enabled no)
				(sheetname "")
			)
			(fill
				(thermal_gap 0.5)
				(thermal_bridge_width 0.5)
				(island_removal_mode 0)
			)
			(polygon
				(pts
					(arc
						(start 246.980964 -50.999898)
						(mid 246.218964 -50.999898)
						(end 246.980964 -50.999898)
					)
				)
			)
		)
		(zone
			(layer "F.Cu")
			(hatch none 0.5)
			(connect_pads
				(clearance 0)
			)
			(min_thickness 0.25)
			(keepout
				(tracks allowed)
				(vias not_allowed)
				(pads allowed)
				(copperpour not_allowed)
				(footprints allowed)
			)
			(placement
				(enabled no)
				(sheetname "")
			)
			(fill
				(thermal_gap 0.5)
				(thermal_bridge_width 0.5)
				(island_removal_mode 0)
			)
			(polygon
				(pts
					(arc
						(start 246.980964 -49.9999)
						(mid 246.218964 -49.9999)
						(end 246.980964 -49.9999)
					)
				)
			)
		)
		(zone
			(layer "F.Cu")
			(hatch none 0.5)
			(connect_pads
				(clearance 0)
			)
			(min_thickness 0.25)
			(keepout
				(tracks allowed)
				(vias not_allowed)
				(pads allowed)
				(copperpour not_allowed)
				(footprints allowed)
			)
			(placement
				(enabled no)
				(sheetname "")
			)
			(fill
				(thermal_gap 0.5)
				(thermal_bridge_width 0.5)
				(island_removal_mode 0)
			)
			(polygon
				(pts
					(arc
						(start 246.980964 -48.999902)
						(mid 246.218964 -48.999902)
						(end 246.980964 -48.999902)
					)
				)
			)
		)
		(zone
			(layer "F.Cu")
			(hatch none 0.5)
			(connect_pads
				(clearance 0)
			)
			(min_thickness 0.25)
			(keepout
				(tracks allowed)
				(vias not_allowed)
				(pads allowed)
				(copperpour not_allowed)
				(footprints allowed)
			)
			(placement
				(enabled no)
				(sheetname "")
			)
			(fill
				(thermal_gap 0.5)
				(thermal_bridge_width 0.5)
				(island_removal_mode 0)
			)
			(polygon
				(pts
					(arc
						(start 246.980964 -47.999904)
						(mid 246.218964 -47.999904)
						(end 246.980964 -47.999904)
					)
				)
			)
		)
		(zone
			(layer "F.Cu")
			(hatch none 0.5)
			(connect_pads
				(clearance 0)
			)
			(min_thickness 0.25)
			(keepout
				(tracks allowed)
				(vias not_allowed)
				(pads allowed)
				(copperpour not_allowed)
				(footprints allowed)
			)
			(placement
				(enabled no)
				(sheetname "")
			)
			(fill
				(thermal_gap 0.5)
				(thermal_bridge_width 0.5)
				(island_removal_mode 0)
			)
			(polygon
				(pts
					(arc
						(start 246.980964 -46.999906)
						(mid 246.218964 -46.999906)
						(end 246.980964 -46.999906)
					)
				)
			)
		)
		(zone
			(layer "F.Cu")
			(hatch none 0.5)
			(connect_pads
				(clearance 0)
			)
			(min_thickness 0.25)
			(keepout
				(tracks allowed)
				(vias not_allowed)
				(pads allowed)
				(copperpour not_allowed)
				(footprints allowed)
			)
			(placement
				(enabled no)
				(sheetname "")
			)
			(fill
				(thermal_gap 0.5)
				(thermal_bridge_width 0.5)
				(island_removal_mode 0)
			)
			(polygon
				(pts
					(arc
						(start 246.980964 -45.999908)
						(mid 246.218964 -45.999908)
						(end 246.980964 -45.999908)
					)
				)
			)
		)
		(zone
			(layer "F.Cu")
			(hatch none 0.5)
			(connect_pads
				(clearance 0)
			)
			(min_thickness 0.25)
			(keepout
				(tracks allowed)
				(vias not_allowed)
				(pads allowed)
				(copperpour not_allowed)
				(footprints allowed)
			)
			(placement
				(enabled no)
				(sheetname "")
			)
			(fill
				(thermal_gap 0.5)
				(thermal_bridge_width 0.5)
				(island_removal_mode 0)
			)
			(polygon
				(pts
					(arc
						(start 246.980964 -44.99991)
						(mid 246.218964 -44.99991)
						(end 246.980964 -44.99991)
					)
				)
			)
		)
		(zone
			(layer "F.Cu")
			(hatch none 0.5)
			(connect_pads
				(clearance 0)
			)
			(min_thickness 0.25)
			(keepout
				(tracks allowed)
				(vias not_allowed)
				(pads allowed)
				(copperpour not_allowed)
				(footprints allowed)
			)
			(placement
				(enabled no)
				(sheetname "")
			)
			(fill
				(thermal_gap 0.5)
				(thermal_bridge_width 0.5)
				(island_removal_mode 0)
			)
			(polygon
				(pts
					(arc
						(start 246.980964 -43.999912)
						(mid 246.218964 -43.999912)
						(end 246.980964 -43.999912)
					)
				)
			)
		)
		(zone
			(layer "F.Cu")
			(hatch none 0.5)
			(connect_pads
				(clearance 0)
			)
			(min_thickness 0.25)
			(keepout
				(tracks allowed)
				(vias not_allowed)
				(pads allowed)
				(copperpour not_allowed)
				(footprints allowed)
			)
			(placement
				(enabled no)
				(sheetname "")
			)
			(fill
				(thermal_gap 0.5)
				(thermal_bridge_width 0.5)
				(island_removal_mode 0)
			)
			(polygon
				(pts
					(arc
						(start 246.980964 -42.999914)
						(mid 246.218964 -42.999914)
						(end 246.980964 -42.999914)
					)
				)
			)
		)
		(zone
			(layer "F.Cu")
			(hatch none 0.5)
			(connect_pads
				(clearance 0)
			)
			(min_thickness 0.25)
			(keepout
				(tracks allowed)
				(vias not_allowed)
				(pads allowed)
				(copperpour not_allowed)
				(footprints allowed)
			)
			(placement
				(enabled no)
				(sheetname "")
			)
			(fill
				(thermal_gap 0.5)
				(thermal_bridge_width 0.5)
				(island_removal_mode 0)
			)
			(polygon
				(pts
					(arc
						(start 246.980964 -41.999916)
						(mid 246.218964 -41.999916)
						(end 246.980964 -41.999916)
					)
				)
			)
		)
		(zone
			(layer "F.Cu")
			(hatch none 0.5)
			(connect_pads
				(clearance 0)
			)
			(min_thickness 0.25)
			(keepout
				(tracks allowed)
				(vias not_allowed)
				(pads allowed)
				(copperpour not_allowed)
				(footprints allowed)
			)
			(placement
				(enabled no)
				(sheetname "")
			)
			(fill
				(thermal_gap 0.5)
				(thermal_bridge_width 0.5)
				(island_removal_mode 0)
			)
			(polygon
				(pts
					(arc
						(start 246.980964 -40.999918)
						(mid 246.218964 -40.999918)
						(end 246.980964 -40.999918)
					)
				)
			)
		)
		(zone
			(layer "F.Cu")
			(hatch none 0.5)
			(connect_pads
				(clearance 0)
			)
			(min_thickness 0.25)
			(keepout
				(tracks allowed)
				(vias not_allowed)
				(pads allowed)
				(copperpour not_allowed)
				(footprints allowed)
			)
			(placement
				(enabled no)
				(sheetname "")
			)
			(fill
				(thermal_gap 0.5)
				(thermal_bridge_width 0.5)
				(island_removal_mode 0)
			)
			(polygon
				(pts
					(arc
						(start 246.980964 -39.99992)
						(mid 246.218964 -39.99992)
						(end 246.980964 -39.99992)
					)
				)
			)
		)
		(zone
			(layer "F.Cu")
			(hatch none 0.5)
			(connect_pads
				(clearance 0)
			)
			(min_thickness 0.25)
			(keepout
				(tracks allowed)
				(vias not_allowed)
				(pads allowed)
				(copperpour not_allowed)
				(footprints allowed)
			)
			(placement
				(enabled no)
				(sheetname "")
			)
			(fill
				(thermal_gap 0.5)
				(thermal_bridge_width 0.5)
				(island_removal_mode 0)
			)
			(polygon
				(pts
					(arc
						(start 246.980964 -38.999922)
						(mid 246.218964 -38.999922)
						(end 246.980964 -38.999922)
					)
				)
			)
		)
		(zone
			(layer "F.Cu")
			(hatch none 0.5)
			(connect_pads
				(clearance 0)
			)
			(min_thickness 0.25)
			(keepout
				(tracks allowed)
				(vias not_allowed)
				(pads allowed)
				(copperpour not_allowed)
				(footprints allowed)
			)
			(placement
				(enabled no)
				(sheetname "")
			)
			(fill
				(thermal_gap 0.5)
				(thermal_bridge_width 0.5)
				(island_removal_mode 0)
			)
			(polygon
				(pts
					(arc
						(start 246.980964 -37.999924)
						(mid 246.218964 -37.999924)
						(end 246.980964 -37.999924)
					)
				)
			)
		)
		(zone
			(layer "F.Cu")
			(hatch none 0.5)
			(connect_pads
				(clearance 0)
			)
			(min_thickness 0.25)
			(keepout
				(tracks allowed)
				(vias not_allowed)
				(pads allowed)
				(copperpour not_allowed)
				(footprints allowed)
			)
			(placement
				(enabled no)
				(sheetname "")
			)
			(fill
				(thermal_gap 0.5)
				(thermal_bridge_width 0.5)
				(island_removal_mode 0)
			)
			(polygon
				(pts
					(arc
						(start 246.980964 -36.999926)
						(mid 246.218964 -36.999926)
						(end 246.980964 -36.999926)
					)
				)
			)
		)
		(zone
			(layer "F.Cu")
			(hatch none 0.5)
			(connect_pads
				(clearance 0)
			)
			(min_thickness 0.25)
			(keepout
				(tracks allowed)
				(vias not_allowed)
				(pads allowed)
				(copperpour not_allowed)
				(footprints allowed)
			)
			(placement
				(enabled no)
				(sheetname "")
			)
			(fill
				(thermal_gap 0.5)
				(thermal_bridge_width 0.5)
				(island_removal_mode 0)
			)
			(polygon
				(pts
					(arc
						(start 246.980964 -35.999928)
						(mid 246.218964 -35.999928)
						(end 246.980964 -35.999928)
					)
				)
			)
		)
		(zone
			(layer "F.Cu")
			(hatch none 0.5)
			(connect_pads
				(clearance 0)
			)
			(min_thickness 0.25)
			(keepout
				(tracks allowed)
				(vias not_allowed)
				(pads allowed)
				(copperpour not_allowed)
				(footprints allowed)
			)
			(placement
				(enabled no)
				(sheetname "")
			)
			(fill
				(thermal_gap 0.5)
				(thermal_bridge_width 0.5)
				(island_removal_mode 0)
			)
			(polygon
				(pts
					(arc
						(start 246.980964 -34.99993)
						(mid 246.218964 -34.99993)
						(end 246.980964 -34.99993)
					)
				)
			)
		)
		(zone
			(layer "F.Cu")
			(hatch none 0.5)
			(connect_pads
				(clearance 0)
			)
			(min_thickness 0.25)
			(keepout
				(tracks allowed)
				(vias not_allowed)
				(pads allowed)
				(copperpour not_allowed)
				(footprints allowed)
			)
			(placement
				(enabled no)
				(sheetname "")
			)
			(fill
				(thermal_gap 0.5)
				(thermal_bridge_width 0.5)
				(island_removal_mode 0)
			)
			(polygon
				(pts
					(arc
						(start 246.980964 -33.999932)
						(mid 246.218964 -33.999932)
						(end 246.980964 -33.999932)
					)
				)
			)
		)
		(zone
			(layer "F.Cu")
			(hatch none 0.5)
			(connect_pads
				(clearance 0)
			)
			(min_thickness 0.25)
			(keepout
				(tracks allowed)
				(vias not_allowed)
				(pads allowed)
				(copperpour not_allowed)
				(footprints allowed)
			)
			(placement
				(enabled no)
				(sheetname "")
			)
			(fill
				(thermal_gap 0.5)
				(thermal_bridge_width 0.5)
				(island_removal_mode 0)
			)
			(polygon
				(pts
					(arc
						(start 246.980964 -32.999934)
						(mid 246.218964 -32.999934)
						(end 246.980964 -32.999934)
					)
				)
			)
		)
		(zone
			(layer "F.Cu")
			(hatch none 0.5)
			(connect_pads
				(clearance 0)
			)
			(min_thickness 0.25)
			(keepout
				(tracks allowed)
				(vias not_allowed)
				(pads allowed)
				(copperpour not_allowed)
				(footprints allowed)
			)
			(placement
				(enabled no)
				(sheetname "")
			)
			(fill
				(thermal_gap 0.5)
				(thermal_bridge_width 0.5)
				(island_removal_mode 0)
			)
			(polygon
				(pts
					(arc
						(start 246.980964 -31.999936)
						(mid 246.218964 -31.999936)
						(end 246.980964 -31.999936)
					)
				)
			)
		)
		(zone
			(layer "F.Cu")
			(hatch none 0.5)
			(connect_pads
				(clearance 0)
			)
			(min_thickness 0.25)
			(keepout
				(tracks allowed)
				(vias not_allowed)
				(pads allowed)
				(copperpour not_allowed)
				(footprints allowed)
			)
			(placement
				(enabled no)
				(sheetname "")
			)
			(fill
				(thermal_gap 0.5)
				(thermal_bridge_width 0.5)
				(island_removal_mode 0)
			)
			(polygon
				(pts
					(arc
						(start 246.980964 -30.999938)
						(mid 246.218964 -30.999938)
						(end 246.980964 -30.999938)
					)
				)
			)
		)
		(zone
			(layer "F.Cu")
			(hatch none 0.5)
			(connect_pads
				(clearance 0)
			)
			(min_thickness 0.25)
			(keepout
				(tracks allowed)
				(vias not_allowed)
				(pads allowed)
				(copperpour not_allowed)
				(footprints allowed)
			)
			(placement
				(enabled no)
				(sheetname "")
			)
			(fill
				(thermal_gap 0.5)
				(thermal_bridge_width 0.5)
				(island_removal_mode 0)
			)
			(polygon
				(pts
					(arc
						(start 246.980964 -29.99994)
						(mid 246.218964 -29.99994)
						(end 246.980964 -29.99994)
					)
				)
			)
		)
		(zone
			(layer "F.Cu")
			(hatch none 0.5)
			(connect_pads
				(clearance 0)
			)
			(min_thickness 0.25)
			(keepout
				(tracks allowed)
				(vias not_allowed)
				(pads allowed)
				(copperpour not_allowed)
				(footprints allowed)
			)
			(placement
				(enabled no)
				(sheetname "")
			)
			(fill
				(thermal_gap 0.5)
				(thermal_bridge_width 0.5)
				(island_removal_mode 0)
			)
			(polygon
				(pts
					(arc
						(start 247.980962 -64.99987)
						(mid 247.218962 -64.99987)
						(end 247.980962 -64.99987)
					)
				)
			)
		)
		(zone
			(layer "F.Cu")
			(hatch none 0.5)
			(connect_pads
				(clearance 0)
			)
			(min_thickness 0.25)
			(keepout
				(tracks allowed)
				(vias not_allowed)
				(pads allowed)
				(copperpour not_allowed)
				(footprints allowed)
			)
			(placement
				(enabled no)
				(sheetname "")
			)
			(fill
				(thermal_gap 0.5)
				(thermal_bridge_width 0.5)
				(island_removal_mode 0)
			)
			(polygon
				(pts
					(arc
						(start 247.980962 -63.999872)
						(mid 247.218962 -63.999872)
						(end 247.980962 -63.999872)
					)
				)
			)
		)
		(zone
			(layer "F.Cu")
			(hatch none 0.5)
			(connect_pads
				(clearance 0)
			)
			(min_thickness 0.25)
			(keepout
				(tracks allowed)
				(vias not_allowed)
				(pads allowed)
				(copperpour not_allowed)
				(footprints allowed)
			)
			(placement
				(enabled no)
				(sheetname "")
			)
			(fill
				(thermal_gap 0.5)
				(thermal_bridge_width 0.5)
				(island_removal_mode 0)
			)
			(polygon
				(pts
					(arc
						(start 247.980962 -62.999874)
						(mid 247.218962 -62.999874)
						(end 247.980962 -62.999874)
					)
				)
			)
		)
		(zone
			(layer "F.Cu")
			(hatch none 0.5)
			(connect_pads
				(clearance 0)
			)
			(min_thickness 0.25)
			(keepout
				(tracks allowed)
				(vias not_allowed)
				(pads allowed)
				(copperpour not_allowed)
				(footprints allowed)
			)
			(placement
				(enabled no)
				(sheetname "")
			)
			(fill
				(thermal_gap 0.5)
				(thermal_bridge_width 0.5)
				(island_removal_mode 0)
			)
			(polygon
				(pts
					(arc
						(start 247.980962 -61.999876)
						(mid 247.218962 -61.999876)
						(end 247.980962 -61.999876)
					)
				)
			)
		)
		(zone
			(layer "F.Cu")
			(hatch none 0.5)
			(connect_pads
				(clearance 0)
			)
			(min_thickness 0.25)
			(keepout
				(tracks allowed)
				(vias not_allowed)
				(pads allowed)
				(copperpour not_allowed)
				(footprints allowed)
			)
			(placement
				(enabled no)
				(sheetname "")
			)
			(fill
				(thermal_gap 0.5)
				(thermal_bridge_width 0.5)
				(island_removal_mode 0)
			)
			(polygon
				(pts
					(arc
						(start 247.980962 -60.999878)
						(mid 247.218962 -60.999878)
						(end 247.980962 -60.999878)
					)
				)
			)
		)
		(zone
			(layer "F.Cu")
			(hatch none 0.5)
			(connect_pads
				(clearance 0)
			)
			(min_thickness 0.25)
			(keepout
				(tracks allowed)
				(vias not_allowed)
				(pads allowed)
				(copperpour not_allowed)
				(footprints allowed)
			)
			(placement
				(enabled no)
				(sheetname "")
			)
			(fill
				(thermal_gap 0.5)
				(thermal_bridge_width 0.5)
				(island_removal_mode 0)
			)
			(polygon
				(pts
					(arc
						(start 247.980962 -59.99988)
						(mid 247.218962 -59.99988)
						(end 247.980962 -59.99988)
					)
				)
			)
		)
		(zone
			(layer "F.Cu")
			(hatch none 0.5)
			(connect_pads
				(clearance 0)
			)
			(min_thickness 0.25)
			(keepout
				(tracks allowed)
				(vias not_allowed)
				(pads allowed)
				(copperpour not_allowed)
				(footprints allowed)
			)
			(placement
				(enabled no)
				(sheetname "")
			)
			(fill
				(thermal_gap 0.5)
				(thermal_bridge_width 0.5)
				(island_removal_mode 0)
			)
			(polygon
				(pts
					(arc
						(start 247.980962 -58.999882)
						(mid 247.218962 -58.999882)
						(end 247.980962 -58.999882)
					)
				)
			)
		)
		(zone
			(layer "F.Cu")
			(hatch none 0.5)
			(connect_pads
				(clearance 0)
			)
			(min_thickness 0.25)
			(keepout
				(tracks allowed)
				(vias not_allowed)
				(pads allowed)
				(copperpour not_allowed)
				(footprints allowed)
			)
			(placement
				(enabled no)
				(sheetname "")
			)
			(fill
				(thermal_gap 0.5)
				(thermal_bridge_width 0.5)
				(island_removal_mode 0)
			)
			(polygon
				(pts
					(arc
						(start 247.980962 -57.999884)
						(mid 247.218962 -57.999884)
						(end 247.980962 -57.999884)
					)
				)
			)
		)
		(zone
			(layer "F.Cu")
			(hatch none 0.5)
			(connect_pads
				(clearance 0)
			)
			(min_thickness 0.25)
			(keepout
				(tracks allowed)
				(vias not_allowed)
				(pads allowed)
				(copperpour not_allowed)
				(footprints allowed)
			)
			(placement
				(enabled no)
				(sheetname "")
			)
			(fill
				(thermal_gap 0.5)
				(thermal_bridge_width 0.5)
				(island_removal_mode 0)
			)
			(polygon
				(pts
					(arc
						(start 247.980962 -56.999886)
						(mid 247.218962 -56.999886)
						(end 247.980962 -56.999886)
					)
				)
			)
		)
		(zone
			(layer "F.Cu")
			(hatch none 0.5)
			(connect_pads
				(clearance 0)
			)
			(min_thickness 0.25)
			(keepout
				(tracks allowed)
				(vias not_allowed)
				(pads allowed)
				(copperpour not_allowed)
				(footprints allowed)
			)
			(placement
				(enabled no)
				(sheetname "")
			)
			(fill
				(thermal_gap 0.5)
				(thermal_bridge_width 0.5)
				(island_removal_mode 0)
			)
			(polygon
				(pts
					(arc
						(start 247.980962 -55.999888)
						(mid 247.218962 -55.999888)
						(end 247.980962 -55.999888)
					)
				)
			)
		)
		(zone
			(layer "F.Cu")
			(hatch none 0.5)
			(connect_pads
				(clearance 0)
			)
			(min_thickness 0.25)
			(keepout
				(tracks allowed)
				(vias not_allowed)
				(pads allowed)
				(copperpour not_allowed)
				(footprints allowed)
			)
			(placement
				(enabled no)
				(sheetname "")
			)
			(fill
				(thermal_gap 0.5)
				(thermal_bridge_width 0.5)
				(island_removal_mode 0)
			)
			(polygon
				(pts
					(arc
						(start 247.980962 -54.99989)
						(mid 247.218962 -54.99989)
						(end 247.980962 -54.99989)
					)
				)
			)
		)
		(zone
			(layer "F.Cu")
			(hatch none 0.5)
			(connect_pads
				(clearance 0)
			)
			(min_thickness 0.25)
			(keepout
				(tracks allowed)
				(vias not_allowed)
				(pads allowed)
				(copperpour not_allowed)
				(footprints allowed)
			)
			(placement
				(enabled no)
				(sheetname "")
			)
			(fill
				(thermal_gap 0.5)
				(thermal_bridge_width 0.5)
				(island_removal_mode 0)
			)
			(polygon
				(pts
					(arc
						(start 247.980962 -53.999892)
						(mid 247.218962 -53.999892)
						(end 247.980962 -53.999892)
					)
				)
			)
		)
		(zone
			(layer "F.Cu")
			(hatch none 0.5)
			(connect_pads
				(clearance 0)
			)
			(min_thickness 0.25)
			(keepout
				(tracks allowed)
				(vias not_allowed)
				(pads allowed)
				(copperpour not_allowed)
				(footprints allowed)
			)
			(placement
				(enabled no)
				(sheetname "")
			)
			(fill
				(thermal_gap 0.5)
				(thermal_bridge_width 0.5)
				(island_removal_mode 0)
			)
			(polygon
				(pts
					(arc
						(start 247.980962 -52.999894)
						(mid 247.218962 -52.999894)
						(end 247.980962 -52.999894)
					)
				)
			)
		)
		(zone
			(layer "F.Cu")
			(hatch none 0.5)
			(connect_pads
				(clearance 0)
			)
			(min_thickness 0.25)
			(keepout
				(tracks allowed)
				(vias not_allowed)
				(pads allowed)
				(copperpour not_allowed)
				(footprints allowed)
			)
			(placement
				(enabled no)
				(sheetname "")
			)
			(fill
				(thermal_gap 0.5)
				(thermal_bridge_width 0.5)
				(island_removal_mode 0)
			)
			(polygon
				(pts
					(arc
						(start 247.980962 -51.999896)
						(mid 247.218962 -51.999896)
						(end 247.980962 -51.999896)
					)
				)
			)
		)
		(zone
			(layer "F.Cu")
			(hatch none 0.5)
			(connect_pads
				(clearance 0)
			)
			(min_thickness 0.25)
			(keepout
				(tracks allowed)
				(vias not_allowed)
				(pads allowed)
				(copperpour not_allowed)
				(footprints allowed)
			)
			(placement
				(enabled no)
				(sheetname "")
			)
			(fill
				(thermal_gap 0.5)
				(thermal_bridge_width 0.5)
				(island_removal_mode 0)
			)
			(polygon
				(pts
					(arc
						(start 247.980962 -50.999898)
						(mid 247.218962 -50.999898)
						(end 247.980962 -50.999898)
					)
				)
			)
		)
		(zone
			(layer "F.Cu")
			(hatch none 0.5)
			(connect_pads
				(clearance 0)
			)
			(min_thickness 0.25)
			(keepout
				(tracks allowed)
				(vias not_allowed)
				(pads allowed)
				(copperpour not_allowed)
				(footprints allowed)
			)
			(placement
				(enabled no)
				(sheetname "")
			)
			(fill
				(thermal_gap 0.5)
				(thermal_bridge_width 0.5)
				(island_removal_mode 0)
			)
			(polygon
				(pts
					(arc
						(start 247.980962 -49.9999)
						(mid 247.218962 -49.9999)
						(end 247.980962 -49.9999)
					)
				)
			)
		)
		(zone
			(layer "F.Cu")
			(hatch none 0.5)
			(connect_pads
				(clearance 0)
			)
			(min_thickness 0.25)
			(keepout
				(tracks allowed)
				(vias not_allowed)
				(pads allowed)
				(copperpour not_allowed)
				(footprints allowed)
			)
			(placement
				(enabled no)
				(sheetname "")
			)
			(fill
				(thermal_gap 0.5)
				(thermal_bridge_width 0.5)
				(island_removal_mode 0)
			)
			(polygon
				(pts
					(arc
						(start 247.980962 -48.999902)
						(mid 247.218962 -48.999902)
						(end 247.980962 -48.999902)
					)
				)
			)
		)
		(zone
			(layer "F.Cu")
			(hatch none 0.5)
			(connect_pads
				(clearance 0)
			)
			(min_thickness 0.25)
			(keepout
				(tracks allowed)
				(vias not_allowed)
				(pads allowed)
				(copperpour not_allowed)
				(footprints allowed)
			)
			(placement
				(enabled no)
				(sheetname "")
			)
			(fill
				(thermal_gap 0.5)
				(thermal_bridge_width 0.5)
				(island_removal_mode 0)
			)
			(polygon
				(pts
					(arc
						(start 247.980962 -47.999904)
						(mid 247.218962 -47.999904)
						(end 247.980962 -47.999904)
					)
				)
			)
		)
		(zone
			(layer "F.Cu")
			(hatch none 0.5)
			(connect_pads
				(clearance 0)
			)
			(min_thickness 0.25)
			(keepout
				(tracks allowed)
				(vias not_allowed)
				(pads allowed)
				(copperpour not_allowed)
				(footprints allowed)
			)
			(placement
				(enabled no)
				(sheetname "")
			)
			(fill
				(thermal_gap 0.5)
				(thermal_bridge_width 0.5)
				(island_removal_mode 0)
			)
			(polygon
				(pts
					(arc
						(start 247.980962 -46.999906)
						(mid 247.218962 -46.999906)
						(end 247.980962 -46.999906)
					)
				)
			)
		)
		(zone
			(layer "F.Cu")
			(hatch none 0.5)
			(connect_pads
				(clearance 0)
			)
			(min_thickness 0.25)
			(keepout
				(tracks allowed)
				(vias not_allowed)
				(pads allowed)
				(copperpour not_allowed)
				(footprints allowed)
			)
			(placement
				(enabled no)
				(sheetname "")
			)
			(fill
				(thermal_gap 0.5)
				(thermal_bridge_width 0.5)
				(island_removal_mode 0)
			)
			(polygon
				(pts
					(arc
						(start 247.980962 -45.999908)
						(mid 247.218962 -45.999908)
						(end 247.980962 -45.999908)
					)
				)
			)
		)
		(zone
			(layer "F.Cu")
			(hatch none 0.5)
			(connect_pads
				(clearance 0)
			)
			(min_thickness 0.25)
			(keepout
				(tracks allowed)
				(vias not_allowed)
				(pads allowed)
				(copperpour not_allowed)
				(footprints allowed)
			)
			(placement
				(enabled no)
				(sheetname "")
			)
			(fill
				(thermal_gap 0.5)
				(thermal_bridge_width 0.5)
				(island_removal_mode 0)
			)
			(polygon
				(pts
					(arc
						(start 247.980962 -44.99991)
						(mid 247.218962 -44.99991)
						(end 247.980962 -44.99991)
					)
				)
			)
		)
		(zone
			(layer "F.Cu")
			(hatch none 0.5)
			(connect_pads
				(clearance 0)
			)
			(min_thickness 0.25)
			(keepout
				(tracks allowed)
				(vias not_allowed)
				(pads allowed)
				(copperpour not_allowed)
				(footprints allowed)
			)
			(placement
				(enabled no)
				(sheetname "")
			)
			(fill
				(thermal_gap 0.5)
				(thermal_bridge_width 0.5)
				(island_removal_mode 0)
			)
			(polygon
				(pts
					(arc
						(start 247.980962 -43.999912)
						(mid 247.218962 -43.999912)
						(end 247.980962 -43.999912)
					)
				)
			)
		)
		(zone
			(layer "F.Cu")
			(hatch none 0.5)
			(connect_pads
				(clearance 0)
			)
			(min_thickness 0.25)
			(keepout
				(tracks allowed)
				(vias not_allowed)
				(pads allowed)
				(copperpour not_allowed)
				(footprints allowed)
			)
			(placement
				(enabled no)
				(sheetname "")
			)
			(fill
				(thermal_gap 0.5)
				(thermal_bridge_width 0.5)
				(island_removal_mode 0)
			)
			(polygon
				(pts
					(arc
						(start 247.980962 -42.999914)
						(mid 247.218962 -42.999914)
						(end 247.980962 -42.999914)
					)
				)
			)
		)
		(zone
			(layer "F.Cu")
			(hatch none 0.5)
			(connect_pads
				(clearance 0)
			)
			(min_thickness 0.25)
			(keepout
				(tracks allowed)
				(vias not_allowed)
				(pads allowed)
				(copperpour not_allowed)
				(footprints allowed)
			)
			(placement
				(enabled no)
				(sheetname "")
			)
			(fill
				(thermal_gap 0.5)
				(thermal_bridge_width 0.5)
				(island_removal_mode 0)
			)
			(polygon
				(pts
					(arc
						(start 247.980962 -41.999916)
						(mid 247.218962 -41.999916)
						(end 247.980962 -41.999916)
					)
				)
			)
		)
		(zone
			(layer "F.Cu")
			(hatch none 0.5)
			(connect_pads
				(clearance 0)
			)
			(min_thickness 0.25)
			(keepout
				(tracks allowed)
				(vias not_allowed)
				(pads allowed)
				(copperpour not_allowed)
				(footprints allowed)
			)
			(placement
				(enabled no)
				(sheetname "")
			)
			(fill
				(thermal_gap 0.5)
				(thermal_bridge_width 0.5)
				(island_removal_mode 0)
			)
			(polygon
				(pts
					(arc
						(start 247.980962 -40.999918)
						(mid 247.218962 -40.999918)
						(end 247.980962 -40.999918)
					)
				)
			)
		)
		(zone
			(layer "F.Cu")
			(hatch none 0.5)
			(connect_pads
				(clearance 0)
			)
			(min_thickness 0.25)
			(keepout
				(tracks allowed)
				(vias not_allowed)
				(pads allowed)
				(copperpour not_allowed)
				(footprints allowed)
			)
			(placement
				(enabled no)
				(sheetname "")
			)
			(fill
				(thermal_gap 0.5)
				(thermal_bridge_width 0.5)
				(island_removal_mode 0)
			)
			(polygon
				(pts
					(arc
						(start 247.980962 -39.99992)
						(mid 247.218962 -39.99992)
						(end 247.980962 -39.99992)
					)
				)
			)
		)
		(zone
			(layer "F.Cu")
			(hatch none 0.5)
			(connect_pads
				(clearance 0)
			)
			(min_thickness 0.25)
			(keepout
				(tracks allowed)
				(vias not_allowed)
				(pads allowed)
				(copperpour not_allowed)
				(footprints allowed)
			)
			(placement
				(enabled no)
				(sheetname "")
			)
			(fill
				(thermal_gap 0.5)
				(thermal_bridge_width 0.5)
				(island_removal_mode 0)
			)
			(polygon
				(pts
					(arc
						(start 247.980962 -38.999922)
						(mid 247.218962 -38.999922)
						(end 247.980962 -38.999922)
					)
				)
			)
		)
		(zone
			(layer "F.Cu")
			(hatch none 0.5)
			(connect_pads
				(clearance 0)
			)
			(min_thickness 0.25)
			(keepout
				(tracks allowed)
				(vias not_allowed)
				(pads allowed)
				(copperpour not_allowed)
				(footprints allowed)
			)
			(placement
				(enabled no)
				(sheetname "")
			)
			(fill
				(thermal_gap 0.5)
				(thermal_bridge_width 0.5)
				(island_removal_mode 0)
			)
			(polygon
				(pts
					(arc
						(start 247.980962 -37.999924)
						(mid 247.218962 -37.999924)
						(end 247.980962 -37.999924)
					)
				)
			)
		)
		(zone
			(layer "F.Cu")
			(hatch none 0.5)
			(connect_pads
				(clearance 0)
			)
			(min_thickness 0.25)
			(keepout
				(tracks allowed)
				(vias not_allowed)
				(pads allowed)
				(copperpour not_allowed)
				(footprints allowed)
			)
			(placement
				(enabled no)
				(sheetname "")
			)
			(fill
				(thermal_gap 0.5)
				(thermal_bridge_width 0.5)
				(island_removal_mode 0)
			)
			(polygon
				(pts
					(arc
						(start 247.980962 -36.999926)
						(mid 247.218962 -36.999926)
						(end 247.980962 -36.999926)
					)
				)
			)
		)
		(zone
			(layer "F.Cu")
			(hatch none 0.5)
			(connect_pads
				(clearance 0)
			)
			(min_thickness 0.25)
			(keepout
				(tracks allowed)
				(vias not_allowed)
				(pads allowed)
				(copperpour not_allowed)
				(footprints allowed)
			)
			(placement
				(enabled no)
				(sheetname "")
			)
			(fill
				(thermal_gap 0.5)
				(thermal_bridge_width 0.5)
				(island_removal_mode 0)
			)
			(polygon
				(pts
					(arc
						(start 247.980962 -35.999928)
						(mid 247.218962 -35.999928)
						(end 247.980962 -35.999928)
					)
				)
			)
		)
		(zone
			(layer "F.Cu")
			(hatch none 0.5)
			(connect_pads
				(clearance 0)
			)
			(min_thickness 0.25)
			(keepout
				(tracks allowed)
				(vias not_allowed)
				(pads allowed)
				(copperpour not_allowed)
				(footprints allowed)
			)
			(placement
				(enabled no)
				(sheetname "")
			)
			(fill
				(thermal_gap 0.5)
				(thermal_bridge_width 0.5)
				(island_removal_mode 0)
			)
			(polygon
				(pts
					(arc
						(start 247.980962 -34.99993)
						(mid 247.218962 -34.99993)
						(end 247.980962 -34.99993)
					)
				)
			)
		)
		(zone
			(layer "F.Cu")
			(hatch none 0.5)
			(connect_pads
				(clearance 0)
			)
			(min_thickness 0.25)
			(keepout
				(tracks allowed)
				(vias not_allowed)
				(pads allowed)
				(copperpour not_allowed)
				(footprints allowed)
			)
			(placement
				(enabled no)
				(sheetname "")
			)
			(fill
				(thermal_gap 0.5)
				(thermal_bridge_width 0.5)
				(island_removal_mode 0)
			)
			(polygon
				(pts
					(arc
						(start 247.980962 -33.999932)
						(mid 247.218962 -33.999932)
						(end 247.980962 -33.999932)
					)
				)
			)
		)
		(zone
			(layer "F.Cu")
			(hatch none 0.5)
			(connect_pads
				(clearance 0)
			)
			(min_thickness 0.25)
			(keepout
				(tracks allowed)
				(vias not_allowed)
				(pads allowed)
				(copperpour not_allowed)
				(footprints allowed)
			)
			(placement
				(enabled no)
				(sheetname "")
			)
			(fill
				(thermal_gap 0.5)
				(thermal_bridge_width 0.5)
				(island_removal_mode 0)
			)
			(polygon
				(pts
					(arc
						(start 247.980962 -32.999934)
						(mid 247.218962 -32.999934)
						(end 247.980962 -32.999934)
					)
				)
			)
		)
		(zone
			(layer "F.Cu")
			(hatch none 0.5)
			(connect_pads
				(clearance 0)
			)
			(min_thickness 0.25)
			(keepout
				(tracks allowed)
				(vias not_allowed)
				(pads allowed)
				(copperpour not_allowed)
				(footprints allowed)
			)
			(placement
				(enabled no)
				(sheetname "")
			)
			(fill
				(thermal_gap 0.5)
				(thermal_bridge_width 0.5)
				(island_removal_mode 0)
			)
			(polygon
				(pts
					(arc
						(start 247.980962 -31.999936)
						(mid 247.218962 -31.999936)
						(end 247.980962 -31.999936)
					)
				)
			)
		)
		(zone
			(layer "F.Cu")
			(hatch none 0.5)
			(connect_pads
				(clearance 0)
			)
			(min_thickness 0.25)
			(keepout
				(tracks allowed)
				(vias not_allowed)
				(pads allowed)
				(copperpour not_allowed)
				(footprints allowed)
			)
			(placement
				(enabled no)
				(sheetname "")
			)
			(fill
				(thermal_gap 0.5)
				(thermal_bridge_width 0.5)
				(island_removal_mode 0)
			)
			(polygon
				(pts
					(arc
						(start 247.980962 -30.999938)
						(mid 247.218962 -30.999938)
						(end 247.980962 -30.999938)
					)
				)
			)
		)
		(zone
			(layer "F.Cu")
			(hatch none 0.5)
			(connect_pads
				(clearance 0)
			)
			(min_thickness 0.25)
			(keepout
				(tracks allowed)
				(vias not_allowed)
				(pads allowed)
				(copperpour not_allowed)
				(footprints allowed)
			)
			(placement
				(enabled no)
				(sheetname "")
			)
			(fill
				(thermal_gap 0.5)
				(thermal_bridge_width 0.5)
				(island_removal_mode 0)
			)
			(polygon
				(pts
					(arc
						(start 248.98096 -65.999868)
						(mid 248.21896 -65.999868)
						(end 248.98096 -65.999868)
					)
				)
			)
		)
		(zone
			(layer "F.Cu")
			(hatch none 0.5)
			(connect_pads
				(clearance 0)
			)
			(min_thickness 0.25)
			(keepout
				(tracks allowed)
				(vias not_allowed)
				(pads allowed)
				(copperpour not_allowed)
				(footprints allowed)
			)
			(placement
				(enabled no)
				(sheetname "")
			)
			(fill
				(thermal_gap 0.5)
				(thermal_bridge_width 0.5)
				(island_removal_mode 0)
			)
			(polygon
				(pts
					(arc
						(start 248.98096 -64.99987)
						(mid 248.21896 -64.99987)
						(end 248.98096 -64.99987)
					)
				)
			)
		)
		(zone
			(layer "F.Cu")
			(hatch none 0.5)
			(connect_pads
				(clearance 0)
			)
			(min_thickness 0.25)
			(keepout
				(tracks allowed)
				(vias not_allowed)
				(pads allowed)
				(copperpour not_allowed)
				(footprints allowed)
			)
			(placement
				(enabled no)
				(sheetname "")
			)
			(fill
				(thermal_gap 0.5)
				(thermal_bridge_width 0.5)
				(island_removal_mode 0)
			)
			(polygon
				(pts
					(arc
						(start 248.98096 -63.999872)
						(mid 248.21896 -63.999872)
						(end 248.98096 -63.999872)
					)
				)
			)
		)
		(zone
			(layer "F.Cu")
			(hatch none 0.5)
			(connect_pads
				(clearance 0)
			)
			(min_thickness 0.25)
			(keepout
				(tracks allowed)
				(vias not_allowed)
				(pads allowed)
				(copperpour not_allowed)
				(footprints allowed)
			)
			(placement
				(enabled no)
				(sheetname "")
			)
			(fill
				(thermal_gap 0.5)
				(thermal_bridge_width 0.5)
				(island_removal_mode 0)
			)
			(polygon
				(pts
					(arc
						(start 248.98096 -62.999874)
						(mid 248.21896 -62.999874)
						(end 248.98096 -62.999874)
					)
				)
			)
		)
		(zone
			(layer "F.Cu")
			(hatch none 0.5)
			(connect_pads
				(clearance 0)
			)
			(min_thickness 0.25)
			(keepout
				(tracks allowed)
				(vias not_allowed)
				(pads allowed)
				(copperpour not_allowed)
				(footprints allowed)
			)
			(placement
				(enabled no)
				(sheetname "")
			)
			(fill
				(thermal_gap 0.5)
				(thermal_bridge_width 0.5)
				(island_removal_mode 0)
			)
			(polygon
				(pts
					(arc
						(start 248.98096 -61.999876)
						(mid 248.21896 -61.999876)
						(end 248.98096 -61.999876)
					)
				)
			)
		)
		(zone
			(layer "F.Cu")
			(hatch none 0.5)
			(connect_pads
				(clearance 0)
			)
			(min_thickness 0.25)
			(keepout
				(tracks allowed)
				(vias not_allowed)
				(pads allowed)
				(copperpour not_allowed)
				(footprints allowed)
			)
			(placement
				(enabled no)
				(sheetname "")
			)
			(fill
				(thermal_gap 0.5)
				(thermal_bridge_width 0.5)
				(island_removal_mode 0)
			)
			(polygon
				(pts
					(arc
						(start 248.98096 -60.999878)
						(mid 248.21896 -60.999878)
						(end 248.98096 -60.999878)
					)
				)
			)
		)
		(zone
			(layer "F.Cu")
			(hatch none 0.5)
			(connect_pads
				(clearance 0)
			)
			(min_thickness 0.25)
			(keepout
				(tracks allowed)
				(vias not_allowed)
				(pads allowed)
				(copperpour not_allowed)
				(footprints allowed)
			)
			(placement
				(enabled no)
				(sheetname "")
			)
			(fill
				(thermal_gap 0.5)
				(thermal_bridge_width 0.5)
				(island_removal_mode 0)
			)
			(polygon
				(pts
					(arc
						(start 248.98096 -59.99988)
						(mid 248.21896 -59.99988)
						(end 248.98096 -59.99988)
					)
				)
			)
		)
		(zone
			(layer "F.Cu")
			(hatch none 0.5)
			(connect_pads
				(clearance 0)
			)
			(min_thickness 0.25)
			(keepout
				(tracks allowed)
				(vias not_allowed)
				(pads allowed)
				(copperpour not_allowed)
				(footprints allowed)
			)
			(placement
				(enabled no)
				(sheetname "")
			)
			(fill
				(thermal_gap 0.5)
				(thermal_bridge_width 0.5)
				(island_removal_mode 0)
			)
			(polygon
				(pts
					(arc
						(start 248.98096 -58.999882)
						(mid 248.21896 -58.999882)
						(end 248.98096 -58.999882)
					)
				)
			)
		)
		(zone
			(layer "F.Cu")
			(hatch none 0.5)
			(connect_pads
				(clearance 0)
			)
			(min_thickness 0.25)
			(keepout
				(tracks allowed)
				(vias not_allowed)
				(pads allowed)
				(copperpour not_allowed)
				(footprints allowed)
			)
			(placement
				(enabled no)
				(sheetname "")
			)
			(fill
				(thermal_gap 0.5)
				(thermal_bridge_width 0.5)
				(island_removal_mode 0)
			)
			(polygon
				(pts
					(arc
						(start 248.98096 -57.999884)
						(mid 248.21896 -57.999884)
						(end 248.98096 -57.999884)
					)
				)
			)
		)
		(zone
			(layer "F.Cu")
			(hatch none 0.5)
			(connect_pads
				(clearance 0)
			)
			(min_thickness 0.25)
			(keepout
				(tracks allowed)
				(vias not_allowed)
				(pads allowed)
				(copperpour not_allowed)
				(footprints allowed)
			)
			(placement
				(enabled no)
				(sheetname "")
			)
			(fill
				(thermal_gap 0.5)
				(thermal_bridge_width 0.5)
				(island_removal_mode 0)
			)
			(polygon
				(pts
					(arc
						(start 248.98096 -56.999886)
						(mid 248.21896 -56.999886)
						(end 248.98096 -56.999886)
					)
				)
			)
		)
		(zone
			(layer "F.Cu")
			(hatch none 0.5)
			(connect_pads
				(clearance 0)
			)
			(min_thickness 0.25)
			(keepout
				(tracks allowed)
				(vias not_allowed)
				(pads allowed)
				(copperpour not_allowed)
				(footprints allowed)
			)
			(placement
				(enabled no)
				(sheetname "")
			)
			(fill
				(thermal_gap 0.5)
				(thermal_bridge_width 0.5)
				(island_removal_mode 0)
			)
			(polygon
				(pts
					(arc
						(start 248.98096 -55.999888)
						(mid 248.21896 -55.999888)
						(end 248.98096 -55.999888)
					)
				)
			)
		)
		(zone
			(layer "F.Cu")
			(hatch none 0.5)
			(connect_pads
				(clearance 0)
			)
			(min_thickness 0.25)
			(keepout
				(tracks allowed)
				(vias not_allowed)
				(pads allowed)
				(copperpour not_allowed)
				(footprints allowed)
			)
			(placement
				(enabled no)
				(sheetname "")
			)
			(fill
				(thermal_gap 0.5)
				(thermal_bridge_width 0.5)
				(island_removal_mode 0)
			)
			(polygon
				(pts
					(arc
						(start 248.98096 -54.99989)
						(mid 248.21896 -54.99989)
						(end 248.98096 -54.99989)
					)
				)
			)
		)
		(zone
			(layer "F.Cu")
			(hatch none 0.5)
			(connect_pads
				(clearance 0)
			)
			(min_thickness 0.25)
			(keepout
				(tracks allowed)
				(vias not_allowed)
				(pads allowed)
				(copperpour not_allowed)
				(footprints allowed)
			)
			(placement
				(enabled no)
				(sheetname "")
			)
			(fill
				(thermal_gap 0.5)
				(thermal_bridge_width 0.5)
				(island_removal_mode 0)
			)
			(polygon
				(pts
					(arc
						(start 248.98096 -53.999892)
						(mid 248.21896 -53.999892)
						(end 248.98096 -53.999892)
					)
				)
			)
		)
		(zone
			(layer "F.Cu")
			(hatch none 0.5)
			(connect_pads
				(clearance 0)
			)
			(min_thickness 0.25)
			(keepout
				(tracks allowed)
				(vias not_allowed)
				(pads allowed)
				(copperpour not_allowed)
				(footprints allowed)
			)
			(placement
				(enabled no)
				(sheetname "")
			)
			(fill
				(thermal_gap 0.5)
				(thermal_bridge_width 0.5)
				(island_removal_mode 0)
			)
			(polygon
				(pts
					(arc
						(start 248.98096 -52.999894)
						(mid 248.21896 -52.999894)
						(end 248.98096 -52.999894)
					)
				)
			)
		)
		(zone
			(layer "F.Cu")
			(hatch none 0.5)
			(connect_pads
				(clearance 0)
			)
			(min_thickness 0.25)
			(keepout
				(tracks allowed)
				(vias not_allowed)
				(pads allowed)
				(copperpour not_allowed)
				(footprints allowed)
			)
			(placement
				(enabled no)
				(sheetname "")
			)
			(fill
				(thermal_gap 0.5)
				(thermal_bridge_width 0.5)
				(island_removal_mode 0)
			)
			(polygon
				(pts
					(arc
						(start 248.98096 -51.999896)
						(mid 248.21896 -51.999896)
						(end 248.98096 -51.999896)
					)
				)
			)
		)
		(zone
			(layer "F.Cu")
			(hatch none 0.5)
			(connect_pads
				(clearance 0)
			)
			(min_thickness 0.25)
			(keepout
				(tracks allowed)
				(vias not_allowed)
				(pads allowed)
				(copperpour not_allowed)
				(footprints allowed)
			)
			(placement
				(enabled no)
				(sheetname "")
			)
			(fill
				(thermal_gap 0.5)
				(thermal_bridge_width 0.5)
				(island_removal_mode 0)
			)
			(polygon
				(pts
					(arc
						(start 248.98096 -50.999898)
						(mid 248.21896 -50.999898)
						(end 248.98096 -50.999898)
					)
				)
			)
		)
		(zone
			(layer "F.Cu")
			(hatch none 0.5)
			(connect_pads
				(clearance 0)
			)
			(min_thickness 0.25)
			(keepout
				(tracks allowed)
				(vias not_allowed)
				(pads allowed)
				(copperpour not_allowed)
				(footprints allowed)
			)
			(placement
				(enabled no)
				(sheetname "")
			)
			(fill
				(thermal_gap 0.5)
				(thermal_bridge_width 0.5)
				(island_removal_mode 0)
			)
			(polygon
				(pts
					(arc
						(start 248.98096 -49.9999)
						(mid 248.21896 -49.9999)
						(end 248.98096 -49.9999)
					)
				)
			)
		)
		(zone
			(layer "F.Cu")
			(hatch none 0.5)
			(connect_pads
				(clearance 0)
			)
			(min_thickness 0.25)
			(keepout
				(tracks allowed)
				(vias not_allowed)
				(pads allowed)
				(copperpour not_allowed)
				(footprints allowed)
			)
			(placement
				(enabled no)
				(sheetname "")
			)
			(fill
				(thermal_gap 0.5)
				(thermal_bridge_width 0.5)
				(island_removal_mode 0)
			)
			(polygon
				(pts
					(arc
						(start 248.98096 -48.999902)
						(mid 248.21896 -48.999902)
						(end 248.98096 -48.999902)
					)
				)
			)
		)
		(zone
			(layer "F.Cu")
			(hatch none 0.5)
			(connect_pads
				(clearance 0)
			)
			(min_thickness 0.25)
			(keepout
				(tracks allowed)
				(vias not_allowed)
				(pads allowed)
				(copperpour not_allowed)
				(footprints allowed)
			)
			(placement
				(enabled no)
				(sheetname "")
			)
			(fill
				(thermal_gap 0.5)
				(thermal_bridge_width 0.5)
				(island_removal_mode 0)
			)
			(polygon
				(pts
					(arc
						(start 248.98096 -47.999904)
						(mid 248.21896 -47.999904)
						(end 248.98096 -47.999904)
					)
				)
			)
		)
		(zone
			(layer "F.Cu")
			(hatch none 0.5)
			(connect_pads
				(clearance 0)
			)
			(min_thickness 0.25)
			(keepout
				(tracks allowed)
				(vias not_allowed)
				(pads allowed)
				(copperpour not_allowed)
				(footprints allowed)
			)
			(placement
				(enabled no)
				(sheetname "")
			)
			(fill
				(thermal_gap 0.5)
				(thermal_bridge_width 0.5)
				(island_removal_mode 0)
			)
			(polygon
				(pts
					(arc
						(start 248.98096 -46.999906)
						(mid 248.21896 -46.999906)
						(end 248.98096 -46.999906)
					)
				)
			)
		)
		(zone
			(layer "F.Cu")
			(hatch none 0.5)
			(connect_pads
				(clearance 0)
			)
			(min_thickness 0.25)
			(keepout
				(tracks allowed)
				(vias not_allowed)
				(pads allowed)
				(copperpour not_allowed)
				(footprints allowed)
			)
			(placement
				(enabled no)
				(sheetname "")
			)
			(fill
				(thermal_gap 0.5)
				(thermal_bridge_width 0.5)
				(island_removal_mode 0)
			)
			(polygon
				(pts
					(arc
						(start 248.98096 -45.999908)
						(mid 248.21896 -45.999908)
						(end 248.98096 -45.999908)
					)
				)
			)
		)
		(zone
			(layer "F.Cu")
			(hatch none 0.5)
			(connect_pads
				(clearance 0)
			)
			(min_thickness 0.25)
			(keepout
				(tracks allowed)
				(vias not_allowed)
				(pads allowed)
				(copperpour not_allowed)
				(footprints allowed)
			)
			(placement
				(enabled no)
				(sheetname "")
			)
			(fill
				(thermal_gap 0.5)
				(thermal_bridge_width 0.5)
				(island_removal_mode 0)
			)
			(polygon
				(pts
					(arc
						(start 248.98096 -44.99991)
						(mid 248.21896 -44.99991)
						(end 248.98096 -44.99991)
					)
				)
			)
		)
		(zone
			(layer "F.Cu")
			(hatch none 0.5)
			(connect_pads
				(clearance 0)
			)
			(min_thickness 0.25)
			(keepout
				(tracks allowed)
				(vias not_allowed)
				(pads allowed)
				(copperpour not_allowed)
				(footprints allowed)
			)
			(placement
				(enabled no)
				(sheetname "")
			)
			(fill
				(thermal_gap 0.5)
				(thermal_bridge_width 0.5)
				(island_removal_mode 0)
			)
			(polygon
				(pts
					(arc
						(start 248.98096 -43.999912)
						(mid 248.21896 -43.999912)
						(end 248.98096 -43.999912)
					)
				)
			)
		)
		(zone
			(layer "F.Cu")
			(hatch none 0.5)
			(connect_pads
				(clearance 0)
			)
			(min_thickness 0.25)
			(keepout
				(tracks allowed)
				(vias not_allowed)
				(pads allowed)
				(copperpour not_allowed)
				(footprints allowed)
			)
			(placement
				(enabled no)
				(sheetname "")
			)
			(fill
				(thermal_gap 0.5)
				(thermal_bridge_width 0.5)
				(island_removal_mode 0)
			)
			(polygon
				(pts
					(arc
						(start 248.98096 -42.999914)
						(mid 248.21896 -42.999914)
						(end 248.98096 -42.999914)
					)
				)
			)
		)
		(zone
			(layer "F.Cu")
			(hatch none 0.5)
			(connect_pads
				(clearance 0)
			)
			(min_thickness 0.25)
			(keepout
				(tracks allowed)
				(vias not_allowed)
				(pads allowed)
				(copperpour not_allowed)
				(footprints allowed)
			)
			(placement
				(enabled no)
				(sheetname "")
			)
			(fill
				(thermal_gap 0.5)
				(thermal_bridge_width 0.5)
				(island_removal_mode 0)
			)
			(polygon
				(pts
					(arc
						(start 248.98096 -41.999916)
						(mid 248.21896 -41.999916)
						(end 248.98096 -41.999916)
					)
				)
			)
		)
		(zone
			(layer "F.Cu")
			(hatch none 0.5)
			(connect_pads
				(clearance 0)
			)
			(min_thickness 0.25)
			(keepout
				(tracks allowed)
				(vias not_allowed)
				(pads allowed)
				(copperpour not_allowed)
				(footprints allowed)
			)
			(placement
				(enabled no)
				(sheetname "")
			)
			(fill
				(thermal_gap 0.5)
				(thermal_bridge_width 0.5)
				(island_removal_mode 0)
			)
			(polygon
				(pts
					(arc
						(start 248.98096 -40.999918)
						(mid 248.21896 -40.999918)
						(end 248.98096 -40.999918)
					)
				)
			)
		)
		(zone
			(layer "F.Cu")
			(hatch none 0.5)
			(connect_pads
				(clearance 0)
			)
			(min_thickness 0.25)
			(keepout
				(tracks allowed)
				(vias not_allowed)
				(pads allowed)
				(copperpour not_allowed)
				(footprints allowed)
			)
			(placement
				(enabled no)
				(sheetname "")
			)
			(fill
				(thermal_gap 0.5)
				(thermal_bridge_width 0.5)
				(island_removal_mode 0)
			)
			(polygon
				(pts
					(arc
						(start 248.98096 -39.99992)
						(mid 248.21896 -39.99992)
						(end 248.98096 -39.99992)
					)
				)
			)
		)
		(zone
			(layer "F.Cu")
			(hatch none 0.5)
			(connect_pads
				(clearance 0)
			)
			(min_thickness 0.25)
			(keepout
				(tracks allowed)
				(vias not_allowed)
				(pads allowed)
				(copperpour not_allowed)
				(footprints allowed)
			)
			(placement
				(enabled no)
				(sheetname "")
			)
			(fill
				(thermal_gap 0.5)
				(thermal_bridge_width 0.5)
				(island_removal_mode 0)
			)
			(polygon
				(pts
					(arc
						(start 248.98096 -38.999922)
						(mid 248.21896 -38.999922)
						(end 248.98096 -38.999922)
					)
				)
			)
		)
		(zone
			(layer "F.Cu")
			(hatch none 0.5)
			(connect_pads
				(clearance 0)
			)
			(min_thickness 0.25)
			(keepout
				(tracks allowed)
				(vias not_allowed)
				(pads allowed)
				(copperpour not_allowed)
				(footprints allowed)
			)
			(placement
				(enabled no)
				(sheetname "")
			)
			(fill
				(thermal_gap 0.5)
				(thermal_bridge_width 0.5)
				(island_removal_mode 0)
			)
			(polygon
				(pts
					(arc
						(start 248.98096 -37.999924)
						(mid 248.21896 -37.999924)
						(end 248.98096 -37.999924)
					)
				)
			)
		)
		(zone
			(layer "F.Cu")
			(hatch none 0.5)
			(connect_pads
				(clearance 0)
			)
			(min_thickness 0.25)
			(keepout
				(tracks allowed)
				(vias not_allowed)
				(pads allowed)
				(copperpour not_allowed)
				(footprints allowed)
			)
			(placement
				(enabled no)
				(sheetname "")
			)
			(fill
				(thermal_gap 0.5)
				(thermal_bridge_width 0.5)
				(island_removal_mode 0)
			)
			(polygon
				(pts
					(arc
						(start 248.98096 -36.999926)
						(mid 248.21896 -36.999926)
						(end 248.98096 -36.999926)
					)
				)
			)
		)
		(zone
			(layer "F.Cu")
			(hatch none 0.5)
			(connect_pads
				(clearance 0)
			)
			(min_thickness 0.25)
			(keepout
				(tracks allowed)
				(vias not_allowed)
				(pads allowed)
				(copperpour not_allowed)
				(footprints allowed)
			)
			(placement
				(enabled no)
				(sheetname "")
			)
			(fill
				(thermal_gap 0.5)
				(thermal_bridge_width 0.5)
				(island_removal_mode 0)
			)
			(polygon
				(pts
					(arc
						(start 248.98096 -35.999928)
						(mid 248.21896 -35.999928)
						(end 248.98096 -35.999928)
					)
				)
			)
		)
		(zone
			(layer "F.Cu")
			(hatch none 0.5)
			(connect_pads
				(clearance 0)
			)
			(min_thickness 0.25)
			(keepout
				(tracks allowed)
				(vias not_allowed)
				(pads allowed)
				(copperpour not_allowed)
				(footprints allowed)
			)
			(placement
				(enabled no)
				(sheetname "")
			)
			(fill
				(thermal_gap 0.5)
				(thermal_bridge_width 0.5)
				(island_removal_mode 0)
			)
			(polygon
				(pts
					(arc
						(start 248.98096 -34.99993)
						(mid 248.21896 -34.99993)
						(end 248.98096 -34.99993)
					)
				)
			)
		)
		(zone
			(layer "F.Cu")
			(hatch none 0.5)
			(connect_pads
				(clearance 0)
			)
			(min_thickness 0.25)
			(keepout
				(tracks allowed)
				(vias not_allowed)
				(pads allowed)
				(copperpour not_allowed)
				(footprints allowed)
			)
			(placement
				(enabled no)
				(sheetname "")
			)
			(fill
				(thermal_gap 0.5)
				(thermal_bridge_width 0.5)
				(island_removal_mode 0)
			)
			(polygon
				(pts
					(arc
						(start 248.98096 -33.999932)
						(mid 248.21896 -33.999932)
						(end 248.98096 -33.999932)
					)
				)
			)
		)
		(zone
			(layer "F.Cu")
			(hatch none 0.5)
			(connect_pads
				(clearance 0)
			)
			(min_thickness 0.25)
			(keepout
				(tracks allowed)
				(vias not_allowed)
				(pads allowed)
				(copperpour not_allowed)
				(footprints allowed)
			)
			(placement
				(enabled no)
				(sheetname "")
			)
			(fill
				(thermal_gap 0.5)
				(thermal_bridge_width 0.5)
				(island_removal_mode 0)
			)
			(polygon
				(pts
					(arc
						(start 248.98096 -32.999934)
						(mid 248.21896 -32.999934)
						(end 248.98096 -32.999934)
					)
				)
			)
		)
		(zone
			(layer "F.Cu")
			(hatch none 0.5)
			(connect_pads
				(clearance 0)
			)
			(min_thickness 0.25)
			(keepout
				(tracks allowed)
				(vias not_allowed)
				(pads allowed)
				(copperpour not_allowed)
				(footprints allowed)
			)
			(placement
				(enabled no)
				(sheetname "")
			)
			(fill
				(thermal_gap 0.5)
				(thermal_bridge_width 0.5)
				(island_removal_mode 0)
			)
			(polygon
				(pts
					(arc
						(start 248.98096 -31.999936)
						(mid 248.21896 -31.999936)
						(end 248.98096 -31.999936)
					)
				)
			)
		)
		(zone
			(layer "F.Cu")
			(hatch none 0.5)
			(connect_pads
				(clearance 0)
			)
			(min_thickness 0.25)
			(keepout
				(tracks allowed)
				(vias not_allowed)
				(pads allowed)
				(copperpour not_allowed)
				(footprints allowed)
			)
			(placement
				(enabled no)
				(sheetname "")
			)
			(fill
				(thermal_gap 0.5)
				(thermal_bridge_width 0.5)
				(island_removal_mode 0)
			)
			(polygon
				(pts
					(arc
						(start 248.98096 -30.999938)
						(mid 248.21896 -30.999938)
						(end 248.98096 -30.999938)
					)
				)
			)
		)
		(zone
			(layer "F.Cu")
			(hatch none 0.5)
			(connect_pads
				(clearance 0)
			)
			(min_thickness 0.25)
			(keepout
				(tracks allowed)
				(vias not_allowed)
				(pads allowed)
				(copperpour not_allowed)
				(footprints allowed)
			)
			(placement
				(enabled no)
				(sheetname "")
			)
			(fill
				(thermal_gap 0.5)
				(thermal_bridge_width 0.5)
				(island_removal_mode 0)
			)
			(polygon
				(pts
					(arc
						(start 248.98096 -29.99994)
						(mid 248.21896 -29.99994)
						(end 248.98096 -29.99994)
					)
				)
			)
		)
		(zone
			(layer "F.Cu")
			(hatch none 0.5)
			(connect_pads
				(clearance 0)
			)
			(min_thickness 0.25)
			(keepout
				(tracks allowed)
				(vias not_allowed)
				(pads allowed)
				(copperpour not_allowed)
				(footprints allowed)
			)
			(placement
				(enabled no)
				(sheetname "")
			)
			(fill
				(thermal_gap 0.5)
				(thermal_bridge_width 0.5)
				(island_removal_mode 0)
			)
			(polygon
				(pts
					(arc
						(start 249.980958 -65.999868)
						(mid 249.218958 -65.999868)
						(end 249.980958 -65.999868)
					)
				)
			)
		)
		(zone
			(layer "F.Cu")
			(hatch none 0.5)
			(connect_pads
				(clearance 0)
			)
			(min_thickness 0.25)
			(keepout
				(tracks allowed)
				(vias not_allowed)
				(pads allowed)
				(copperpour not_allowed)
				(footprints allowed)
			)
			(placement
				(enabled no)
				(sheetname "")
			)
			(fill
				(thermal_gap 0.5)
				(thermal_bridge_width 0.5)
				(island_removal_mode 0)
			)
			(polygon
				(pts
					(arc
						(start 249.980958 -64.99987)
						(mid 249.218958 -64.99987)
						(end 249.980958 -64.99987)
					)
				)
			)
		)
		(zone
			(layer "F.Cu")
			(hatch none 0.5)
			(connect_pads
				(clearance 0)
			)
			(min_thickness 0.25)
			(keepout
				(tracks allowed)
				(vias not_allowed)
				(pads allowed)
				(copperpour not_allowed)
				(footprints allowed)
			)
			(placement
				(enabled no)
				(sheetname "")
			)
			(fill
				(thermal_gap 0.5)
				(thermal_bridge_width 0.5)
				(island_removal_mode 0)
			)
			(polygon
				(pts
					(arc
						(start 249.980958 -63.999872)
						(mid 249.218958 -63.999872)
						(end 249.980958 -63.999872)
					)
				)
			)
		)
		(zone
			(layer "F.Cu")
			(hatch none 0.5)
			(connect_pads
				(clearance 0)
			)
			(min_thickness 0.25)
			(keepout
				(tracks allowed)
				(vias not_allowed)
				(pads allowed)
				(copperpour not_allowed)
				(footprints allowed)
			)
			(placement
				(enabled no)
				(sheetname "")
			)
			(fill
				(thermal_gap 0.5)
				(thermal_bridge_width 0.5)
				(island_removal_mode 0)
			)
			(polygon
				(pts
					(arc
						(start 249.980958 -62.999874)
						(mid 249.218958 -62.999874)
						(end 249.980958 -62.999874)
					)
				)
			)
		)
		(zone
			(layer "F.Cu")
			(hatch none 0.5)
			(connect_pads
				(clearance 0)
			)
			(min_thickness 0.25)
			(keepout
				(tracks allowed)
				(vias not_allowed)
				(pads allowed)
				(copperpour not_allowed)
				(footprints allowed)
			)
			(placement
				(enabled no)
				(sheetname "")
			)
			(fill
				(thermal_gap 0.5)
				(thermal_bridge_width 0.5)
				(island_removal_mode 0)
			)
			(polygon
				(pts
					(arc
						(start 249.980958 -61.999876)
						(mid 249.218958 -61.999876)
						(end 249.980958 -61.999876)
					)
				)
			)
		)
		(zone
			(layer "F.Cu")
			(hatch none 0.5)
			(connect_pads
				(clearance 0)
			)
			(min_thickness 0.25)
			(keepout
				(tracks allowed)
				(vias not_allowed)
				(pads allowed)
				(copperpour not_allowed)
				(footprints allowed)
			)
			(placement
				(enabled no)
				(sheetname "")
			)
			(fill
				(thermal_gap 0.5)
				(thermal_bridge_width 0.5)
				(island_removal_mode 0)
			)
			(polygon
				(pts
					(arc
						(start 249.980958 -60.999878)
						(mid 249.218958 -60.999878)
						(end 249.980958 -60.999878)
					)
				)
			)
		)
		(zone
			(layer "F.Cu")
			(hatch none 0.5)
			(connect_pads
				(clearance 0)
			)
			(min_thickness 0.25)
			(keepout
				(tracks allowed)
				(vias not_allowed)
				(pads allowed)
				(copperpour not_allowed)
				(footprints allowed)
			)
			(placement
				(enabled no)
				(sheetname "")
			)
			(fill
				(thermal_gap 0.5)
				(thermal_bridge_width 0.5)
				(island_removal_mode 0)
			)
			(polygon
				(pts
					(arc
						(start 249.980958 -59.99988)
						(mid 249.218958 -59.99988)
						(end 249.980958 -59.99988)
					)
				)
			)
		)
		(zone
			(layer "F.Cu")
			(hatch none 0.5)
			(connect_pads
				(clearance 0)
			)
			(min_thickness 0.25)
			(keepout
				(tracks allowed)
				(vias not_allowed)
				(pads allowed)
				(copperpour not_allowed)
				(footprints allowed)
			)
			(placement
				(enabled no)
				(sheetname "")
			)
			(fill
				(thermal_gap 0.5)
				(thermal_bridge_width 0.5)
				(island_removal_mode 0)
			)
			(polygon
				(pts
					(arc
						(start 249.980958 -58.999882)
						(mid 249.218958 -58.999882)
						(end 249.980958 -58.999882)
					)
				)
			)
		)
		(zone
			(layer "F.Cu")
			(hatch none 0.5)
			(connect_pads
				(clearance 0)
			)
			(min_thickness 0.25)
			(keepout
				(tracks allowed)
				(vias not_allowed)
				(pads allowed)
				(copperpour not_allowed)
				(footprints allowed)
			)
			(placement
				(enabled no)
				(sheetname "")
			)
			(fill
				(thermal_gap 0.5)
				(thermal_bridge_width 0.5)
				(island_removal_mode 0)
			)
			(polygon
				(pts
					(arc
						(start 249.980958 -57.999884)
						(mid 249.218958 -57.999884)
						(end 249.980958 -57.999884)
					)
				)
			)
		)
		(zone
			(layer "F.Cu")
			(hatch none 0.5)
			(connect_pads
				(clearance 0)
			)
			(min_thickness 0.25)
			(keepout
				(tracks allowed)
				(vias not_allowed)
				(pads allowed)
				(copperpour not_allowed)
				(footprints allowed)
			)
			(placement
				(enabled no)
				(sheetname "")
			)
			(fill
				(thermal_gap 0.5)
				(thermal_bridge_width 0.5)
				(island_removal_mode 0)
			)
			(polygon
				(pts
					(arc
						(start 249.980958 -56.999886)
						(mid 249.218958 -56.999886)
						(end 249.980958 -56.999886)
					)
				)
			)
		)
		(zone
			(layer "F.Cu")
			(hatch none 0.5)
			(connect_pads
				(clearance 0)
			)
			(min_thickness 0.25)
			(keepout
				(tracks allowed)
				(vias not_allowed)
				(pads allowed)
				(copperpour not_allowed)
				(footprints allowed)
			)
			(placement
				(enabled no)
				(sheetname "")
			)
			(fill
				(thermal_gap 0.5)
				(thermal_bridge_width 0.5)
				(island_removal_mode 0)
			)
			(polygon
				(pts
					(arc
						(start 249.980958 -55.999888)
						(mid 249.218958 -55.999888)
						(end 249.980958 -55.999888)
					)
				)
			)
		)
		(zone
			(layer "F.Cu")
			(hatch none 0.5)
			(connect_pads
				(clearance 0)
			)
			(min_thickness 0.25)
			(keepout
				(tracks allowed)
				(vias not_allowed)
				(pads allowed)
				(copperpour not_allowed)
				(footprints allowed)
			)
			(placement
				(enabled no)
				(sheetname "")
			)
			(fill
				(thermal_gap 0.5)
				(thermal_bridge_width 0.5)
				(island_removal_mode 0)
			)
			(polygon
				(pts
					(arc
						(start 249.980958 -54.99989)
						(mid 249.218958 -54.99989)
						(end 249.980958 -54.99989)
					)
				)
			)
		)
		(zone
			(layer "F.Cu")
			(hatch none 0.5)
			(connect_pads
				(clearance 0)
			)
			(min_thickness 0.25)
			(keepout
				(tracks allowed)
				(vias not_allowed)
				(pads allowed)
				(copperpour not_allowed)
				(footprints allowed)
			)
			(placement
				(enabled no)
				(sheetname "")
			)
			(fill
				(thermal_gap 0.5)
				(thermal_bridge_width 0.5)
				(island_removal_mode 0)
			)
			(polygon
				(pts
					(arc
						(start 249.980958 -53.999892)
						(mid 249.218958 -53.999892)
						(end 249.980958 -53.999892)
					)
				)
			)
		)
		(zone
			(layer "F.Cu")
			(hatch none 0.5)
			(connect_pads
				(clearance 0)
			)
			(min_thickness 0.25)
			(keepout
				(tracks allowed)
				(vias not_allowed)
				(pads allowed)
				(copperpour not_allowed)
				(footprints allowed)
			)
			(placement
				(enabled no)
				(sheetname "")
			)
			(fill
				(thermal_gap 0.5)
				(thermal_bridge_width 0.5)
				(island_removal_mode 0)
			)
			(polygon
				(pts
					(arc
						(start 249.980958 -52.999894)
						(mid 249.218958 -52.999894)
						(end 249.980958 -52.999894)
					)
				)
			)
		)
		(zone
			(layer "F.Cu")
			(hatch none 0.5)
			(connect_pads
				(clearance 0)
			)
			(min_thickness 0.25)
			(keepout
				(tracks allowed)
				(vias not_allowed)
				(pads allowed)
				(copperpour not_allowed)
				(footprints allowed)
			)
			(placement
				(enabled no)
				(sheetname "")
			)
			(fill
				(thermal_gap 0.5)
				(thermal_bridge_width 0.5)
				(island_removal_mode 0)
			)
			(polygon
				(pts
					(arc
						(start 249.980958 -51.999896)
						(mid 249.218958 -51.999896)
						(end 249.980958 -51.999896)
					)
				)
			)
		)
		(zone
			(layer "F.Cu")
			(hatch none 0.5)
			(connect_pads
				(clearance 0)
			)
			(min_thickness 0.25)
			(keepout
				(tracks allowed)
				(vias not_allowed)
				(pads allowed)
				(copperpour not_allowed)
				(footprints allowed)
			)
			(placement
				(enabled no)
				(sheetname "")
			)
			(fill
				(thermal_gap 0.5)
				(thermal_bridge_width 0.5)
				(island_removal_mode 0)
			)
			(polygon
				(pts
					(arc
						(start 249.980958 -50.999898)
						(mid 249.218958 -50.999898)
						(end 249.980958 -50.999898)
					)
				)
			)
		)
		(zone
			(layer "F.Cu")
			(hatch none 0.5)
			(connect_pads
				(clearance 0)
			)
			(min_thickness 0.25)
			(keepout
				(tracks allowed)
				(vias not_allowed)
				(pads allowed)
				(copperpour not_allowed)
				(footprints allowed)
			)
			(placement
				(enabled no)
				(sheetname "")
			)
			(fill
				(thermal_gap 0.5)
				(thermal_bridge_width 0.5)
				(island_removal_mode 0)
			)
			(polygon
				(pts
					(arc
						(start 249.980958 -49.9999)
						(mid 249.218958 -49.9999)
						(end 249.980958 -49.9999)
					)
				)
			)
		)
		(zone
			(layer "F.Cu")
			(hatch none 0.5)
			(connect_pads
				(clearance 0)
			)
			(min_thickness 0.25)
			(keepout
				(tracks allowed)
				(vias not_allowed)
				(pads allowed)
				(copperpour not_allowed)
				(footprints allowed)
			)
			(placement
				(enabled no)
				(sheetname "")
			)
			(fill
				(thermal_gap 0.5)
				(thermal_bridge_width 0.5)
				(island_removal_mode 0)
			)
			(polygon
				(pts
					(arc
						(start 249.980958 -48.999902)
						(mid 249.218958 -48.999902)
						(end 249.980958 -48.999902)
					)
				)
			)
		)
		(zone
			(layer "F.Cu")
			(hatch none 0.5)
			(connect_pads
				(clearance 0)
			)
			(min_thickness 0.25)
			(keepout
				(tracks allowed)
				(vias not_allowed)
				(pads allowed)
				(copperpour not_allowed)
				(footprints allowed)
			)
			(placement
				(enabled no)
				(sheetname "")
			)
			(fill
				(thermal_gap 0.5)
				(thermal_bridge_width 0.5)
				(island_removal_mode 0)
			)
			(polygon
				(pts
					(arc
						(start 249.980958 -47.999904)
						(mid 249.218958 -47.999904)
						(end 249.980958 -47.999904)
					)
				)
			)
		)
		(zone
			(layer "F.Cu")
			(hatch none 0.5)
			(connect_pads
				(clearance 0)
			)
			(min_thickness 0.25)
			(keepout
				(tracks allowed)
				(vias not_allowed)
				(pads allowed)
				(copperpour not_allowed)
				(footprints allowed)
			)
			(placement
				(enabled no)
				(sheetname "")
			)
			(fill
				(thermal_gap 0.5)
				(thermal_bridge_width 0.5)
				(island_removal_mode 0)
			)
			(polygon
				(pts
					(arc
						(start 249.980958 -46.999906)
						(mid 249.218958 -46.999906)
						(end 249.980958 -46.999906)
					)
				)
			)
		)
		(zone
			(layer "F.Cu")
			(hatch none 0.5)
			(connect_pads
				(clearance 0)
			)
			(min_thickness 0.25)
			(keepout
				(tracks allowed)
				(vias not_allowed)
				(pads allowed)
				(copperpour not_allowed)
				(footprints allowed)
			)
			(placement
				(enabled no)
				(sheetname "")
			)
			(fill
				(thermal_gap 0.5)
				(thermal_bridge_width 0.5)
				(island_removal_mode 0)
			)
			(polygon
				(pts
					(arc
						(start 249.980958 -45.999908)
						(mid 249.218958 -45.999908)
						(end 249.980958 -45.999908)
					)
				)
			)
		)
		(zone
			(layer "F.Cu")
			(hatch none 0.5)
			(connect_pads
				(clearance 0)
			)
			(min_thickness 0.25)
			(keepout
				(tracks allowed)
				(vias not_allowed)
				(pads allowed)
				(copperpour not_allowed)
				(footprints allowed)
			)
			(placement
				(enabled no)
				(sheetname "")
			)
			(fill
				(thermal_gap 0.5)
				(thermal_bridge_width 0.5)
				(island_removal_mode 0)
			)
			(polygon
				(pts
					(arc
						(start 249.980958 -44.99991)
						(mid 249.218958 -44.99991)
						(end 249.980958 -44.99991)
					)
				)
			)
		)
		(zone
			(layer "F.Cu")
			(hatch none 0.5)
			(connect_pads
				(clearance 0)
			)
			(min_thickness 0.25)
			(keepout
				(tracks allowed)
				(vias not_allowed)
				(pads allowed)
				(copperpour not_allowed)
				(footprints allowed)
			)
			(placement
				(enabled no)
				(sheetname "")
			)
			(fill
				(thermal_gap 0.5)
				(thermal_bridge_width 0.5)
				(island_removal_mode 0)
			)
			(polygon
				(pts
					(arc
						(start 249.980958 -43.999912)
						(mid 249.218958 -43.999912)
						(end 249.980958 -43.999912)
					)
				)
			)
		)
		(zone
			(layer "F.Cu")
			(hatch none 0.5)
			(connect_pads
				(clearance 0)
			)
			(min_thickness 0.25)
			(keepout
				(tracks allowed)
				(vias not_allowed)
				(pads allowed)
				(copperpour not_allowed)
				(footprints allowed)
			)
			(placement
				(enabled no)
				(sheetname "")
			)
			(fill
				(thermal_gap 0.5)
				(thermal_bridge_width 0.5)
				(island_removal_mode 0)
			)
			(polygon
				(pts
					(arc
						(start 249.980958 -42.999914)
						(mid 249.218958 -42.999914)
						(end 249.980958 -42.999914)
					)
				)
			)
		)
		(zone
			(layer "F.Cu")
			(hatch none 0.5)
			(connect_pads
				(clearance 0)
			)
			(min_thickness 0.25)
			(keepout
				(tracks allowed)
				(vias not_allowed)
				(pads allowed)
				(copperpour not_allowed)
				(footprints allowed)
			)
			(placement
				(enabled no)
				(sheetname "")
			)
			(fill
				(thermal_gap 0.5)
				(thermal_bridge_width 0.5)
				(island_removal_mode 0)
			)
			(polygon
				(pts
					(arc
						(start 249.980958 -41.999916)
						(mid 249.218958 -41.999916)
						(end 249.980958 -41.999916)
					)
				)
			)
		)
		(zone
			(layer "F.Cu")
			(hatch none 0.5)
			(connect_pads
				(clearance 0)
			)
			(min_thickness 0.25)
			(keepout
				(tracks allowed)
				(vias not_allowed)
				(pads allowed)
				(copperpour not_allowed)
				(footprints allowed)
			)
			(placement
				(enabled no)
				(sheetname "")
			)
			(fill
				(thermal_gap 0.5)
				(thermal_bridge_width 0.5)
				(island_removal_mode 0)
			)
			(polygon
				(pts
					(arc
						(start 249.980958 -40.999918)
						(mid 249.218958 -40.999918)
						(end 249.980958 -40.999918)
					)
				)
			)
		)
		(zone
			(layer "F.Cu")
			(hatch none 0.5)
			(connect_pads
				(clearance 0)
			)
			(min_thickness 0.25)
			(keepout
				(tracks allowed)
				(vias not_allowed)
				(pads allowed)
				(copperpour not_allowed)
				(footprints allowed)
			)
			(placement
				(enabled no)
				(sheetname "")
			)
			(fill
				(thermal_gap 0.5)
				(thermal_bridge_width 0.5)
				(island_removal_mode 0)
			)
			(polygon
				(pts
					(arc
						(start 249.980958 -39.99992)
						(mid 249.218958 -39.99992)
						(end 249.980958 -39.99992)
					)
				)
			)
		)
		(zone
			(layer "F.Cu")
			(hatch none 0.5)
			(connect_pads
				(clearance 0)
			)
			(min_thickness 0.25)
			(keepout
				(tracks allowed)
				(vias not_allowed)
				(pads allowed)
				(copperpour not_allowed)
				(footprints allowed)
			)
			(placement
				(enabled no)
				(sheetname "")
			)
			(fill
				(thermal_gap 0.5)
				(thermal_bridge_width 0.5)
				(island_removal_mode 0)
			)
			(polygon
				(pts
					(arc
						(start 249.980958 -38.999922)
						(mid 249.218958 -38.999922)
						(end 249.980958 -38.999922)
					)
				)
			)
		)
		(zone
			(layer "F.Cu")
			(hatch none 0.5)
			(connect_pads
				(clearance 0)
			)
			(min_thickness 0.25)
			(keepout
				(tracks allowed)
				(vias not_allowed)
				(pads allowed)
				(copperpour not_allowed)
				(footprints allowed)
			)
			(placement
				(enabled no)
				(sheetname "")
			)
			(fill
				(thermal_gap 0.5)
				(thermal_bridge_width 0.5)
				(island_removal_mode 0)
			)
			(polygon
				(pts
					(arc
						(start 249.980958 -37.999924)
						(mid 249.218958 -37.999924)
						(end 249.980958 -37.999924)
					)
				)
			)
		)
		(zone
			(layer "F.Cu")
			(hatch none 0.5)
			(connect_pads
				(clearance 0)
			)
			(min_thickness 0.25)
			(keepout
				(tracks allowed)
				(vias not_allowed)
				(pads allowed)
				(copperpour not_allowed)
				(footprints allowed)
			)
			(placement
				(enabled no)
				(sheetname "")
			)
			(fill
				(thermal_gap 0.5)
				(thermal_bridge_width 0.5)
				(island_removal_mode 0)
			)
			(polygon
				(pts
					(arc
						(start 249.980958 -36.999926)
						(mid 249.218958 -36.999926)
						(end 249.980958 -36.999926)
					)
				)
			)
		)
		(zone
			(layer "F.Cu")
			(hatch none 0.5)
			(connect_pads
				(clearance 0)
			)
			(min_thickness 0.25)
			(keepout
				(tracks allowed)
				(vias not_allowed)
				(pads allowed)
				(copperpour not_allowed)
				(footprints allowed)
			)
			(placement
				(enabled no)
				(sheetname "")
			)
			(fill
				(thermal_gap 0.5)
				(thermal_bridge_width 0.5)
				(island_removal_mode 0)
			)
			(polygon
				(pts
					(arc
						(start 249.980958 -35.999928)
						(mid 249.218958 -35.999928)
						(end 249.980958 -35.999928)
					)
				)
			)
		)
		(zone
			(layer "F.Cu")
			(hatch none 0.5)
			(connect_pads
				(clearance 0)
			)
			(min_thickness 0.25)
			(keepout
				(tracks allowed)
				(vias not_allowed)
				(pads allowed)
				(copperpour not_allowed)
				(footprints allowed)
			)
			(placement
				(enabled no)
				(sheetname "")
			)
			(fill
				(thermal_gap 0.5)
				(thermal_bridge_width 0.5)
				(island_removal_mode 0)
			)
			(polygon
				(pts
					(arc
						(start 249.980958 -34.99993)
						(mid 249.218958 -34.99993)
						(end 249.980958 -34.99993)
					)
				)
			)
		)
		(zone
			(layer "F.Cu")
			(hatch none 0.5)
			(connect_pads
				(clearance 0)
			)
			(min_thickness 0.25)
			(keepout
				(tracks allowed)
				(vias not_allowed)
				(pads allowed)
				(copperpour not_allowed)
				(footprints allowed)
			)
			(placement
				(enabled no)
				(sheetname "")
			)
			(fill
				(thermal_gap 0.5)
				(thermal_bridge_width 0.5)
				(island_removal_mode 0)
			)
			(polygon
				(pts
					(arc
						(start 249.980958 -33.999932)
						(mid 249.218958 -33.999932)
						(end 249.980958 -33.999932)
					)
				)
			)
		)
		(zone
			(layer "F.Cu")
			(hatch none 0.5)
			(connect_pads
				(clearance 0)
			)
			(min_thickness 0.25)
			(keepout
				(tracks allowed)
				(vias not_allowed)
				(pads allowed)
				(copperpour not_allowed)
				(footprints allowed)
			)
			(placement
				(enabled no)
				(sheetname "")
			)
			(fill
				(thermal_gap 0.5)
				(thermal_bridge_width 0.5)
				(island_removal_mode 0)
			)
			(polygon
				(pts
					(arc
						(start 249.980958 -32.999934)
						(mid 249.218958 -32.999934)
						(end 249.980958 -32.999934)
					)
				)
			)
		)
		(zone
			(layer "F.Cu")
			(hatch none 0.5)
			(connect_pads
				(clearance 0)
			)
			(min_thickness 0.25)
			(keepout
				(tracks allowed)
				(vias not_allowed)
				(pads allowed)
				(copperpour not_allowed)
				(footprints allowed)
			)
			(placement
				(enabled no)
				(sheetname "")
			)
			(fill
				(thermal_gap 0.5)
				(thermal_bridge_width 0.5)
				(island_removal_mode 0)
			)
			(polygon
				(pts
					(arc
						(start 249.980958 -31.999936)
						(mid 249.218958 -31.999936)
						(end 249.980958 -31.999936)
					)
				)
			)
		)
		(zone
			(layer "F.Cu")
			(hatch none 0.5)
			(connect_pads
				(clearance 0)
			)
			(min_thickness 0.25)
			(keepout
				(tracks allowed)
				(vias not_allowed)
				(pads allowed)
				(copperpour not_allowed)
				(footprints allowed)
			)
			(placement
				(enabled no)
				(sheetname "")
			)
			(fill
				(thermal_gap 0.5)
				(thermal_bridge_width 0.5)
				(island_removal_mode 0)
			)
			(polygon
				(pts
					(arc
						(start 249.980958 -30.999938)
						(mid 249.218958 -30.999938)
						(end 249.980958 -30.999938)
					)
				)
			)
		)
		(zone
			(layer "F.Cu")
			(hatch none 0.5)
			(connect_pads
				(clearance 0)
			)
			(min_thickness 0.25)
			(keepout
				(tracks allowed)
				(vias not_allowed)
				(pads allowed)
				(copperpour not_allowed)
				(footprints allowed)
			)
			(placement
				(enabled no)
				(sheetname "")
			)
			(fill
				(thermal_gap 0.5)
				(thermal_bridge_width 0.5)
				(island_removal_mode 0)
			)
			(polygon
				(pts
					(arc
						(start 250.980956 -64.99987)
						(mid 250.218956 -64.99987)
						(end 250.980956 -64.99987)
					)
				)
			)
		)
		(zone
			(layer "F.Cu")
			(hatch none 0.5)
			(connect_pads
				(clearance 0)
			)
			(min_thickness 0.25)
			(keepout
				(tracks allowed)
				(vias not_allowed)
				(pads allowed)
				(copperpour not_allowed)
				(footprints allowed)
			)
			(placement
				(enabled no)
				(sheetname "")
			)
			(fill
				(thermal_gap 0.5)
				(thermal_bridge_width 0.5)
				(island_removal_mode 0)
			)
			(polygon
				(pts
					(arc
						(start 250.980956 -63.999872)
						(mid 250.218956 -63.999872)
						(end 250.980956 -63.999872)
					)
				)
			)
		)
		(zone
			(layer "F.Cu")
			(hatch none 0.5)
			(connect_pads
				(clearance 0)
			)
			(min_thickness 0.25)
			(keepout
				(tracks allowed)
				(vias not_allowed)
				(pads allowed)
				(copperpour not_allowed)
				(footprints allowed)
			)
			(placement
				(enabled no)
				(sheetname "")
			)
			(fill
				(thermal_gap 0.5)
				(thermal_bridge_width 0.5)
				(island_removal_mode 0)
			)
			(polygon
				(pts
					(arc
						(start 250.980956 -62.999874)
						(mid 250.218956 -62.999874)
						(end 250.980956 -62.999874)
					)
				)
			)
		)
		(zone
			(layer "F.Cu")
			(hatch none 0.5)
			(connect_pads
				(clearance 0)
			)
			(min_thickness 0.25)
			(keepout
				(tracks allowed)
				(vias not_allowed)
				(pads allowed)
				(copperpour not_allowed)
				(footprints allowed)
			)
			(placement
				(enabled no)
				(sheetname "")
			)
			(fill
				(thermal_gap 0.5)
				(thermal_bridge_width 0.5)
				(island_removal_mode 0)
			)
			(polygon
				(pts
					(arc
						(start 250.980956 -61.999876)
						(mid 250.218956 -61.999876)
						(end 250.980956 -61.999876)
					)
				)
			)
		)
		(zone
			(layer "F.Cu")
			(hatch none 0.5)
			(connect_pads
				(clearance 0)
			)
			(min_thickness 0.25)
			(keepout
				(tracks allowed)
				(vias not_allowed)
				(pads allowed)
				(copperpour not_allowed)
				(footprints allowed)
			)
			(placement
				(enabled no)
				(sheetname "")
			)
			(fill
				(thermal_gap 0.5)
				(thermal_bridge_width 0.5)
				(island_removal_mode 0)
			)
			(polygon
				(pts
					(arc
						(start 250.980956 -60.999878)
						(mid 250.218956 -60.999878)
						(end 250.980956 -60.999878)
					)
				)
			)
		)
		(zone
			(layer "F.Cu")
			(hatch none 0.5)
			(connect_pads
				(clearance 0)
			)
			(min_thickness 0.25)
			(keepout
				(tracks allowed)
				(vias not_allowed)
				(pads allowed)
				(copperpour not_allowed)
				(footprints allowed)
			)
			(placement
				(enabled no)
				(sheetname "")
			)
			(fill
				(thermal_gap 0.5)
				(thermal_bridge_width 0.5)
				(island_removal_mode 0)
			)
			(polygon
				(pts
					(arc
						(start 250.980956 -59.99988)
						(mid 250.218956 -59.99988)
						(end 250.980956 -59.99988)
					)
				)
			)
		)
		(zone
			(layer "F.Cu")
			(hatch none 0.5)
			(connect_pads
				(clearance 0)
			)
			(min_thickness 0.25)
			(keepout
				(tracks allowed)
				(vias not_allowed)
				(pads allowed)
				(copperpour not_allowed)
				(footprints allowed)
			)
			(placement
				(enabled no)
				(sheetname "")
			)
			(fill
				(thermal_gap 0.5)
				(thermal_bridge_width 0.5)
				(island_removal_mode 0)
			)
			(polygon
				(pts
					(arc
						(start 250.980956 -58.999882)
						(mid 250.218956 -58.999882)
						(end 250.980956 -58.999882)
					)
				)
			)
		)
		(zone
			(layer "F.Cu")
			(hatch none 0.5)
			(connect_pads
				(clearance 0)
			)
			(min_thickness 0.25)
			(keepout
				(tracks allowed)
				(vias not_allowed)
				(pads allowed)
				(copperpour not_allowed)
				(footprints allowed)
			)
			(placement
				(enabled no)
				(sheetname "")
			)
			(fill
				(thermal_gap 0.5)
				(thermal_bridge_width 0.5)
				(island_removal_mode 0)
			)
			(polygon
				(pts
					(arc
						(start 250.980956 -57.999884)
						(mid 250.218956 -57.999884)
						(end 250.980956 -57.999884)
					)
				)
			)
		)
		(zone
			(layer "F.Cu")
			(hatch none 0.5)
			(connect_pads
				(clearance 0)
			)
			(min_thickness 0.25)
			(keepout
				(tracks allowed)
				(vias not_allowed)
				(pads allowed)
				(copperpour not_allowed)
				(footprints allowed)
			)
			(placement
				(enabled no)
				(sheetname "")
			)
			(fill
				(thermal_gap 0.5)
				(thermal_bridge_width 0.5)
				(island_removal_mode 0)
			)
			(polygon
				(pts
					(arc
						(start 250.980956 -56.999886)
						(mid 250.218956 -56.999886)
						(end 250.980956 -56.999886)
					)
				)
			)
		)
		(zone
			(layer "F.Cu")
			(hatch none 0.5)
			(connect_pads
				(clearance 0)
			)
			(min_thickness 0.25)
			(keepout
				(tracks allowed)
				(vias not_allowed)
				(pads allowed)
				(copperpour not_allowed)
				(footprints allowed)
			)
			(placement
				(enabled no)
				(sheetname "")
			)
			(fill
				(thermal_gap 0.5)
				(thermal_bridge_width 0.5)
				(island_removal_mode 0)
			)
			(polygon
				(pts
					(arc
						(start 250.980956 -55.999888)
						(mid 250.218956 -55.999888)
						(end 250.980956 -55.999888)
					)
				)
			)
		)
		(zone
			(layer "F.Cu")
			(hatch none 0.5)
			(connect_pads
				(clearance 0)
			)
			(min_thickness 0.25)
			(keepout
				(tracks allowed)
				(vias not_allowed)
				(pads allowed)
				(copperpour not_allowed)
				(footprints allowed)
			)
			(placement
				(enabled no)
				(sheetname "")
			)
			(fill
				(thermal_gap 0.5)
				(thermal_bridge_width 0.5)
				(island_removal_mode 0)
			)
			(polygon
				(pts
					(arc
						(start 250.980956 -54.99989)
						(mid 250.218956 -54.99989)
						(end 250.980956 -54.99989)
					)
				)
			)
		)
		(zone
			(layer "F.Cu")
			(hatch none 0.5)
			(connect_pads
				(clearance 0)
			)
			(min_thickness 0.25)
			(keepout
				(tracks allowed)
				(vias not_allowed)
				(pads allowed)
				(copperpour not_allowed)
				(footprints allowed)
			)
			(placement
				(enabled no)
				(sheetname "")
			)
			(fill
				(thermal_gap 0.5)
				(thermal_bridge_width 0.5)
				(island_removal_mode 0)
			)
			(polygon
				(pts
					(arc
						(start 250.980956 -53.999892)
						(mid 250.218956 -53.999892)
						(end 250.980956 -53.999892)
					)
				)
			)
		)
		(zone
			(layer "F.Cu")
			(hatch none 0.5)
			(connect_pads
				(clearance 0)
			)
			(min_thickness 0.25)
			(keepout
				(tracks allowed)
				(vias not_allowed)
				(pads allowed)
				(copperpour not_allowed)
				(footprints allowed)
			)
			(placement
				(enabled no)
				(sheetname "")
			)
			(fill
				(thermal_gap 0.5)
				(thermal_bridge_width 0.5)
				(island_removal_mode 0)
			)
			(polygon
				(pts
					(arc
						(start 250.980956 -52.999894)
						(mid 250.218956 -52.999894)
						(end 250.980956 -52.999894)
					)
				)
			)
		)
		(zone
			(layer "F.Cu")
			(hatch none 0.5)
			(connect_pads
				(clearance 0)
			)
			(min_thickness 0.25)
			(keepout
				(tracks allowed)
				(vias not_allowed)
				(pads allowed)
				(copperpour not_allowed)
				(footprints allowed)
			)
			(placement
				(enabled no)
				(sheetname "")
			)
			(fill
				(thermal_gap 0.5)
				(thermal_bridge_width 0.5)
				(island_removal_mode 0)
			)
			(polygon
				(pts
					(arc
						(start 250.980956 -51.999896)
						(mid 250.218956 -51.999896)
						(end 250.980956 -51.999896)
					)
				)
			)
		)
		(zone
			(layer "F.Cu")
			(hatch none 0.5)
			(connect_pads
				(clearance 0)
			)
			(min_thickness 0.25)
			(keepout
				(tracks allowed)
				(vias not_allowed)
				(pads allowed)
				(copperpour not_allowed)
				(footprints allowed)
			)
			(placement
				(enabled no)
				(sheetname "")
			)
			(fill
				(thermal_gap 0.5)
				(thermal_bridge_width 0.5)
				(island_removal_mode 0)
			)
			(polygon
				(pts
					(arc
						(start 250.980956 -50.999898)
						(mid 250.218956 -50.999898)
						(end 250.980956 -50.999898)
					)
				)
			)
		)
		(zone
			(layer "F.Cu")
			(hatch none 0.5)
			(connect_pads
				(clearance 0)
			)
			(min_thickness 0.25)
			(keepout
				(tracks allowed)
				(vias not_allowed)
				(pads allowed)
				(copperpour not_allowed)
				(footprints allowed)
			)
			(placement
				(enabled no)
				(sheetname "")
			)
			(fill
				(thermal_gap 0.5)
				(thermal_bridge_width 0.5)
				(island_removal_mode 0)
			)
			(polygon
				(pts
					(arc
						(start 250.980956 -49.9999)
						(mid 250.218956 -49.9999)
						(end 250.980956 -49.9999)
					)
				)
			)
		)
		(zone
			(layer "F.Cu")
			(hatch none 0.5)
			(connect_pads
				(clearance 0)
			)
			(min_thickness 0.25)
			(keepout
				(tracks allowed)
				(vias not_allowed)
				(pads allowed)
				(copperpour not_allowed)
				(footprints allowed)
			)
			(placement
				(enabled no)
				(sheetname "")
			)
			(fill
				(thermal_gap 0.5)
				(thermal_bridge_width 0.5)
				(island_removal_mode 0)
			)
			(polygon
				(pts
					(arc
						(start 250.980956 -48.999902)
						(mid 250.218956 -48.999902)
						(end 250.980956 -48.999902)
					)
				)
			)
		)
		(zone
			(layer "F.Cu")
			(hatch none 0.5)
			(connect_pads
				(clearance 0)
			)
			(min_thickness 0.25)
			(keepout
				(tracks allowed)
				(vias not_allowed)
				(pads allowed)
				(copperpour not_allowed)
				(footprints allowed)
			)
			(placement
				(enabled no)
				(sheetname "")
			)
			(fill
				(thermal_gap 0.5)
				(thermal_bridge_width 0.5)
				(island_removal_mode 0)
			)
			(polygon
				(pts
					(arc
						(start 250.980956 -47.999904)
						(mid 250.218956 -47.999904)
						(end 250.980956 -47.999904)
					)
				)
			)
		)
		(zone
			(layer "F.Cu")
			(hatch none 0.5)
			(connect_pads
				(clearance 0)
			)
			(min_thickness 0.25)
			(keepout
				(tracks allowed)
				(vias not_allowed)
				(pads allowed)
				(copperpour not_allowed)
				(footprints allowed)
			)
			(placement
				(enabled no)
				(sheetname "")
			)
			(fill
				(thermal_gap 0.5)
				(thermal_bridge_width 0.5)
				(island_removal_mode 0)
			)
			(polygon
				(pts
					(arc
						(start 250.980956 -46.999906)
						(mid 250.218956 -46.999906)
						(end 250.980956 -46.999906)
					)
				)
			)
		)
		(zone
			(layer "F.Cu")
			(hatch none 0.5)
			(connect_pads
				(clearance 0)
			)
			(min_thickness 0.25)
			(keepout
				(tracks allowed)
				(vias not_allowed)
				(pads allowed)
				(copperpour not_allowed)
				(footprints allowed)
			)
			(placement
				(enabled no)
				(sheetname "")
			)
			(fill
				(thermal_gap 0.5)
				(thermal_bridge_width 0.5)
				(island_removal_mode 0)
			)
			(polygon
				(pts
					(arc
						(start 250.980956 -45.999908)
						(mid 250.218956 -45.999908)
						(end 250.980956 -45.999908)
					)
				)
			)
		)
		(zone
			(layer "F.Cu")
			(hatch none 0.5)
			(connect_pads
				(clearance 0)
			)
			(min_thickness 0.25)
			(keepout
				(tracks allowed)
				(vias not_allowed)
				(pads allowed)
				(copperpour not_allowed)
				(footprints allowed)
			)
			(placement
				(enabled no)
				(sheetname "")
			)
			(fill
				(thermal_gap 0.5)
				(thermal_bridge_width 0.5)
				(island_removal_mode 0)
			)
			(polygon
				(pts
					(arc
						(start 250.980956 -44.99991)
						(mid 250.218956 -44.99991)
						(end 250.980956 -44.99991)
					)
				)
			)
		)
		(zone
			(layer "F.Cu")
			(hatch none 0.5)
			(connect_pads
				(clearance 0)
			)
			(min_thickness 0.25)
			(keepout
				(tracks allowed)
				(vias not_allowed)
				(pads allowed)
				(copperpour not_allowed)
				(footprints allowed)
			)
			(placement
				(enabled no)
				(sheetname "")
			)
			(fill
				(thermal_gap 0.5)
				(thermal_bridge_width 0.5)
				(island_removal_mode 0)
			)
			(polygon
				(pts
					(arc
						(start 250.980956 -43.999912)
						(mid 250.218956 -43.999912)
						(end 250.980956 -43.999912)
					)
				)
			)
		)
		(zone
			(layer "F.Cu")
			(hatch none 0.5)
			(connect_pads
				(clearance 0)
			)
			(min_thickness 0.25)
			(keepout
				(tracks allowed)
				(vias not_allowed)
				(pads allowed)
				(copperpour not_allowed)
				(footprints allowed)
			)
			(placement
				(enabled no)
				(sheetname "")
			)
			(fill
				(thermal_gap 0.5)
				(thermal_bridge_width 0.5)
				(island_removal_mode 0)
			)
			(polygon
				(pts
					(arc
						(start 250.980956 -42.999914)
						(mid 250.218956 -42.999914)
						(end 250.980956 -42.999914)
					)
				)
			)
		)
		(zone
			(layer "F.Cu")
			(hatch none 0.5)
			(connect_pads
				(clearance 0)
			)
			(min_thickness 0.25)
			(keepout
				(tracks allowed)
				(vias not_allowed)
				(pads allowed)
				(copperpour not_allowed)
				(footprints allowed)
			)
			(placement
				(enabled no)
				(sheetname "")
			)
			(fill
				(thermal_gap 0.5)
				(thermal_bridge_width 0.5)
				(island_removal_mode 0)
			)
			(polygon
				(pts
					(arc
						(start 250.980956 -41.999916)
						(mid 250.218956 -41.999916)
						(end 250.980956 -41.999916)
					)
				)
			)
		)
		(zone
			(layer "F.Cu")
			(hatch none 0.5)
			(connect_pads
				(clearance 0)
			)
			(min_thickness 0.25)
			(keepout
				(tracks allowed)
				(vias not_allowed)
				(pads allowed)
				(copperpour not_allowed)
				(footprints allowed)
			)
			(placement
				(enabled no)
				(sheetname "")
			)
			(fill
				(thermal_gap 0.5)
				(thermal_bridge_width 0.5)
				(island_removal_mode 0)
			)
			(polygon
				(pts
					(arc
						(start 250.980956 -40.999918)
						(mid 250.218956 -40.999918)
						(end 250.980956 -40.999918)
					)
				)
			)
		)
		(zone
			(layer "F.Cu")
			(hatch none 0.5)
			(connect_pads
				(clearance 0)
			)
			(min_thickness 0.25)
			(keepout
				(tracks allowed)
				(vias not_allowed)
				(pads allowed)
				(copperpour not_allowed)
				(footprints allowed)
			)
			(placement
				(enabled no)
				(sheetname "")
			)
			(fill
				(thermal_gap 0.5)
				(thermal_bridge_width 0.5)
				(island_removal_mode 0)
			)
			(polygon
				(pts
					(arc
						(start 250.980956 -39.99992)
						(mid 250.218956 -39.99992)
						(end 250.980956 -39.99992)
					)
				)
			)
		)
		(zone
			(layer "F.Cu")
			(hatch none 0.5)
			(connect_pads
				(clearance 0)
			)
			(min_thickness 0.25)
			(keepout
				(tracks allowed)
				(vias not_allowed)
				(pads allowed)
				(copperpour not_allowed)
				(footprints allowed)
			)
			(placement
				(enabled no)
				(sheetname "")
			)
			(fill
				(thermal_gap 0.5)
				(thermal_bridge_width 0.5)
				(island_removal_mode 0)
			)
			(polygon
				(pts
					(arc
						(start 250.980956 -38.999922)
						(mid 250.218956 -38.999922)
						(end 250.980956 -38.999922)
					)
				)
			)
		)
		(zone
			(layer "F.Cu")
			(hatch none 0.5)
			(connect_pads
				(clearance 0)
			)
			(min_thickness 0.25)
			(keepout
				(tracks allowed)
				(vias not_allowed)
				(pads allowed)
				(copperpour not_allowed)
				(footprints allowed)
			)
			(placement
				(enabled no)
				(sheetname "")
			)
			(fill
				(thermal_gap 0.5)
				(thermal_bridge_width 0.5)
				(island_removal_mode 0)
			)
			(polygon
				(pts
					(arc
						(start 250.980956 -37.999924)
						(mid 250.218956 -37.999924)
						(end 250.980956 -37.999924)
					)
				)
			)
		)
		(zone
			(layer "F.Cu")
			(hatch none 0.5)
			(connect_pads
				(clearance 0)
			)
			(min_thickness 0.25)
			(keepout
				(tracks allowed)
				(vias not_allowed)
				(pads allowed)
				(copperpour not_allowed)
				(footprints allowed)
			)
			(placement
				(enabled no)
				(sheetname "")
			)
			(fill
				(thermal_gap 0.5)
				(thermal_bridge_width 0.5)
				(island_removal_mode 0)
			)
			(polygon
				(pts
					(arc
						(start 250.980956 -36.999926)
						(mid 250.218956 -36.999926)
						(end 250.980956 -36.999926)
					)
				)
			)
		)
		(zone
			(layer "F.Cu")
			(hatch none 0.5)
			(connect_pads
				(clearance 0)
			)
			(min_thickness 0.25)
			(keepout
				(tracks allowed)
				(vias not_allowed)
				(pads allowed)
				(copperpour not_allowed)
				(footprints allowed)
			)
			(placement
				(enabled no)
				(sheetname "")
			)
			(fill
				(thermal_gap 0.5)
				(thermal_bridge_width 0.5)
				(island_removal_mode 0)
			)
			(polygon
				(pts
					(arc
						(start 250.980956 -35.999928)
						(mid 250.218956 -35.999928)
						(end 250.980956 -35.999928)
					)
				)
			)
		)
		(zone
			(layer "F.Cu")
			(hatch none 0.5)
			(connect_pads
				(clearance 0)
			)
			(min_thickness 0.25)
			(keepout
				(tracks allowed)
				(vias not_allowed)
				(pads allowed)
				(copperpour not_allowed)
				(footprints allowed)
			)
			(placement
				(enabled no)
				(sheetname "")
			)
			(fill
				(thermal_gap 0.5)
				(thermal_bridge_width 0.5)
				(island_removal_mode 0)
			)
			(polygon
				(pts
					(arc
						(start 250.980956 -34.99993)
						(mid 250.218956 -34.99993)
						(end 250.980956 -34.99993)
					)
				)
			)
		)
		(zone
			(layer "F.Cu")
			(hatch none 0.5)
			(connect_pads
				(clearance 0)
			)
			(min_thickness 0.25)
			(keepout
				(tracks allowed)
				(vias not_allowed)
				(pads allowed)
				(copperpour not_allowed)
				(footprints allowed)
			)
			(placement
				(enabled no)
				(sheetname "")
			)
			(fill
				(thermal_gap 0.5)
				(thermal_bridge_width 0.5)
				(island_removal_mode 0)
			)
			(polygon
				(pts
					(arc
						(start 250.980956 -33.999932)
						(mid 250.218956 -33.999932)
						(end 250.980956 -33.999932)
					)
				)
			)
		)
		(zone
			(layer "F.Cu")
			(hatch none 0.5)
			(connect_pads
				(clearance 0)
			)
			(min_thickness 0.25)
			(keepout
				(tracks allowed)
				(vias not_allowed)
				(pads allowed)
				(copperpour not_allowed)
				(footprints allowed)
			)
			(placement
				(enabled no)
				(sheetname "")
			)
			(fill
				(thermal_gap 0.5)
				(thermal_bridge_width 0.5)
				(island_removal_mode 0)
			)
			(polygon
				(pts
					(arc
						(start 250.980956 -32.999934)
						(mid 250.218956 -32.999934)
						(end 250.980956 -32.999934)
					)
				)
			)
		)
		(zone
			(layer "F.Cu")
			(hatch none 0.5)
			(connect_pads
				(clearance 0)
			)
			(min_thickness 0.25)
			(keepout
				(tracks allowed)
				(vias not_allowed)
				(pads allowed)
				(copperpour not_allowed)
				(footprints allowed)
			)
			(placement
				(enabled no)
				(sheetname "")
			)
			(fill
				(thermal_gap 0.5)
				(thermal_bridge_width 0.5)
				(island_removal_mode 0)
			)
			(polygon
				(pts
					(arc
						(start 250.980956 -31.999936)
						(mid 250.218956 -31.999936)
						(end 250.980956 -31.999936)
					)
				)
			)
		)
		(zone
			(layer "F.Cu")
			(hatch none 0.5)
			(connect_pads
				(clearance 0)
			)
			(min_thickness 0.25)
			(keepout
				(tracks allowed)
				(vias not_allowed)
				(pads allowed)
				(copperpour not_allowed)
				(footprints allowed)
			)
			(placement
				(enabled no)
				(sheetname "")
			)
			(fill
				(thermal_gap 0.5)
				(thermal_bridge_width 0.5)
				(island_removal_mode 0)
			)
			(polygon
				(pts
					(arc
						(start 250.980956 -30.999938)
						(mid 250.218956 -30.999938)
						(end 250.980956 -30.999938)
					)
				)
			)
		)
		(zone
			(layer "F.Cu")
			(hatch none 0.5)
			(connect_pads
				(clearance 0)
			)
			(min_thickness 0.25)
			(keepout
				(tracks allowed)
				(vias not_allowed)
				(pads allowed)
				(copperpour not_allowed)
				(footprints allowed)
			)
			(placement
				(enabled no)
				(sheetname "")
			)
			(fill
				(thermal_gap 0.5)
				(thermal_bridge_width 0.5)
				(island_removal_mode 0)
			)
			(polygon
				(pts
					(arc
						(start 250.980956 -29.99994)
						(mid 250.218956 -29.99994)
						(end 250.980956 -29.99994)
					)
				)
			)
		)
		(zone
			(layer "F.Cu")
			(hatch none 0.5)
			(connect_pads
				(clearance 0)
			)
			(min_thickness 0.25)
			(keepout
				(tracks allowed)
				(vias not_allowed)
				(pads allowed)
				(copperpour not_allowed)
				(footprints allowed)
			)
			(placement
				(enabled no)
				(sheetname "")
			)
			(fill
				(thermal_gap 0.5)
				(thermal_bridge_width 0.5)
				(island_removal_mode 0)
			)
			(polygon
				(pts
					(arc
						(start 251.980954 -65.999868)
						(mid 251.218954 -65.999868)
						(end 251.980954 -65.999868)
					)
				)
			)
		)
		(zone
			(layer "F.Cu")
			(hatch none 0.5)
			(connect_pads
				(clearance 0)
			)
			(min_thickness 0.25)
			(keepout
				(tracks allowed)
				(vias not_allowed)
				(pads allowed)
				(copperpour not_allowed)
				(footprints allowed)
			)
			(placement
				(enabled no)
				(sheetname "")
			)
			(fill
				(thermal_gap 0.5)
				(thermal_bridge_width 0.5)
				(island_removal_mode 0)
			)
			(polygon
				(pts
					(arc
						(start 251.980954 -64.99987)
						(mid 251.218954 -64.99987)
						(end 251.980954 -64.99987)
					)
				)
			)
		)
		(zone
			(layer "F.Cu")
			(hatch none 0.5)
			(connect_pads
				(clearance 0)
			)
			(min_thickness 0.25)
			(keepout
				(tracks allowed)
				(vias not_allowed)
				(pads allowed)
				(copperpour not_allowed)
				(footprints allowed)
			)
			(placement
				(enabled no)
				(sheetname "")
			)
			(fill
				(thermal_gap 0.5)
				(thermal_bridge_width 0.5)
				(island_removal_mode 0)
			)
			(polygon
				(pts
					(arc
						(start 251.980954 -63.999872)
						(mid 251.218954 -63.999872)
						(end 251.980954 -63.999872)
					)
				)
			)
		)
		(zone
			(layer "F.Cu")
			(hatch none 0.5)
			(connect_pads
				(clearance 0)
			)
			(min_thickness 0.25)
			(keepout
				(tracks allowed)
				(vias not_allowed)
				(pads allowed)
				(copperpour not_allowed)
				(footprints allowed)
			)
			(placement
				(enabled no)
				(sheetname "")
			)
			(fill
				(thermal_gap 0.5)
				(thermal_bridge_width 0.5)
				(island_removal_mode 0)
			)
			(polygon
				(pts
					(arc
						(start 251.980954 -62.999874)
						(mid 251.218954 -62.999874)
						(end 251.980954 -62.999874)
					)
				)
			)
		)
		(zone
			(layer "F.Cu")
			(hatch none 0.5)
			(connect_pads
				(clearance 0)
			)
			(min_thickness 0.25)
			(keepout
				(tracks allowed)
				(vias not_allowed)
				(pads allowed)
				(copperpour not_allowed)
				(footprints allowed)
			)
			(placement
				(enabled no)
				(sheetname "")
			)
			(fill
				(thermal_gap 0.5)
				(thermal_bridge_width 0.5)
				(island_removal_mode 0)
			)
			(polygon
				(pts
					(arc
						(start 251.980954 -61.999876)
						(mid 251.218954 -61.999876)
						(end 251.980954 -61.999876)
					)
				)
			)
		)
		(zone
			(layer "F.Cu")
			(hatch none 0.5)
			(connect_pads
				(clearance 0)
			)
			(min_thickness 0.25)
			(keepout
				(tracks allowed)
				(vias not_allowed)
				(pads allowed)
				(copperpour not_allowed)
				(footprints allowed)
			)
			(placement
				(enabled no)
				(sheetname "")
			)
			(fill
				(thermal_gap 0.5)
				(thermal_bridge_width 0.5)
				(island_removal_mode 0)
			)
			(polygon
				(pts
					(arc
						(start 251.980954 -60.999878)
						(mid 251.218954 -60.999878)
						(end 251.980954 -60.999878)
					)
				)
			)
		)
		(zone
			(layer "F.Cu")
			(hatch none 0.5)
			(connect_pads
				(clearance 0)
			)
			(min_thickness 0.25)
			(keepout
				(tracks allowed)
				(vias not_allowed)
				(pads allowed)
				(copperpour not_allowed)
				(footprints allowed)
			)
			(placement
				(enabled no)
				(sheetname "")
			)
			(fill
				(thermal_gap 0.5)
				(thermal_bridge_width 0.5)
				(island_removal_mode 0)
			)
			(polygon
				(pts
					(arc
						(start 251.980954 -59.99988)
						(mid 251.218954 -59.99988)
						(end 251.980954 -59.99988)
					)
				)
			)
		)
		(zone
			(layer "F.Cu")
			(hatch none 0.5)
			(connect_pads
				(clearance 0)
			)
			(min_thickness 0.25)
			(keepout
				(tracks allowed)
				(vias not_allowed)
				(pads allowed)
				(copperpour not_allowed)
				(footprints allowed)
			)
			(placement
				(enabled no)
				(sheetname "")
			)
			(fill
				(thermal_gap 0.5)
				(thermal_bridge_width 0.5)
				(island_removal_mode 0)
			)
			(polygon
				(pts
					(arc
						(start 251.980954 -58.999882)
						(mid 251.218954 -58.999882)
						(end 251.980954 -58.999882)
					)
				)
			)
		)
		(zone
			(layer "F.Cu")
			(hatch none 0.5)
			(connect_pads
				(clearance 0)
			)
			(min_thickness 0.25)
			(keepout
				(tracks allowed)
				(vias not_allowed)
				(pads allowed)
				(copperpour not_allowed)
				(footprints allowed)
			)
			(placement
				(enabled no)
				(sheetname "")
			)
			(fill
				(thermal_gap 0.5)
				(thermal_bridge_width 0.5)
				(island_removal_mode 0)
			)
			(polygon
				(pts
					(arc
						(start 251.980954 -57.999884)
						(mid 251.218954 -57.999884)
						(end 251.980954 -57.999884)
					)
				)
			)
		)
		(zone
			(layer "F.Cu")
			(hatch none 0.5)
			(connect_pads
				(clearance 0)
			)
			(min_thickness 0.25)
			(keepout
				(tracks allowed)
				(vias not_allowed)
				(pads allowed)
				(copperpour not_allowed)
				(footprints allowed)
			)
			(placement
				(enabled no)
				(sheetname "")
			)
			(fill
				(thermal_gap 0.5)
				(thermal_bridge_width 0.5)
				(island_removal_mode 0)
			)
			(polygon
				(pts
					(arc
						(start 251.980954 -56.999886)
						(mid 251.218954 -56.999886)
						(end 251.980954 -56.999886)
					)
				)
			)
		)
		(zone
			(layer "F.Cu")
			(hatch none 0.5)
			(connect_pads
				(clearance 0)
			)
			(min_thickness 0.25)
			(keepout
				(tracks allowed)
				(vias not_allowed)
				(pads allowed)
				(copperpour not_allowed)
				(footprints allowed)
			)
			(placement
				(enabled no)
				(sheetname "")
			)
			(fill
				(thermal_gap 0.5)
				(thermal_bridge_width 0.5)
				(island_removal_mode 0)
			)
			(polygon
				(pts
					(arc
						(start 251.980954 -55.999888)
						(mid 251.218954 -55.999888)
						(end 251.980954 -55.999888)
					)
				)
			)
		)
		(zone
			(layer "F.Cu")
			(hatch none 0.5)
			(connect_pads
				(clearance 0)
			)
			(min_thickness 0.25)
			(keepout
				(tracks allowed)
				(vias not_allowed)
				(pads allowed)
				(copperpour not_allowed)
				(footprints allowed)
			)
			(placement
				(enabled no)
				(sheetname "")
			)
			(fill
				(thermal_gap 0.5)
				(thermal_bridge_width 0.5)
				(island_removal_mode 0)
			)
			(polygon
				(pts
					(arc
						(start 251.980954 -54.99989)
						(mid 251.218954 -54.99989)
						(end 251.980954 -54.99989)
					)
				)
			)
		)
		(zone
			(layer "F.Cu")
			(hatch none 0.5)
			(connect_pads
				(clearance 0)
			)
			(min_thickness 0.25)
			(keepout
				(tracks allowed)
				(vias not_allowed)
				(pads allowed)
				(copperpour not_allowed)
				(footprints allowed)
			)
			(placement
				(enabled no)
				(sheetname "")
			)
			(fill
				(thermal_gap 0.5)
				(thermal_bridge_width 0.5)
				(island_removal_mode 0)
			)
			(polygon
				(pts
					(arc
						(start 251.980954 -53.999892)
						(mid 251.218954 -53.999892)
						(end 251.980954 -53.999892)
					)
				)
			)
		)
		(zone
			(layer "F.Cu")
			(hatch none 0.5)
			(connect_pads
				(clearance 0)
			)
			(min_thickness 0.25)
			(keepout
				(tracks allowed)
				(vias not_allowed)
				(pads allowed)
				(copperpour not_allowed)
				(footprints allowed)
			)
			(placement
				(enabled no)
				(sheetname "")
			)
			(fill
				(thermal_gap 0.5)
				(thermal_bridge_width 0.5)
				(island_removal_mode 0)
			)
			(polygon
				(pts
					(arc
						(start 251.980954 -52.999894)
						(mid 251.218954 -52.999894)
						(end 251.980954 -52.999894)
					)
				)
			)
		)
		(zone
			(layer "F.Cu")
			(hatch none 0.5)
			(connect_pads
				(clearance 0)
			)
			(min_thickness 0.25)
			(keepout
				(tracks allowed)
				(vias not_allowed)
				(pads allowed)
				(copperpour not_allowed)
				(footprints allowed)
			)
			(placement
				(enabled no)
				(sheetname "")
			)
			(fill
				(thermal_gap 0.5)
				(thermal_bridge_width 0.5)
				(island_removal_mode 0)
			)
			(polygon
				(pts
					(arc
						(start 251.980954 -51.999896)
						(mid 251.218954 -51.999896)
						(end 251.980954 -51.999896)
					)
				)
			)
		)
		(zone
			(layer "F.Cu")
			(hatch none 0.5)
			(connect_pads
				(clearance 0)
			)
			(min_thickness 0.25)
			(keepout
				(tracks allowed)
				(vias not_allowed)
				(pads allowed)
				(copperpour not_allowed)
				(footprints allowed)
			)
			(placement
				(enabled no)
				(sheetname "")
			)
			(fill
				(thermal_gap 0.5)
				(thermal_bridge_width 0.5)
				(island_removal_mode 0)
			)
			(polygon
				(pts
					(arc
						(start 251.980954 -50.999898)
						(mid 251.218954 -50.999898)
						(end 251.980954 -50.999898)
					)
				)
			)
		)
		(zone
			(layer "F.Cu")
			(hatch none 0.5)
			(connect_pads
				(clearance 0)
			)
			(min_thickness 0.25)
			(keepout
				(tracks allowed)
				(vias not_allowed)
				(pads allowed)
				(copperpour not_allowed)
				(footprints allowed)
			)
			(placement
				(enabled no)
				(sheetname "")
			)
			(fill
				(thermal_gap 0.5)
				(thermal_bridge_width 0.5)
				(island_removal_mode 0)
			)
			(polygon
				(pts
					(arc
						(start 251.980954 -49.9999)
						(mid 251.218954 -49.9999)
						(end 251.980954 -49.9999)
					)
				)
			)
		)
		(zone
			(layer "F.Cu")
			(hatch none 0.5)
			(connect_pads
				(clearance 0)
			)
			(min_thickness 0.25)
			(keepout
				(tracks allowed)
				(vias not_allowed)
				(pads allowed)
				(copperpour not_allowed)
				(footprints allowed)
			)
			(placement
				(enabled no)
				(sheetname "")
			)
			(fill
				(thermal_gap 0.5)
				(thermal_bridge_width 0.5)
				(island_removal_mode 0)
			)
			(polygon
				(pts
					(arc
						(start 251.980954 -48.999902)
						(mid 251.218954 -48.999902)
						(end 251.980954 -48.999902)
					)
				)
			)
		)
		(zone
			(layer "F.Cu")
			(hatch none 0.5)
			(connect_pads
				(clearance 0)
			)
			(min_thickness 0.25)
			(keepout
				(tracks allowed)
				(vias not_allowed)
				(pads allowed)
				(copperpour not_allowed)
				(footprints allowed)
			)
			(placement
				(enabled no)
				(sheetname "")
			)
			(fill
				(thermal_gap 0.5)
				(thermal_bridge_width 0.5)
				(island_removal_mode 0)
			)
			(polygon
				(pts
					(arc
						(start 251.980954 -47.999904)
						(mid 251.218954 -47.999904)
						(end 251.980954 -47.999904)
					)
				)
			)
		)
		(zone
			(layer "F.Cu")
			(hatch none 0.5)
			(connect_pads
				(clearance 0)
			)
			(min_thickness 0.25)
			(keepout
				(tracks allowed)
				(vias not_allowed)
				(pads allowed)
				(copperpour not_allowed)
				(footprints allowed)
			)
			(placement
				(enabled no)
				(sheetname "")
			)
			(fill
				(thermal_gap 0.5)
				(thermal_bridge_width 0.5)
				(island_removal_mode 0)
			)
			(polygon
				(pts
					(arc
						(start 251.980954 -46.999906)
						(mid 251.218954 -46.999906)
						(end 251.980954 -46.999906)
					)
				)
			)
		)
		(zone
			(layer "F.Cu")
			(hatch none 0.5)
			(connect_pads
				(clearance 0)
			)
			(min_thickness 0.25)
			(keepout
				(tracks allowed)
				(vias not_allowed)
				(pads allowed)
				(copperpour not_allowed)
				(footprints allowed)
			)
			(placement
				(enabled no)
				(sheetname "")
			)
			(fill
				(thermal_gap 0.5)
				(thermal_bridge_width 0.5)
				(island_removal_mode 0)
			)
			(polygon
				(pts
					(arc
						(start 251.980954 -45.999908)
						(mid 251.218954 -45.999908)
						(end 251.980954 -45.999908)
					)
				)
			)
		)
		(zone
			(layer "F.Cu")
			(hatch none 0.5)
			(connect_pads
				(clearance 0)
			)
			(min_thickness 0.25)
			(keepout
				(tracks allowed)
				(vias not_allowed)
				(pads allowed)
				(copperpour not_allowed)
				(footprints allowed)
			)
			(placement
				(enabled no)
				(sheetname "")
			)
			(fill
				(thermal_gap 0.5)
				(thermal_bridge_width 0.5)
				(island_removal_mode 0)
			)
			(polygon
				(pts
					(arc
						(start 251.980954 -44.99991)
						(mid 251.218954 -44.99991)
						(end 251.980954 -44.99991)
					)
				)
			)
		)
		(zone
			(layer "F.Cu")
			(hatch none 0.5)
			(connect_pads
				(clearance 0)
			)
			(min_thickness 0.25)
			(keepout
				(tracks allowed)
				(vias not_allowed)
				(pads allowed)
				(copperpour not_allowed)
				(footprints allowed)
			)
			(placement
				(enabled no)
				(sheetname "")
			)
			(fill
				(thermal_gap 0.5)
				(thermal_bridge_width 0.5)
				(island_removal_mode 0)
			)
			(polygon
				(pts
					(arc
						(start 251.980954 -43.999912)
						(mid 251.218954 -43.999912)
						(end 251.980954 -43.999912)
					)
				)
			)
		)
		(zone
			(layer "F.Cu")
			(hatch none 0.5)
			(connect_pads
				(clearance 0)
			)
			(min_thickness 0.25)
			(keepout
				(tracks allowed)
				(vias not_allowed)
				(pads allowed)
				(copperpour not_allowed)
				(footprints allowed)
			)
			(placement
				(enabled no)
				(sheetname "")
			)
			(fill
				(thermal_gap 0.5)
				(thermal_bridge_width 0.5)
				(island_removal_mode 0)
			)
			(polygon
				(pts
					(arc
						(start 251.980954 -42.999914)
						(mid 251.218954 -42.999914)
						(end 251.980954 -42.999914)
					)
				)
			)
		)
		(zone
			(layer "F.Cu")
			(hatch none 0.5)
			(connect_pads
				(clearance 0)
			)
			(min_thickness 0.25)
			(keepout
				(tracks allowed)
				(vias not_allowed)
				(pads allowed)
				(copperpour not_allowed)
				(footprints allowed)
			)
			(placement
				(enabled no)
				(sheetname "")
			)
			(fill
				(thermal_gap 0.5)
				(thermal_bridge_width 0.5)
				(island_removal_mode 0)
			)
			(polygon
				(pts
					(arc
						(start 251.980954 -41.999916)
						(mid 251.218954 -41.999916)
						(end 251.980954 -41.999916)
					)
				)
			)
		)
		(zone
			(layer "F.Cu")
			(hatch none 0.5)
			(connect_pads
				(clearance 0)
			)
			(min_thickness 0.25)
			(keepout
				(tracks allowed)
				(vias not_allowed)
				(pads allowed)
				(copperpour not_allowed)
				(footprints allowed)
			)
			(placement
				(enabled no)
				(sheetname "")
			)
			(fill
				(thermal_gap 0.5)
				(thermal_bridge_width 0.5)
				(island_removal_mode 0)
			)
			(polygon
				(pts
					(arc
						(start 251.980954 -40.999918)
						(mid 251.218954 -40.999918)
						(end 251.980954 -40.999918)
					)
				)
			)
		)
		(zone
			(layer "F.Cu")
			(hatch none 0.5)
			(connect_pads
				(clearance 0)
			)
			(min_thickness 0.25)
			(keepout
				(tracks allowed)
				(vias not_allowed)
				(pads allowed)
				(copperpour not_allowed)
				(footprints allowed)
			)
			(placement
				(enabled no)
				(sheetname "")
			)
			(fill
				(thermal_gap 0.5)
				(thermal_bridge_width 0.5)
				(island_removal_mode 0)
			)
			(polygon
				(pts
					(arc
						(start 251.980954 -39.99992)
						(mid 251.218954 -39.99992)
						(end 251.980954 -39.99992)
					)
				)
			)
		)
		(zone
			(layer "F.Cu")
			(hatch none 0.5)
			(connect_pads
				(clearance 0)
			)
			(min_thickness 0.25)
			(keepout
				(tracks allowed)
				(vias not_allowed)
				(pads allowed)
				(copperpour not_allowed)
				(footprints allowed)
			)
			(placement
				(enabled no)
				(sheetname "")
			)
			(fill
				(thermal_gap 0.5)
				(thermal_bridge_width 0.5)
				(island_removal_mode 0)
			)
			(polygon
				(pts
					(arc
						(start 251.980954 -38.999922)
						(mid 251.218954 -38.999922)
						(end 251.980954 -38.999922)
					)
				)
			)
		)
		(zone
			(layer "F.Cu")
			(hatch none 0.5)
			(connect_pads
				(clearance 0)
			)
			(min_thickness 0.25)
			(keepout
				(tracks allowed)
				(vias not_allowed)
				(pads allowed)
				(copperpour not_allowed)
				(footprints allowed)
			)
			(placement
				(enabled no)
				(sheetname "")
			)
			(fill
				(thermal_gap 0.5)
				(thermal_bridge_width 0.5)
				(island_removal_mode 0)
			)
			(polygon
				(pts
					(arc
						(start 251.980954 -37.999924)
						(mid 251.218954 -37.999924)
						(end 251.980954 -37.999924)
					)
				)
			)
		)
		(zone
			(layer "F.Cu")
			(hatch none 0.5)
			(connect_pads
				(clearance 0)
			)
			(min_thickness 0.25)
			(keepout
				(tracks allowed)
				(vias not_allowed)
				(pads allowed)
				(copperpour not_allowed)
				(footprints allowed)
			)
			(placement
				(enabled no)
				(sheetname "")
			)
			(fill
				(thermal_gap 0.5)
				(thermal_bridge_width 0.5)
				(island_removal_mode 0)
			)
			(polygon
				(pts
					(arc
						(start 251.980954 -36.999926)
						(mid 251.218954 -36.999926)
						(end 251.980954 -36.999926)
					)
				)
			)
		)
		(zone
			(layer "F.Cu")
			(hatch none 0.5)
			(connect_pads
				(clearance 0)
			)
			(min_thickness 0.25)
			(keepout
				(tracks allowed)
				(vias not_allowed)
				(pads allowed)
				(copperpour not_allowed)
				(footprints allowed)
			)
			(placement
				(enabled no)
				(sheetname "")
			)
			(fill
				(thermal_gap 0.5)
				(thermal_bridge_width 0.5)
				(island_removal_mode 0)
			)
			(polygon
				(pts
					(arc
						(start 251.980954 -35.999928)
						(mid 251.218954 -35.999928)
						(end 251.980954 -35.999928)
					)
				)
			)
		)
		(zone
			(layer "F.Cu")
			(hatch none 0.5)
			(connect_pads
				(clearance 0)
			)
			(min_thickness 0.25)
			(keepout
				(tracks allowed)
				(vias not_allowed)
				(pads allowed)
				(copperpour not_allowed)
				(footprints allowed)
			)
			(placement
				(enabled no)
				(sheetname "")
			)
			(fill
				(thermal_gap 0.5)
				(thermal_bridge_width 0.5)
				(island_removal_mode 0)
			)
			(polygon
				(pts
					(arc
						(start 251.980954 -34.99993)
						(mid 251.218954 -34.99993)
						(end 251.980954 -34.99993)
					)
				)
			)
		)
		(zone
			(layer "F.Cu")
			(hatch none 0.5)
			(connect_pads
				(clearance 0)
			)
			(min_thickness 0.25)
			(keepout
				(tracks allowed)
				(vias not_allowed)
				(pads allowed)
				(copperpour not_allowed)
				(footprints allowed)
			)
			(placement
				(enabled no)
				(sheetname "")
			)
			(fill
				(thermal_gap 0.5)
				(thermal_bridge_width 0.5)
				(island_removal_mode 0)
			)
			(polygon
				(pts
					(arc
						(start 251.980954 -33.999932)
						(mid 251.218954 -33.999932)
						(end 251.980954 -33.999932)
					)
				)
			)
		)
		(zone
			(layer "F.Cu")
			(hatch none 0.5)
			(connect_pads
				(clearance 0)
			)
			(min_thickness 0.25)
			(keepout
				(tracks allowed)
				(vias not_allowed)
				(pads allowed)
				(copperpour not_allowed)
				(footprints allowed)
			)
			(placement
				(enabled no)
				(sheetname "")
			)
			(fill
				(thermal_gap 0.5)
				(thermal_bridge_width 0.5)
				(island_removal_mode 0)
			)
			(polygon
				(pts
					(arc
						(start 251.980954 -32.999934)
						(mid 251.218954 -32.999934)
						(end 251.980954 -32.999934)
					)
				)
			)
		)
		(zone
			(layer "F.Cu")
			(hatch none 0.5)
			(connect_pads
				(clearance 0)
			)
			(min_thickness 0.25)
			(keepout
				(tracks allowed)
				(vias not_allowed)
				(pads allowed)
				(copperpour not_allowed)
				(footprints allowed)
			)
			(placement
				(enabled no)
				(sheetname "")
			)
			(fill
				(thermal_gap 0.5)
				(thermal_bridge_width 0.5)
				(island_removal_mode 0)
			)
			(polygon
				(pts
					(arc
						(start 251.980954 -31.999936)
						(mid 251.218954 -31.999936)
						(end 251.980954 -31.999936)
					)
				)
			)
		)
		(zone
			(layer "F.Cu")
			(hatch none 0.5)
			(connect_pads
				(clearance 0)
			)
			(min_thickness 0.25)
			(keepout
				(tracks allowed)
				(vias not_allowed)
				(pads allowed)
				(copperpour not_allowed)
				(footprints allowed)
			)
			(placement
				(enabled no)
				(sheetname "")
			)
			(fill
				(thermal_gap 0.5)
				(thermal_bridge_width 0.5)
				(island_removal_mode 0)
			)
			(polygon
				(pts
					(arc
						(start 251.980954 -30.999938)
						(mid 251.218954 -30.999938)
						(end 251.980954 -30.999938)
					)
				)
			)
		)
		(zone
			(layer "F.Cu")
			(hatch none 0.5)
			(connect_pads
				(clearance 0)
			)
			(min_thickness 0.25)
			(keepout
				(tracks allowed)
				(vias not_allowed)
				(pads allowed)
				(copperpour not_allowed)
				(footprints allowed)
			)
			(placement
				(enabled no)
				(sheetname "")
			)
			(fill
				(thermal_gap 0.5)
				(thermal_bridge_width 0.5)
				(island_removal_mode 0)
			)
			(polygon
				(pts
					(arc
						(start 251.980954 -29.99994)
						(mid 251.218954 -29.99994)
						(end 251.980954 -29.99994)
					)
				)
			)
		)
		(zone
			(layer "F.Cu")
			(hatch none 0.5)
			(connect_pads
				(clearance 0)
			)
			(min_thickness 0.25)
			(keepout
				(tracks allowed)
				(vias not_allowed)
				(pads allowed)
				(copperpour not_allowed)
				(footprints allowed)
			)
			(placement
				(enabled no)
				(sheetname "")
			)
			(fill
				(thermal_gap 0.5)
				(thermal_bridge_width 0.5)
				(island_removal_mode 0)
			)
			(polygon
				(pts
					(arc
						(start 252.980952 -64.99987)
						(mid 252.218952 -64.99987)
						(end 252.980952 -64.99987)
					)
				)
			)
		)
		(zone
			(layer "F.Cu")
			(hatch none 0.5)
			(connect_pads
				(clearance 0)
			)
			(min_thickness 0.25)
			(keepout
				(tracks allowed)
				(vias not_allowed)
				(pads allowed)
				(copperpour not_allowed)
				(footprints allowed)
			)
			(placement
				(enabled no)
				(sheetname "")
			)
			(fill
				(thermal_gap 0.5)
				(thermal_bridge_width 0.5)
				(island_removal_mode 0)
			)
			(polygon
				(pts
					(arc
						(start 252.980952 -63.999872)
						(mid 252.218952 -63.999872)
						(end 252.980952 -63.999872)
					)
				)
			)
		)
		(zone
			(layer "F.Cu")
			(hatch none 0.5)
			(connect_pads
				(clearance 0)
			)
			(min_thickness 0.25)
			(keepout
				(tracks allowed)
				(vias not_allowed)
				(pads allowed)
				(copperpour not_allowed)
				(footprints allowed)
			)
			(placement
				(enabled no)
				(sheetname "")
			)
			(fill
				(thermal_gap 0.5)
				(thermal_bridge_width 0.5)
				(island_removal_mode 0)
			)
			(polygon
				(pts
					(arc
						(start 252.980952 -62.999874)
						(mid 252.218952 -62.999874)
						(end 252.980952 -62.999874)
					)
				)
			)
		)
		(zone
			(layer "F.Cu")
			(hatch none 0.5)
			(connect_pads
				(clearance 0)
			)
			(min_thickness 0.25)
			(keepout
				(tracks allowed)
				(vias not_allowed)
				(pads allowed)
				(copperpour not_allowed)
				(footprints allowed)
			)
			(placement
				(enabled no)
				(sheetname "")
			)
			(fill
				(thermal_gap 0.5)
				(thermal_bridge_width 0.5)
				(island_removal_mode 0)
			)
			(polygon
				(pts
					(arc
						(start 252.980952 -61.999876)
						(mid 252.218952 -61.999876)
						(end 252.980952 -61.999876)
					)
				)
			)
		)
		(zone
			(layer "F.Cu")
			(hatch none 0.5)
			(connect_pads
				(clearance 0)
			)
			(min_thickness 0.25)
			(keepout
				(tracks allowed)
				(vias not_allowed)
				(pads allowed)
				(copperpour not_allowed)
				(footprints allowed)
			)
			(placement
				(enabled no)
				(sheetname "")
			)
			(fill
				(thermal_gap 0.5)
				(thermal_bridge_width 0.5)
				(island_removal_mode 0)
			)
			(polygon
				(pts
					(arc
						(start 252.980952 -60.999878)
						(mid 252.218952 -60.999878)
						(end 252.980952 -60.999878)
					)
				)
			)
		)
		(zone
			(layer "F.Cu")
			(hatch none 0.5)
			(connect_pads
				(clearance 0)
			)
			(min_thickness 0.25)
			(keepout
				(tracks allowed)
				(vias not_allowed)
				(pads allowed)
				(copperpour not_allowed)
				(footprints allowed)
			)
			(placement
				(enabled no)
				(sheetname "")
			)
			(fill
				(thermal_gap 0.5)
				(thermal_bridge_width 0.5)
				(island_removal_mode 0)
			)
			(polygon
				(pts
					(arc
						(start 252.980952 -59.99988)
						(mid 252.218952 -59.99988)
						(end 252.980952 -59.99988)
					)
				)
			)
		)
		(zone
			(layer "F.Cu")
			(hatch none 0.5)
			(connect_pads
				(clearance 0)
			)
			(min_thickness 0.25)
			(keepout
				(tracks allowed)
				(vias not_allowed)
				(pads allowed)
				(copperpour not_allowed)
				(footprints allowed)
			)
			(placement
				(enabled no)
				(sheetname "")
			)
			(fill
				(thermal_gap 0.5)
				(thermal_bridge_width 0.5)
				(island_removal_mode 0)
			)
			(polygon
				(pts
					(arc
						(start 252.980952 -58.999882)
						(mid 252.218952 -58.999882)
						(end 252.980952 -58.999882)
					)
				)
			)
		)
		(zone
			(layer "F.Cu")
			(hatch none 0.5)
			(connect_pads
				(clearance 0)
			)
			(min_thickness 0.25)
			(keepout
				(tracks allowed)
				(vias not_allowed)
				(pads allowed)
				(copperpour not_allowed)
				(footprints allowed)
			)
			(placement
				(enabled no)
				(sheetname "")
			)
			(fill
				(thermal_gap 0.5)
				(thermal_bridge_width 0.5)
				(island_removal_mode 0)
			)
			(polygon
				(pts
					(arc
						(start 252.980952 -57.999884)
						(mid 252.218952 -57.999884)
						(end 252.980952 -57.999884)
					)
				)
			)
		)
		(zone
			(layer "F.Cu")
			(hatch none 0.5)
			(connect_pads
				(clearance 0)
			)
			(min_thickness 0.25)
			(keepout
				(tracks allowed)
				(vias not_allowed)
				(pads allowed)
				(copperpour not_allowed)
				(footprints allowed)
			)
			(placement
				(enabled no)
				(sheetname "")
			)
			(fill
				(thermal_gap 0.5)
				(thermal_bridge_width 0.5)
				(island_removal_mode 0)
			)
			(polygon
				(pts
					(arc
						(start 252.980952 -56.999886)
						(mid 252.218952 -56.999886)
						(end 252.980952 -56.999886)
					)
				)
			)
		)
		(zone
			(layer "F.Cu")
			(hatch none 0.5)
			(connect_pads
				(clearance 0)
			)
			(min_thickness 0.25)
			(keepout
				(tracks allowed)
				(vias not_allowed)
				(pads allowed)
				(copperpour not_allowed)
				(footprints allowed)
			)
			(placement
				(enabled no)
				(sheetname "")
			)
			(fill
				(thermal_gap 0.5)
				(thermal_bridge_width 0.5)
				(island_removal_mode 0)
			)
			(polygon
				(pts
					(arc
						(start 252.980952 -55.999888)
						(mid 252.218952 -55.999888)
						(end 252.980952 -55.999888)
					)
				)
			)
		)
		(zone
			(layer "F.Cu")
			(hatch none 0.5)
			(connect_pads
				(clearance 0)
			)
			(min_thickness 0.25)
			(keepout
				(tracks allowed)
				(vias not_allowed)
				(pads allowed)
				(copperpour not_allowed)
				(footprints allowed)
			)
			(placement
				(enabled no)
				(sheetname "")
			)
			(fill
				(thermal_gap 0.5)
				(thermal_bridge_width 0.5)
				(island_removal_mode 0)
			)
			(polygon
				(pts
					(arc
						(start 252.980952 -54.99989)
						(mid 252.218952 -54.99989)
						(end 252.980952 -54.99989)
					)
				)
			)
		)
		(zone
			(layer "F.Cu")
			(hatch none 0.5)
			(connect_pads
				(clearance 0)
			)
			(min_thickness 0.25)
			(keepout
				(tracks allowed)
				(vias not_allowed)
				(pads allowed)
				(copperpour not_allowed)
				(footprints allowed)
			)
			(placement
				(enabled no)
				(sheetname "")
			)
			(fill
				(thermal_gap 0.5)
				(thermal_bridge_width 0.5)
				(island_removal_mode 0)
			)
			(polygon
				(pts
					(arc
						(start 252.980952 -53.999892)
						(mid 252.218952 -53.999892)
						(end 252.980952 -53.999892)
					)
				)
			)
		)
		(zone
			(layer "F.Cu")
			(hatch none 0.5)
			(connect_pads
				(clearance 0)
			)
			(min_thickness 0.25)
			(keepout
				(tracks allowed)
				(vias not_allowed)
				(pads allowed)
				(copperpour not_allowed)
				(footprints allowed)
			)
			(placement
				(enabled no)
				(sheetname "")
			)
			(fill
				(thermal_gap 0.5)
				(thermal_bridge_width 0.5)
				(island_removal_mode 0)
			)
			(polygon
				(pts
					(arc
						(start 252.980952 -52.999894)
						(mid 252.218952 -52.999894)
						(end 252.980952 -52.999894)
					)
				)
			)
		)
		(zone
			(layer "F.Cu")
			(hatch none 0.5)
			(connect_pads
				(clearance 0)
			)
			(min_thickness 0.25)
			(keepout
				(tracks allowed)
				(vias not_allowed)
				(pads allowed)
				(copperpour not_allowed)
				(footprints allowed)
			)
			(placement
				(enabled no)
				(sheetname "")
			)
			(fill
				(thermal_gap 0.5)
				(thermal_bridge_width 0.5)
				(island_removal_mode 0)
			)
			(polygon
				(pts
					(arc
						(start 252.980952 -51.999896)
						(mid 252.218952 -51.999896)
						(end 252.980952 -51.999896)
					)
				)
			)
		)
		(zone
			(layer "F.Cu")
			(hatch none 0.5)
			(connect_pads
				(clearance 0)
			)
			(min_thickness 0.25)
			(keepout
				(tracks allowed)
				(vias not_allowed)
				(pads allowed)
				(copperpour not_allowed)
				(footprints allowed)
			)
			(placement
				(enabled no)
				(sheetname "")
			)
			(fill
				(thermal_gap 0.5)
				(thermal_bridge_width 0.5)
				(island_removal_mode 0)
			)
			(polygon
				(pts
					(arc
						(start 252.980952 -50.999898)
						(mid 252.218952 -50.999898)
						(end 252.980952 -50.999898)
					)
				)
			)
		)
		(zone
			(layer "F.Cu")
			(hatch none 0.5)
			(connect_pads
				(clearance 0)
			)
			(min_thickness 0.25)
			(keepout
				(tracks allowed)
				(vias not_allowed)
				(pads allowed)
				(copperpour not_allowed)
				(footprints allowed)
			)
			(placement
				(enabled no)
				(sheetname "")
			)
			(fill
				(thermal_gap 0.5)
				(thermal_bridge_width 0.5)
				(island_removal_mode 0)
			)
			(polygon
				(pts
					(arc
						(start 252.980952 -49.9999)
						(mid 252.218952 -49.9999)
						(end 252.980952 -49.9999)
					)
				)
			)
		)
		(zone
			(layer "F.Cu")
			(hatch none 0.5)
			(connect_pads
				(clearance 0)
			)
			(min_thickness 0.25)
			(keepout
				(tracks allowed)
				(vias not_allowed)
				(pads allowed)
				(copperpour not_allowed)
				(footprints allowed)
			)
			(placement
				(enabled no)
				(sheetname "")
			)
			(fill
				(thermal_gap 0.5)
				(thermal_bridge_width 0.5)
				(island_removal_mode 0)
			)
			(polygon
				(pts
					(arc
						(start 252.980952 -48.999902)
						(mid 252.218952 -48.999902)
						(end 252.980952 -48.999902)
					)
				)
			)
		)
		(zone
			(layer "F.Cu")
			(hatch none 0.5)
			(connect_pads
				(clearance 0)
			)
			(min_thickness 0.25)
			(keepout
				(tracks allowed)
				(vias not_allowed)
				(pads allowed)
				(copperpour not_allowed)
				(footprints allowed)
			)
			(placement
				(enabled no)
				(sheetname "")
			)
			(fill
				(thermal_gap 0.5)
				(thermal_bridge_width 0.5)
				(island_removal_mode 0)
			)
			(polygon
				(pts
					(arc
						(start 252.980952 -47.999904)
						(mid 252.218952 -47.999904)
						(end 252.980952 -47.999904)
					)
				)
			)
		)
		(zone
			(layer "F.Cu")
			(hatch none 0.5)
			(connect_pads
				(clearance 0)
			)
			(min_thickness 0.25)
			(keepout
				(tracks allowed)
				(vias not_allowed)
				(pads allowed)
				(copperpour not_allowed)
				(footprints allowed)
			)
			(placement
				(enabled no)
				(sheetname "")
			)
			(fill
				(thermal_gap 0.5)
				(thermal_bridge_width 0.5)
				(island_removal_mode 0)
			)
			(polygon
				(pts
					(arc
						(start 252.980952 -46.999906)
						(mid 252.218952 -46.999906)
						(end 252.980952 -46.999906)
					)
				)
			)
		)
		(zone
			(layer "F.Cu")
			(hatch none 0.5)
			(connect_pads
				(clearance 0)
			)
			(min_thickness 0.25)
			(keepout
				(tracks allowed)
				(vias not_allowed)
				(pads allowed)
				(copperpour not_allowed)
				(footprints allowed)
			)
			(placement
				(enabled no)
				(sheetname "")
			)
			(fill
				(thermal_gap 0.5)
				(thermal_bridge_width 0.5)
				(island_removal_mode 0)
			)
			(polygon
				(pts
					(arc
						(start 252.980952 -45.999908)
						(mid 252.218952 -45.999908)
						(end 252.980952 -45.999908)
					)
				)
			)
		)
		(zone
			(layer "F.Cu")
			(hatch none 0.5)
			(connect_pads
				(clearance 0)
			)
			(min_thickness 0.25)
			(keepout
				(tracks allowed)
				(vias not_allowed)
				(pads allowed)
				(copperpour not_allowed)
				(footprints allowed)
			)
			(placement
				(enabled no)
				(sheetname "")
			)
			(fill
				(thermal_gap 0.5)
				(thermal_bridge_width 0.5)
				(island_removal_mode 0)
			)
			(polygon
				(pts
					(arc
						(start 252.980952 -44.99991)
						(mid 252.218952 -44.99991)
						(end 252.980952 -44.99991)
					)
				)
			)
		)
		(zone
			(layer "F.Cu")
			(hatch none 0.5)
			(connect_pads
				(clearance 0)
			)
			(min_thickness 0.25)
			(keepout
				(tracks allowed)
				(vias not_allowed)
				(pads allowed)
				(copperpour not_allowed)
				(footprints allowed)
			)
			(placement
				(enabled no)
				(sheetname "")
			)
			(fill
				(thermal_gap 0.5)
				(thermal_bridge_width 0.5)
				(island_removal_mode 0)
			)
			(polygon
				(pts
					(arc
						(start 252.980952 -43.999912)
						(mid 252.218952 -43.999912)
						(end 252.980952 -43.999912)
					)
				)
			)
		)
		(zone
			(layer "F.Cu")
			(hatch none 0.5)
			(connect_pads
				(clearance 0)
			)
			(min_thickness 0.25)
			(keepout
				(tracks allowed)
				(vias not_allowed)
				(pads allowed)
				(copperpour not_allowed)
				(footprints allowed)
			)
			(placement
				(enabled no)
				(sheetname "")
			)
			(fill
				(thermal_gap 0.5)
				(thermal_bridge_width 0.5)
				(island_removal_mode 0)
			)
			(polygon
				(pts
					(arc
						(start 252.980952 -42.999914)
						(mid 252.218952 -42.999914)
						(end 252.980952 -42.999914)
					)
				)
			)
		)
		(zone
			(layer "F.Cu")
			(hatch none 0.5)
			(connect_pads
				(clearance 0)
			)
			(min_thickness 0.25)
			(keepout
				(tracks allowed)
				(vias not_allowed)
				(pads allowed)
				(copperpour not_allowed)
				(footprints allowed)
			)
			(placement
				(enabled no)
				(sheetname "")
			)
			(fill
				(thermal_gap 0.5)
				(thermal_bridge_width 0.5)
				(island_removal_mode 0)
			)
			(polygon
				(pts
					(arc
						(start 252.980952 -41.999916)
						(mid 252.218952 -41.999916)
						(end 252.980952 -41.999916)
					)
				)
			)
		)
		(zone
			(layer "F.Cu")
			(hatch none 0.5)
			(connect_pads
				(clearance 0)
			)
			(min_thickness 0.25)
			(keepout
				(tracks allowed)
				(vias not_allowed)
				(pads allowed)
				(copperpour not_allowed)
				(footprints allowed)
			)
			(placement
				(enabled no)
				(sheetname "")
			)
			(fill
				(thermal_gap 0.5)
				(thermal_bridge_width 0.5)
				(island_removal_mode 0)
			)
			(polygon
				(pts
					(arc
						(start 252.980952 -40.999918)
						(mid 252.218952 -40.999918)
						(end 252.980952 -40.999918)
					)
				)
			)
		)
		(zone
			(layer "F.Cu")
			(hatch none 0.5)
			(connect_pads
				(clearance 0)
			)
			(min_thickness 0.25)
			(keepout
				(tracks allowed)
				(vias not_allowed)
				(pads allowed)
				(copperpour not_allowed)
				(footprints allowed)
			)
			(placement
				(enabled no)
				(sheetname "")
			)
			(fill
				(thermal_gap 0.5)
				(thermal_bridge_width 0.5)
				(island_removal_mode 0)
			)
			(polygon
				(pts
					(arc
						(start 252.980952 -39.99992)
						(mid 252.218952 -39.99992)
						(end 252.980952 -39.99992)
					)
				)
			)
		)
		(zone
			(layer "F.Cu")
			(hatch none 0.5)
			(connect_pads
				(clearance 0)
			)
			(min_thickness 0.25)
			(keepout
				(tracks allowed)
				(vias not_allowed)
				(pads allowed)
				(copperpour not_allowed)
				(footprints allowed)
			)
			(placement
				(enabled no)
				(sheetname "")
			)
			(fill
				(thermal_gap 0.5)
				(thermal_bridge_width 0.5)
				(island_removal_mode 0)
			)
			(polygon
				(pts
					(arc
						(start 252.980952 -38.999922)
						(mid 252.218952 -38.999922)
						(end 252.980952 -38.999922)
					)
				)
			)
		)
		(zone
			(layer "F.Cu")
			(hatch none 0.5)
			(connect_pads
				(clearance 0)
			)
			(min_thickness 0.25)
			(keepout
				(tracks allowed)
				(vias not_allowed)
				(pads allowed)
				(copperpour not_allowed)
				(footprints allowed)
			)
			(placement
				(enabled no)
				(sheetname "")
			)
			(fill
				(thermal_gap 0.5)
				(thermal_bridge_width 0.5)
				(island_removal_mode 0)
			)
			(polygon
				(pts
					(arc
						(start 252.980952 -37.999924)
						(mid 252.218952 -37.999924)
						(end 252.980952 -37.999924)
					)
				)
			)
		)
		(zone
			(layer "F.Cu")
			(hatch none 0.5)
			(connect_pads
				(clearance 0)
			)
			(min_thickness 0.25)
			(keepout
				(tracks allowed)
				(vias not_allowed)
				(pads allowed)
				(copperpour not_allowed)
				(footprints allowed)
			)
			(placement
				(enabled no)
				(sheetname "")
			)
			(fill
				(thermal_gap 0.5)
				(thermal_bridge_width 0.5)
				(island_removal_mode 0)
			)
			(polygon
				(pts
					(arc
						(start 252.980952 -36.999926)
						(mid 252.218952 -36.999926)
						(end 252.980952 -36.999926)
					)
				)
			)
		)
		(zone
			(layer "F.Cu")
			(hatch none 0.5)
			(connect_pads
				(clearance 0)
			)
			(min_thickness 0.25)
			(keepout
				(tracks allowed)
				(vias not_allowed)
				(pads allowed)
				(copperpour not_allowed)
				(footprints allowed)
			)
			(placement
				(enabled no)
				(sheetname "")
			)
			(fill
				(thermal_gap 0.5)
				(thermal_bridge_width 0.5)
				(island_removal_mode 0)
			)
			(polygon
				(pts
					(arc
						(start 252.980952 -35.999928)
						(mid 252.218952 -35.999928)
						(end 252.980952 -35.999928)
					)
				)
			)
		)
		(zone
			(layer "F.Cu")
			(hatch none 0.5)
			(connect_pads
				(clearance 0)
			)
			(min_thickness 0.25)
			(keepout
				(tracks allowed)
				(vias not_allowed)
				(pads allowed)
				(copperpour not_allowed)
				(footprints allowed)
			)
			(placement
				(enabled no)
				(sheetname "")
			)
			(fill
				(thermal_gap 0.5)
				(thermal_bridge_width 0.5)
				(island_removal_mode 0)
			)
			(polygon
				(pts
					(arc
						(start 252.980952 -34.99993)
						(mid 252.218952 -34.99993)
						(end 252.980952 -34.99993)
					)
				)
			)
		)
		(zone
			(layer "F.Cu")
			(hatch none 0.5)
			(connect_pads
				(clearance 0)
			)
			(min_thickness 0.25)
			(keepout
				(tracks allowed)
				(vias not_allowed)
				(pads allowed)
				(copperpour not_allowed)
				(footprints allowed)
			)
			(placement
				(enabled no)
				(sheetname "")
			)
			(fill
				(thermal_gap 0.5)
				(thermal_bridge_width 0.5)
				(island_removal_mode 0)
			)
			(polygon
				(pts
					(arc
						(start 252.980952 -33.999932)
						(mid 252.218952 -33.999932)
						(end 252.980952 -33.999932)
					)
				)
			)
		)
		(zone
			(layer "F.Cu")
			(hatch none 0.5)
			(connect_pads
				(clearance 0)
			)
			(min_thickness 0.25)
			(keepout
				(tracks allowed)
				(vias not_allowed)
				(pads allowed)
				(copperpour not_allowed)
				(footprints allowed)
			)
			(placement
				(enabled no)
				(sheetname "")
			)
			(fill
				(thermal_gap 0.5)
				(thermal_bridge_width 0.5)
				(island_removal_mode 0)
			)
			(polygon
				(pts
					(arc
						(start 252.980952 -32.999934)
						(mid 252.218952 -32.999934)
						(end 252.980952 -32.999934)
					)
				)
			)
		)
		(zone
			(layer "F.Cu")
			(hatch none 0.5)
			(connect_pads
				(clearance 0)
			)
			(min_thickness 0.25)
			(keepout
				(tracks allowed)
				(vias not_allowed)
				(pads allowed)
				(copperpour not_allowed)
				(footprints allowed)
			)
			(placement
				(enabled no)
				(sheetname "")
			)
			(fill
				(thermal_gap 0.5)
				(thermal_bridge_width 0.5)
				(island_removal_mode 0)
			)
			(polygon
				(pts
					(arc
						(start 252.980952 -31.999936)
						(mid 252.218952 -31.999936)
						(end 252.980952 -31.999936)
					)
				)
			)
		)
		(zone
			(layer "F.Cu")
			(hatch none 0.5)
			(connect_pads
				(clearance 0)
			)
			(min_thickness 0.25)
			(keepout
				(tracks allowed)
				(vias not_allowed)
				(pads allowed)
				(copperpour not_allowed)
				(footprints allowed)
			)
			(placement
				(enabled no)
				(sheetname "")
			)
			(fill
				(thermal_gap 0.5)
				(thermal_bridge_width 0.5)
				(island_removal_mode 0)
			)
			(polygon
				(pts
					(arc
						(start 252.980952 -30.999938)
						(mid 252.218952 -30.999938)
						(end 252.980952 -30.999938)
					)
				)
			)
		)
		(zone
			(layer "F.Cu")
			(hatch none 0.5)
			(connect_pads
				(clearance 0)
			)
			(min_thickness 0.25)
			(keepout
				(tracks allowed)
				(vias not_allowed)
				(pads allowed)
				(copperpour not_allowed)
				(footprints allowed)
			)
			(placement
				(enabled no)
				(sheetname "")
			)
			(fill
				(thermal_gap 0.5)
				(thermal_bridge_width 0.5)
				(island_removal_mode 0)
			)
			(polygon
				(pts
					(arc
						(start 253.98095 -65.999868)
						(mid 253.21895 -65.999868)
						(end 253.98095 -65.999868)
					)
				)
			)
		)
		(zone
			(layer "F.Cu")
			(hatch none 0.5)
			(connect_pads
				(clearance 0)
			)
			(min_thickness 0.25)
			(keepout
				(tracks allowed)
				(vias not_allowed)
				(pads allowed)
				(copperpour not_allowed)
				(footprints allowed)
			)
			(placement
				(enabled no)
				(sheetname "")
			)
			(fill
				(thermal_gap 0.5)
				(thermal_bridge_width 0.5)
				(island_removal_mode 0)
			)
			(polygon
				(pts
					(arc
						(start 253.98095 -64.99987)
						(mid 253.21895 -64.99987)
						(end 253.98095 -64.99987)
					)
				)
			)
		)
		(zone
			(layer "F.Cu")
			(hatch none 0.5)
			(connect_pads
				(clearance 0)
			)
			(min_thickness 0.25)
			(keepout
				(tracks allowed)
				(vias not_allowed)
				(pads allowed)
				(copperpour not_allowed)
				(footprints allowed)
			)
			(placement
				(enabled no)
				(sheetname "")
			)
			(fill
				(thermal_gap 0.5)
				(thermal_bridge_width 0.5)
				(island_removal_mode 0)
			)
			(polygon
				(pts
					(arc
						(start 253.98095 -63.999872)
						(mid 253.21895 -63.999872)
						(end 253.98095 -63.999872)
					)
				)
			)
		)
		(zone
			(layer "F.Cu")
			(hatch none 0.5)
			(connect_pads
				(clearance 0)
			)
			(min_thickness 0.25)
			(keepout
				(tracks allowed)
				(vias not_allowed)
				(pads allowed)
				(copperpour not_allowed)
				(footprints allowed)
			)
			(placement
				(enabled no)
				(sheetname "")
			)
			(fill
				(thermal_gap 0.5)
				(thermal_bridge_width 0.5)
				(island_removal_mode 0)
			)
			(polygon
				(pts
					(arc
						(start 253.98095 -62.999874)
						(mid 253.21895 -62.999874)
						(end 253.98095 -62.999874)
					)
				)
			)
		)
		(zone
			(layer "F.Cu")
			(hatch none 0.5)
			(connect_pads
				(clearance 0)
			)
			(min_thickness 0.25)
			(keepout
				(tracks allowed)
				(vias not_allowed)
				(pads allowed)
				(copperpour not_allowed)
				(footprints allowed)
			)
			(placement
				(enabled no)
				(sheetname "")
			)
			(fill
				(thermal_gap 0.5)
				(thermal_bridge_width 0.5)
				(island_removal_mode 0)
			)
			(polygon
				(pts
					(arc
						(start 253.98095 -61.999876)
						(mid 253.21895 -61.999876)
						(end 253.98095 -61.999876)
					)
				)
			)
		)
		(zone
			(layer "F.Cu")
			(hatch none 0.5)
			(connect_pads
				(clearance 0)
			)
			(min_thickness 0.25)
			(keepout
				(tracks allowed)
				(vias not_allowed)
				(pads allowed)
				(copperpour not_allowed)
				(footprints allowed)
			)
			(placement
				(enabled no)
				(sheetname "")
			)
			(fill
				(thermal_gap 0.5)
				(thermal_bridge_width 0.5)
				(island_removal_mode 0)
			)
			(polygon
				(pts
					(arc
						(start 253.98095 -60.999878)
						(mid 253.21895 -60.999878)
						(end 253.98095 -60.999878)
					)
				)
			)
		)
		(zone
			(layer "F.Cu")
			(hatch none 0.5)
			(connect_pads
				(clearance 0)
			)
			(min_thickness 0.25)
			(keepout
				(tracks allowed)
				(vias not_allowed)
				(pads allowed)
				(copperpour not_allowed)
				(footprints allowed)
			)
			(placement
				(enabled no)
				(sheetname "")
			)
			(fill
				(thermal_gap 0.5)
				(thermal_bridge_width 0.5)
				(island_removal_mode 0)
			)
			(polygon
				(pts
					(arc
						(start 253.98095 -59.99988)
						(mid 253.21895 -59.99988)
						(end 253.98095 -59.99988)
					)
				)
			)
		)
		(zone
			(layer "F.Cu")
			(hatch none 0.5)
			(connect_pads
				(clearance 0)
			)
			(min_thickness 0.25)
			(keepout
				(tracks allowed)
				(vias not_allowed)
				(pads allowed)
				(copperpour not_allowed)
				(footprints allowed)
			)
			(placement
				(enabled no)
				(sheetname "")
			)
			(fill
				(thermal_gap 0.5)
				(thermal_bridge_width 0.5)
				(island_removal_mode 0)
			)
			(polygon
				(pts
					(arc
						(start 253.98095 -58.999882)
						(mid 253.21895 -58.999882)
						(end 253.98095 -58.999882)
					)
				)
			)
		)
		(zone
			(layer "F.Cu")
			(hatch none 0.5)
			(connect_pads
				(clearance 0)
			)
			(min_thickness 0.25)
			(keepout
				(tracks allowed)
				(vias not_allowed)
				(pads allowed)
				(copperpour not_allowed)
				(footprints allowed)
			)
			(placement
				(enabled no)
				(sheetname "")
			)
			(fill
				(thermal_gap 0.5)
				(thermal_bridge_width 0.5)
				(island_removal_mode 0)
			)
			(polygon
				(pts
					(arc
						(start 253.98095 -57.999884)
						(mid 253.21895 -57.999884)
						(end 253.98095 -57.999884)
					)
				)
			)
		)
		(zone
			(layer "F.Cu")
			(hatch none 0.5)
			(connect_pads
				(clearance 0)
			)
			(min_thickness 0.25)
			(keepout
				(tracks allowed)
				(vias not_allowed)
				(pads allowed)
				(copperpour not_allowed)
				(footprints allowed)
			)
			(placement
				(enabled no)
				(sheetname "")
			)
			(fill
				(thermal_gap 0.5)
				(thermal_bridge_width 0.5)
				(island_removal_mode 0)
			)
			(polygon
				(pts
					(arc
						(start 253.98095 -56.999886)
						(mid 253.21895 -56.999886)
						(end 253.98095 -56.999886)
					)
				)
			)
		)
		(zone
			(layer "F.Cu")
			(hatch none 0.5)
			(connect_pads
				(clearance 0)
			)
			(min_thickness 0.25)
			(keepout
				(tracks allowed)
				(vias not_allowed)
				(pads allowed)
				(copperpour not_allowed)
				(footprints allowed)
			)
			(placement
				(enabled no)
				(sheetname "")
			)
			(fill
				(thermal_gap 0.5)
				(thermal_bridge_width 0.5)
				(island_removal_mode 0)
			)
			(polygon
				(pts
					(arc
						(start 253.98095 -55.999888)
						(mid 253.21895 -55.999888)
						(end 253.98095 -55.999888)
					)
				)
			)
		)
		(zone
			(layer "F.Cu")
			(hatch none 0.5)
			(connect_pads
				(clearance 0)
			)
			(min_thickness 0.25)
			(keepout
				(tracks allowed)
				(vias not_allowed)
				(pads allowed)
				(copperpour not_allowed)
				(footprints allowed)
			)
			(placement
				(enabled no)
				(sheetname "")
			)
			(fill
				(thermal_gap 0.5)
				(thermal_bridge_width 0.5)
				(island_removal_mode 0)
			)
			(polygon
				(pts
					(arc
						(start 253.98095 -54.99989)
						(mid 253.21895 -54.99989)
						(end 253.98095 -54.99989)
					)
				)
			)
		)
		(zone
			(layer "F.Cu")
			(hatch none 0.5)
			(connect_pads
				(clearance 0)
			)
			(min_thickness 0.25)
			(keepout
				(tracks allowed)
				(vias not_allowed)
				(pads allowed)
				(copperpour not_allowed)
				(footprints allowed)
			)
			(placement
				(enabled no)
				(sheetname "")
			)
			(fill
				(thermal_gap 0.5)
				(thermal_bridge_width 0.5)
				(island_removal_mode 0)
			)
			(polygon
				(pts
					(arc
						(start 253.98095 -53.999892)
						(mid 253.21895 -53.999892)
						(end 253.98095 -53.999892)
					)
				)
			)
		)
		(zone
			(layer "F.Cu")
			(hatch none 0.5)
			(connect_pads
				(clearance 0)
			)
			(min_thickness 0.25)
			(keepout
				(tracks allowed)
				(vias not_allowed)
				(pads allowed)
				(copperpour not_allowed)
				(footprints allowed)
			)
			(placement
				(enabled no)
				(sheetname "")
			)
			(fill
				(thermal_gap 0.5)
				(thermal_bridge_width 0.5)
				(island_removal_mode 0)
			)
			(polygon
				(pts
					(arc
						(start 253.98095 -52.999894)
						(mid 253.21895 -52.999894)
						(end 253.98095 -52.999894)
					)
				)
			)
		)
		(zone
			(layer "F.Cu")
			(hatch none 0.5)
			(connect_pads
				(clearance 0)
			)
			(min_thickness 0.25)
			(keepout
				(tracks allowed)
				(vias not_allowed)
				(pads allowed)
				(copperpour not_allowed)
				(footprints allowed)
			)
			(placement
				(enabled no)
				(sheetname "")
			)
			(fill
				(thermal_gap 0.5)
				(thermal_bridge_width 0.5)
				(island_removal_mode 0)
			)
			(polygon
				(pts
					(arc
						(start 253.98095 -51.999896)
						(mid 253.21895 -51.999896)
						(end 253.98095 -51.999896)
					)
				)
			)
		)
		(zone
			(layer "F.Cu")
			(hatch none 0.5)
			(connect_pads
				(clearance 0)
			)
			(min_thickness 0.25)
			(keepout
				(tracks allowed)
				(vias not_allowed)
				(pads allowed)
				(copperpour not_allowed)
				(footprints allowed)
			)
			(placement
				(enabled no)
				(sheetname "")
			)
			(fill
				(thermal_gap 0.5)
				(thermal_bridge_width 0.5)
				(island_removal_mode 0)
			)
			(polygon
				(pts
					(arc
						(start 253.98095 -50.999898)
						(mid 253.21895 -50.999898)
						(end 253.98095 -50.999898)
					)
				)
			)
		)
		(zone
			(layer "F.Cu")
			(hatch none 0.5)
			(connect_pads
				(clearance 0)
			)
			(min_thickness 0.25)
			(keepout
				(tracks allowed)
				(vias not_allowed)
				(pads allowed)
				(copperpour not_allowed)
				(footprints allowed)
			)
			(placement
				(enabled no)
				(sheetname "")
			)
			(fill
				(thermal_gap 0.5)
				(thermal_bridge_width 0.5)
				(island_removal_mode 0)
			)
			(polygon
				(pts
					(arc
						(start 253.98095 -49.9999)
						(mid 253.21895 -49.9999)
						(end 253.98095 -49.9999)
					)
				)
			)
		)
		(zone
			(layer "F.Cu")
			(hatch none 0.5)
			(connect_pads
				(clearance 0)
			)
			(min_thickness 0.25)
			(keepout
				(tracks allowed)
				(vias not_allowed)
				(pads allowed)
				(copperpour not_allowed)
				(footprints allowed)
			)
			(placement
				(enabled no)
				(sheetname "")
			)
			(fill
				(thermal_gap 0.5)
				(thermal_bridge_width 0.5)
				(island_removal_mode 0)
			)
			(polygon
				(pts
					(arc
						(start 253.98095 -48.999902)
						(mid 253.21895 -48.999902)
						(end 253.98095 -48.999902)
					)
				)
			)
		)
		(zone
			(layer "F.Cu")
			(hatch none 0.5)
			(connect_pads
				(clearance 0)
			)
			(min_thickness 0.25)
			(keepout
				(tracks allowed)
				(vias not_allowed)
				(pads allowed)
				(copperpour not_allowed)
				(footprints allowed)
			)
			(placement
				(enabled no)
				(sheetname "")
			)
			(fill
				(thermal_gap 0.5)
				(thermal_bridge_width 0.5)
				(island_removal_mode 0)
			)
			(polygon
				(pts
					(arc
						(start 253.98095 -47.999904)
						(mid 253.21895 -47.999904)
						(end 253.98095 -47.999904)
					)
				)
			)
		)
		(zone
			(layer "F.Cu")
			(hatch none 0.5)
			(connect_pads
				(clearance 0)
			)
			(min_thickness 0.25)
			(keepout
				(tracks allowed)
				(vias not_allowed)
				(pads allowed)
				(copperpour not_allowed)
				(footprints allowed)
			)
			(placement
				(enabled no)
				(sheetname "")
			)
			(fill
				(thermal_gap 0.5)
				(thermal_bridge_width 0.5)
				(island_removal_mode 0)
			)
			(polygon
				(pts
					(arc
						(start 253.98095 -46.999906)
						(mid 253.21895 -46.999906)
						(end 253.98095 -46.999906)
					)
				)
			)
		)
		(zone
			(layer "F.Cu")
			(hatch none 0.5)
			(connect_pads
				(clearance 0)
			)
			(min_thickness 0.25)
			(keepout
				(tracks allowed)
				(vias not_allowed)
				(pads allowed)
				(copperpour not_allowed)
				(footprints allowed)
			)
			(placement
				(enabled no)
				(sheetname "")
			)
			(fill
				(thermal_gap 0.5)
				(thermal_bridge_width 0.5)
				(island_removal_mode 0)
			)
			(polygon
				(pts
					(arc
						(start 253.98095 -45.999908)
						(mid 253.21895 -45.999908)
						(end 253.98095 -45.999908)
					)
				)
			)
		)
		(zone
			(layer "F.Cu")
			(hatch none 0.5)
			(connect_pads
				(clearance 0)
			)
			(min_thickness 0.25)
			(keepout
				(tracks allowed)
				(vias not_allowed)
				(pads allowed)
				(copperpour not_allowed)
				(footprints allowed)
			)
			(placement
				(enabled no)
				(sheetname "")
			)
			(fill
				(thermal_gap 0.5)
				(thermal_bridge_width 0.5)
				(island_removal_mode 0)
			)
			(polygon
				(pts
					(arc
						(start 253.98095 -44.99991)
						(mid 253.21895 -44.99991)
						(end 253.98095 -44.99991)
					)
				)
			)
		)
		(zone
			(layer "F.Cu")
			(hatch none 0.5)
			(connect_pads
				(clearance 0)
			)
			(min_thickness 0.25)
			(keepout
				(tracks allowed)
				(vias not_allowed)
				(pads allowed)
				(copperpour not_allowed)
				(footprints allowed)
			)
			(placement
				(enabled no)
				(sheetname "")
			)
			(fill
				(thermal_gap 0.5)
				(thermal_bridge_width 0.5)
				(island_removal_mode 0)
			)
			(polygon
				(pts
					(arc
						(start 253.98095 -43.999912)
						(mid 253.21895 -43.999912)
						(end 253.98095 -43.999912)
					)
				)
			)
		)
		(zone
			(layer "F.Cu")
			(hatch none 0.5)
			(connect_pads
				(clearance 0)
			)
			(min_thickness 0.25)
			(keepout
				(tracks allowed)
				(vias not_allowed)
				(pads allowed)
				(copperpour not_allowed)
				(footprints allowed)
			)
			(placement
				(enabled no)
				(sheetname "")
			)
			(fill
				(thermal_gap 0.5)
				(thermal_bridge_width 0.5)
				(island_removal_mode 0)
			)
			(polygon
				(pts
					(arc
						(start 253.98095 -42.999914)
						(mid 253.21895 -42.999914)
						(end 253.98095 -42.999914)
					)
				)
			)
		)
		(zone
			(layer "F.Cu")
			(hatch none 0.5)
			(connect_pads
				(clearance 0)
			)
			(min_thickness 0.25)
			(keepout
				(tracks allowed)
				(vias not_allowed)
				(pads allowed)
				(copperpour not_allowed)
				(footprints allowed)
			)
			(placement
				(enabled no)
				(sheetname "")
			)
			(fill
				(thermal_gap 0.5)
				(thermal_bridge_width 0.5)
				(island_removal_mode 0)
			)
			(polygon
				(pts
					(arc
						(start 253.98095 -41.999916)
						(mid 253.21895 -41.999916)
						(end 253.98095 -41.999916)
					)
				)
			)
		)
		(zone
			(layer "F.Cu")
			(hatch none 0.5)
			(connect_pads
				(clearance 0)
			)
			(min_thickness 0.25)
			(keepout
				(tracks allowed)
				(vias not_allowed)
				(pads allowed)
				(copperpour not_allowed)
				(footprints allowed)
			)
			(placement
				(enabled no)
				(sheetname "")
			)
			(fill
				(thermal_gap 0.5)
				(thermal_bridge_width 0.5)
				(island_removal_mode 0)
			)
			(polygon
				(pts
					(arc
						(start 253.98095 -40.999918)
						(mid 253.21895 -40.999918)
						(end 253.98095 -40.999918)
					)
				)
			)
		)
		(zone
			(layer "F.Cu")
			(hatch none 0.5)
			(connect_pads
				(clearance 0)
			)
			(min_thickness 0.25)
			(keepout
				(tracks allowed)
				(vias not_allowed)
				(pads allowed)
				(copperpour not_allowed)
				(footprints allowed)
			)
			(placement
				(enabled no)
				(sheetname "")
			)
			(fill
				(thermal_gap 0.5)
				(thermal_bridge_width 0.5)
				(island_removal_mode 0)
			)
			(polygon
				(pts
					(arc
						(start 253.98095 -39.99992)
						(mid 253.21895 -39.99992)
						(end 253.98095 -39.99992)
					)
				)
			)
		)
		(zone
			(layer "F.Cu")
			(hatch none 0.5)
			(connect_pads
				(clearance 0)
			)
			(min_thickness 0.25)
			(keepout
				(tracks allowed)
				(vias not_allowed)
				(pads allowed)
				(copperpour not_allowed)
				(footprints allowed)
			)
			(placement
				(enabled no)
				(sheetname "")
			)
			(fill
				(thermal_gap 0.5)
				(thermal_bridge_width 0.5)
				(island_removal_mode 0)
			)
			(polygon
				(pts
					(arc
						(start 253.98095 -38.999922)
						(mid 253.21895 -38.999922)
						(end 253.98095 -38.999922)
					)
				)
			)
		)
		(zone
			(layer "F.Cu")
			(hatch none 0.5)
			(connect_pads
				(clearance 0)
			)
			(min_thickness 0.25)
			(keepout
				(tracks allowed)
				(vias not_allowed)
				(pads allowed)
				(copperpour not_allowed)
				(footprints allowed)
			)
			(placement
				(enabled no)
				(sheetname "")
			)
			(fill
				(thermal_gap 0.5)
				(thermal_bridge_width 0.5)
				(island_removal_mode 0)
			)
			(polygon
				(pts
					(arc
						(start 253.98095 -37.999924)
						(mid 253.21895 -37.999924)
						(end 253.98095 -37.999924)
					)
				)
			)
		)
		(zone
			(layer "F.Cu")
			(hatch none 0.5)
			(connect_pads
				(clearance 0)
			)
			(min_thickness 0.25)
			(keepout
				(tracks allowed)
				(vias not_allowed)
				(pads allowed)
				(copperpour not_allowed)
				(footprints allowed)
			)
			(placement
				(enabled no)
				(sheetname "")
			)
			(fill
				(thermal_gap 0.5)
				(thermal_bridge_width 0.5)
				(island_removal_mode 0)
			)
			(polygon
				(pts
					(arc
						(start 253.98095 -36.999926)
						(mid 253.21895 -36.999926)
						(end 253.98095 -36.999926)
					)
				)
			)
		)
		(zone
			(layer "F.Cu")
			(hatch none 0.5)
			(connect_pads
				(clearance 0)
			)
			(min_thickness 0.25)
			(keepout
				(tracks allowed)
				(vias not_allowed)
				(pads allowed)
				(copperpour not_allowed)
				(footprints allowed)
			)
			(placement
				(enabled no)
				(sheetname "")
			)
			(fill
				(thermal_gap 0.5)
				(thermal_bridge_width 0.5)
				(island_removal_mode 0)
			)
			(polygon
				(pts
					(arc
						(start 253.98095 -35.999928)
						(mid 253.21895 -35.999928)
						(end 253.98095 -35.999928)
					)
				)
			)
		)
		(zone
			(layer "F.Cu")
			(hatch none 0.5)
			(connect_pads
				(clearance 0)
			)
			(min_thickness 0.25)
			(keepout
				(tracks allowed)
				(vias not_allowed)
				(pads allowed)
				(copperpour not_allowed)
				(footprints allowed)
			)
			(placement
				(enabled no)
				(sheetname "")
			)
			(fill
				(thermal_gap 0.5)
				(thermal_bridge_width 0.5)
				(island_removal_mode 0)
			)
			(polygon
				(pts
					(arc
						(start 253.98095 -34.99993)
						(mid 253.21895 -34.99993)
						(end 253.98095 -34.99993)
					)
				)
			)
		)
		(zone
			(layer "F.Cu")
			(hatch none 0.5)
			(connect_pads
				(clearance 0)
			)
			(min_thickness 0.25)
			(keepout
				(tracks allowed)
				(vias not_allowed)
				(pads allowed)
				(copperpour not_allowed)
				(footprints allowed)
			)
			(placement
				(enabled no)
				(sheetname "")
			)
			(fill
				(thermal_gap 0.5)
				(thermal_bridge_width 0.5)
				(island_removal_mode 0)
			)
			(polygon
				(pts
					(arc
						(start 253.98095 -33.999932)
						(mid 253.21895 -33.999932)
						(end 253.98095 -33.999932)
					)
				)
			)
		)
		(zone
			(layer "F.Cu")
			(hatch none 0.5)
			(connect_pads
				(clearance 0)
			)
			(min_thickness 0.25)
			(keepout
				(tracks allowed)
				(vias not_allowed)
				(pads allowed)
				(copperpour not_allowed)
				(footprints allowed)
			)
			(placement
				(enabled no)
				(sheetname "")
			)
			(fill
				(thermal_gap 0.5)
				(thermal_bridge_width 0.5)
				(island_removal_mode 0)
			)
			(polygon
				(pts
					(arc
						(start 253.98095 -32.999934)
						(mid 253.21895 -32.999934)
						(end 253.98095 -32.999934)
					)
				)
			)
		)
		(zone
			(layer "F.Cu")
			(hatch none 0.5)
			(connect_pads
				(clearance 0)
			)
			(min_thickness 0.25)
			(keepout
				(tracks allowed)
				(vias not_allowed)
				(pads allowed)
				(copperpour not_allowed)
				(footprints allowed)
			)
			(placement
				(enabled no)
				(sheetname "")
			)
			(fill
				(thermal_gap 0.5)
				(thermal_bridge_width 0.5)
				(island_removal_mode 0)
			)
			(polygon
				(pts
					(arc
						(start 253.98095 -31.999936)
						(mid 253.21895 -31.999936)
						(end 253.98095 -31.999936)
					)
				)
			)
		)
		(zone
			(layer "F.Cu")
			(hatch none 0.5)
			(connect_pads
				(clearance 0)
			)
			(min_thickness 0.25)
			(keepout
				(tracks allowed)
				(vias not_allowed)
				(pads allowed)
				(copperpour not_allowed)
				(footprints allowed)
			)
			(placement
				(enabled no)
				(sheetname "")
			)
			(fill
				(thermal_gap 0.5)
				(thermal_bridge_width 0.5)
				(island_removal_mode 0)
			)
			(polygon
				(pts
					(arc
						(start 253.98095 -30.999938)
						(mid 253.21895 -30.999938)
						(end 253.98095 -30.999938)
					)
				)
			)
		)
		(zone
			(layer "F.Cu")
			(hatch none 0.5)
			(connect_pads
				(clearance 0)
			)
			(min_thickness 0.25)
			(keepout
				(tracks allowed)
				(vias not_allowed)
				(pads allowed)
				(copperpour not_allowed)
				(footprints allowed)
			)
			(placement
				(enabled no)
				(sheetname "")
			)
			(fill
				(thermal_gap 0.5)
				(thermal_bridge_width 0.5)
				(island_removal_mode 0)
			)
			(polygon
				(pts
					(arc
						(start 253.98095 -29.99994)
						(mid 253.21895 -29.99994)
						(end 253.98095 -29.99994)
					)
				)
			)
		)
		(zone
			(layer "F.Cu")
			(hatch none 0.5)
			(connect_pads
				(clearance 0)
			)
			(min_thickness 0.25)
			(keepout
				(tracks allowed)
				(vias not_allowed)
				(pads allowed)
				(copperpour not_allowed)
				(footprints allowed)
			)
			(placement
				(enabled no)
				(sheetname "")
			)
			(fill
				(thermal_gap 0.5)
				(thermal_bridge_width 0.5)
				(island_removal_mode 0)
			)
			(polygon
				(pts
					(arc
						(start 254.980948 -64.99987)
						(mid 254.218948 -64.99987)
						(end 254.980948 -64.99987)
					)
				)
			)
		)
		(zone
			(layer "F.Cu")
			(hatch none 0.5)
			(connect_pads
				(clearance 0)
			)
			(min_thickness 0.25)
			(keepout
				(tracks allowed)
				(vias not_allowed)
				(pads allowed)
				(copperpour not_allowed)
				(footprints allowed)
			)
			(placement
				(enabled no)
				(sheetname "")
			)
			(fill
				(thermal_gap 0.5)
				(thermal_bridge_width 0.5)
				(island_removal_mode 0)
			)
			(polygon
				(pts
					(arc
						(start 254.980948 -63.999872)
						(mid 254.218948 -63.999872)
						(end 254.980948 -63.999872)
					)
				)
			)
		)
		(zone
			(layer "F.Cu")
			(hatch none 0.5)
			(connect_pads
				(clearance 0)
			)
			(min_thickness 0.25)
			(keepout
				(tracks allowed)
				(vias not_allowed)
				(pads allowed)
				(copperpour not_allowed)
				(footprints allowed)
			)
			(placement
				(enabled no)
				(sheetname "")
			)
			(fill
				(thermal_gap 0.5)
				(thermal_bridge_width 0.5)
				(island_removal_mode 0)
			)
			(polygon
				(pts
					(arc
						(start 254.980948 -62.999874)
						(mid 254.218948 -62.999874)
						(end 254.980948 -62.999874)
					)
				)
			)
		)
		(zone
			(layer "F.Cu")
			(hatch none 0.5)
			(connect_pads
				(clearance 0)
			)
			(min_thickness 0.25)
			(keepout
				(tracks allowed)
				(vias not_allowed)
				(pads allowed)
				(copperpour not_allowed)
				(footprints allowed)
			)
			(placement
				(enabled no)
				(sheetname "")
			)
			(fill
				(thermal_gap 0.5)
				(thermal_bridge_width 0.5)
				(island_removal_mode 0)
			)
			(polygon
				(pts
					(arc
						(start 254.980948 -61.999876)
						(mid 254.218948 -61.999876)
						(end 254.980948 -61.999876)
					)
				)
			)
		)
		(zone
			(layer "F.Cu")
			(hatch none 0.5)
			(connect_pads
				(clearance 0)
			)
			(min_thickness 0.25)
			(keepout
				(tracks allowed)
				(vias not_allowed)
				(pads allowed)
				(copperpour not_allowed)
				(footprints allowed)
			)
			(placement
				(enabled no)
				(sheetname "")
			)
			(fill
				(thermal_gap 0.5)
				(thermal_bridge_width 0.5)
				(island_removal_mode 0)
			)
			(polygon
				(pts
					(arc
						(start 254.980948 -60.999878)
						(mid 254.218948 -60.999878)
						(end 254.980948 -60.999878)
					)
				)
			)
		)
		(zone
			(layer "F.Cu")
			(hatch none 0.5)
			(connect_pads
				(clearance 0)
			)
			(min_thickness 0.25)
			(keepout
				(tracks allowed)
				(vias not_allowed)
				(pads allowed)
				(copperpour not_allowed)
				(footprints allowed)
			)
			(placement
				(enabled no)
				(sheetname "")
			)
			(fill
				(thermal_gap 0.5)
				(thermal_bridge_width 0.5)
				(island_removal_mode 0)
			)
			(polygon
				(pts
					(arc
						(start 254.980948 -59.99988)
						(mid 254.218948 -59.99988)
						(end 254.980948 -59.99988)
					)
				)
			)
		)
		(zone
			(layer "F.Cu")
			(hatch none 0.5)
			(connect_pads
				(clearance 0)
			)
			(min_thickness 0.25)
			(keepout
				(tracks allowed)
				(vias not_allowed)
				(pads allowed)
				(copperpour not_allowed)
				(footprints allowed)
			)
			(placement
				(enabled no)
				(sheetname "")
			)
			(fill
				(thermal_gap 0.5)
				(thermal_bridge_width 0.5)
				(island_removal_mode 0)
			)
			(polygon
				(pts
					(arc
						(start 254.980948 -58.999882)
						(mid 254.218948 -58.999882)
						(end 254.980948 -58.999882)
					)
				)
			)
		)
		(zone
			(layer "F.Cu")
			(hatch none 0.5)
			(connect_pads
				(clearance 0)
			)
			(min_thickness 0.25)
			(keepout
				(tracks allowed)
				(vias not_allowed)
				(pads allowed)
				(copperpour not_allowed)
				(footprints allowed)
			)
			(placement
				(enabled no)
				(sheetname "")
			)
			(fill
				(thermal_gap 0.5)
				(thermal_bridge_width 0.5)
				(island_removal_mode 0)
			)
			(polygon
				(pts
					(arc
						(start 254.980948 -57.999884)
						(mid 254.218948 -57.999884)
						(end 254.980948 -57.999884)
					)
				)
			)
		)
		(zone
			(layer "F.Cu")
			(hatch none 0.5)
			(connect_pads
				(clearance 0)
			)
			(min_thickness 0.25)
			(keepout
				(tracks allowed)
				(vias not_allowed)
				(pads allowed)
				(copperpour not_allowed)
				(footprints allowed)
			)
			(placement
				(enabled no)
				(sheetname "")
			)
			(fill
				(thermal_gap 0.5)
				(thermal_bridge_width 0.5)
				(island_removal_mode 0)
			)
			(polygon
				(pts
					(arc
						(start 254.980948 -56.999886)
						(mid 254.218948 -56.999886)
						(end 254.980948 -56.999886)
					)
				)
			)
		)
		(zone
			(layer "F.Cu")
			(hatch none 0.5)
			(connect_pads
				(clearance 0)
			)
			(min_thickness 0.25)
			(keepout
				(tracks allowed)
				(vias not_allowed)
				(pads allowed)
				(copperpour not_allowed)
				(footprints allowed)
			)
			(placement
				(enabled no)
				(sheetname "")
			)
			(fill
				(thermal_gap 0.5)
				(thermal_bridge_width 0.5)
				(island_removal_mode 0)
			)
			(polygon
				(pts
					(arc
						(start 254.980948 -55.999888)
						(mid 254.218948 -55.999888)
						(end 254.980948 -55.999888)
					)
				)
			)
		)
		(zone
			(layer "F.Cu")
			(hatch none 0.5)
			(connect_pads
				(clearance 0)
			)
			(min_thickness 0.25)
			(keepout
				(tracks allowed)
				(vias not_allowed)
				(pads allowed)
				(copperpour not_allowed)
				(footprints allowed)
			)
			(placement
				(enabled no)
				(sheetname "")
			)
			(fill
				(thermal_gap 0.5)
				(thermal_bridge_width 0.5)
				(island_removal_mode 0)
			)
			(polygon
				(pts
					(arc
						(start 254.980948 -54.99989)
						(mid 254.218948 -54.99989)
						(end 254.980948 -54.99989)
					)
				)
			)
		)
		(zone
			(layer "F.Cu")
			(hatch none 0.5)
			(connect_pads
				(clearance 0)
			)
			(min_thickness 0.25)
			(keepout
				(tracks allowed)
				(vias not_allowed)
				(pads allowed)
				(copperpour not_allowed)
				(footprints allowed)
			)
			(placement
				(enabled no)
				(sheetname "")
			)
			(fill
				(thermal_gap 0.5)
				(thermal_bridge_width 0.5)
				(island_removal_mode 0)
			)
			(polygon
				(pts
					(arc
						(start 254.980948 -53.999892)
						(mid 254.218948 -53.999892)
						(end 254.980948 -53.999892)
					)
				)
			)
		)
		(zone
			(layer "F.Cu")
			(hatch none 0.5)
			(connect_pads
				(clearance 0)
			)
			(min_thickness 0.25)
			(keepout
				(tracks allowed)
				(vias not_allowed)
				(pads allowed)
				(copperpour not_allowed)
				(footprints allowed)
			)
			(placement
				(enabled no)
				(sheetname "")
			)
			(fill
				(thermal_gap 0.5)
				(thermal_bridge_width 0.5)
				(island_removal_mode 0)
			)
			(polygon
				(pts
					(arc
						(start 254.980948 -52.999894)
						(mid 254.218948 -52.999894)
						(end 254.980948 -52.999894)
					)
				)
			)
		)
		(zone
			(layer "F.Cu")
			(hatch none 0.5)
			(connect_pads
				(clearance 0)
			)
			(min_thickness 0.25)
			(keepout
				(tracks allowed)
				(vias not_allowed)
				(pads allowed)
				(copperpour not_allowed)
				(footprints allowed)
			)
			(placement
				(enabled no)
				(sheetname "")
			)
			(fill
				(thermal_gap 0.5)
				(thermal_bridge_width 0.5)
				(island_removal_mode 0)
			)
			(polygon
				(pts
					(arc
						(start 254.980948 -51.999896)
						(mid 254.218948 -51.999896)
						(end 254.980948 -51.999896)
					)
				)
			)
		)
		(zone
			(layer "F.Cu")
			(hatch none 0.5)
			(connect_pads
				(clearance 0)
			)
			(min_thickness 0.25)
			(keepout
				(tracks allowed)
				(vias not_allowed)
				(pads allowed)
				(copperpour not_allowed)
				(footprints allowed)
			)
			(placement
				(enabled no)
				(sheetname "")
			)
			(fill
				(thermal_gap 0.5)
				(thermal_bridge_width 0.5)
				(island_removal_mode 0)
			)
			(polygon
				(pts
					(arc
						(start 254.980948 -50.999898)
						(mid 254.218948 -50.999898)
						(end 254.980948 -50.999898)
					)
				)
			)
		)
		(zone
			(layer "F.Cu")
			(hatch none 0.5)
			(connect_pads
				(clearance 0)
			)
			(min_thickness 0.25)
			(keepout
				(tracks allowed)
				(vias not_allowed)
				(pads allowed)
				(copperpour not_allowed)
				(footprints allowed)
			)
			(placement
				(enabled no)
				(sheetname "")
			)
			(fill
				(thermal_gap 0.5)
				(thermal_bridge_width 0.5)
				(island_removal_mode 0)
			)
			(polygon
				(pts
					(arc
						(start 254.980948 -49.9999)
						(mid 254.218948 -49.9999)
						(end 254.980948 -49.9999)
					)
				)
			)
		)
		(zone
			(layer "F.Cu")
			(hatch none 0.5)
			(connect_pads
				(clearance 0)
			)
			(min_thickness 0.25)
			(keepout
				(tracks allowed)
				(vias not_allowed)
				(pads allowed)
				(copperpour not_allowed)
				(footprints allowed)
			)
			(placement
				(enabled no)
				(sheetname "")
			)
			(fill
				(thermal_gap 0.5)
				(thermal_bridge_width 0.5)
				(island_removal_mode 0)
			)
			(polygon
				(pts
					(arc
						(start 254.980948 -48.999902)
						(mid 254.218948 -48.999902)
						(end 254.980948 -48.999902)
					)
				)
			)
		)
		(zone
			(layer "F.Cu")
			(hatch none 0.5)
			(connect_pads
				(clearance 0)
			)
			(min_thickness 0.25)
			(keepout
				(tracks allowed)
				(vias not_allowed)
				(pads allowed)
				(copperpour not_allowed)
				(footprints allowed)
			)
			(placement
				(enabled no)
				(sheetname "")
			)
			(fill
				(thermal_gap 0.5)
				(thermal_bridge_width 0.5)
				(island_removal_mode 0)
			)
			(polygon
				(pts
					(arc
						(start 254.980948 -47.999904)
						(mid 254.218948 -47.999904)
						(end 254.980948 -47.999904)
					)
				)
			)
		)
		(zone
			(layer "F.Cu")
			(hatch none 0.5)
			(connect_pads
				(clearance 0)
			)
			(min_thickness 0.25)
			(keepout
				(tracks allowed)
				(vias not_allowed)
				(pads allowed)
				(copperpour not_allowed)
				(footprints allowed)
			)
			(placement
				(enabled no)
				(sheetname "")
			)
			(fill
				(thermal_gap 0.5)
				(thermal_bridge_width 0.5)
				(island_removal_mode 0)
			)
			(polygon
				(pts
					(arc
						(start 254.980948 -46.999906)
						(mid 254.218948 -46.999906)
						(end 254.980948 -46.999906)
					)
				)
			)
		)
		(zone
			(layer "F.Cu")
			(hatch none 0.5)
			(connect_pads
				(clearance 0)
			)
			(min_thickness 0.25)
			(keepout
				(tracks allowed)
				(vias not_allowed)
				(pads allowed)
				(copperpour not_allowed)
				(footprints allowed)
			)
			(placement
				(enabled no)
				(sheetname "")
			)
			(fill
				(thermal_gap 0.5)
				(thermal_bridge_width 0.5)
				(island_removal_mode 0)
			)
			(polygon
				(pts
					(arc
						(start 254.980948 -45.999908)
						(mid 254.218948 -45.999908)
						(end 254.980948 -45.999908)
					)
				)
			)
		)
		(zone
			(layer "F.Cu")
			(hatch none 0.5)
			(connect_pads
				(clearance 0)
			)
			(min_thickness 0.25)
			(keepout
				(tracks allowed)
				(vias not_allowed)
				(pads allowed)
				(copperpour not_allowed)
				(footprints allowed)
			)
			(placement
				(enabled no)
				(sheetname "")
			)
			(fill
				(thermal_gap 0.5)
				(thermal_bridge_width 0.5)
				(island_removal_mode 0)
			)
			(polygon
				(pts
					(arc
						(start 254.980948 -44.99991)
						(mid 254.218948 -44.99991)
						(end 254.980948 -44.99991)
					)
				)
			)
		)
		(zone
			(layer "F.Cu")
			(hatch none 0.5)
			(connect_pads
				(clearance 0)
			)
			(min_thickness 0.25)
			(keepout
				(tracks allowed)
				(vias not_allowed)
				(pads allowed)
				(copperpour not_allowed)
				(footprints allowed)
			)
			(placement
				(enabled no)
				(sheetname "")
			)
			(fill
				(thermal_gap 0.5)
				(thermal_bridge_width 0.5)
				(island_removal_mode 0)
			)
			(polygon
				(pts
					(arc
						(start 254.980948 -43.999912)
						(mid 254.218948 -43.999912)
						(end 254.980948 -43.999912)
					)
				)
			)
		)
		(zone
			(layer "F.Cu")
			(hatch none 0.5)
			(connect_pads
				(clearance 0)
			)
			(min_thickness 0.25)
			(keepout
				(tracks allowed)
				(vias not_allowed)
				(pads allowed)
				(copperpour not_allowed)
				(footprints allowed)
			)
			(placement
				(enabled no)
				(sheetname "")
			)
			(fill
				(thermal_gap 0.5)
				(thermal_bridge_width 0.5)
				(island_removal_mode 0)
			)
			(polygon
				(pts
					(arc
						(start 254.980948 -42.999914)
						(mid 254.218948 -42.999914)
						(end 254.980948 -42.999914)
					)
				)
			)
		)
		(zone
			(layer "F.Cu")
			(hatch none 0.5)
			(connect_pads
				(clearance 0)
			)
			(min_thickness 0.25)
			(keepout
				(tracks allowed)
				(vias not_allowed)
				(pads allowed)
				(copperpour not_allowed)
				(footprints allowed)
			)
			(placement
				(enabled no)
				(sheetname "")
			)
			(fill
				(thermal_gap 0.5)
				(thermal_bridge_width 0.5)
				(island_removal_mode 0)
			)
			(polygon
				(pts
					(arc
						(start 254.980948 -41.999916)
						(mid 254.218948 -41.999916)
						(end 254.980948 -41.999916)
					)
				)
			)
		)
		(zone
			(layer "F.Cu")
			(hatch none 0.5)
			(connect_pads
				(clearance 0)
			)
			(min_thickness 0.25)
			(keepout
				(tracks allowed)
				(vias not_allowed)
				(pads allowed)
				(copperpour not_allowed)
				(footprints allowed)
			)
			(placement
				(enabled no)
				(sheetname "")
			)
			(fill
				(thermal_gap 0.5)
				(thermal_bridge_width 0.5)
				(island_removal_mode 0)
			)
			(polygon
				(pts
					(arc
						(start 254.980948 -40.999918)
						(mid 254.218948 -40.999918)
						(end 254.980948 -40.999918)
					)
				)
			)
		)
		(zone
			(layer "F.Cu")
			(hatch none 0.5)
			(connect_pads
				(clearance 0)
			)
			(min_thickness 0.25)
			(keepout
				(tracks allowed)
				(vias not_allowed)
				(pads allowed)
				(copperpour not_allowed)
				(footprints allowed)
			)
			(placement
				(enabled no)
				(sheetname "")
			)
			(fill
				(thermal_gap 0.5)
				(thermal_bridge_width 0.5)
				(island_removal_mode 0)
			)
			(polygon
				(pts
					(arc
						(start 254.980948 -39.99992)
						(mid 254.218948 -39.99992)
						(end 254.980948 -39.99992)
					)
				)
			)
		)
		(zone
			(layer "F.Cu")
			(hatch none 0.5)
			(connect_pads
				(clearance 0)
			)
			(min_thickness 0.25)
			(keepout
				(tracks allowed)
				(vias not_allowed)
				(pads allowed)
				(copperpour not_allowed)
				(footprints allowed)
			)
			(placement
				(enabled no)
				(sheetname "")
			)
			(fill
				(thermal_gap 0.5)
				(thermal_bridge_width 0.5)
				(island_removal_mode 0)
			)
			(polygon
				(pts
					(arc
						(start 254.980948 -38.999922)
						(mid 254.218948 -38.999922)
						(end 254.980948 -38.999922)
					)
				)
			)
		)
		(zone
			(layer "F.Cu")
			(hatch none 0.5)
			(connect_pads
				(clearance 0)
			)
			(min_thickness 0.25)
			(keepout
				(tracks allowed)
				(vias not_allowed)
				(pads allowed)
				(copperpour not_allowed)
				(footprints allowed)
			)
			(placement
				(enabled no)
				(sheetname "")
			)
			(fill
				(thermal_gap 0.5)
				(thermal_bridge_width 0.5)
				(island_removal_mode 0)
			)
			(polygon
				(pts
					(arc
						(start 254.980948 -37.999924)
						(mid 254.218948 -37.999924)
						(end 254.980948 -37.999924)
					)
				)
			)
		)
		(zone
			(layer "F.Cu")
			(hatch none 0.5)
			(connect_pads
				(clearance 0)
			)
			(min_thickness 0.25)
			(keepout
				(tracks allowed)
				(vias not_allowed)
				(pads allowed)
				(copperpour not_allowed)
				(footprints allowed)
			)
			(placement
				(enabled no)
				(sheetname "")
			)
			(fill
				(thermal_gap 0.5)
				(thermal_bridge_width 0.5)
				(island_removal_mode 0)
			)
			(polygon
				(pts
					(arc
						(start 254.980948 -36.999926)
						(mid 254.218948 -36.999926)
						(end 254.980948 -36.999926)
					)
				)
			)
		)
		(zone
			(layer "F.Cu")
			(hatch none 0.5)
			(connect_pads
				(clearance 0)
			)
			(min_thickness 0.25)
			(keepout
				(tracks allowed)
				(vias not_allowed)
				(pads allowed)
				(copperpour not_allowed)
				(footprints allowed)
			)
			(placement
				(enabled no)
				(sheetname "")
			)
			(fill
				(thermal_gap 0.5)
				(thermal_bridge_width 0.5)
				(island_removal_mode 0)
			)
			(polygon
				(pts
					(arc
						(start 254.980948 -35.999928)
						(mid 254.218948 -35.999928)
						(end 254.980948 -35.999928)
					)
				)
			)
		)
		(zone
			(layer "F.Cu")
			(hatch none 0.5)
			(connect_pads
				(clearance 0)
			)
			(min_thickness 0.25)
			(keepout
				(tracks allowed)
				(vias not_allowed)
				(pads allowed)
				(copperpour not_allowed)
				(footprints allowed)
			)
			(placement
				(enabled no)
				(sheetname "")
			)
			(fill
				(thermal_gap 0.5)
				(thermal_bridge_width 0.5)
				(island_removal_mode 0)
			)
			(polygon
				(pts
					(arc
						(start 254.980948 -34.99993)
						(mid 254.218948 -34.99993)
						(end 254.980948 -34.99993)
					)
				)
			)
		)
		(zone
			(layer "F.Cu")
			(hatch none 0.5)
			(connect_pads
				(clearance 0)
			)
			(min_thickness 0.25)
			(keepout
				(tracks allowed)
				(vias not_allowed)
				(pads allowed)
				(copperpour not_allowed)
				(footprints allowed)
			)
			(placement
				(enabled no)
				(sheetname "")
			)
			(fill
				(thermal_gap 0.5)
				(thermal_bridge_width 0.5)
				(island_removal_mode 0)
			)
			(polygon
				(pts
					(arc
						(start 254.980948 -33.999932)
						(mid 254.218948 -33.999932)
						(end 254.980948 -33.999932)
					)
				)
			)
		)
		(zone
			(layer "F.Cu")
			(hatch none 0.5)
			(connect_pads
				(clearance 0)
			)
			(min_thickness 0.25)
			(keepout
				(tracks allowed)
				(vias not_allowed)
				(pads allowed)
				(copperpour not_allowed)
				(footprints allowed)
			)
			(placement
				(enabled no)
				(sheetname "")
			)
			(fill
				(thermal_gap 0.5)
				(thermal_bridge_width 0.5)
				(island_removal_mode 0)
			)
			(polygon
				(pts
					(arc
						(start 254.980948 -32.999934)
						(mid 254.218948 -32.999934)
						(end 254.980948 -32.999934)
					)
				)
			)
		)
		(zone
			(layer "F.Cu")
			(hatch none 0.5)
			(connect_pads
				(clearance 0)
			)
			(min_thickness 0.25)
			(keepout
				(tracks allowed)
				(vias not_allowed)
				(pads allowed)
				(copperpour not_allowed)
				(footprints allowed)
			)
			(placement
				(enabled no)
				(sheetname "")
			)
			(fill
				(thermal_gap 0.5)
				(thermal_bridge_width 0.5)
				(island_removal_mode 0)
			)
			(polygon
				(pts
					(arc
						(start 254.980948 -31.999936)
						(mid 254.218948 -31.999936)
						(end 254.980948 -31.999936)
					)
				)
			)
		)
		(zone
			(layer "F.Cu")
			(hatch none 0.5)
			(connect_pads
				(clearance 0)
			)
			(min_thickness 0.25)
			(keepout
				(tracks allowed)
				(vias not_allowed)
				(pads allowed)
				(copperpour not_allowed)
				(footprints allowed)
			)
			(placement
				(enabled no)
				(sheetname "")
			)
			(fill
				(thermal_gap 0.5)
				(thermal_bridge_width 0.5)
				(island_removal_mode 0)
			)
			(polygon
				(pts
					(arc
						(start 254.980948 -30.999938)
						(mid 254.218948 -30.999938)
						(end 254.980948 -30.999938)
					)
				)
			)
		)
		(zone
			(layer "F.Cu")
			(hatch none 0.5)
			(connect_pads
				(clearance 0)
			)
			(min_thickness 0.25)
			(keepout
				(tracks allowed)
				(vias not_allowed)
				(pads allowed)
				(copperpour not_allowed)
				(footprints allowed)
			)
			(placement
				(enabled no)
				(sheetname "")
			)
			(fill
				(thermal_gap 0.5)
				(thermal_bridge_width 0.5)
				(island_removal_mode 0)
			)
			(polygon
				(pts
					(arc
						(start 255.980946 -65.999868)
						(mid 255.218946 -65.999868)
						(end 255.980946 -65.999868)
					)
				)
			)
		)
		(zone
			(layer "F.Cu")
			(hatch none 0.5)
			(connect_pads
				(clearance 0)
			)
			(min_thickness 0.25)
			(keepout
				(tracks allowed)
				(vias not_allowed)
				(pads allowed)
				(copperpour not_allowed)
				(footprints allowed)
			)
			(placement
				(enabled no)
				(sheetname "")
			)
			(fill
				(thermal_gap 0.5)
				(thermal_bridge_width 0.5)
				(island_removal_mode 0)
			)
			(polygon
				(pts
					(arc
						(start 255.980946 -64.99987)
						(mid 255.218946 -64.99987)
						(end 255.980946 -64.99987)
					)
				)
			)
		)
		(zone
			(layer "F.Cu")
			(hatch none 0.5)
			(connect_pads
				(clearance 0)
			)
			(min_thickness 0.25)
			(keepout
				(tracks allowed)
				(vias not_allowed)
				(pads allowed)
				(copperpour not_allowed)
				(footprints allowed)
			)
			(placement
				(enabled no)
				(sheetname "")
			)
			(fill
				(thermal_gap 0.5)
				(thermal_bridge_width 0.5)
				(island_removal_mode 0)
			)
			(polygon
				(pts
					(arc
						(start 255.980946 -63.999872)
						(mid 255.218946 -63.999872)
						(end 255.980946 -63.999872)
					)
				)
			)
		)
		(zone
			(layer "F.Cu")
			(hatch none 0.5)
			(connect_pads
				(clearance 0)
			)
			(min_thickness 0.25)
			(keepout
				(tracks allowed)
				(vias not_allowed)
				(pads allowed)
				(copperpour not_allowed)
				(footprints allowed)
			)
			(placement
				(enabled no)
				(sheetname "")
			)
			(fill
				(thermal_gap 0.5)
				(thermal_bridge_width 0.5)
				(island_removal_mode 0)
			)
			(polygon
				(pts
					(arc
						(start 255.980946 -62.999874)
						(mid 255.218946 -62.999874)
						(end 255.980946 -62.999874)
					)
				)
			)
		)
		(zone
			(layer "F.Cu")
			(hatch none 0.5)
			(connect_pads
				(clearance 0)
			)
			(min_thickness 0.25)
			(keepout
				(tracks allowed)
				(vias not_allowed)
				(pads allowed)
				(copperpour not_allowed)
				(footprints allowed)
			)
			(placement
				(enabled no)
				(sheetname "")
			)
			(fill
				(thermal_gap 0.5)
				(thermal_bridge_width 0.5)
				(island_removal_mode 0)
			)
			(polygon
				(pts
					(arc
						(start 255.980946 -61.999876)
						(mid 255.218946 -61.999876)
						(end 255.980946 -61.999876)
					)
				)
			)
		)
		(zone
			(layer "F.Cu")
			(hatch none 0.5)
			(connect_pads
				(clearance 0)
			)
			(min_thickness 0.25)
			(keepout
				(tracks allowed)
				(vias not_allowed)
				(pads allowed)
				(copperpour not_allowed)
				(footprints allowed)
			)
			(placement
				(enabled no)
				(sheetname "")
			)
			(fill
				(thermal_gap 0.5)
				(thermal_bridge_width 0.5)
				(island_removal_mode 0)
			)
			(polygon
				(pts
					(arc
						(start 255.980946 -60.999878)
						(mid 255.218946 -60.999878)
						(end 255.980946 -60.999878)
					)
				)
			)
		)
		(zone
			(layer "F.Cu")
			(hatch none 0.5)
			(connect_pads
				(clearance 0)
			)
			(min_thickness 0.25)
			(keepout
				(tracks allowed)
				(vias not_allowed)
				(pads allowed)
				(copperpour not_allowed)
				(footprints allowed)
			)
			(placement
				(enabled no)
				(sheetname "")
			)
			(fill
				(thermal_gap 0.5)
				(thermal_bridge_width 0.5)
				(island_removal_mode 0)
			)
			(polygon
				(pts
					(arc
						(start 255.980946 -59.99988)
						(mid 255.218946 -59.99988)
						(end 255.980946 -59.99988)
					)
				)
			)
		)
		(zone
			(layer "F.Cu")
			(hatch none 0.5)
			(connect_pads
				(clearance 0)
			)
			(min_thickness 0.25)
			(keepout
				(tracks allowed)
				(vias not_allowed)
				(pads allowed)
				(copperpour not_allowed)
				(footprints allowed)
			)
			(placement
				(enabled no)
				(sheetname "")
			)
			(fill
				(thermal_gap 0.5)
				(thermal_bridge_width 0.5)
				(island_removal_mode 0)
			)
			(polygon
				(pts
					(arc
						(start 255.980946 -58.999882)
						(mid 255.218946 -58.999882)
						(end 255.980946 -58.999882)
					)
				)
			)
		)
		(zone
			(layer "F.Cu")
			(hatch none 0.5)
			(connect_pads
				(clearance 0)
			)
			(min_thickness 0.25)
			(keepout
				(tracks allowed)
				(vias not_allowed)
				(pads allowed)
				(copperpour not_allowed)
				(footprints allowed)
			)
			(placement
				(enabled no)
				(sheetname "")
			)
			(fill
				(thermal_gap 0.5)
				(thermal_bridge_width 0.5)
				(island_removal_mode 0)
			)
			(polygon
				(pts
					(arc
						(start 255.980946 -57.999884)
						(mid 255.218946 -57.999884)
						(end 255.980946 -57.999884)
					)
				)
			)
		)
		(zone
			(layer "F.Cu")
			(hatch none 0.5)
			(connect_pads
				(clearance 0)
			)
			(min_thickness 0.25)
			(keepout
				(tracks allowed)
				(vias not_allowed)
				(pads allowed)
				(copperpour not_allowed)
				(footprints allowed)
			)
			(placement
				(enabled no)
				(sheetname "")
			)
			(fill
				(thermal_gap 0.5)
				(thermal_bridge_width 0.5)
				(island_removal_mode 0)
			)
			(polygon
				(pts
					(arc
						(start 255.980946 -56.999886)
						(mid 255.218946 -56.999886)
						(end 255.980946 -56.999886)
					)
				)
			)
		)
		(zone
			(layer "F.Cu")
			(hatch none 0.5)
			(connect_pads
				(clearance 0)
			)
			(min_thickness 0.25)
			(keepout
				(tracks allowed)
				(vias not_allowed)
				(pads allowed)
				(copperpour not_allowed)
				(footprints allowed)
			)
			(placement
				(enabled no)
				(sheetname "")
			)
			(fill
				(thermal_gap 0.5)
				(thermal_bridge_width 0.5)
				(island_removal_mode 0)
			)
			(polygon
				(pts
					(arc
						(start 255.980946 -55.999888)
						(mid 255.218946 -55.999888)
						(end 255.980946 -55.999888)
					)
				)
			)
		)
		(zone
			(layer "F.Cu")
			(hatch none 0.5)
			(connect_pads
				(clearance 0)
			)
			(min_thickness 0.25)
			(keepout
				(tracks allowed)
				(vias not_allowed)
				(pads allowed)
				(copperpour not_allowed)
				(footprints allowed)
			)
			(placement
				(enabled no)
				(sheetname "")
			)
			(fill
				(thermal_gap 0.5)
				(thermal_bridge_width 0.5)
				(island_removal_mode 0)
			)
			(polygon
				(pts
					(arc
						(start 255.980946 -54.99989)
						(mid 255.218946 -54.99989)
						(end 255.980946 -54.99989)
					)
				)
			)
		)
		(zone
			(layer "F.Cu")
			(hatch none 0.5)
			(connect_pads
				(clearance 0)
			)
			(min_thickness 0.25)
			(keepout
				(tracks allowed)
				(vias not_allowed)
				(pads allowed)
				(copperpour not_allowed)
				(footprints allowed)
			)
			(placement
				(enabled no)
				(sheetname "")
			)
			(fill
				(thermal_gap 0.5)
				(thermal_bridge_width 0.5)
				(island_removal_mode 0)
			)
			(polygon
				(pts
					(arc
						(start 255.980946 -53.999892)
						(mid 255.218946 -53.999892)
						(end 255.980946 -53.999892)
					)
				)
			)
		)
		(zone
			(layer "F.Cu")
			(hatch none 0.5)
			(connect_pads
				(clearance 0)
			)
			(min_thickness 0.25)
			(keepout
				(tracks allowed)
				(vias not_allowed)
				(pads allowed)
				(copperpour not_allowed)
				(footprints allowed)
			)
			(placement
				(enabled no)
				(sheetname "")
			)
			(fill
				(thermal_gap 0.5)
				(thermal_bridge_width 0.5)
				(island_removal_mode 0)
			)
			(polygon
				(pts
					(arc
						(start 255.980946 -52.999894)
						(mid 255.218946 -52.999894)
						(end 255.980946 -52.999894)
					)
				)
			)
		)
		(zone
			(layer "F.Cu")
			(hatch none 0.5)
			(connect_pads
				(clearance 0)
			)
			(min_thickness 0.25)
			(keepout
				(tracks allowed)
				(vias not_allowed)
				(pads allowed)
				(copperpour not_allowed)
				(footprints allowed)
			)
			(placement
				(enabled no)
				(sheetname "")
			)
			(fill
				(thermal_gap 0.5)
				(thermal_bridge_width 0.5)
				(island_removal_mode 0)
			)
			(polygon
				(pts
					(arc
						(start 255.980946 -51.999896)
						(mid 255.218946 -51.999896)
						(end 255.980946 -51.999896)
					)
				)
			)
		)
		(zone
			(layer "F.Cu")
			(hatch none 0.5)
			(connect_pads
				(clearance 0)
			)
			(min_thickness 0.25)
			(keepout
				(tracks allowed)
				(vias not_allowed)
				(pads allowed)
				(copperpour not_allowed)
				(footprints allowed)
			)
			(placement
				(enabled no)
				(sheetname "")
			)
			(fill
				(thermal_gap 0.5)
				(thermal_bridge_width 0.5)
				(island_removal_mode 0)
			)
			(polygon
				(pts
					(arc
						(start 255.980946 -50.999898)
						(mid 255.218946 -50.999898)
						(end 255.980946 -50.999898)
					)
				)
			)
		)
		(zone
			(layer "F.Cu")
			(hatch none 0.5)
			(connect_pads
				(clearance 0)
			)
			(min_thickness 0.25)
			(keepout
				(tracks allowed)
				(vias not_allowed)
				(pads allowed)
				(copperpour not_allowed)
				(footprints allowed)
			)
			(placement
				(enabled no)
				(sheetname "")
			)
			(fill
				(thermal_gap 0.5)
				(thermal_bridge_width 0.5)
				(island_removal_mode 0)
			)
			(polygon
				(pts
					(arc
						(start 255.980946 -49.9999)
						(mid 255.218946 -49.9999)
						(end 255.980946 -49.9999)
					)
				)
			)
		)
		(zone
			(layer "F.Cu")
			(hatch none 0.5)
			(connect_pads
				(clearance 0)
			)
			(min_thickness 0.25)
			(keepout
				(tracks allowed)
				(vias not_allowed)
				(pads allowed)
				(copperpour not_allowed)
				(footprints allowed)
			)
			(placement
				(enabled no)
				(sheetname "")
			)
			(fill
				(thermal_gap 0.5)
				(thermal_bridge_width 0.5)
				(island_removal_mode 0)
			)
			(polygon
				(pts
					(arc
						(start 255.980946 -48.999902)
						(mid 255.218946 -48.999902)
						(end 255.980946 -48.999902)
					)
				)
			)
		)
		(zone
			(layer "F.Cu")
			(hatch none 0.5)
			(connect_pads
				(clearance 0)
			)
			(min_thickness 0.25)
			(keepout
				(tracks allowed)
				(vias not_allowed)
				(pads allowed)
				(copperpour not_allowed)
				(footprints allowed)
			)
			(placement
				(enabled no)
				(sheetname "")
			)
			(fill
				(thermal_gap 0.5)
				(thermal_bridge_width 0.5)
				(island_removal_mode 0)
			)
			(polygon
				(pts
					(arc
						(start 255.980946 -47.999904)
						(mid 255.218946 -47.999904)
						(end 255.980946 -47.999904)
					)
				)
			)
		)
		(zone
			(layer "F.Cu")
			(hatch none 0.5)
			(connect_pads
				(clearance 0)
			)
			(min_thickness 0.25)
			(keepout
				(tracks allowed)
				(vias not_allowed)
				(pads allowed)
				(copperpour not_allowed)
				(footprints allowed)
			)
			(placement
				(enabled no)
				(sheetname "")
			)
			(fill
				(thermal_gap 0.5)
				(thermal_bridge_width 0.5)
				(island_removal_mode 0)
			)
			(polygon
				(pts
					(arc
						(start 255.980946 -46.999906)
						(mid 255.218946 -46.999906)
						(end 255.980946 -46.999906)
					)
				)
			)
		)
		(zone
			(layer "F.Cu")
			(hatch none 0.5)
			(connect_pads
				(clearance 0)
			)
			(min_thickness 0.25)
			(keepout
				(tracks allowed)
				(vias not_allowed)
				(pads allowed)
				(copperpour not_allowed)
				(footprints allowed)
			)
			(placement
				(enabled no)
				(sheetname "")
			)
			(fill
				(thermal_gap 0.5)
				(thermal_bridge_width 0.5)
				(island_removal_mode 0)
			)
			(polygon
				(pts
					(arc
						(start 255.980946 -45.999908)
						(mid 255.218946 -45.999908)
						(end 255.980946 -45.999908)
					)
				)
			)
		)
		(zone
			(layer "F.Cu")
			(hatch none 0.5)
			(connect_pads
				(clearance 0)
			)
			(min_thickness 0.25)
			(keepout
				(tracks allowed)
				(vias not_allowed)
				(pads allowed)
				(copperpour not_allowed)
				(footprints allowed)
			)
			(placement
				(enabled no)
				(sheetname "")
			)
			(fill
				(thermal_gap 0.5)
				(thermal_bridge_width 0.5)
				(island_removal_mode 0)
			)
			(polygon
				(pts
					(arc
						(start 255.980946 -44.99991)
						(mid 255.218946 -44.99991)
						(end 255.980946 -44.99991)
					)
				)
			)
		)
		(zone
			(layer "F.Cu")
			(hatch none 0.5)
			(connect_pads
				(clearance 0)
			)
			(min_thickness 0.25)
			(keepout
				(tracks allowed)
				(vias not_allowed)
				(pads allowed)
				(copperpour not_allowed)
				(footprints allowed)
			)
			(placement
				(enabled no)
				(sheetname "")
			)
			(fill
				(thermal_gap 0.5)
				(thermal_bridge_width 0.5)
				(island_removal_mode 0)
			)
			(polygon
				(pts
					(arc
						(start 255.980946 -43.999912)
						(mid 255.218946 -43.999912)
						(end 255.980946 -43.999912)
					)
				)
			)
		)
		(zone
			(layer "F.Cu")
			(hatch none 0.5)
			(connect_pads
				(clearance 0)
			)
			(min_thickness 0.25)
			(keepout
				(tracks allowed)
				(vias not_allowed)
				(pads allowed)
				(copperpour not_allowed)
				(footprints allowed)
			)
			(placement
				(enabled no)
				(sheetname "")
			)
			(fill
				(thermal_gap 0.5)
				(thermal_bridge_width 0.5)
				(island_removal_mode 0)
			)
			(polygon
				(pts
					(arc
						(start 255.980946 -42.999914)
						(mid 255.218946 -42.999914)
						(end 255.980946 -42.999914)
					)
				)
			)
		)
		(zone
			(layer "F.Cu")
			(hatch none 0.5)
			(connect_pads
				(clearance 0)
			)
			(min_thickness 0.25)
			(keepout
				(tracks allowed)
				(vias not_allowed)
				(pads allowed)
				(copperpour not_allowed)
				(footprints allowed)
			)
			(placement
				(enabled no)
				(sheetname "")
			)
			(fill
				(thermal_gap 0.5)
				(thermal_bridge_width 0.5)
				(island_removal_mode 0)
			)
			(polygon
				(pts
					(arc
						(start 255.980946 -41.999916)
						(mid 255.218946 -41.999916)
						(end 255.980946 -41.999916)
					)
				)
			)
		)
		(zone
			(layer "F.Cu")
			(hatch none 0.5)
			(connect_pads
				(clearance 0)
			)
			(min_thickness 0.25)
			(keepout
				(tracks allowed)
				(vias not_allowed)
				(pads allowed)
				(copperpour not_allowed)
				(footprints allowed)
			)
			(placement
				(enabled no)
				(sheetname "")
			)
			(fill
				(thermal_gap 0.5)
				(thermal_bridge_width 0.5)
				(island_removal_mode 0)
			)
			(polygon
				(pts
					(arc
						(start 255.980946 -40.999918)
						(mid 255.218946 -40.999918)
						(end 255.980946 -40.999918)
					)
				)
			)
		)
		(zone
			(layer "F.Cu")
			(hatch none 0.5)
			(connect_pads
				(clearance 0)
			)
			(min_thickness 0.25)
			(keepout
				(tracks allowed)
				(vias not_allowed)
				(pads allowed)
				(copperpour not_allowed)
				(footprints allowed)
			)
			(placement
				(enabled no)
				(sheetname "")
			)
			(fill
				(thermal_gap 0.5)
				(thermal_bridge_width 0.5)
				(island_removal_mode 0)
			)
			(polygon
				(pts
					(arc
						(start 255.980946 -39.99992)
						(mid 255.218946 -39.99992)
						(end 255.980946 -39.99992)
					)
				)
			)
		)
		(zone
			(layer "F.Cu")
			(hatch none 0.5)
			(connect_pads
				(clearance 0)
			)
			(min_thickness 0.25)
			(keepout
				(tracks allowed)
				(vias not_allowed)
				(pads allowed)
				(copperpour not_allowed)
				(footprints allowed)
			)
			(placement
				(enabled no)
				(sheetname "")
			)
			(fill
				(thermal_gap 0.5)
				(thermal_bridge_width 0.5)
				(island_removal_mode 0)
			)
			(polygon
				(pts
					(arc
						(start 255.980946 -38.999922)
						(mid 255.218946 -38.999922)
						(end 255.980946 -38.999922)
					)
				)
			)
		)
		(zone
			(layer "F.Cu")
			(hatch none 0.5)
			(connect_pads
				(clearance 0)
			)
			(min_thickness 0.25)
			(keepout
				(tracks allowed)
				(vias not_allowed)
				(pads allowed)
				(copperpour not_allowed)
				(footprints allowed)
			)
			(placement
				(enabled no)
				(sheetname "")
			)
			(fill
				(thermal_gap 0.5)
				(thermal_bridge_width 0.5)
				(island_removal_mode 0)
			)
			(polygon
				(pts
					(arc
						(start 255.980946 -37.999924)
						(mid 255.218946 -37.999924)
						(end 255.980946 -37.999924)
					)
				)
			)
		)
		(zone
			(layer "F.Cu")
			(hatch none 0.5)
			(connect_pads
				(clearance 0)
			)
			(min_thickness 0.25)
			(keepout
				(tracks allowed)
				(vias not_allowed)
				(pads allowed)
				(copperpour not_allowed)
				(footprints allowed)
			)
			(placement
				(enabled no)
				(sheetname "")
			)
			(fill
				(thermal_gap 0.5)
				(thermal_bridge_width 0.5)
				(island_removal_mode 0)
			)
			(polygon
				(pts
					(arc
						(start 255.980946 -36.999926)
						(mid 255.218946 -36.999926)
						(end 255.980946 -36.999926)
					)
				)
			)
		)
		(zone
			(layer "F.Cu")
			(hatch none 0.5)
			(connect_pads
				(clearance 0)
			)
			(min_thickness 0.25)
			(keepout
				(tracks allowed)
				(vias not_allowed)
				(pads allowed)
				(copperpour not_allowed)
				(footprints allowed)
			)
			(placement
				(enabled no)
				(sheetname "")
			)
			(fill
				(thermal_gap 0.5)
				(thermal_bridge_width 0.5)
				(island_removal_mode 0)
			)
			(polygon
				(pts
					(arc
						(start 255.980946 -35.999928)
						(mid 255.218946 -35.999928)
						(end 255.980946 -35.999928)
					)
				)
			)
		)
		(zone
			(layer "F.Cu")
			(hatch none 0.5)
			(connect_pads
				(clearance 0)
			)
			(min_thickness 0.25)
			(keepout
				(tracks allowed)
				(vias not_allowed)
				(pads allowed)
				(copperpour not_allowed)
				(footprints allowed)
			)
			(placement
				(enabled no)
				(sheetname "")
			)
			(fill
				(thermal_gap 0.5)
				(thermal_bridge_width 0.5)
				(island_removal_mode 0)
			)
			(polygon
				(pts
					(arc
						(start 255.980946 -34.99993)
						(mid 255.218946 -34.99993)
						(end 255.980946 -34.99993)
					)
				)
			)
		)
		(zone
			(layer "F.Cu")
			(hatch none 0.5)
			(connect_pads
				(clearance 0)
			)
			(min_thickness 0.25)
			(keepout
				(tracks allowed)
				(vias not_allowed)
				(pads allowed)
				(copperpour not_allowed)
				(footprints allowed)
			)
			(placement
				(enabled no)
				(sheetname "")
			)
			(fill
				(thermal_gap 0.5)
				(thermal_bridge_width 0.5)
				(island_removal_mode 0)
			)
			(polygon
				(pts
					(arc
						(start 255.980946 -33.999932)
						(mid 255.218946 -33.999932)
						(end 255.980946 -33.999932)
					)
				)
			)
		)
		(zone
			(layer "F.Cu")
			(hatch none 0.5)
			(connect_pads
				(clearance 0)
			)
			(min_thickness 0.25)
			(keepout
				(tracks allowed)
				(vias not_allowed)
				(pads allowed)
				(copperpour not_allowed)
				(footprints allowed)
			)
			(placement
				(enabled no)
				(sheetname "")
			)
			(fill
				(thermal_gap 0.5)
				(thermal_bridge_width 0.5)
				(island_removal_mode 0)
			)
			(polygon
				(pts
					(arc
						(start 255.980946 -32.999934)
						(mid 255.218946 -32.999934)
						(end 255.980946 -32.999934)
					)
				)
			)
		)
		(zone
			(layer "F.Cu")
			(hatch none 0.5)
			(connect_pads
				(clearance 0)
			)
			(min_thickness 0.25)
			(keepout
				(tracks allowed)
				(vias not_allowed)
				(pads allowed)
				(copperpour not_allowed)
				(footprints allowed)
			)
			(placement
				(enabled no)
				(sheetname "")
			)
			(fill
				(thermal_gap 0.5)
				(thermal_bridge_width 0.5)
				(island_removal_mode 0)
			)
			(polygon
				(pts
					(arc
						(start 255.980946 -31.999936)
						(mid 255.218946 -31.999936)
						(end 255.980946 -31.999936)
					)
				)
			)
		)
		(zone
			(layer "F.Cu")
			(hatch none 0.5)
			(connect_pads
				(clearance 0)
			)
			(min_thickness 0.25)
			(keepout
				(tracks allowed)
				(vias not_allowed)
				(pads allowed)
				(copperpour not_allowed)
				(footprints allowed)
			)
			(placement
				(enabled no)
				(sheetname "")
			)
			(fill
				(thermal_gap 0.5)
				(thermal_bridge_width 0.5)
				(island_removal_mode 0)
			)
			(polygon
				(pts
					(arc
						(start 255.980946 -30.999938)
						(mid 255.218946 -30.999938)
						(end 255.980946 -30.999938)
					)
				)
			)
		)
		(zone
			(layer "F.Cu")
			(hatch none 0.5)
			(connect_pads
				(clearance 0)
			)
			(min_thickness 0.25)
			(keepout
				(tracks allowed)
				(vias not_allowed)
				(pads allowed)
				(copperpour not_allowed)
				(footprints allowed)
			)
			(placement
				(enabled no)
				(sheetname "")
			)
			(fill
				(thermal_gap 0.5)
				(thermal_bridge_width 0.5)
				(island_removal_mode 0)
			)
			(polygon
				(pts
					(arc
						(start 255.980946 -29.99994)
						(mid 255.218946 -29.99994)
						(end 255.980946 -29.99994)
					)
				)
			)
		)
		(zone
			(layer "F.Cu")
			(hatch none 0.5)
			(connect_pads
				(clearance 0)
			)
			(min_thickness 0.25)
			(keepout
				(tracks allowed)
				(vias not_allowed)
				(pads allowed)
				(copperpour not_allowed)
				(footprints allowed)
			)
			(placement
				(enabled no)
				(sheetname "")
			)
			(fill
				(thermal_gap 0.5)
				(thermal_bridge_width 0.5)
				(island_removal_mode 0)
			)
			(polygon
				(pts
					(arc
						(start 256.980944 -62.999874)
						(mid 256.218944 -62.999874)
						(end 256.980944 -62.999874)
					)
				)
			)
		)
		(zone
			(layer "F.Cu")
			(hatch none 0.5)
			(connect_pads
				(clearance 0)
			)
			(min_thickness 0.25)
			(keepout
				(tracks allowed)
				(vias not_allowed)
				(pads allowed)
				(copperpour not_allowed)
				(footprints allowed)
			)
			(placement
				(enabled no)
				(sheetname "")
			)
			(fill
				(thermal_gap 0.5)
				(thermal_bridge_width 0.5)
				(island_removal_mode 0)
			)
			(polygon
				(pts
					(arc
						(start 256.980944 -61.999876)
						(mid 256.218944 -61.999876)
						(end 256.980944 -61.999876)
					)
				)
			)
		)
		(zone
			(layer "F.Cu")
			(hatch none 0.5)
			(connect_pads
				(clearance 0)
			)
			(min_thickness 0.25)
			(keepout
				(tracks allowed)
				(vias not_allowed)
				(pads allowed)
				(copperpour not_allowed)
				(footprints allowed)
			)
			(placement
				(enabled no)
				(sheetname "")
			)
			(fill
				(thermal_gap 0.5)
				(thermal_bridge_width 0.5)
				(island_removal_mode 0)
			)
			(polygon
				(pts
					(arc
						(start 256.980944 -60.999878)
						(mid 256.218944 -60.999878)
						(end 256.980944 -60.999878)
					)
				)
			)
		)
		(zone
			(layer "F.Cu")
			(hatch none 0.5)
			(connect_pads
				(clearance 0)
			)
			(min_thickness 0.25)
			(keepout
				(tracks allowed)
				(vias not_allowed)
				(pads allowed)
				(copperpour not_allowed)
				(footprints allowed)
			)
			(placement
				(enabled no)
				(sheetname "")
			)
			(fill
				(thermal_gap 0.5)
				(thermal_bridge_width 0.5)
				(island_removal_mode 0)
			)
			(polygon
				(pts
					(arc
						(start 256.980944 -59.99988)
						(mid 256.218944 -59.99988)
						(end 256.980944 -59.99988)
					)
				)
			)
		)
		(zone
			(layer "F.Cu")
			(hatch none 0.5)
			(connect_pads
				(clearance 0)
			)
			(min_thickness 0.25)
			(keepout
				(tracks allowed)
				(vias not_allowed)
				(pads allowed)
				(copperpour not_allowed)
				(footprints allowed)
			)
			(placement
				(enabled no)
				(sheetname "")
			)
			(fill
				(thermal_gap 0.5)
				(thermal_bridge_width 0.5)
				(island_removal_mode 0)
			)
			(polygon
				(pts
					(arc
						(start 256.980944 -58.999882)
						(mid 256.218944 -58.999882)
						(end 256.980944 -58.999882)
					)
				)
			)
		)
		(zone
			(layer "F.Cu")
			(hatch none 0.5)
			(connect_pads
				(clearance 0)
			)
			(min_thickness 0.25)
			(keepout
				(tracks allowed)
				(vias not_allowed)
				(pads allowed)
				(copperpour not_allowed)
				(footprints allowed)
			)
			(placement
				(enabled no)
				(sheetname "")
			)
			(fill
				(thermal_gap 0.5)
				(thermal_bridge_width 0.5)
				(island_removal_mode 0)
			)
			(polygon
				(pts
					(arc
						(start 256.980944 -57.999884)
						(mid 256.218944 -57.999884)
						(end 256.980944 -57.999884)
					)
				)
			)
		)
		(zone
			(layer "F.Cu")
			(hatch none 0.5)
			(connect_pads
				(clearance 0)
			)
			(min_thickness 0.25)
			(keepout
				(tracks allowed)
				(vias not_allowed)
				(pads allowed)
				(copperpour not_allowed)
				(footprints allowed)
			)
			(placement
				(enabled no)
				(sheetname "")
			)
			(fill
				(thermal_gap 0.5)
				(thermal_bridge_width 0.5)
				(island_removal_mode 0)
			)
			(polygon
				(pts
					(arc
						(start 256.980944 -56.999886)
						(mid 256.218944 -56.999886)
						(end 256.980944 -56.999886)
					)
				)
			)
		)
		(zone
			(layer "F.Cu")
			(hatch none 0.5)
			(connect_pads
				(clearance 0)
			)
			(min_thickness 0.25)
			(keepout
				(tracks allowed)
				(vias not_allowed)
				(pads allowed)
				(copperpour not_allowed)
				(footprints allowed)
			)
			(placement
				(enabled no)
				(sheetname "")
			)
			(fill
				(thermal_gap 0.5)
				(thermal_bridge_width 0.5)
				(island_removal_mode 0)
			)
			(polygon
				(pts
					(arc
						(start 256.980944 -55.999888)
						(mid 256.218944 -55.999888)
						(end 256.980944 -55.999888)
					)
				)
			)
		)
		(zone
			(layer "F.Cu")
			(hatch none 0.5)
			(connect_pads
				(clearance 0)
			)
			(min_thickness 0.25)
			(keepout
				(tracks allowed)
				(vias not_allowed)
				(pads allowed)
				(copperpour not_allowed)
				(footprints allowed)
			)
			(placement
				(enabled no)
				(sheetname "")
			)
			(fill
				(thermal_gap 0.5)
				(thermal_bridge_width 0.5)
				(island_removal_mode 0)
			)
			(polygon
				(pts
					(arc
						(start 256.980944 -54.99989)
						(mid 256.218944 -54.99989)
						(end 256.980944 -54.99989)
					)
				)
			)
		)
		(zone
			(layer "F.Cu")
			(hatch none 0.5)
			(connect_pads
				(clearance 0)
			)
			(min_thickness 0.25)
			(keepout
				(tracks allowed)
				(vias not_allowed)
				(pads allowed)
				(copperpour not_allowed)
				(footprints allowed)
			)
			(placement
				(enabled no)
				(sheetname "")
			)
			(fill
				(thermal_gap 0.5)
				(thermal_bridge_width 0.5)
				(island_removal_mode 0)
			)
			(polygon
				(pts
					(arc
						(start 256.980944 -53.999892)
						(mid 256.218944 -53.999892)
						(end 256.980944 -53.999892)
					)
				)
			)
		)
		(zone
			(layer "F.Cu")
			(hatch none 0.5)
			(connect_pads
				(clearance 0)
			)
			(min_thickness 0.25)
			(keepout
				(tracks allowed)
				(vias not_allowed)
				(pads allowed)
				(copperpour not_allowed)
				(footprints allowed)
			)
			(placement
				(enabled no)
				(sheetname "")
			)
			(fill
				(thermal_gap 0.5)
				(thermal_bridge_width 0.5)
				(island_removal_mode 0)
			)
			(polygon
				(pts
					(arc
						(start 256.980944 -52.999894)
						(mid 256.218944 -52.999894)
						(end 256.980944 -52.999894)
					)
				)
			)
		)
		(zone
			(layer "F.Cu")
			(hatch none 0.5)
			(connect_pads
				(clearance 0)
			)
			(min_thickness 0.25)
			(keepout
				(tracks allowed)
				(vias not_allowed)
				(pads allowed)
				(copperpour not_allowed)
				(footprints allowed)
			)
			(placement
				(enabled no)
				(sheetname "")
			)
			(fill
				(thermal_gap 0.5)
				(thermal_bridge_width 0.5)
				(island_removal_mode 0)
			)
			(polygon
				(pts
					(arc
						(start 256.980944 -51.999896)
						(mid 256.218944 -51.999896)
						(end 256.980944 -51.999896)
					)
				)
			)
		)
		(zone
			(layer "F.Cu")
			(hatch none 0.5)
			(connect_pads
				(clearance 0)
			)
			(min_thickness 0.25)
			(keepout
				(tracks allowed)
				(vias not_allowed)
				(pads allowed)
				(copperpour not_allowed)
				(footprints allowed)
			)
			(placement
				(enabled no)
				(sheetname "")
			)
			(fill
				(thermal_gap 0.5)
				(thermal_bridge_width 0.5)
				(island_removal_mode 0)
			)
			(polygon
				(pts
					(arc
						(start 256.980944 -50.999898)
						(mid 256.218944 -50.999898)
						(end 256.980944 -50.999898)
					)
				)
			)
		)
		(zone
			(layer "F.Cu")
			(hatch none 0.5)
			(connect_pads
				(clearance 0)
			)
			(min_thickness 0.25)
			(keepout
				(tracks allowed)
				(vias not_allowed)
				(pads allowed)
				(copperpour not_allowed)
				(footprints allowed)
			)
			(placement
				(enabled no)
				(sheetname "")
			)
			(fill
				(thermal_gap 0.5)
				(thermal_bridge_width 0.5)
				(island_removal_mode 0)
			)
			(polygon
				(pts
					(arc
						(start 256.980944 -49.9999)
						(mid 256.218944 -49.9999)
						(end 256.980944 -49.9999)
					)
				)
			)
		)
		(zone
			(layer "F.Cu")
			(hatch none 0.5)
			(connect_pads
				(clearance 0)
			)
			(min_thickness 0.25)
			(keepout
				(tracks allowed)
				(vias not_allowed)
				(pads allowed)
				(copperpour not_allowed)
				(footprints allowed)
			)
			(placement
				(enabled no)
				(sheetname "")
			)
			(fill
				(thermal_gap 0.5)
				(thermal_bridge_width 0.5)
				(island_removal_mode 0)
			)
			(polygon
				(pts
					(arc
						(start 256.980944 -48.999902)
						(mid 256.218944 -48.999902)
						(end 256.980944 -48.999902)
					)
				)
			)
		)
		(zone
			(layer "F.Cu")
			(hatch none 0.5)
			(connect_pads
				(clearance 0)
			)
			(min_thickness 0.25)
			(keepout
				(tracks allowed)
				(vias not_allowed)
				(pads allowed)
				(copperpour not_allowed)
				(footprints allowed)
			)
			(placement
				(enabled no)
				(sheetname "")
			)
			(fill
				(thermal_gap 0.5)
				(thermal_bridge_width 0.5)
				(island_removal_mode 0)
			)
			(polygon
				(pts
					(arc
						(start 256.980944 -47.999904)
						(mid 256.218944 -47.999904)
						(end 256.980944 -47.999904)
					)
				)
			)
		)
		(zone
			(layer "F.Cu")
			(hatch none 0.5)
			(connect_pads
				(clearance 0)
			)
			(min_thickness 0.25)
			(keepout
				(tracks allowed)
				(vias not_allowed)
				(pads allowed)
				(copperpour not_allowed)
				(footprints allowed)
			)
			(placement
				(enabled no)
				(sheetname "")
			)
			(fill
				(thermal_gap 0.5)
				(thermal_bridge_width 0.5)
				(island_removal_mode 0)
			)
			(polygon
				(pts
					(arc
						(start 256.980944 -46.999906)
						(mid 256.218944 -46.999906)
						(end 256.980944 -46.999906)
					)
				)
			)
		)
		(zone
			(layer "F.Cu")
			(hatch none 0.5)
			(connect_pads
				(clearance 0)
			)
			(min_thickness 0.25)
			(keepout
				(tracks allowed)
				(vias not_allowed)
				(pads allowed)
				(copperpour not_allowed)
				(footprints allowed)
			)
			(placement
				(enabled no)
				(sheetname "")
			)
			(fill
				(thermal_gap 0.5)
				(thermal_bridge_width 0.5)
				(island_removal_mode 0)
			)
			(polygon
				(pts
					(arc
						(start 256.980944 -45.999908)
						(mid 256.218944 -45.999908)
						(end 256.980944 -45.999908)
					)
				)
			)
		)
		(zone
			(layer "F.Cu")
			(hatch none 0.5)
			(connect_pads
				(clearance 0)
			)
			(min_thickness 0.25)
			(keepout
				(tracks allowed)
				(vias not_allowed)
				(pads allowed)
				(copperpour not_allowed)
				(footprints allowed)
			)
			(placement
				(enabled no)
				(sheetname "")
			)
			(fill
				(thermal_gap 0.5)
				(thermal_bridge_width 0.5)
				(island_removal_mode 0)
			)
			(polygon
				(pts
					(arc
						(start 256.980944 -44.99991)
						(mid 256.218944 -44.99991)
						(end 256.980944 -44.99991)
					)
				)
			)
		)
		(zone
			(layer "F.Cu")
			(hatch none 0.5)
			(connect_pads
				(clearance 0)
			)
			(min_thickness 0.25)
			(keepout
				(tracks allowed)
				(vias not_allowed)
				(pads allowed)
				(copperpour not_allowed)
				(footprints allowed)
			)
			(placement
				(enabled no)
				(sheetname "")
			)
			(fill
				(thermal_gap 0.5)
				(thermal_bridge_width 0.5)
				(island_removal_mode 0)
			)
			(polygon
				(pts
					(arc
						(start 256.980944 -43.999912)
						(mid 256.218944 -43.999912)
						(end 256.980944 -43.999912)
					)
				)
			)
		)
		(zone
			(layer "F.Cu")
			(hatch none 0.5)
			(connect_pads
				(clearance 0)
			)
			(min_thickness 0.25)
			(keepout
				(tracks allowed)
				(vias not_allowed)
				(pads allowed)
				(copperpour not_allowed)
				(footprints allowed)
			)
			(placement
				(enabled no)
				(sheetname "")
			)
			(fill
				(thermal_gap 0.5)
				(thermal_bridge_width 0.5)
				(island_removal_mode 0)
			)
			(polygon
				(pts
					(arc
						(start 256.980944 -42.999914)
						(mid 256.218944 -42.999914)
						(end 256.980944 -42.999914)
					)
				)
			)
		)
		(zone
			(layer "F.Cu")
			(hatch none 0.5)
			(connect_pads
				(clearance 0)
			)
			(min_thickness 0.25)
			(keepout
				(tracks allowed)
				(vias not_allowed)
				(pads allowed)
				(copperpour not_allowed)
				(footprints allowed)
			)
			(placement
				(enabled no)
				(sheetname "")
			)
			(fill
				(thermal_gap 0.5)
				(thermal_bridge_width 0.5)
				(island_removal_mode 0)
			)
			(polygon
				(pts
					(arc
						(start 256.980944 -41.999916)
						(mid 256.218944 -41.999916)
						(end 256.980944 -41.999916)
					)
				)
			)
		)
		(zone
			(layer "F.Cu")
			(hatch none 0.5)
			(connect_pads
				(clearance 0)
			)
			(min_thickness 0.25)
			(keepout
				(tracks allowed)
				(vias not_allowed)
				(pads allowed)
				(copperpour not_allowed)
				(footprints allowed)
			)
			(placement
				(enabled no)
				(sheetname "")
			)
			(fill
				(thermal_gap 0.5)
				(thermal_bridge_width 0.5)
				(island_removal_mode 0)
			)
			(polygon
				(pts
					(arc
						(start 256.980944 -40.999918)
						(mid 256.218944 -40.999918)
						(end 256.980944 -40.999918)
					)
				)
			)
		)
		(zone
			(layer "F.Cu")
			(hatch none 0.5)
			(connect_pads
				(clearance 0)
			)
			(min_thickness 0.25)
			(keepout
				(tracks allowed)
				(vias not_allowed)
				(pads allowed)
				(copperpour not_allowed)
				(footprints allowed)
			)
			(placement
				(enabled no)
				(sheetname "")
			)
			(fill
				(thermal_gap 0.5)
				(thermal_bridge_width 0.5)
				(island_removal_mode 0)
			)
			(polygon
				(pts
					(arc
						(start 256.980944 -39.99992)
						(mid 256.218944 -39.99992)
						(end 256.980944 -39.99992)
					)
				)
			)
		)
		(zone
			(layer "F.Cu")
			(hatch none 0.5)
			(connect_pads
				(clearance 0)
			)
			(min_thickness 0.25)
			(keepout
				(tracks allowed)
				(vias not_allowed)
				(pads allowed)
				(copperpour not_allowed)
				(footprints allowed)
			)
			(placement
				(enabled no)
				(sheetname "")
			)
			(fill
				(thermal_gap 0.5)
				(thermal_bridge_width 0.5)
				(island_removal_mode 0)
			)
			(polygon
				(pts
					(arc
						(start 256.980944 -38.999922)
						(mid 256.218944 -38.999922)
						(end 256.980944 -38.999922)
					)
				)
			)
		)
		(zone
			(layer "F.Cu")
			(hatch none 0.5)
			(connect_pads
				(clearance 0)
			)
			(min_thickness 0.25)
			(keepout
				(tracks allowed)
				(vias not_allowed)
				(pads allowed)
				(copperpour not_allowed)
				(footprints allowed)
			)
			(placement
				(enabled no)
				(sheetname "")
			)
			(fill
				(thermal_gap 0.5)
				(thermal_bridge_width 0.5)
				(island_removal_mode 0)
			)
			(polygon
				(pts
					(arc
						(start 256.980944 -37.999924)
						(mid 256.218944 -37.999924)
						(end 256.980944 -37.999924)
					)
				)
			)
		)
		(zone
			(layer "F.Cu")
			(hatch none 0.5)
			(connect_pads
				(clearance 0)
			)
			(min_thickness 0.25)
			(keepout
				(tracks allowed)
				(vias not_allowed)
				(pads allowed)
				(copperpour not_allowed)
				(footprints allowed)
			)
			(placement
				(enabled no)
				(sheetname "")
			)
			(fill
				(thermal_gap 0.5)
				(thermal_bridge_width 0.5)
				(island_removal_mode 0)
			)
			(polygon
				(pts
					(arc
						(start 256.980944 -36.999926)
						(mid 256.218944 -36.999926)
						(end 256.980944 -36.999926)
					)
				)
			)
		)
		(zone
			(layer "F.Cu")
			(hatch none 0.5)
			(connect_pads
				(clearance 0)
			)
			(min_thickness 0.25)
			(keepout
				(tracks allowed)
				(vias not_allowed)
				(pads allowed)
				(copperpour not_allowed)
				(footprints allowed)
			)
			(placement
				(enabled no)
				(sheetname "")
			)
			(fill
				(thermal_gap 0.5)
				(thermal_bridge_width 0.5)
				(island_removal_mode 0)
			)
			(polygon
				(pts
					(arc
						(start 256.980944 -35.999928)
						(mid 256.218944 -35.999928)
						(end 256.980944 -35.999928)
					)
				)
			)
		)
		(zone
			(layer "F.Cu")
			(hatch none 0.5)
			(connect_pads
				(clearance 0)
			)
			(min_thickness 0.25)
			(keepout
				(tracks allowed)
				(vias not_allowed)
				(pads allowed)
				(copperpour not_allowed)
				(footprints allowed)
			)
			(placement
				(enabled no)
				(sheetname "")
			)
			(fill
				(thermal_gap 0.5)
				(thermal_bridge_width 0.5)
				(island_removal_mode 0)
			)
			(polygon
				(pts
					(arc
						(start 256.980944 -34.99993)
						(mid 256.218944 -34.99993)
						(end 256.980944 -34.99993)
					)
				)
			)
		)
		(zone
			(layer "F.Cu")
			(hatch none 0.5)
			(connect_pads
				(clearance 0)
			)
			(min_thickness 0.25)
			(keepout
				(tracks allowed)
				(vias not_allowed)
				(pads allowed)
				(copperpour not_allowed)
				(footprints allowed)
			)
			(placement
				(enabled no)
				(sheetname "")
			)
			(fill
				(thermal_gap 0.5)
				(thermal_bridge_width 0.5)
				(island_removal_mode 0)
			)
			(polygon
				(pts
					(arc
						(start 256.980944 -33.999932)
						(mid 256.218944 -33.999932)
						(end 256.980944 -33.999932)
					)
				)
			)
		)
		(zone
			(layer "F.Cu")
			(hatch none 0.5)
			(connect_pads
				(clearance 0)
			)
			(min_thickness 0.25)
			(keepout
				(tracks allowed)
				(vias not_allowed)
				(pads allowed)
				(copperpour not_allowed)
				(footprints allowed)
			)
			(placement
				(enabled no)
				(sheetname "")
			)
			(fill
				(thermal_gap 0.5)
				(thermal_bridge_width 0.5)
				(island_removal_mode 0)
			)
			(polygon
				(pts
					(arc
						(start 256.980944 -32.999934)
						(mid 256.218944 -32.999934)
						(end 256.980944 -32.999934)
					)
				)
			)
		)
		(zone
			(layer "F.Cu")
			(hatch none 0.5)
			(connect_pads
				(clearance 0)
			)
			(min_thickness 0.25)
			(keepout
				(tracks allowed)
				(vias not_allowed)
				(pads allowed)
				(copperpour not_allowed)
				(footprints allowed)
			)
			(placement
				(enabled no)
				(sheetname "")
			)
			(fill
				(thermal_gap 0.5)
				(thermal_bridge_width 0.5)
				(island_removal_mode 0)
			)
			(polygon
				(pts
					(arc
						(start 257.980942 -62.999874)
						(mid 257.218942 -62.999874)
						(end 257.980942 -62.999874)
					)
				)
			)
		)
		(zone
			(layer "F.Cu")
			(hatch none 0.5)
			(connect_pads
				(clearance 0)
			)
			(min_thickness 0.25)
			(keepout
				(tracks allowed)
				(vias not_allowed)
				(pads allowed)
				(copperpour not_allowed)
				(footprints allowed)
			)
			(placement
				(enabled no)
				(sheetname "")
			)
			(fill
				(thermal_gap 0.5)
				(thermal_bridge_width 0.5)
				(island_removal_mode 0)
			)
			(polygon
				(pts
					(arc
						(start 257.980942 -61.999876)
						(mid 257.218942 -61.999876)
						(end 257.980942 -61.999876)
					)
				)
			)
		)
		(zone
			(layer "F.Cu")
			(hatch none 0.5)
			(connect_pads
				(clearance 0)
			)
			(min_thickness 0.25)
			(keepout
				(tracks allowed)
				(vias not_allowed)
				(pads allowed)
				(copperpour not_allowed)
				(footprints allowed)
			)
			(placement
				(enabled no)
				(sheetname "")
			)
			(fill
				(thermal_gap 0.5)
				(thermal_bridge_width 0.5)
				(island_removal_mode 0)
			)
			(polygon
				(pts
					(arc
						(start 257.980942 -60.999878)
						(mid 257.218942 -60.999878)
						(end 257.980942 -60.999878)
					)
				)
			)
		)
		(zone
			(layer "F.Cu")
			(hatch none 0.5)
			(connect_pads
				(clearance 0)
			)
			(min_thickness 0.25)
			(keepout
				(tracks allowed)
				(vias not_allowed)
				(pads allowed)
				(copperpour not_allowed)
				(footprints allowed)
			)
			(placement
				(enabled no)
				(sheetname "")
			)
			(fill
				(thermal_gap 0.5)
				(thermal_bridge_width 0.5)
				(island_removal_mode 0)
			)
			(polygon
				(pts
					(arc
						(start 257.980942 -59.99988)
						(mid 257.218942 -59.99988)
						(end 257.980942 -59.99988)
					)
				)
			)
		)
		(zone
			(layer "F.Cu")
			(hatch none 0.5)
			(connect_pads
				(clearance 0)
			)
			(min_thickness 0.25)
			(keepout
				(tracks allowed)
				(vias not_allowed)
				(pads allowed)
				(copperpour not_allowed)
				(footprints allowed)
			)
			(placement
				(enabled no)
				(sheetname "")
			)
			(fill
				(thermal_gap 0.5)
				(thermal_bridge_width 0.5)
				(island_removal_mode 0)
			)
			(polygon
				(pts
					(arc
						(start 257.980942 -58.999882)
						(mid 257.218942 -58.999882)
						(end 257.980942 -58.999882)
					)
				)
			)
		)
		(zone
			(layer "F.Cu")
			(hatch none 0.5)
			(connect_pads
				(clearance 0)
			)
			(min_thickness 0.25)
			(keepout
				(tracks allowed)
				(vias not_allowed)
				(pads allowed)
				(copperpour not_allowed)
				(footprints allowed)
			)
			(placement
				(enabled no)
				(sheetname "")
			)
			(fill
				(thermal_gap 0.5)
				(thermal_bridge_width 0.5)
				(island_removal_mode 0)
			)
			(polygon
				(pts
					(arc
						(start 257.980942 -57.999884)
						(mid 257.218942 -57.999884)
						(end 257.980942 -57.999884)
					)
				)
			)
		)
		(zone
			(layer "F.Cu")
			(hatch none 0.5)
			(connect_pads
				(clearance 0)
			)
			(min_thickness 0.25)
			(keepout
				(tracks allowed)
				(vias not_allowed)
				(pads allowed)
				(copperpour not_allowed)
				(footprints allowed)
			)
			(placement
				(enabled no)
				(sheetname "")
			)
			(fill
				(thermal_gap 0.5)
				(thermal_bridge_width 0.5)
				(island_removal_mode 0)
			)
			(polygon
				(pts
					(arc
						(start 257.980942 -56.999886)
						(mid 257.218942 -56.999886)
						(end 257.980942 -56.999886)
					)
				)
			)
		)
		(zone
			(layer "F.Cu")
			(hatch none 0.5)
			(connect_pads
				(clearance 0)
			)
			(min_thickness 0.25)
			(keepout
				(tracks allowed)
				(vias not_allowed)
				(pads allowed)
				(copperpour not_allowed)
				(footprints allowed)
			)
			(placement
				(enabled no)
				(sheetname "")
			)
			(fill
				(thermal_gap 0.5)
				(thermal_bridge_width 0.5)
				(island_removal_mode 0)
			)
			(polygon
				(pts
					(arc
						(start 257.980942 -55.999888)
						(mid 257.218942 -55.999888)
						(end 257.980942 -55.999888)
					)
				)
			)
		)
		(zone
			(layer "F.Cu")
			(hatch none 0.5)
			(connect_pads
				(clearance 0)
			)
			(min_thickness 0.25)
			(keepout
				(tracks allowed)
				(vias not_allowed)
				(pads allowed)
				(copperpour not_allowed)
				(footprints allowed)
			)
			(placement
				(enabled no)
				(sheetname "")
			)
			(fill
				(thermal_gap 0.5)
				(thermal_bridge_width 0.5)
				(island_removal_mode 0)
			)
			(polygon
				(pts
					(arc
						(start 257.980942 -54.99989)
						(mid 257.218942 -54.99989)
						(end 257.980942 -54.99989)
					)
				)
			)
		)
		(zone
			(layer "F.Cu")
			(hatch none 0.5)
			(connect_pads
				(clearance 0)
			)
			(min_thickness 0.25)
			(keepout
				(tracks allowed)
				(vias not_allowed)
				(pads allowed)
				(copperpour not_allowed)
				(footprints allowed)
			)
			(placement
				(enabled no)
				(sheetname "")
			)
			(fill
				(thermal_gap 0.5)
				(thermal_bridge_width 0.5)
				(island_removal_mode 0)
			)
			(polygon
				(pts
					(arc
						(start 257.980942 -53.999892)
						(mid 257.218942 -53.999892)
						(end 257.980942 -53.999892)
					)
				)
			)
		)
		(zone
			(layer "F.Cu")
			(hatch none 0.5)
			(connect_pads
				(clearance 0)
			)
			(min_thickness 0.25)
			(keepout
				(tracks allowed)
				(vias not_allowed)
				(pads allowed)
				(copperpour not_allowed)
				(footprints allowed)
			)
			(placement
				(enabled no)
				(sheetname "")
			)
			(fill
				(thermal_gap 0.5)
				(thermal_bridge_width 0.5)
				(island_removal_mode 0)
			)
			(polygon
				(pts
					(arc
						(start 257.980942 -52.999894)
						(mid 257.218942 -52.999894)
						(end 257.980942 -52.999894)
					)
				)
			)
		)
		(zone
			(layer "F.Cu")
			(hatch none 0.5)
			(connect_pads
				(clearance 0)
			)
			(min_thickness 0.25)
			(keepout
				(tracks allowed)
				(vias not_allowed)
				(pads allowed)
				(copperpour not_allowed)
				(footprints allowed)
			)
			(placement
				(enabled no)
				(sheetname "")
			)
			(fill
				(thermal_gap 0.5)
				(thermal_bridge_width 0.5)
				(island_removal_mode 0)
			)
			(polygon
				(pts
					(arc
						(start 257.980942 -51.999896)
						(mid 257.218942 -51.999896)
						(end 257.980942 -51.999896)
					)
				)
			)
		)
		(zone
			(layer "F.Cu")
			(hatch none 0.5)
			(connect_pads
				(clearance 0)
			)
			(min_thickness 0.25)
			(keepout
				(tracks allowed)
				(vias not_allowed)
				(pads allowed)
				(copperpour not_allowed)
				(footprints allowed)
			)
			(placement
				(enabled no)
				(sheetname "")
			)
			(fill
				(thermal_gap 0.5)
				(thermal_bridge_width 0.5)
				(island_removal_mode 0)
			)
			(polygon
				(pts
					(arc
						(start 257.980942 -50.999898)
						(mid 257.218942 -50.999898)
						(end 257.980942 -50.999898)
					)
				)
			)
		)
		(zone
			(layer "F.Cu")
			(hatch none 0.5)
			(connect_pads
				(clearance 0)
			)
			(min_thickness 0.25)
			(keepout
				(tracks allowed)
				(vias not_allowed)
				(pads allowed)
				(copperpour not_allowed)
				(footprints allowed)
			)
			(placement
				(enabled no)
				(sheetname "")
			)
			(fill
				(thermal_gap 0.5)
				(thermal_bridge_width 0.5)
				(island_removal_mode 0)
			)
			(polygon
				(pts
					(arc
						(start 257.980942 -49.9999)
						(mid 257.218942 -49.9999)
						(end 257.980942 -49.9999)
					)
				)
			)
		)
		(zone
			(layer "F.Cu")
			(hatch none 0.5)
			(connect_pads
				(clearance 0)
			)
			(min_thickness 0.25)
			(keepout
				(tracks allowed)
				(vias not_allowed)
				(pads allowed)
				(copperpour not_allowed)
				(footprints allowed)
			)
			(placement
				(enabled no)
				(sheetname "")
			)
			(fill
				(thermal_gap 0.5)
				(thermal_bridge_width 0.5)
				(island_removal_mode 0)
			)
			(polygon
				(pts
					(arc
						(start 257.980942 -48.999902)
						(mid 257.218942 -48.999902)
						(end 257.980942 -48.999902)
					)
				)
			)
		)
		(zone
			(layer "F.Cu")
			(hatch none 0.5)
			(connect_pads
				(clearance 0)
			)
			(min_thickness 0.25)
			(keepout
				(tracks allowed)
				(vias not_allowed)
				(pads allowed)
				(copperpour not_allowed)
				(footprints allowed)
			)
			(placement
				(enabled no)
				(sheetname "")
			)
			(fill
				(thermal_gap 0.5)
				(thermal_bridge_width 0.5)
				(island_removal_mode 0)
			)
			(polygon
				(pts
					(arc
						(start 257.980942 -47.999904)
						(mid 257.218942 -47.999904)
						(end 257.980942 -47.999904)
					)
				)
			)
		)
		(zone
			(layer "F.Cu")
			(hatch none 0.5)
			(connect_pads
				(clearance 0)
			)
			(min_thickness 0.25)
			(keepout
				(tracks allowed)
				(vias not_allowed)
				(pads allowed)
				(copperpour not_allowed)
				(footprints allowed)
			)
			(placement
				(enabled no)
				(sheetname "")
			)
			(fill
				(thermal_gap 0.5)
				(thermal_bridge_width 0.5)
				(island_removal_mode 0)
			)
			(polygon
				(pts
					(arc
						(start 257.980942 -46.999906)
						(mid 257.218942 -46.999906)
						(end 257.980942 -46.999906)
					)
				)
			)
		)
		(zone
			(layer "F.Cu")
			(hatch none 0.5)
			(connect_pads
				(clearance 0)
			)
			(min_thickness 0.25)
			(keepout
				(tracks allowed)
				(vias not_allowed)
				(pads allowed)
				(copperpour not_allowed)
				(footprints allowed)
			)
			(placement
				(enabled no)
				(sheetname "")
			)
			(fill
				(thermal_gap 0.5)
				(thermal_bridge_width 0.5)
				(island_removal_mode 0)
			)
			(polygon
				(pts
					(arc
						(start 257.980942 -45.999908)
						(mid 257.218942 -45.999908)
						(end 257.980942 -45.999908)
					)
				)
			)
		)
		(zone
			(layer "F.Cu")
			(hatch none 0.5)
			(connect_pads
				(clearance 0)
			)
			(min_thickness 0.25)
			(keepout
				(tracks allowed)
				(vias not_allowed)
				(pads allowed)
				(copperpour not_allowed)
				(footprints allowed)
			)
			(placement
				(enabled no)
				(sheetname "")
			)
			(fill
				(thermal_gap 0.5)
				(thermal_bridge_width 0.5)
				(island_removal_mode 0)
			)
			(polygon
				(pts
					(arc
						(start 257.980942 -44.99991)
						(mid 257.218942 -44.99991)
						(end 257.980942 -44.99991)
					)
				)
			)
		)
		(zone
			(layer "F.Cu")
			(hatch none 0.5)
			(connect_pads
				(clearance 0)
			)
			(min_thickness 0.25)
			(keepout
				(tracks allowed)
				(vias not_allowed)
				(pads allowed)
				(copperpour not_allowed)
				(footprints allowed)
			)
			(placement
				(enabled no)
				(sheetname "")
			)
			(fill
				(thermal_gap 0.5)
				(thermal_bridge_width 0.5)
				(island_removal_mode 0)
			)
			(polygon
				(pts
					(arc
						(start 257.980942 -43.999912)
						(mid 257.218942 -43.999912)
						(end 257.980942 -43.999912)
					)
				)
			)
		)
		(zone
			(layer "F.Cu")
			(hatch none 0.5)
			(connect_pads
				(clearance 0)
			)
			(min_thickness 0.25)
			(keepout
				(tracks allowed)
				(vias not_allowed)
				(pads allowed)
				(copperpour not_allowed)
				(footprints allowed)
			)
			(placement
				(enabled no)
				(sheetname "")
			)
			(fill
				(thermal_gap 0.5)
				(thermal_bridge_width 0.5)
				(island_removal_mode 0)
			)
			(polygon
				(pts
					(arc
						(start 257.980942 -42.999914)
						(mid 257.218942 -42.999914)
						(end 257.980942 -42.999914)
					)
				)
			)
		)
		(zone
			(layer "F.Cu")
			(hatch none 0.5)
			(connect_pads
				(clearance 0)
			)
			(min_thickness 0.25)
			(keepout
				(tracks allowed)
				(vias not_allowed)
				(pads allowed)
				(copperpour not_allowed)
				(footprints allowed)
			)
			(placement
				(enabled no)
				(sheetname "")
			)
			(fill
				(thermal_gap 0.5)
				(thermal_bridge_width 0.5)
				(island_removal_mode 0)
			)
			(polygon
				(pts
					(arc
						(start 257.980942 -41.999916)
						(mid 257.218942 -41.999916)
						(end 257.980942 -41.999916)
					)
				)
			)
		)
		(zone
			(layer "F.Cu")
			(hatch none 0.5)
			(connect_pads
				(clearance 0)
			)
			(min_thickness 0.25)
			(keepout
				(tracks allowed)
				(vias not_allowed)
				(pads allowed)
				(copperpour not_allowed)
				(footprints allowed)
			)
			(placement
				(enabled no)
				(sheetname "")
			)
			(fill
				(thermal_gap 0.5)
				(thermal_bridge_width 0.5)
				(island_removal_mode 0)
			)
			(polygon
				(pts
					(arc
						(start 257.980942 -40.999918)
						(mid 257.218942 -40.999918)
						(end 257.980942 -40.999918)
					)
				)
			)
		)
		(zone
			(layer "F.Cu")
			(hatch none 0.5)
			(connect_pads
				(clearance 0)
			)
			(min_thickness 0.25)
			(keepout
				(tracks allowed)
				(vias not_allowed)
				(pads allowed)
				(copperpour not_allowed)
				(footprints allowed)
			)
			(placement
				(enabled no)
				(sheetname "")
			)
			(fill
				(thermal_gap 0.5)
				(thermal_bridge_width 0.5)
				(island_removal_mode 0)
			)
			(polygon
				(pts
					(arc
						(start 257.980942 -39.99992)
						(mid 257.218942 -39.99992)
						(end 257.980942 -39.99992)
					)
				)
			)
		)
		(zone
			(layer "F.Cu")
			(hatch none 0.5)
			(connect_pads
				(clearance 0)
			)
			(min_thickness 0.25)
			(keepout
				(tracks allowed)
				(vias not_allowed)
				(pads allowed)
				(copperpour not_allowed)
				(footprints allowed)
			)
			(placement
				(enabled no)
				(sheetname "")
			)
			(fill
				(thermal_gap 0.5)
				(thermal_bridge_width 0.5)
				(island_removal_mode 0)
			)
			(polygon
				(pts
					(arc
						(start 257.980942 -38.999922)
						(mid 257.218942 -38.999922)
						(end 257.980942 -38.999922)
					)
				)
			)
		)
		(zone
			(layer "F.Cu")
			(hatch none 0.5)
			(connect_pads
				(clearance 0)
			)
			(min_thickness 0.25)
			(keepout
				(tracks allowed)
				(vias not_allowed)
				(pads allowed)
				(copperpour not_allowed)
				(footprints allowed)
			)
			(placement
				(enabled no)
				(sheetname "")
			)
			(fill
				(thermal_gap 0.5)
				(thermal_bridge_width 0.5)
				(island_removal_mode 0)
			)
			(polygon
				(pts
					(arc
						(start 257.980942 -37.999924)
						(mid 257.218942 -37.999924)
						(end 257.980942 -37.999924)
					)
				)
			)
		)
		(zone
			(layer "F.Cu")
			(hatch none 0.5)
			(connect_pads
				(clearance 0)
			)
			(min_thickness 0.25)
			(keepout
				(tracks allowed)
				(vias not_allowed)
				(pads allowed)
				(copperpour not_allowed)
				(footprints allowed)
			)
			(placement
				(enabled no)
				(sheetname "")
			)
			(fill
				(thermal_gap 0.5)
				(thermal_bridge_width 0.5)
				(island_removal_mode 0)
			)
			(polygon
				(pts
					(arc
						(start 257.980942 -36.999926)
						(mid 257.218942 -36.999926)
						(end 257.980942 -36.999926)
					)
				)
			)
		)
		(zone
			(layer "F.Cu")
			(hatch none 0.5)
			(connect_pads
				(clearance 0)
			)
			(min_thickness 0.25)
			(keepout
				(tracks allowed)
				(vias not_allowed)
				(pads allowed)
				(copperpour not_allowed)
				(footprints allowed)
			)
			(placement
				(enabled no)
				(sheetname "")
			)
			(fill
				(thermal_gap 0.5)
				(thermal_bridge_width 0.5)
				(island_removal_mode 0)
			)
			(polygon
				(pts
					(arc
						(start 257.980942 -35.999928)
						(mid 257.218942 -35.999928)
						(end 257.980942 -35.999928)
					)
				)
			)
		)
		(zone
			(layer "F.Cu")
			(hatch none 0.5)
			(connect_pads
				(clearance 0)
			)
			(min_thickness 0.25)
			(keepout
				(tracks allowed)
				(vias not_allowed)
				(pads allowed)
				(copperpour not_allowed)
				(footprints allowed)
			)
			(placement
				(enabled no)
				(sheetname "")
			)
			(fill
				(thermal_gap 0.5)
				(thermal_bridge_width 0.5)
				(island_removal_mode 0)
			)
			(polygon
				(pts
					(arc
						(start 257.980942 -34.99993)
						(mid 257.218942 -34.99993)
						(end 257.980942 -34.99993)
					)
				)
			)
		)
		(zone
			(layer "F.Cu")
			(hatch none 0.5)
			(connect_pads
				(clearance 0)
			)
			(min_thickness 0.25)
			(keepout
				(tracks allowed)
				(vias not_allowed)
				(pads allowed)
				(copperpour not_allowed)
				(footprints allowed)
			)
			(placement
				(enabled no)
				(sheetname "")
			)
			(fill
				(thermal_gap 0.5)
				(thermal_bridge_width 0.5)
				(island_removal_mode 0)
			)
			(polygon
				(pts
					(arc
						(start 257.980942 -33.999932)
						(mid 257.218942 -33.999932)
						(end 257.980942 -33.999932)
					)
				)
			)
		)
		(zone
			(layer "F.Cu")
			(hatch none 0.5)
			(connect_pads
				(clearance 0)
			)
			(min_thickness 0.25)
			(keepout
				(tracks allowed)
				(vias not_allowed)
				(pads allowed)
				(copperpour not_allowed)
				(footprints allowed)
			)
			(placement
				(enabled no)
				(sheetname "")
			)
			(fill
				(thermal_gap 0.5)
				(thermal_bridge_width 0.5)
				(island_removal_mode 0)
			)
			(polygon
				(pts
					(arc
						(start 257.980942 -32.999934)
						(mid 257.218942 -32.999934)
						(end 257.980942 -32.999934)
					)
				)
			)
		)
		(zone
			(layer "F.Cu")
			(hatch none 0.5)
			(connect_pads
				(clearance 0)
			)
			(min_thickness 0.25)
			(keepout
				(tracks allowed)
				(vias not_allowed)
				(pads allowed)
				(copperpour not_allowed)
				(footprints allowed)
			)
			(placement
				(enabled no)
				(sheetname "")
			)
			(fill
				(thermal_gap 0.5)
				(thermal_bridge_width 0.5)
				(island_removal_mode 0)
			)
			(polygon
				(pts
					(arc
						(start 258.98094 -62.999874)
						(mid 258.21894 -62.999874)
						(end 258.98094 -62.999874)
					)
				)
			)
		)
		(zone
			(layer "F.Cu")
			(hatch none 0.5)
			(connect_pads
				(clearance 0)
			)
			(min_thickness 0.25)
			(keepout
				(tracks allowed)
				(vias not_allowed)
				(pads allowed)
				(copperpour not_allowed)
				(footprints allowed)
			)
			(placement
				(enabled no)
				(sheetname "")
			)
			(fill
				(thermal_gap 0.5)
				(thermal_bridge_width 0.5)
				(island_removal_mode 0)
			)
			(polygon
				(pts
					(arc
						(start 258.98094 -61.999876)
						(mid 258.21894 -61.999876)
						(end 258.98094 -61.999876)
					)
				)
			)
		)
		(zone
			(layer "F.Cu")
			(hatch none 0.5)
			(connect_pads
				(clearance 0)
			)
			(min_thickness 0.25)
			(keepout
				(tracks allowed)
				(vias not_allowed)
				(pads allowed)
				(copperpour not_allowed)
				(footprints allowed)
			)
			(placement
				(enabled no)
				(sheetname "")
			)
			(fill
				(thermal_gap 0.5)
				(thermal_bridge_width 0.5)
				(island_removal_mode 0)
			)
			(polygon
				(pts
					(arc
						(start 258.98094 -60.999878)
						(mid 258.21894 -60.999878)
						(end 258.98094 -60.999878)
					)
				)
			)
		)
		(zone
			(layer "F.Cu")
			(hatch none 0.5)
			(connect_pads
				(clearance 0)
			)
			(min_thickness 0.25)
			(keepout
				(tracks allowed)
				(vias not_allowed)
				(pads allowed)
				(copperpour not_allowed)
				(footprints allowed)
			)
			(placement
				(enabled no)
				(sheetname "")
			)
			(fill
				(thermal_gap 0.5)
				(thermal_bridge_width 0.5)
				(island_removal_mode 0)
			)
			(polygon
				(pts
					(arc
						(start 258.98094 -59.99988)
						(mid 258.21894 -59.99988)
						(end 258.98094 -59.99988)
					)
				)
			)
		)
		(zone
			(layer "F.Cu")
			(hatch none 0.5)
			(connect_pads
				(clearance 0)
			)
			(min_thickness 0.25)
			(keepout
				(tracks allowed)
				(vias not_allowed)
				(pads allowed)
				(copperpour not_allowed)
				(footprints allowed)
			)
			(placement
				(enabled no)
				(sheetname "")
			)
			(fill
				(thermal_gap 0.5)
				(thermal_bridge_width 0.5)
				(island_removal_mode 0)
			)
			(polygon
				(pts
					(arc
						(start 258.98094 -57.999884)
						(mid 258.21894 -57.999884)
						(end 258.98094 -57.999884)
					)
				)
			)
		)
		(zone
			(layer "F.Cu")
			(hatch none 0.5)
			(connect_pads
				(clearance 0)
			)
			(min_thickness 0.25)
			(keepout
				(tracks allowed)
				(vias not_allowed)
				(pads allowed)
				(copperpour not_allowed)
				(footprints allowed)
			)
			(placement
				(enabled no)
				(sheetname "")
			)
			(fill
				(thermal_gap 0.5)
				(thermal_bridge_width 0.5)
				(island_removal_mode 0)
			)
			(polygon
				(pts
					(arc
						(start 258.98094 -55.999888)
						(mid 258.21894 -55.999888)
						(end 258.98094 -55.999888)
					)
				)
			)
		)
		(zone
			(layer "F.Cu")
			(hatch none 0.5)
			(connect_pads
				(clearance 0)
			)
			(min_thickness 0.25)
			(keepout
				(tracks allowed)
				(vias not_allowed)
				(pads allowed)
				(copperpour not_allowed)
				(footprints allowed)
			)
			(placement
				(enabled no)
				(sheetname "")
			)
			(fill
				(thermal_gap 0.5)
				(thermal_bridge_width 0.5)
				(island_removal_mode 0)
			)
			(polygon
				(pts
					(arc
						(start 258.98094 -53.999892)
						(mid 258.21894 -53.999892)
						(end 258.98094 -53.999892)
					)
				)
			)
		)
		(zone
			(layer "F.Cu")
			(hatch none 0.5)
			(connect_pads
				(clearance 0)
			)
			(min_thickness 0.25)
			(keepout
				(tracks allowed)
				(vias not_allowed)
				(pads allowed)
				(copperpour not_allowed)
				(footprints allowed)
			)
			(placement
				(enabled no)
				(sheetname "")
			)
			(fill
				(thermal_gap 0.5)
				(thermal_bridge_width 0.5)
				(island_removal_mode 0)
			)
			(polygon
				(pts
					(arc
						(start 258.98094 -51.999896)
						(mid 258.21894 -51.999896)
						(end 258.98094 -51.999896)
					)
				)
			)
		)
		(zone
			(layer "F.Cu")
			(hatch none 0.5)
			(connect_pads
				(clearance 0)
			)
			(min_thickness 0.25)
			(keepout
				(tracks allowed)
				(vias not_allowed)
				(pads allowed)
				(copperpour not_allowed)
				(footprints allowed)
			)
			(placement
				(enabled no)
				(sheetname "")
			)
			(fill
				(thermal_gap 0.5)
				(thermal_bridge_width 0.5)
				(island_removal_mode 0)
			)
			(polygon
				(pts
					(arc
						(start 258.98094 -50.999898)
						(mid 258.21894 -50.999898)
						(end 258.98094 -50.999898)
					)
				)
			)
		)
		(zone
			(layer "F.Cu")
			(hatch none 0.5)
			(connect_pads
				(clearance 0)
			)
			(min_thickness 0.25)
			(keepout
				(tracks allowed)
				(vias not_allowed)
				(pads allowed)
				(copperpour not_allowed)
				(footprints allowed)
			)
			(placement
				(enabled no)
				(sheetname "")
			)
			(fill
				(thermal_gap 0.5)
				(thermal_bridge_width 0.5)
				(island_removal_mode 0)
			)
			(polygon
				(pts
					(arc
						(start 258.98094 -48.999902)
						(mid 258.21894 -48.999902)
						(end 258.98094 -48.999902)
					)
				)
			)
		)
		(zone
			(layer "F.Cu")
			(hatch none 0.5)
			(connect_pads
				(clearance 0)
			)
			(min_thickness 0.25)
			(keepout
				(tracks allowed)
				(vias not_allowed)
				(pads allowed)
				(copperpour not_allowed)
				(footprints allowed)
			)
			(placement
				(enabled no)
				(sheetname "")
			)
			(fill
				(thermal_gap 0.5)
				(thermal_bridge_width 0.5)
				(island_removal_mode 0)
			)
			(polygon
				(pts
					(arc
						(start 258.98094 -46.999906)
						(mid 258.21894 -46.999906)
						(end 258.98094 -46.999906)
					)
				)
			)
		)
		(zone
			(layer "F.Cu")
			(hatch none 0.5)
			(connect_pads
				(clearance 0)
			)
			(min_thickness 0.25)
			(keepout
				(tracks allowed)
				(vias not_allowed)
				(pads allowed)
				(copperpour not_allowed)
				(footprints allowed)
			)
			(placement
				(enabled no)
				(sheetname "")
			)
			(fill
				(thermal_gap 0.5)
				(thermal_bridge_width 0.5)
				(island_removal_mode 0)
			)
			(polygon
				(pts
					(arc
						(start 258.98094 -44.99991)
						(mid 258.21894 -44.99991)
						(end 258.98094 -44.99991)
					)
				)
			)
		)
		(zone
			(layer "F.Cu")
			(hatch none 0.5)
			(connect_pads
				(clearance 0)
			)
			(min_thickness 0.25)
			(keepout
				(tracks allowed)
				(vias not_allowed)
				(pads allowed)
				(copperpour not_allowed)
				(footprints allowed)
			)
			(placement
				(enabled no)
				(sheetname "")
			)
			(fill
				(thermal_gap 0.5)
				(thermal_bridge_width 0.5)
				(island_removal_mode 0)
			)
			(polygon
				(pts
					(arc
						(start 258.98094 -42.999914)
						(mid 258.21894 -42.999914)
						(end 258.98094 -42.999914)
					)
				)
			)
		)
		(zone
			(layer "F.Cu")
			(hatch none 0.5)
			(connect_pads
				(clearance 0)
			)
			(min_thickness 0.25)
			(keepout
				(tracks allowed)
				(vias not_allowed)
				(pads allowed)
				(copperpour not_allowed)
				(footprints allowed)
			)
			(placement
				(enabled no)
				(sheetname "")
			)
			(fill
				(thermal_gap 0.5)
				(thermal_bridge_width 0.5)
				(island_removal_mode 0)
			)
			(polygon
				(pts
					(arc
						(start 258.98094 -41.999916)
						(mid 258.21894 -41.999916)
						(end 258.98094 -41.999916)
					)
				)
			)
		)
		(zone
			(layer "F.Cu")
			(hatch none 0.5)
			(connect_pads
				(clearance 0)
			)
			(min_thickness 0.25)
			(keepout
				(tracks allowed)
				(vias not_allowed)
				(pads allowed)
				(copperpour not_allowed)
				(footprints allowed)
			)
			(placement
				(enabled no)
				(sheetname "")
			)
			(fill
				(thermal_gap 0.5)
				(thermal_bridge_width 0.5)
				(island_removal_mode 0)
			)
			(polygon
				(pts
					(arc
						(start 258.98094 -39.99992)
						(mid 258.21894 -39.99992)
						(end 258.98094 -39.99992)
					)
				)
			)
		)
		(zone
			(layer "F.Cu")
			(hatch none 0.5)
			(connect_pads
				(clearance 0)
			)
			(min_thickness 0.25)
			(keepout
				(tracks allowed)
				(vias not_allowed)
				(pads allowed)
				(copperpour not_allowed)
				(footprints allowed)
			)
			(placement
				(enabled no)
				(sheetname "")
			)
			(fill
				(thermal_gap 0.5)
				(thermal_bridge_width 0.5)
				(island_removal_mode 0)
			)
			(polygon
				(pts
					(arc
						(start 258.98094 -37.999924)
						(mid 258.21894 -37.999924)
						(end 258.98094 -37.999924)
					)
				)
			)
		)
		(zone
			(layer "F.Cu")
			(hatch none 0.5)
			(connect_pads
				(clearance 0)
			)
			(min_thickness 0.25)
			(keepout
				(tracks allowed)
				(vias not_allowed)
				(pads allowed)
				(copperpour not_allowed)
				(footprints allowed)
			)
			(placement
				(enabled no)
				(sheetname "")
			)
			(fill
				(thermal_gap 0.5)
				(thermal_bridge_width 0.5)
				(island_removal_mode 0)
			)
			(polygon
				(pts
					(arc
						(start 258.98094 -35.999928)
						(mid 258.21894 -35.999928)
						(end 258.98094 -35.999928)
					)
				)
			)
		)
		(zone
			(layer "F.Cu")
			(hatch none 0.5)
			(connect_pads
				(clearance 0)
			)
			(min_thickness 0.25)
			(keepout
				(tracks allowed)
				(vias not_allowed)
				(pads allowed)
				(copperpour not_allowed)
				(footprints allowed)
			)
			(placement
				(enabled no)
				(sheetname "")
			)
			(fill
				(thermal_gap 0.5)
				(thermal_bridge_width 0.5)
				(island_removal_mode 0)
			)
			(polygon
				(pts
					(arc
						(start 258.98094 -33.999932)
						(mid 258.21894 -33.999932)
						(end 258.98094 -33.999932)
					)
				)
			)
		)
		(zone
			(layer "F.Cu")
			(hatch none 0.5)
			(connect_pads
				(clearance 0)
			)
			(min_thickness 0.25)
			(keepout
				(tracks allowed)
				(vias not_allowed)
				(pads allowed)
				(copperpour not_allowed)
				(footprints allowed)
			)
			(placement
				(enabled no)
				(sheetname "")
			)
			(fill
				(thermal_gap 0.5)
				(thermal_bridge_width 0.5)
				(island_removal_mode 0)
			)
			(polygon
				(pts
					(arc
						(start 258.98094 -32.999934)
						(mid 258.21894 -32.999934)
						(end 258.98094 -32.999934)
					)
				)
			)
		)
		(zone
			(layer "F.Cu")
			(hatch none 0.5)
			(connect_pads
				(clearance 0)
			)
			(min_thickness 0.25)
			(keepout
				(tracks allowed)
				(vias not_allowed)
				(pads allowed)
				(copperpour not_allowed)
				(footprints allowed)
			)
			(placement
				(enabled no)
				(sheetname "")
			)
			(fill
				(thermal_gap 0.5)
				(thermal_bridge_width 0.5)
				(island_removal_mode 0)
			)
			(polygon
				(pts
					(arc
						(start 223.006412 -64.99987)
						(mid 222.193612 -64.99987)
						(end 223.006412 -64.99987)
					)
				)
			)
		)
		(zone
			(layer "F.Cu")
			(hatch none 0.5)
			(connect_pads
				(clearance 0)
			)
			(min_thickness 0.25)
			(keepout
				(tracks allowed)
				(vias not_allowed)
				(pads allowed)
				(copperpour not_allowed)
				(footprints allowed)
			)
			(placement
				(enabled no)
				(sheetname "")
			)
			(fill
				(thermal_gap 0.5)
				(thermal_bridge_width 0.5)
				(island_removal_mode 0)
			)
			(polygon
				(pts
					(arc
						(start 223.006412 -63.999872)
						(mid 222.193612 -63.999872)
						(end 223.006412 -63.999872)
					)
				)
			)
		)
		(zone
			(layer "F.Cu")
			(hatch none 0.5)
			(connect_pads
				(clearance 0)
			)
			(min_thickness 0.25)
			(keepout
				(tracks allowed)
				(vias not_allowed)
				(pads allowed)
				(copperpour not_allowed)
				(footprints allowed)
			)
			(placement
				(enabled no)
				(sheetname "")
			)
			(fill
				(thermal_gap 0.5)
				(thermal_bridge_width 0.5)
				(island_removal_mode 0)
			)
			(polygon
				(pts
					(arc
						(start 223.006412 -31.999936)
						(mid 222.193612 -31.999936)
						(end 223.006412 -31.999936)
					)
				)
			)
		)
		(zone
			(layer "F.Cu")
			(hatch none 0.5)
			(connect_pads
				(clearance 0)
			)
			(min_thickness 0.25)
			(keepout
				(tracks allowed)
				(vias not_allowed)
				(pads allowed)
				(copperpour not_allowed)
				(footprints allowed)
			)
			(placement
				(enabled no)
				(sheetname "")
			)
			(fill
				(thermal_gap 0.5)
				(thermal_bridge_width 0.5)
				(island_removal_mode 0)
			)
			(polygon
				(pts
					(arc
						(start 223.006412 -30.999938)
						(mid 222.193612 -30.999938)
						(end 223.006412 -30.999938)
					)
				)
			)
		)
		(zone
			(layer "F.Cu")
			(hatch none 0.5)
			(connect_pads
				(clearance 0)
			)
			(min_thickness 0.25)
			(keepout
				(tracks allowed)
				(vias not_allowed)
				(pads allowed)
				(copperpour not_allowed)
				(footprints allowed)
			)
			(placement
				(enabled no)
				(sheetname "")
			)
			(fill
				(thermal_gap 0.5)
				(thermal_bridge_width 0.5)
				(island_removal_mode 0)
			)
			(polygon
				(pts
					(arc
						(start 224.00641 -65.999868)
						(mid 223.19361 -65.999868)
						(end 224.00641 -65.999868)
					)
				)
			)
		)
		(zone
			(layer "F.Cu")
			(hatch none 0.5)
			(connect_pads
				(clearance 0)
			)
			(min_thickness 0.25)
			(keepout
				(tracks allowed)
				(vias not_allowed)
				(pads allowed)
				(copperpour not_allowed)
				(footprints allowed)
			)
			(placement
				(enabled no)
				(sheetname "")
			)
			(fill
				(thermal_gap 0.5)
				(thermal_bridge_width 0.5)
				(island_removal_mode 0)
			)
			(polygon
				(pts
					(arc
						(start 224.00641 -64.99987)
						(mid 223.19361 -64.99987)
						(end 224.00641 -64.99987)
					)
				)
			)
		)
		(zone
			(layer "F.Cu")
			(hatch none 0.5)
			(connect_pads
				(clearance 0)
			)
			(min_thickness 0.25)
			(keepout
				(tracks allowed)
				(vias not_allowed)
				(pads allowed)
				(copperpour not_allowed)
				(footprints allowed)
			)
			(placement
				(enabled no)
				(sheetname "")
			)
			(fill
				(thermal_gap 0.5)
				(thermal_bridge_width 0.5)
				(island_removal_mode 0)
			)
			(polygon
				(pts
					(arc
						(start 224.00641 -63.999872)
						(mid 223.19361 -63.999872)
						(end 224.00641 -63.999872)
					)
				)
			)
		)
		(zone
			(layer "F.Cu")
			(hatch none 0.5)
			(connect_pads
				(clearance 0)
			)
			(min_thickness 0.25)
			(keepout
				(tracks allowed)
				(vias not_allowed)
				(pads allowed)
				(copperpour not_allowed)
				(footprints allowed)
			)
			(placement
				(enabled no)
				(sheetname "")
			)
			(fill
				(thermal_gap 0.5)
				(thermal_bridge_width 0.5)
				(island_removal_mode 0)
			)
			(polygon
				(pts
					(arc
						(start 224.00641 -31.999936)
						(mid 223.19361 -31.999936)
						(end 224.00641 -31.999936)
					)
				)
			)
		)
		(zone
			(layer "F.Cu")
			(hatch none 0.5)
			(connect_pads
				(clearance 0)
			)
			(min_thickness 0.25)
			(keepout
				(tracks allowed)
				(vias not_allowed)
				(pads allowed)
				(copperpour not_allowed)
				(footprints allowed)
			)
			(placement
				(enabled no)
				(sheetname "")
			)
			(fill
				(thermal_gap 0.5)
				(thermal_bridge_width 0.5)
				(island_removal_mode 0)
			)
			(polygon
				(pts
					(arc
						(start 224.00641 -30.999938)
						(mid 223.19361 -30.999938)
						(end 224.00641 -30.999938)
					)
				)
			)
		)
		(zone
			(layer "F.Cu")
			(hatch none 0.5)
			(connect_pads
				(clearance 0)
			)
			(min_thickness 0.25)
			(keepout
				(tracks allowed)
				(vias not_allowed)
				(pads allowed)
				(copperpour not_allowed)
				(footprints allowed)
			)
			(placement
				(enabled no)
				(sheetname "")
			)
			(fill
				(thermal_gap 0.5)
				(thermal_bridge_width 0.5)
				(island_removal_mode 0)
			)
			(polygon
				(pts
					(arc
						(start 224.00641 -29.99994)
						(mid 223.19361 -29.99994)
						(end 224.00641 -29.99994)
					)
				)
			)
		)
		(zone
			(layer "F.Cu")
			(hatch none 0.5)
			(connect_pads
				(clearance 0)
			)
			(min_thickness 0.25)
			(keepout
				(tracks allowed)
				(vias not_allowed)
				(pads allowed)
				(copperpour not_allowed)
				(footprints allowed)
			)
			(placement
				(enabled no)
				(sheetname "")
			)
			(fill
				(thermal_gap 0.5)
				(thermal_bridge_width 0.5)
				(island_removal_mode 0)
			)
			(polygon
				(pts
					(arc
						(start 225.006408 -64.99987)
						(mid 224.193608 -64.99987)
						(end 225.006408 -64.99987)
					)
				)
			)
		)
		(zone
			(layer "F.Cu")
			(hatch none 0.5)
			(connect_pads
				(clearance 0)
			)
			(min_thickness 0.25)
			(keepout
				(tracks allowed)
				(vias not_allowed)
				(pads allowed)
				(copperpour not_allowed)
				(footprints allowed)
			)
			(placement
				(enabled no)
				(sheetname "")
			)
			(fill
				(thermal_gap 0.5)
				(thermal_bridge_width 0.5)
				(island_removal_mode 0)
			)
			(polygon
				(pts
					(arc
						(start 225.006408 -63.999872)
						(mid 224.193608 -63.999872)
						(end 225.006408 -63.999872)
					)
				)
			)
		)
		(zone
			(layer "F.Cu")
			(hatch none 0.5)
			(connect_pads
				(clearance 0)
			)
			(min_thickness 0.25)
			(keepout
				(tracks allowed)
				(vias not_allowed)
				(pads allowed)
				(copperpour not_allowed)
				(footprints allowed)
			)
			(placement
				(enabled no)
				(sheetname "")
			)
			(fill
				(thermal_gap 0.5)
				(thermal_bridge_width 0.5)
				(island_removal_mode 0)
			)
			(polygon
				(pts
					(arc
						(start 225.006408 -31.999936)
						(mid 224.193608 -31.999936)
						(end 225.006408 -31.999936)
					)
				)
			)
		)
		(zone
			(layer "F.Cu")
			(hatch none 0.5)
			(connect_pads
				(clearance 0)
			)
			(min_thickness 0.25)
			(keepout
				(tracks allowed)
				(vias not_allowed)
				(pads allowed)
				(copperpour not_allowed)
				(footprints allowed)
			)
			(placement
				(enabled no)
				(sheetname "")
			)
			(fill
				(thermal_gap 0.5)
				(thermal_bridge_width 0.5)
				(island_removal_mode 0)
			)
			(polygon
				(pts
					(arc
						(start 225.006408 -30.999938)
						(mid 224.193608 -30.999938)
						(end 225.006408 -30.999938)
					)
				)
			)
		)
		(zone
			(layer "F.Cu")
			(hatch none 0.5)
			(connect_pads
				(clearance 0)
			)
			(min_thickness 0.25)
			(keepout
				(tracks allowed)
				(vias not_allowed)
				(pads allowed)
				(copperpour not_allowed)
				(footprints allowed)
			)
			(placement
				(enabled no)
				(sheetname "")
			)
			(fill
				(thermal_gap 0.5)
				(thermal_bridge_width 0.5)
				(island_removal_mode 0)
			)
			(polygon
				(pts
					(arc
						(start 257.006344 -64.99987)
						(mid 256.193544 -64.99987)
						(end 257.006344 -64.99987)
					)
				)
			)
		)
		(zone
			(layer "F.Cu")
			(hatch none 0.5)
			(connect_pads
				(clearance 0)
			)
			(min_thickness 0.25)
			(keepout
				(tracks allowed)
				(vias not_allowed)
				(pads allowed)
				(copperpour not_allowed)
				(footprints allowed)
			)
			(placement
				(enabled no)
				(sheetname "")
			)
			(fill
				(thermal_gap 0.5)
				(thermal_bridge_width 0.5)
				(island_removal_mode 0)
			)
			(polygon
				(pts
					(arc
						(start 257.006344 -63.999872)
						(mid 256.193544 -63.999872)
						(end 257.006344 -63.999872)
					)
				)
			)
		)
		(zone
			(layer "F.Cu")
			(hatch none 0.5)
			(connect_pads
				(clearance 0)
			)
			(min_thickness 0.25)
			(keepout
				(tracks allowed)
				(vias not_allowed)
				(pads allowed)
				(copperpour not_allowed)
				(footprints allowed)
			)
			(placement
				(enabled no)
				(sheetname "")
			)
			(fill
				(thermal_gap 0.5)
				(thermal_bridge_width 0.5)
				(island_removal_mode 0)
			)
			(polygon
				(pts
					(arc
						(start 257.006344 -31.999936)
						(mid 256.193544 -31.999936)
						(end 257.006344 -31.999936)
					)
				)
			)
		)
		(zone
			(layer "F.Cu")
			(hatch none 0.5)
			(connect_pads
				(clearance 0)
			)
			(min_thickness 0.25)
			(keepout
				(tracks allowed)
				(vias not_allowed)
				(pads allowed)
				(copperpour not_allowed)
				(footprints allowed)
			)
			(placement
				(enabled no)
				(sheetname "")
			)
			(fill
				(thermal_gap 0.5)
				(thermal_bridge_width 0.5)
				(island_removal_mode 0)
			)
			(polygon
				(pts
					(arc
						(start 257.006344 -30.999938)
						(mid 256.193544 -30.999938)
						(end 257.006344 -30.999938)
					)
				)
			)
		)
		(zone
			(layer "F.Cu")
			(hatch none 0.5)
			(connect_pads
				(clearance 0)
			)
			(min_thickness 0.25)
			(keepout
				(tracks allowed)
				(vias not_allowed)
				(pads allowed)
				(copperpour not_allowed)
				(footprints allowed)
			)
			(placement
				(enabled no)
				(sheetname "")
			)
			(fill
				(thermal_gap 0.5)
				(thermal_bridge_width 0.5)
				(island_removal_mode 0)
			)
			(polygon
				(pts
					(arc
						(start 258.006342 -65.999868)
						(mid 257.193542 -65.999868)
						(end 258.006342 -65.999868)
					)
				)
			)
		)
		(zone
			(layer "F.Cu")
			(hatch none 0.5)
			(connect_pads
				(clearance 0)
			)
			(min_thickness 0.25)
			(keepout
				(tracks allowed)
				(vias not_allowed)
				(pads allowed)
				(copperpour not_allowed)
				(footprints allowed)
			)
			(placement
				(enabled no)
				(sheetname "")
			)
			(fill
				(thermal_gap 0.5)
				(thermal_bridge_width 0.5)
				(island_removal_mode 0)
			)
			(polygon
				(pts
					(arc
						(start 258.006342 -64.99987)
						(mid 257.193542 -64.99987)
						(end 258.006342 -64.99987)
					)
				)
			)
		)
		(zone
			(layer "F.Cu")
			(hatch none 0.5)
			(connect_pads
				(clearance 0)
			)
			(min_thickness 0.25)
			(keepout
				(tracks allowed)
				(vias not_allowed)
				(pads allowed)
				(copperpour not_allowed)
				(footprints allowed)
			)
			(placement
				(enabled no)
				(sheetname "")
			)
			(fill
				(thermal_gap 0.5)
				(thermal_bridge_width 0.5)
				(island_removal_mode 0)
			)
			(polygon
				(pts
					(arc
						(start 258.006342 -63.999872)
						(mid 257.193542 -63.999872)
						(end 258.006342 -63.999872)
					)
				)
			)
		)
		(zone
			(layer "F.Cu")
			(hatch none 0.5)
			(connect_pads
				(clearance 0)
			)
			(min_thickness 0.25)
			(keepout
				(tracks allowed)
				(vias not_allowed)
				(pads allowed)
				(copperpour not_allowed)
				(footprints allowed)
			)
			(placement
				(enabled no)
				(sheetname "")
			)
			(fill
				(thermal_gap 0.5)
				(thermal_bridge_width 0.5)
				(island_removal_mode 0)
			)
			(polygon
				(pts
					(arc
						(start 258.006342 -31.999936)
						(mid 257.193542 -31.999936)
						(end 258.006342 -31.999936)
					)
				)
			)
		)
		(zone
			(layer "F.Cu")
			(hatch none 0.5)
			(connect_pads
				(clearance 0)
			)
			(min_thickness 0.25)
			(keepout
				(tracks allowed)
				(vias not_allowed)
				(pads allowed)
				(copperpour not_allowed)
				(footprints allowed)
			)
			(placement
				(enabled no)
				(sheetname "")
			)
			(fill
				(thermal_gap 0.5)
				(thermal_bridge_width 0.5)
				(island_removal_mode 0)
			)
			(polygon
				(pts
					(arc
						(start 258.006342 -30.999938)
						(mid 257.193542 -30.999938)
						(end 258.006342 -30.999938)
					)
				)
			)
		)
		(zone
			(layer "F.Cu")
			(hatch none 0.5)
			(connect_pads
				(clearance 0)
			)
			(min_thickness 0.25)
			(keepout
				(tracks allowed)
				(vias not_allowed)
				(pads allowed)
				(copperpour not_allowed)
				(footprints allowed)
			)
			(placement
				(enabled no)
				(sheetname "")
			)
			(fill
				(thermal_gap 0.5)
				(thermal_bridge_width 0.5)
				(island_removal_mode 0)
			)
			(polygon
				(pts
					(arc
						(start 258.006342 -29.99994)
						(mid 257.193542 -29.99994)
						(end 258.006342 -29.99994)
					)
				)
			)
		)
		(zone
			(layer "F.Cu")
			(hatch none 0.5)
			(connect_pads
				(clearance 0)
			)
			(min_thickness 0.25)
			(keepout
				(tracks allowed)
				(vias not_allowed)
				(pads allowed)
				(copperpour not_allowed)
				(footprints allowed)
			)
			(placement
				(enabled no)
				(sheetname "")
			)
			(fill
				(thermal_gap 0.5)
				(thermal_bridge_width 0.5)
				(island_removal_mode 0)
			)
			(polygon
				(pts
					(arc
						(start 259.00634 -64.99987)
						(mid 258.19354 -64.99987)
						(end 259.00634 -64.99987)
					)
				)
			)
		)
		(zone
			(layer "F.Cu")
			(hatch none 0.5)
			(connect_pads
				(clearance 0)
			)
			(min_thickness 0.25)
			(keepout
				(tracks allowed)
				(vias not_allowed)
				(pads allowed)
				(copperpour not_allowed)
				(footprints allowed)
			)
			(placement
				(enabled no)
				(sheetname "")
			)
			(fill
				(thermal_gap 0.5)
				(thermal_bridge_width 0.5)
				(island_removal_mode 0)
			)
			(polygon
				(pts
					(arc
						(start 259.00634 -63.999872)
						(mid 258.19354 -63.999872)
						(end 259.00634 -63.999872)
					)
				)
			)
		)
		(zone
			(layer "F.Cu")
			(hatch none 0.5)
			(connect_pads
				(clearance 0)
			)
			(min_thickness 0.25)
			(keepout
				(tracks allowed)
				(vias not_allowed)
				(pads allowed)
				(copperpour not_allowed)
				(footprints allowed)
			)
			(placement
				(enabled no)
				(sheetname "")
			)
			(fill
				(thermal_gap 0.5)
				(thermal_bridge_width 0.5)
				(island_removal_mode 0)
			)
			(polygon
				(pts
					(arc
						(start 259.00634 -31.999936)
						(mid 258.19354 -31.999936)
						(end 259.00634 -31.999936)
					)
				)
			)
		)
		(zone
			(layer "F.Cu")
			(hatch none 0.5)
			(connect_pads
				(clearance 0)
			)
			(min_thickness 0.25)
			(keepout
				(tracks allowed)
				(vias not_allowed)
				(pads allowed)
				(copperpour not_allowed)
				(footprints allowed)
			)
			(placement
				(enabled no)
				(sheetname "")
			)
			(fill
				(thermal_gap 0.5)
				(thermal_bridge_width 0.5)
				(island_removal_mode 0)
			)
			(polygon
				(pts
					(arc
						(start 259.00634 -30.999938)
						(mid 258.19354 -30.999938)
						(end 259.00634 -30.999938)
					)
				)
			)
		)
	)
	(footprint ""
		(layer "F.Cu")
		(at 59.817 -119.126)
		(property "Reference" "G1"
			(at 0 0 0)
			(layer "F.SilkS")
			(hide yes)
			(effects
				(font
					(size 1.27 1.27)
				)
			)
		)
		(property "Value" "TPAD-JTAG-7P-GP"
			(at 0.0762 -11.5062 0)
			(unlocked yes)
			(layer "F.Fab")
			(hide yes)
			(effects
				(font
					(size 1.016 1.016)
					(thickness 0.1524)
				)
			)
		)
		(property "Device Type" "TPAD-JTAG-7P"
			(at 0.0762 -13.4112 0)
			(unlocked yes)
			(layer "F.Fab")
			(hide yes)
			(effects
				(font
					(size 1.016 1.016)
					(thickness 0.1524)
				)
			)
		)
		(duplicate_pad_numbers_are_jumpers no)
		(fp_line
			(start -1.0922 -8.4836)
			(end 1.0922 -8.4836)
			(stroke
				(width 0.1524)
				(type default)
			)
			(layer "F.SilkS")
		)
		(fp_line
			(start -1.0922 8.4836)
			(end -1.0922 -8.4836)
			(stroke
				(width 0.1524)
				(type default)
			)
			(layer "F.SilkS")
		)
		(fp_line
			(start 1.0922 -8.4836)
			(end 1.0922 8.4836)
			(stroke
				(width 0.1524)
				(type default)
			)
			(layer "F.SilkS")
		)
		(fp_line
			(start 1.0922 8.4836)
			(end -1.0922 8.4836)
			(stroke
				(width 0.1524)
				(type default)
			)
			(layer "F.SilkS")
		)
		(fp_rect
			(start -1.1684 8.5598)
			(end 1.1684 -8.5598)
			(stroke
				(width 0)
				(type default)
			)
			(fill no)
			(layer "F.CrtYd")
		)
		(fp_poly
			(pts
				(xy -1.3462 -8.7376) (xy 1.3462 -8.7376) (xy 1.3462 8.7376) (xy -1.3462 8.7376)
			)
			(stroke
				(width 0)
				(type default)
			)
			(fill no)
			(layer "F.Fab")
		)
		(pad "1" smd rect
			(at 0 -7.62)
			(size 1.4986 0.9906)
			(layers "F.Cu" "F.Mask" "F.Paste")
			(net "JTAG_BMC_TRST_N")
		)
		(pad "2" smd rect
			(at 0 -5.08)
			(size 1.4986 0.9906)
			(layers "F.Cu" "F.Mask" "F.Paste")
			(net "JTAG_BMC_TDI")
		)
		(pad "3" smd rect
			(at 0 -2.54)
			(size 1.4986 0.9906)
			(layers "F.Cu" "F.Mask" "F.Paste")
			(net "JTAG_BMC_TMS")
		)
		(pad "4" smd rect
			(at 0 0)
			(size 1.4986 0.9906)
			(layers "F.Cu" "F.Mask" "F.Paste")
			(net "JTAG_BMC_TCK")
		)
		(pad "5" smd rect
			(at 0 2.54)
			(size 1.4986 0.9906)
			(layers "F.Cu" "F.Mask" "F.Paste")
			(net "BMC0_JTAG_RTCK")
		)
		(pad "6" smd rect
			(at 0 5.08)
			(size 1.4986 0.9906)
			(layers "F.Cu" "F.Mask" "F.Paste")
			(net "JTAG_BMC_TDO")
		)
		(pad "7" smd rect
			(at 0 7.62)
			(size 1.4986 0.9906)
			(layers "F.Cu" "F.Mask" "F.Paste")
			(net "FM_BMC_RESET_N")
		)
	)
	(footprint ""
		(layer "F.Cu")
		(at 214.948008 -4.064)
		(property "Reference" "R675"
			(at 0 0 0)
			(layer "F.SilkS")
			(hide yes)
			(effects
				(font
					(size 1.27 1.27)
				)
			)
		)
		(property "Value" "100KR2F-L1-GP"
			(at 0.064008 -3.993896 0)
			(unlocked yes)
			(layer "F.Fab")
			(hide yes)
			(effects
				(font
					(size 1.016 1.016)
					(thickness 0.1524)
				)
			)
		)
		(property "Device Type" "R402H16"
			(at 0.064008 -5.517896 0)
			(unlocked yes)
			(layer "F.Fab")
			(hide yes)
			(effects
				(font
					(size 1.016 1.016)
					(thickness 0.1524)
				)
			)
		)
		(duplicate_pad_numbers_are_jumpers no)
		(fp_line
			(start -0.508 -0.9398)
			(end -0.508 0.9398)
			(stroke
				(width 0.1524)
				(type default)
			)
			(layer "F.SilkS")
		)
		(fp_line
			(start 0.508 -0.9398)
			(end -0.508 -0.9398)
			(stroke
				(width 0.1524)
				(type default)
			)
			(layer "F.SilkS")
		)
		(fp_rect
			(start -0.508 0.9398)
			(end 0.508 -0.9398)
			(stroke
				(width 0)
				(type default)
			)
			(fill no)
			(layer "F.CrtYd")
		)
		(fp_rect
			(start -0.508 0.9398)
			(end 0.508 -0.9398)
			(stroke
				(width 0)
				(type default)
			)
			(fill no)
			(layer "F.Fab")
		)
		(pad "1" smd custom
			(at 0 -0.4445)
			(size 0.1397 0.1397)
			(layers "F.Cu" "F.Mask" "F.Paste")
			(net "HOST2_RST_N")
			(options
				(clearance outline)
				(anchor circle)
			)
			(primitives
				(gr_poly
					(pts
						(arc
							(start -0.1778 -0.2794)
							(mid -0.249642 -0.249642)
							(end -0.2794 -0.1778)
						)
						(arc
							(start -0.2794 0.1778)
							(mid -0.249642 0.249642)
							(end -0.1778 0.2794)
						)
						(arc
							(start 0.1778 0.2794)
							(mid 0.249642 0.249642)
							(end 0.2794 0.1778)
						)
						(arc
							(start 0.2794 -0.1778)
							(mid 0.249642 -0.249642)
							(end 0.1778 -0.2794)
						)
					)
					(width 0)
					(fill yes)
				)
			)
		)
		(pad "2" smd custom
			(at 0 0.4445)
			(size 0.1397 0.1397)
			(layers "F.Cu" "F.Mask" "F.Paste")
			(net "GND")
			(options
				(clearance outline)
				(anchor circle)
			)
			(primitives
				(gr_poly
					(pts
						(arc
							(start -0.1778 -0.2794)
							(mid -0.249642 -0.249642)
							(end -0.2794 -0.1778)
						)
						(arc
							(start -0.2794 0.1778)
							(mid -0.249642 0.249642)
							(end -0.1778 0.2794)
						)
						(arc
							(start 0.1778 0.2794)
							(mid 0.249642 0.249642)
							(end 0.2794 0.1778)
						)
						(arc
							(start 0.2794 -0.1778)
							(mid 0.249642 -0.249642)
							(end 0.1778 -0.2794)
						)
					)
					(width 0)
					(fill yes)
				)
			)
		)
	)
	(footprint ""
		(layer "F.Cu")
		(at 140.8176 -86.6394)
		(property "Reference" "PC92"
			(at 0 0 0)
			(layer "F.SilkS")
			(hide yes)
			(effects
				(font
					(size 1.27 1.27)
				)
			)
		)
		(property "Value" "SC820P50V2KX-1GP"
			(at 1.1811 -2.7051 0)
			(unlocked yes)
			(layer "F.Fab")
			(hide yes)
			(effects
				(font
					(size 1.016 1.016)
					(thickness 0.1524)
				)
			)
		)
		(property "Device Type" "C402H22"
			(at 1.1811 -4.2291 0)
			(unlocked yes)
			(layer "F.Fab")
			(hide yes)
			(effects
				(font
					(size 1.016 1.016)
					(thickness 0.1524)
				)
			)
		)
		(duplicate_pad_numbers_are_jumpers no)
		(fp_rect
			(start -0.4318 0.9525)
			(end 0.4318 -0.9525)
			(stroke
				(width 0)
				(type default)
			)
			(fill no)
			(layer "F.CrtYd")
		)
		(fp_rect
			(start -0.4318 0.9525)
			(end 0.4318 -0.9525)
			(stroke
				(width 0)
				(type default)
			)
			(fill no)
			(layer "F.Fab")
		)
		(pad "1" smd custom
			(at 0 -0.4445)
			(size 0.1524 0.1524)
			(layers "F.Cu" "F.Mask" "F.Paste")
			(net "VR_P1V8_STBY_SS_C")
			(options
				(clearance outline)
				(anchor circle)
			)
			(primitives
				(gr_poly
					(pts
						(arc
							(start 0.3048 -0.2032)
							(mid 0.275042 -0.275042)
							(end 0.2032 -0.3048)
						)
						(arc
							(start -0.2032 -0.3048)
							(mid -0.275042 -0.275042)
							(end -0.3048 -0.2032)
						)
						(arc
							(start -0.3048 0.2032)
							(mid -0.275042 0.275042)
							(end -0.2032 0.3048)
						)
						(arc
							(start 0.2032 0.3048)
							(mid 0.275042 0.275042)
							(end 0.3048 0.2032)
						)
					)
					(width 0)
					(fill yes)
				)
			)
		)
		(pad "2" smd custom
			(at 0 0.4445)
			(size 0.1524 0.1524)
			(layers "F.Cu" "F.Mask" "F.Paste")
			(net "GND")
			(options
				(clearance outline)
				(anchor circle)
			)
			(primitives
				(gr_poly
					(pts
						(arc
							(start 0.3048 -0.2032)
							(mid 0.275042 -0.275042)
							(end 0.2032 -0.3048)
						)
						(arc
							(start -0.2032 -0.3048)
							(mid -0.275042 -0.275042)
							(end -0.3048 -0.2032)
						)
						(arc
							(start -0.3048 0.2032)
							(mid -0.275042 0.275042)
							(end -0.2032 0.3048)
						)
						(arc
							(start 0.2032 0.3048)
							(mid 0.275042 0.275042)
							(end 0.3048 0.2032)
						)
					)
					(width 0)
					(fill yes)
				)
			)
		)
	)
	(footprint ""
		(layer "F.Cu")
		(at 125.1204 -42.164 90)
		(property "Reference" "R932"
			(at 0 0 90)
			(layer "F.SilkS")
			(hide yes)
			(effects
				(font
					(size 1.27 1.27)
				)
			)
		)
		(property "Value" "4K7R2F-GP"
			(at 0.064008 -3.993896 90)
			(unlocked yes)
			(layer "F.Fab")
			(hide yes)
			(effects
				(font
					(size 1.016 1.016)
					(thickness 0.1524)
				)
			)
		)
		(property "Device Type" "R402H16"
			(at 0.064008 -5.517896 90)
			(unlocked yes)
			(layer "F.Fab")
			(hide yes)
			(effects
				(font
					(size 1.016 1.016)
					(thickness 0.1524)
				)
			)
		)
		(duplicate_pad_numbers_are_jumpers no)
		(fp_line
			(start 0.508 -0.9398)
			(end -0.508 -0.9398)
			(stroke
				(width 0.1524)
				(type default)
			)
			(layer "F.SilkS")
		)
		(fp_line
			(start -0.508 -0.9398)
			(end -0.508 0.9398)
			(stroke
				(width 0.1524)
				(type default)
			)
			(layer "F.SilkS")
		)
		(fp_rect
			(start -0.508 0.9398)
			(end 0.508 -0.9398)
			(stroke
				(width 0)
				(type default)
			)
			(fill no)
			(layer "F.CrtYd")
		)
		(fp_rect
			(start -0.508 0.9398)
			(end 0.508 -0.9398)
			(stroke
				(width 0)
				(type default)
			)
			(fill no)
			(layer "F.Fab")
		)
		(pad "1" smd custom
			(at 0 -0.4445 90)
			(size 0.1397 0.1397)
			(layers "F.Cu" "F.Mask" "F.Paste")
			(net "BMC_ADD1_GND")
			(options
				(clearance outline)
				(anchor circle)
			)
			(primitives
				(gr_poly
					(pts
						(arc
							(start -0.1778 -0.2794)
							(mid -0.249642 -0.249642)
							(end -0.2794 -0.1778)
						)
						(arc
							(start -0.2794 0.1778)
							(mid -0.249642 0.249642)
							(end -0.1778 0.2794)
						)
						(arc
							(start 0.1778 0.2794)
							(mid 0.249642 0.249642)
							(end 0.2794 0.1778)
						)
						(arc
							(start 0.2794 -0.1778)
							(mid 0.249642 -0.249642)
							(end 0.1778 -0.2794)
						)
					)
					(width 0)
					(fill yes)
				)
			)
		)
		(pad "2" smd custom
			(at 0 0.4445 90)
			(size 0.1397 0.1397)
			(layers "F.Cu" "F.Mask" "F.Paste")
			(net "GND")
			(options
				(clearance outline)
				(anchor circle)
			)
			(primitives
				(gr_poly
					(pts
						(arc
							(start -0.1778 -0.2794)
							(mid -0.249642 -0.249642)
							(end -0.2794 -0.1778)
						)
						(arc
							(start -0.2794 0.1778)
							(mid -0.249642 0.249642)
							(end -0.1778 0.2794)
						)
						(arc
							(start 0.1778 0.2794)
							(mid 0.249642 0.249642)
							(end 0.2794 0.1778)
						)
						(arc
							(start 0.2794 -0.1778)
							(mid 0.249642 -0.249642)
							(end 0.1778 -0.2794)
						)
					)
					(width 0)
					(fill yes)
				)
			)
		)
	)
	(footprint ""
		(layer "F.Cu")
		(at 51.816 -200.914)
		(property "Reference" "R894"
			(at 0 0 0)
			(layer "F.SilkS")
			(hide yes)
			(effects
				(font
					(size 1.27 1.27)
				)
			)
		)
		(property "Value" "0R2J-2-GP"
			(at 0.064008 -3.993896 0)
			(unlocked yes)
			(layer "F.Fab")
			(hide yes)
			(effects
				(font
					(size 1.016 1.016)
					(thickness 0.1524)
				)
			)
		)
		(property "Device Type" "R402H16"
			(at 0.064008 -5.517896 0)
			(unlocked yes)
			(layer "F.Fab")
			(hide yes)
			(effects
				(font
					(size 1.016 1.016)
					(thickness 0.1524)
				)
			)
		)
		(duplicate_pad_numbers_are_jumpers no)
		(fp_line
			(start -0.508 -0.9398)
			(end -0.508 0.9398)
			(stroke
				(width 0.1524)
				(type default)
			)
			(layer "F.SilkS")
		)
		(fp_line
			(start 0.508 -0.9398)
			(end -0.508 -0.9398)
			(stroke
				(width 0.1524)
				(type default)
			)
			(layer "F.SilkS")
		)
		(fp_rect
			(start -0.508 0.9398)
			(end 0.508 -0.9398)
			(stroke
				(width 0)
				(type default)
			)
			(fill no)
			(layer "F.CrtYd")
		)
		(fp_rect
			(start -0.508 0.9398)
			(end 0.508 -0.9398)
			(stroke
				(width 0)
				(type default)
			)
			(fill no)
			(layer "F.Fab")
		)
		(pad "1" smd custom
			(at 0 -0.4445)
			(size 0.1397 0.1397)
			(layers "F.Cu" "F.Mask" "F.Paste")
			(net "BUF_I2C7_B_DBP_SCL")
			(options
				(clearance outline)
				(anchor circle)
			)
			(primitives
				(gr_poly
					(pts
						(arc
							(start -0.1778 -0.2794)
							(mid -0.249642 -0.249642)
							(end -0.2794 -0.1778)
						)
						(arc
							(start -0.2794 0.1778)
							(mid -0.249642 0.249642)
							(end -0.1778 0.2794)
						)
						(arc
							(start 0.1778 0.2794)
							(mid 0.249642 0.249642)
							(end 0.2794 0.1778)
						)
						(arc
							(start 0.2794 -0.1778)
							(mid 0.249642 -0.249642)
							(end 0.1778 -0.2794)
						)
					)
					(width 0)
					(fill yes)
				)
			)
		)
		(pad "2" smd custom
			(at 0 0.4445)
			(size 0.1397 0.1397)
			(layers "F.Cu" "F.Mask" "F.Paste")
			(net "BUF_I2C7_B_DBP_SCL_R")
			(options
				(clearance outline)
				(anchor circle)
			)
			(primitives
				(gr_poly
					(pts
						(arc
							(start -0.1778 -0.2794)
							(mid -0.249642 -0.249642)
							(end -0.2794 -0.1778)
						)
						(arc
							(start -0.2794 0.1778)
							(mid -0.249642 0.249642)
							(end -0.1778 0.2794)
						)
						(arc
							(start 0.1778 0.2794)
							(mid 0.249642 0.249642)
							(end 0.2794 0.1778)
						)
						(arc
							(start 0.2794 -0.1778)
							(mid 0.249642 -0.249642)
							(end 0.1778 -0.2794)
						)
					)
					(width 0)
					(fill yes)
				)
			)
		)
	)
	(footprint ""
		(layer "F.Cu")
		(at 65.8622 -161.5186 -90)
		(property "Reference" "PU4"
			(at 0 0 270)
			(layer "F.SilkS")
			(hide yes)
			(effects
				(font
					(size 1.27 1.27)
				)
			)
		)
		(property "Value" "TPS74801DRCR-1-GP-U"
			(at -3.5306 1.3208 270)
			(unlocked yes)
			(layer "F.Fab")
			(hide yes)
			(effects
				(font
					(size 1.016 1.016)
					(thickness 0.1524)
				)
			)
		)
		(property "Device Type" "DFN10G3-G315175H40"
			(at -3.5306 -0.2032 270)
			(unlocked yes)
			(layer "F.Fab")
			(hide yes)
			(effects
				(font
					(size 1.016 1.016)
					(thickness 0.1524)
				)
			)
		)
		(duplicate_pad_numbers_are_jumpers no)
		(fp_line
			(start -2.3876 2.5146)
			(end -1.6256 2.5146)
			(stroke
				(width 0.1524)
				(type default)
			)
			(layer "F.SilkS")
		)
		(fp_line
			(start 1.6256 2.5146)
			(end 2.3876 2.5146)
			(stroke
				(width 0.1524)
				(type default)
			)
			(layer "F.SilkS")
		)
		(fp_line
			(start 2.3876 2.5146)
			(end 2.3876 1.7526)
			(stroke
				(width 0.1524)
				(type default)
			)
			(layer "F.SilkS")
		)
		(fp_line
			(start 0.9906 2.286)
			(end 0.9906 3.048)
			(stroke
				(width 0.1524)
				(type default)
			)
			(layer "F.SilkS")
		)
		(fp_line
			(start -2.3876 1.7526)
			(end -2.3876 2.5146)
			(stroke
				(width 0.1524)
				(type default)
			)
			(layer "F.SilkS")
		)
		(fp_line
			(start -2.3876 -2.5146)
			(end -2.3876 -1.7526)
			(stroke
				(width 0.1524)
				(type default)
			)
			(layer "F.SilkS")
		)
		(fp_line
			(start -1.6256 -2.5146)
			(end -2.3876 -2.5146)
			(stroke
				(width 0.1524)
				(type default)
			)
			(layer "F.SilkS")
		)
		(fp_line
			(start -0.9906 -2.794)
			(end -0.9906 -2.286)
			(stroke
				(width 0.1524)
				(type default)
			)
			(layer "F.SilkS")
		)
		(fp_poly
			(pts
				(xy 1.6256 -2.5146) (xy 2.3876 -2.5146) (xy 2.3876 -1.7526)
			)
			(stroke
				(width 0)
				(type default)
			)
			(fill yes)
			(layer "F.SilkS")
		)
		(fp_rect
			(start -1.4986 1.4986)
			(end 1.4986 -1.4986)
			(stroke
				(width 0)
				(type default)
			)
			(fill no)
			(layer "F.CrtYd")
		)
		(fp_poly
			(pts
				(xy -2.3876 2.5146) (xy -2.3876 0.00254) (xy -1.4986 0.00254) (xy -1.4986 1.4986) (xy 1.4986 1.4986)
				(xy 1.4986 -1.4986) (xy -1.4986 -1.4986) (xy -1.4986 -0.00254) (xy -2.3876 -0.00254) (xy -2.3876 -2.5146)
				(xy 2.3876 -2.5146) (xy 2.3876 2.5146)
			)
			(stroke
				(width 0)
				(type default)
			)
			(fill no)
			(layer "F.CrtYd")
		)
		(fp_rect
			(start -2.3876 2.5146)
			(end 2.3876 -2.5146)
			(stroke
				(width 0)
				(type default)
			)
			(fill no)
			(layer "F.Fab")
		)
		(pad "1" smd rect
			(at 0.99949 -1.5494 270)
			(size 0.3048 0.9144)
			(layers "F.Cu" "F.Mask" "F.Paste")
			(net "VR_P1V538_STBY_IN")
		)
		(pad "2" smd rect
			(at 0.50038 -1.5494 270)
			(size 0.3048 0.9144)
			(layers "F.Cu" "F.Mask" "F.Paste")
			(net "VR_P1V538_STBY_IN")
		)
		(pad "3" smd rect
			(at 0 -1.5494 270)
			(size 0.3048 0.9144)
			(layers "F.Cu" "F.Mask" "F.Paste")
			(net "PWRGD_P1V538_STBY")
		)
		(pad "4" smd rect
			(at -0.50038 -1.5494 270)
			(size 0.3048 0.9144)
			(layers "F.Cu" "F.Mask" "F.Paste")
			(net "VR_P1V538_STBY_BIAS")
		)
		(pad "5" smd rect
			(at -0.99949 -1.5494 270)
			(size 0.3048 0.9144)
			(layers "F.Cu" "F.Mask" "F.Paste")
			(net "VR_P1V538_STBY_EN_R")
		)
		(pad "6" smd rect
			(at -0.99949 1.5494 270)
			(size 0.3048 0.9144)
			(layers "F.Cu" "F.Mask" "F.Paste")
			(net "GND")
		)
		(pad "7" smd rect
			(at -0.50038 1.5494 270)
			(size 0.3048 0.9144)
			(layers "F.Cu" "F.Mask" "F.Paste")
			(net "VR_P1V538_STBY_SS_C")
		)
		(pad "8" smd rect
			(at 0 1.5494 270)
			(size 0.3048 0.9144)
			(layers "F.Cu" "F.Mask" "F.Paste")
			(net "VR_P1V538_STBY_FB")
		)
		(pad "9" smd rect
			(at 0.50038 1.5494 270)
			(size 0.3048 0.9144)
			(layers "F.Cu" "F.Mask" "F.Paste")
			(net "P1V53_PWR")
		)
		(pad "10" smd rect
			(at 0.99949 1.5494 270)
			(size 0.3048 0.9144)
			(layers "F.Cu" "F.Mask" "F.Paste")
			(net "P1V53_PWR")
		)
		(pad "11" smd custom
			(at 0 0 270)
			(size 0.4318 0.4318)
			(layers "F.Cu" "F.Mask" "F.Paste")
			(net "GND")
			(options
				(clearance outline)
				(anchor circle)
			)
			(primitives
				(gr_poly
					(pts
						(xy -1.2446 0.8636) (xy -1.2446 0.3937) (xy -1.8796 0.3937) (xy -1.8796 0.1143) (xy -1.2446 0.1143)
						(xy -1.2446 -0.1143) (xy -1.8796 -0.1143) (xy -1.8796 -0.3937) (xy -1.2446 -0.3937) (xy -1.2446 -0.8636)
						(xy 1.2446 -0.8636) (xy 1.2446 -0.3937) (xy 1.8796 -0.3937) (xy 1.8796 -0.1143) (xy 1.2446 -0.1143)
						(xy 1.2446 0.1143) (xy 1.8796 0.1143) (xy 1.8796 0.3937) (xy 1.2446 0.3937) (xy 1.2446 0.8636)
					)
					(width 0)
					(fill yes)
				)
			)
		)
	)
	(footprint ""
		(layer "F.Cu")
		(at 219.413582 -11.184636 90)
		(property "Reference" "R661"
			(at 0 0 90)
			(layer "F.SilkS")
			(hide yes)
			(effects
				(font
					(size 1.27 1.27)
				)
			)
		)
		(property "Value" "100KR2F-L1-GP"
			(at 0.064008 -3.993896 90)
			(unlocked yes)
			(layer "F.Fab")
			(hide yes)
			(effects
				(font
					(size 1.016 1.016)
					(thickness 0.1524)
				)
			)
		)
		(property "Device Type" "R402H16"
			(at 0.064008 -5.517896 90)
			(unlocked yes)
			(layer "F.Fab")
			(hide yes)
			(effects
				(font
					(size 1.016 1.016)
					(thickness 0.1524)
				)
			)
		)
		(duplicate_pad_numbers_are_jumpers no)
		(fp_line
			(start 0.508 -0.9398)
			(end -0.508 -0.9398)
			(stroke
				(width 0.1524)
				(type default)
			)
			(layer "F.SilkS")
		)
		(fp_line
			(start -0.508 -0.9398)
			(end -0.508 0.9398)
			(stroke
				(width 0.1524)
				(type default)
			)
			(layer "F.SilkS")
		)
		(fp_rect
			(start -0.508 0.9398)
			(end 0.508 -0.9398)
			(stroke
				(width 0)
				(type default)
			)
			(fill no)
			(layer "F.CrtYd")
		)
		(fp_rect
			(start -0.508 0.9398)
			(end 0.508 -0.9398)
			(stroke
				(width 0)
				(type default)
			)
			(fill no)
			(layer "F.Fab")
		)
		(pad "1" smd custom
			(at 0 -0.4445 90)
			(size 0.1397 0.1397)
			(layers "F.Cu" "F.Mask" "F.Paste")
			(net "P3V3_STBY")
			(options
				(clearance outline)
				(anchor circle)
			)
			(primitives
				(gr_poly
					(pts
						(arc
							(start -0.1778 -0.2794)
							(mid -0.249642 -0.249642)
							(end -0.2794 -0.1778)
						)
						(arc
							(start -0.2794 0.1778)
							(mid -0.249642 0.249642)
							(end -0.1778 0.2794)
						)
						(arc
							(start 0.1778 0.2794)
							(mid 0.249642 0.249642)
							(end 0.2794 0.1778)
						)
						(arc
							(start 0.2794 -0.1778)
							(mid 0.249642 -0.249642)
							(end 0.1778 -0.2794)
						)
					)
					(width 0)
					(fill yes)
				)
			)
		)
		(pad "2" smd custom
			(at 0 0.4445 90)
			(size 0.1397 0.1397)
			(layers "F.Cu" "F.Mask" "F.Paste")
			(net "EEPROM_A0")
			(options
				(clearance outline)
				(anchor circle)
			)
			(primitives
				(gr_poly
					(pts
						(arc
							(start -0.1778 -0.2794)
							(mid -0.249642 -0.249642)
							(end -0.2794 -0.1778)
						)
						(arc
							(start -0.2794 0.1778)
							(mid -0.249642 0.249642)
							(end -0.1778 0.2794)
						)
						(arc
							(start 0.1778 0.2794)
							(mid 0.249642 0.249642)
							(end 0.2794 0.1778)
						)
						(arc
							(start 0.2794 -0.1778)
							(mid 0.249642 -0.249642)
							(end 0.1778 -0.2794)
						)
					)
					(width 0)
					(fill yes)
				)
			)
		)
	)
	(footprint ""
		(layer "F.Cu")
		(at 128.7272 -47.371 90)
		(property "Reference" "R773"
			(at 0 0 90)
			(layer "F.SilkS")
			(hide yes)
			(effects
				(font
					(size 1.27 1.27)
				)
			)
		)
		(property "Value" "1KR2F-3-GP"
			(at 0.064008 -3.993896 90)
			(unlocked yes)
			(layer "F.Fab")
			(hide yes)
			(effects
				(font
					(size 1.016 1.016)
					(thickness 0.1524)
				)
			)
		)
		(property "Device Type" "R402H16"
			(at 0.064008 -5.517896 90)
			(unlocked yes)
			(layer "F.Fab")
			(hide yes)
			(effects
				(font
					(size 1.016 1.016)
					(thickness 0.1524)
				)
			)
		)
		(duplicate_pad_numbers_are_jumpers no)
		(fp_line
			(start 0.508 -0.9398)
			(end -0.508 -0.9398)
			(stroke
				(width 0.1524)
				(type default)
			)
			(layer "F.SilkS")
		)
		(fp_line
			(start -0.508 -0.9398)
			(end -0.508 0.9398)
			(stroke
				(width 0.1524)
				(type default)
			)
			(layer "F.SilkS")
		)
		(fp_rect
			(start -0.508 0.9398)
			(end 0.508 -0.9398)
			(stroke
				(width 0)
				(type default)
			)
			(fill no)
			(layer "F.CrtYd")
		)
		(fp_rect
			(start -0.508 0.9398)
			(end 0.508 -0.9398)
			(stroke
				(width 0)
				(type default)
			)
			(fill no)
			(layer "F.Fab")
		)
		(pad "1" smd custom
			(at 0 -0.4445 90)
			(size 0.1397 0.1397)
			(layers "F.Cu" "F.Mask" "F.Paste")
			(net "EJTAG_TRSTB")
			(options
				(clearance outline)
				(anchor circle)
			)
			(primitives
				(gr_poly
					(pts
						(arc
							(start -0.1778 -0.2794)
							(mid -0.249642 -0.249642)
							(end -0.2794 -0.1778)
						)
						(arc
							(start -0.2794 0.1778)
							(mid -0.249642 0.249642)
							(end -0.1778 0.2794)
						)
						(arc
							(start 0.1778 0.2794)
							(mid 0.249642 0.249642)
							(end 0.2794 0.1778)
						)
						(arc
							(start 0.2794 -0.1778)
							(mid 0.249642 -0.249642)
							(end 0.1778 -0.2794)
						)
					)
					(width 0)
					(fill yes)
				)
			)
		)
		(pad "2" smd custom
			(at 0 0.4445 90)
			(size 0.1397 0.1397)
			(layers "F.Cu" "F.Mask" "F.Paste")
			(net "GND")
			(options
				(clearance outline)
				(anchor circle)
			)
			(primitives
				(gr_poly
					(pts
						(arc
							(start -0.1778 -0.2794)
							(mid -0.249642 -0.249642)
							(end -0.2794 -0.1778)
						)
						(arc
							(start -0.2794 0.1778)
							(mid -0.249642 0.249642)
							(end -0.1778 0.2794)
						)
						(arc
							(start 0.1778 0.2794)
							(mid 0.249642 0.249642)
							(end 0.2794 0.1778)
						)
						(arc
							(start 0.2794 -0.1778)
							(mid 0.249642 -0.249642)
							(end 0.1778 -0.2794)
						)
					)
					(width 0)
					(fill yes)
				)
			)
		)
	)
	(footprint ""
		(layer "F.Cu")
		(at 76.581 -123.2662 180)
		(property "Reference" "C281"
			(at 0 0 180)
			(layer "F.SilkS")
			(hide yes)
			(effects
				(font
					(size 1.27 1.27)
				)
			)
		)
		(property "Value" "SCD1U16V2KX-3GP"
			(at 1.1811 -2.7051 180)
			(unlocked yes)
			(layer "F.Fab")
			(hide yes)
			(effects
				(font
					(size 1.016 1.016)
					(thickness 0.1524)
				)
			)
		)
		(property "Device Type" "C402H22"
			(at 1.1811 -4.2291 180)
			(unlocked yes)
			(layer "F.Fab")
			(hide yes)
			(effects
				(font
					(size 1.016 1.016)
					(thickness 0.1524)
				)
			)
		)
		(duplicate_pad_numbers_are_jumpers no)
		(fp_rect
			(start -0.4318 0.9525)
			(end 0.4318 -0.9525)
			(stroke
				(width 0)
				(type default)
			)
			(fill no)
			(layer "F.CrtYd")
		)
		(fp_rect
			(start -0.4318 0.9525)
			(end 0.4318 -0.9525)
			(stroke
				(width 0)
				(type default)
			)
			(fill no)
			(layer "F.Fab")
		)
		(pad "1" smd custom
			(at 0 -0.4445 180)
			(size 0.1524 0.1524)
			(layers "F.Cu" "F.Mask" "F.Paste")
			(net "P3V3_STBY")
			(options
				(clearance outline)
				(anchor circle)
			)
			(primitives
				(gr_poly
					(pts
						(arc
							(start 0.3048 -0.2032)
							(mid 0.275042 -0.275042)
							(end 0.2032 -0.3048)
						)
						(arc
							(start -0.2032 -0.3048)
							(mid -0.275042 -0.275042)
							(end -0.3048 -0.2032)
						)
						(arc
							(start -0.3048 0.2032)
							(mid -0.275042 0.275042)
							(end -0.2032 0.3048)
						)
						(arc
							(start 0.2032 0.3048)
							(mid 0.275042 0.275042)
							(end 0.3048 0.2032)
						)
					)
					(width 0)
					(fill yes)
				)
			)
		)
		(pad "2" smd custom
			(at 0 0.4445 180)
			(size 0.1524 0.1524)
			(layers "F.Cu" "F.Mask" "F.Paste")
			(net "GND")
			(options
				(clearance outline)
				(anchor circle)
			)
			(primitives
				(gr_poly
					(pts
						(arc
							(start 0.3048 -0.2032)
							(mid 0.275042 -0.275042)
							(end 0.2032 -0.3048)
						)
						(arc
							(start -0.2032 -0.3048)
							(mid -0.275042 -0.275042)
							(end -0.3048 -0.2032)
						)
						(arc
							(start -0.3048 0.2032)
							(mid -0.275042 0.275042)
							(end -0.2032 0.3048)
						)
						(arc
							(start 0.2032 0.3048)
							(mid 0.275042 0.275042)
							(end 0.3048 0.2032)
						)
					)
					(width 0)
					(fill yes)
				)
			)
		)
	)
	(footprint ""
		(layer "F.Cu")
		(at 66.860166 -84.87156 90)
		(property "Reference" "R478"
			(at 0 0 90)
			(layer "F.SilkS")
			(hide yes)
			(effects
				(font
					(size 1.27 1.27)
				)
			)
		)
		(property "Value" "2MR2F-GP"
			(at 0.064008 -3.993896 90)
			(unlocked yes)
			(layer "F.Fab")
			(hide yes)
			(effects
				(font
					(size 1.016 1.016)
					(thickness 0.1524)
				)
			)
		)
		(property "Device Type" "R402H16"
			(at 0.064008 -5.517896 90)
			(unlocked yes)
			(layer "F.Fab")
			(hide yes)
			(effects
				(font
					(size 1.016 1.016)
					(thickness 0.1524)
				)
			)
		)
		(duplicate_pad_numbers_are_jumpers no)
		(fp_line
			(start 0.508 -0.9398)
			(end -0.508 -0.9398)
			(stroke
				(width 0.1524)
				(type default)
			)
			(layer "F.SilkS")
		)
		(fp_line
			(start -0.508 -0.9398)
			(end -0.508 0.9398)
			(stroke
				(width 0.1524)
				(type default)
			)
			(layer "F.SilkS")
		)
		(fp_rect
			(start -0.508 0.9398)
			(end 0.508 -0.9398)
			(stroke
				(width 0)
				(type default)
			)
			(fill no)
			(layer "F.CrtYd")
		)
		(fp_rect
			(start -0.508 0.9398)
			(end 0.508 -0.9398)
			(stroke
				(width 0)
				(type default)
			)
			(fill no)
			(layer "F.Fab")
		)
		(pad "1" smd custom
			(at 0 -0.4445 90)
			(size 0.1397 0.1397)
			(layers "F.Cu" "F.Mask" "F.Paste")
			(net "HB_OUT_BMC")
			(options
				(clearance outline)
				(anchor circle)
			)
			(primitives
				(gr_poly
					(pts
						(arc
							(start -0.1778 -0.2794)
							(mid -0.249642 -0.249642)
							(end -0.2794 -0.1778)
						)
						(arc
							(start -0.2794 0.1778)
							(mid -0.249642 0.249642)
							(end -0.1778 0.2794)
						)
						(arc
							(start 0.1778 0.2794)
							(mid 0.249642 0.249642)
							(end 0.2794 0.1778)
						)
						(arc
							(start 0.2794 -0.1778)
							(mid 0.249642 -0.249642)
							(end 0.1778 -0.2794)
						)
					)
					(width 0)
					(fill yes)
				)
			)
		)
		(pad "2" smd custom
			(at 0 0.4445 90)
			(size 0.1397 0.1397)
			(layers "F.Cu" "F.Mask" "F.Paste")
			(net "HB_A_IN")
			(options
				(clearance outline)
				(anchor circle)
			)
			(primitives
				(gr_poly
					(pts
						(arc
							(start -0.1778 -0.2794)
							(mid -0.249642 -0.249642)
							(end -0.2794 -0.1778)
						)
						(arc
							(start -0.2794 0.1778)
							(mid -0.249642 0.249642)
							(end -0.1778 0.2794)
						)
						(arc
							(start 0.1778 0.2794)
							(mid 0.249642 0.249642)
							(end 0.2794 0.1778)
						)
						(arc
							(start 0.2794 -0.1778)
							(mid 0.249642 -0.249642)
							(end 0.1778 -0.2794)
						)
					)
					(width 0)
					(fill yes)
				)
			)
		)
	)
	(footprint ""
		(layer "F.Cu")
		(at 25.4 -144.653 -90)
		(property "Reference" "R298"
			(at 0 0 270)
			(layer "F.SilkS")
			(hide yes)
			(effects
				(font
					(size 1.27 1.27)
				)
			)
		)
		(property "Value" "10R2F-L-GP"
			(at 0.064008 -3.993896 270)
			(unlocked yes)
			(layer "F.Fab")
			(hide yes)
			(effects
				(font
					(size 1.016 1.016)
					(thickness 0.1524)
				)
			)
		)
		(property "Device Type" "R402H14"
			(at 0.064008 -5.517896 270)
			(unlocked yes)
			(layer "F.Fab")
			(hide yes)
			(effects
				(font
					(size 1.016 1.016)
					(thickness 0.1524)
				)
			)
		)
		(duplicate_pad_numbers_are_jumpers no)
		(fp_line
			(start -0.508 -0.9398)
			(end -0.508 0.9398)
			(stroke
				(width 0.1524)
				(type default)
			)
			(layer "F.SilkS")
		)
		(fp_line
			(start 0.508 -0.9398)
			(end -0.508 -0.9398)
			(stroke
				(width 0.1524)
				(type default)
			)
			(layer "F.SilkS")
		)
		(fp_rect
			(start -0.508 0.9398)
			(end 0.508 -0.9398)
			(stroke
				(width 0)
				(type default)
			)
			(fill no)
			(layer "F.CrtYd")
		)
		(fp_rect
			(start -0.508 0.9398)
			(end 0.508 -0.9398)
			(stroke
				(width 0)
				(type default)
			)
			(fill no)
			(layer "F.Fab")
		)
		(pad "1" smd custom
			(at 0 -0.4445 270)
			(size 0.1397 0.1397)
			(layers "F.Cu" "F.Mask" "F.Paste")
			(net "OSC2_OUT")
			(options
				(clearance outline)
				(anchor circle)
			)
			(primitives
				(gr_poly
					(pts
						(arc
							(start -0.1778 -0.2794)
							(mid -0.249642 -0.249642)
							(end -0.2794 -0.1778)
						)
						(arc
							(start -0.2794 0.1778)
							(mid -0.249642 0.249642)
							(end -0.1778 0.2794)
						)
						(arc
							(start 0.1778 0.2794)
							(mid 0.249642 0.249642)
							(end 0.2794 0.1778)
						)
						(arc
							(start 0.2794 -0.1778)
							(mid 0.249642 -0.249642)
							(end 0.1778 -0.2794)
						)
					)
					(width 0)
					(fill yes)
				)
			)
		)
		(pad "2" smd custom
			(at 0 0.4445 270)
			(size 0.1397 0.1397)
			(layers "F.Cu" "F.Mask" "F.Paste")
			(net "OSC0_AS_CLKIN")
			(options
				(clearance outline)
				(anchor circle)
			)
			(primitives
				(gr_poly
					(pts
						(arc
							(start -0.1778 -0.2794)
							(mid -0.249642 -0.249642)
							(end -0.2794 -0.1778)
						)
						(arc
							(start -0.2794 0.1778)
							(mid -0.249642 0.249642)
							(end -0.1778 0.2794)
						)
						(arc
							(start 0.1778 0.2794)
							(mid 0.249642 0.249642)
							(end 0.2794 0.1778)
						)
						(arc
							(start 0.2794 -0.1778)
							(mid 0.249642 -0.249642)
							(end 0.1778 -0.2794)
						)
					)
					(width 0)
					(fill yes)
				)
			)
		)
	)
	(footprint ""
		(layer "F.Cu")
		(at 44.323 -143.891)
		(property "Reference" "TP240"
			(at 0 0 0)
			(layer "F.SilkS")
			(hide yes)
			(effects
				(font
					(size 1.27 1.27)
				)
			)
		)
		(property "Value" "TPAD28-2-GP"
			(at -0.0127 -1.6637 0)
			(unlocked yes)
			(layer "F.Fab")
			(hide yes)
			(effects
				(font
					(size 1.016 1.016)
					(thickness 0.1524)
				)
			)
		)
		(property "Device Type" "TPAD28"
			(at -0.0127 -3.1877 0)
			(unlocked yes)
			(layer "F.Fab")
			(hide yes)
			(effects
				(font
					(size 1.016 1.016)
					(thickness 0.1524)
				)
			)
		)
		(duplicate_pad_numbers_are_jumpers no)
		(fp_poly
			(pts
				(arc
					(start 0.3556 0)
					(mid -0.3556 0)
					(end 0.3556 0)
				)
			)
			(stroke
				(width 0)
				(type default)
			)
			(fill no)
			(layer "F.CrtYd")
		)
		(fp_poly
			(pts
				(arc
					(start 0.6096 0)
					(mid -0.6096 0)
					(end 0.6096 0)
				)
			)
			(stroke
				(width 0)
				(type default)
			)
			(fill no)
			(layer "F.Fab")
		)
		(pad "1" smd circle
			(at 0 0)
			(size 0.7112 0.7112)
			(layers "F.Cu" "F.Mask" "F.Paste")
			(net "TP_GPIOP4")
		)
	)
	(footprint ""
		(layer "F.Cu")
		(at 135.96493 -59.755532 180)
		(property "Reference" "R956"
			(at 0 0 180)
			(layer "F.SilkS")
			(hide yes)
			(effects
				(font
					(size 1.27 1.27)
				)
			)
		)
		(property "Value" "33R2J-2-GP"
			(at 0.064008 -3.993896 180)
			(unlocked yes)
			(layer "F.Fab")
			(hide yes)
			(effects
				(font
					(size 1.016 1.016)
					(thickness 0.1524)
				)
			)
		)
		(property "Device Type" "R402H16"
			(at 0.064008 -5.517896 180)
			(unlocked yes)
			(layer "F.Fab")
			(hide yes)
			(effects
				(font
					(size 1.016 1.016)
					(thickness 0.1524)
				)
			)
		)
		(duplicate_pad_numbers_are_jumpers no)
		(fp_line
			(start 0.508 -0.9398)
			(end -0.508 -0.9398)
			(stroke
				(width 0.1524)
				(type default)
			)
			(layer "F.SilkS")
		)
		(fp_line
			(start -0.508 -0.9398)
			(end -0.508 0.9398)
			(stroke
				(width 0.1524)
				(type default)
			)
			(layer "F.SilkS")
		)
		(fp_rect
			(start -0.508 0.9398)
			(end 0.508 -0.9398)
			(stroke
				(width 0)
				(type default)
			)
			(fill no)
			(layer "F.CrtYd")
		)
		(fp_rect
			(start -0.508 0.9398)
			(end 0.508 -0.9398)
			(stroke
				(width 0)
				(type default)
			)
			(fill no)
			(layer "F.Fab")
		)
		(pad "1" smd custom
			(at 0 -0.4445 180)
			(size 0.1397 0.1397)
			(layers "F.Cu" "F.Mask" "F.Paste")
			(net "SPI_DATA0_2")
			(options
				(clearance outline)
				(anchor circle)
			)
			(primitives
				(gr_poly
					(pts
						(arc
							(start -0.1778 -0.2794)
							(mid -0.249642 -0.249642)
							(end -0.2794 -0.1778)
						)
						(arc
							(start -0.2794 0.1778)
							(mid -0.249642 0.249642)
							(end -0.1778 0.2794)
						)
						(arc
							(start 0.1778 0.2794)
							(mid 0.249642 0.249642)
							(end 0.2794 0.1778)
						)
						(arc
							(start 0.2794 -0.1778)
							(mid 0.249642 -0.249642)
							(end 0.1778 -0.2794)
						)
					)
					(width 0)
					(fill yes)
				)
			)
		)
		(pad "2" smd custom
			(at 0 0.4445 180)
			(size 0.1397 0.1397)
			(layers "F.Cu" "F.Mask" "F.Paste")
			(net "SPI_DATA0_2_R")
			(options
				(clearance outline)
				(anchor circle)
			)
			(primitives
				(gr_poly
					(pts
						(arc
							(start -0.1778 -0.2794)
							(mid -0.249642 -0.249642)
							(end -0.2794 -0.1778)
						)
						(arc
							(start -0.2794 0.1778)
							(mid -0.249642 0.249642)
							(end -0.1778 0.2794)
						)
						(arc
							(start 0.1778 0.2794)
							(mid 0.249642 0.249642)
							(end 0.2794 0.1778)
						)
						(arc
							(start 0.2794 -0.1778)
							(mid 0.249642 -0.249642)
							(end 0.1778 -0.2794)
						)
					)
					(width 0)
					(fill yes)
				)
			)
		)
	)
	(footprint ""
		(layer "F.Cu")
		(at 70.993 -36.957 90)
		(property "Reference" "PR25"
			(at 0 0 90)
			(layer "F.SilkS")
			(hide yes)
			(effects
				(font
					(size 1.27 1.27)
				)
			)
		)
		(property "Value" "10KR2F-2-GP"
			(at 0.064008 -3.993896 90)
			(unlocked yes)
			(layer "F.Fab")
			(hide yes)
			(effects
				(font
					(size 1.016 1.016)
					(thickness 0.1524)
				)
			)
		)
		(property "Device Type" "R402H16"
			(at 0.064008 -5.517896 90)
			(unlocked yes)
			(layer "F.Fab")
			(hide yes)
			(effects
				(font
					(size 1.016 1.016)
					(thickness 0.1524)
				)
			)
		)
		(duplicate_pad_numbers_are_jumpers no)
		(fp_line
			(start 0.508 -0.9398)
			(end -0.508 -0.9398)
			(stroke
				(width 0.1524)
				(type default)
			)
			(layer "F.SilkS")
		)
		(fp_line
			(start -0.508 -0.9398)
			(end -0.508 0.9398)
			(stroke
				(width 0.1524)
				(type default)
			)
			(layer "F.SilkS")
		)
		(fp_rect
			(start -0.508 0.9398)
			(end 0.508 -0.9398)
			(stroke
				(width 0)
				(type default)
			)
			(fill no)
			(layer "F.CrtYd")
		)
		(fp_rect
			(start -0.508 0.9398)
			(end 0.508 -0.9398)
			(stroke
				(width 0)
				(type default)
			)
			(fill no)
			(layer "F.Fab")
		)
		(pad "1" smd custom
			(at 0 -0.4445 90)
			(size 0.1397 0.1397)
			(layers "F.Cu" "F.Mask" "F.Paste")
			(net "P3V3_STBY_PG")
			(options
				(clearance outline)
				(anchor circle)
			)
			(primitives
				(gr_poly
					(pts
						(arc
							(start -0.1778 -0.2794)
							(mid -0.249642 -0.249642)
							(end -0.2794 -0.1778)
						)
						(arc
							(start -0.2794 0.1778)
							(mid -0.249642 0.249642)
							(end -0.1778 0.2794)
						)
						(arc
							(start 0.1778 0.2794)
							(mid 0.249642 0.249642)
							(end 0.2794 0.1778)
						)
						(arc
							(start 0.2794 -0.1778)
							(mid 0.249642 -0.249642)
							(end 0.1778 -0.2794)
						)
					)
					(width 0)
					(fill yes)
				)
			)
		)
		(pad "2" smd custom
			(at 0 0.4445 90)
			(size 0.1397 0.1397)
			(layers "F.Cu" "F.Mask" "F.Paste")
			(net "P3V3_STBY")
			(options
				(clearance outline)
				(anchor circle)
			)
			(primitives
				(gr_poly
					(pts
						(arc
							(start -0.1778 -0.2794)
							(mid -0.249642 -0.249642)
							(end -0.2794 -0.1778)
						)
						(arc
							(start -0.2794 0.1778)
							(mid -0.249642 0.249642)
							(end -0.1778 0.2794)
						)
						(arc
							(start 0.1778 0.2794)
							(mid 0.249642 0.249642)
							(end 0.2794 0.1778)
						)
						(arc
							(start 0.2794 -0.1778)
							(mid 0.249642 -0.249642)
							(end 0.1778 -0.2794)
						)
					)
					(width 0)
					(fill yes)
				)
			)
		)
	)
	(footprint ""
		(layer "F.Cu")
		(at 330.581 -99.568 180)
		(property "Reference" "R4164"
			(at 0 0 180)
			(layer "F.SilkS")
			(hide yes)
			(effects
				(font
					(size 1.27 1.27)
				)
			)
		)
		(property "Value" "4K7R2F-GP"
			(at 0.064008 -3.993896 180)
			(unlocked yes)
			(layer "F.Fab")
			(hide yes)
			(effects
				(font
					(size 1.016 1.016)
					(thickness 0.1524)
				)
			)
		)
		(property "Device Type" "R402H16"
			(at 0.064008 -5.517896 180)
			(unlocked yes)
			(layer "F.Fab")
			(hide yes)
			(effects
				(font
					(size 1.016 1.016)
					(thickness 0.1524)
				)
			)
		)
		(duplicate_pad_numbers_are_jumpers no)
		(fp_line
			(start 0.508 -0.9398)
			(end -0.508 -0.9398)
			(stroke
				(width 0.1524)
				(type default)
			)
			(layer "F.SilkS")
		)
		(fp_line
			(start -0.508 -0.9398)
			(end -0.508 0.9398)
			(stroke
				(width 0.1524)
				(type default)
			)
			(layer "F.SilkS")
		)
		(fp_rect
			(start -0.508 0.9398)
			(end 0.508 -0.9398)
			(stroke
				(width 0)
				(type default)
			)
			(fill no)
			(layer "F.CrtYd")
		)
		(fp_rect
			(start -0.508 0.9398)
			(end 0.508 -0.9398)
			(stroke
				(width 0)
				(type default)
			)
			(fill no)
			(layer "F.Fab")
		)
		(pad "1" smd custom
			(at 0 -0.4445 180)
			(size 0.1397 0.1397)
			(layers "F.Cu" "F.Mask" "F.Paste")
			(net "VS2_LED")
			(options
				(clearance outline)
				(anchor circle)
			)
			(primitives
				(gr_poly
					(pts
						(arc
							(start -0.1778 -0.2794)
							(mid -0.249642 -0.249642)
							(end -0.2794 -0.1778)
						)
						(arc
							(start -0.2794 0.1778)
							(mid -0.249642 0.249642)
							(end -0.1778 0.2794)
						)
						(arc
							(start 0.1778 0.2794)
							(mid 0.249642 0.249642)
							(end 0.2794 0.1778)
						)
						(arc
							(start 0.2794 -0.1778)
							(mid 0.249642 -0.249642)
							(end 0.1778 -0.2794)
						)
					)
					(width 0)
					(fill yes)
				)
			)
		)
		(pad "2" smd custom
			(at 0 0.4445 180)
			(size 0.1397 0.1397)
			(layers "F.Cu" "F.Mask" "F.Paste")
			(net "P3V3_STBY")
			(options
				(clearance outline)
				(anchor circle)
			)
			(primitives
				(gr_poly
					(pts
						(arc
							(start -0.1778 -0.2794)
							(mid -0.249642 -0.249642)
							(end -0.2794 -0.1778)
						)
						(arc
							(start -0.2794 0.1778)
							(mid -0.249642 0.249642)
							(end -0.1778 0.2794)
						)
						(arc
							(start 0.1778 0.2794)
							(mid 0.249642 0.249642)
							(end 0.2794 0.1778)
						)
						(arc
							(start 0.2794 -0.1778)
							(mid 0.249642 -0.249642)
							(end 0.1778 -0.2794)
						)
					)
					(width 0)
					(fill yes)
				)
			)
		)
	)
	(footprint ""
		(layer "F.Cu")
		(at 123.17984 -3.34772 90)
		(property "Reference" "SR711"
			(at 0 0 90)
			(layer "F.SilkS")
			(hide yes)
			(effects
				(font
					(size 1.27 1.27)
				)
			)
		)
		(property "Value" "150R2F-1-GP"
			(at 0.064008 -3.993896 90)
			(unlocked yes)
			(layer "F.Fab")
			(hide yes)
			(effects
				(font
					(size 1.016 1.016)
					(thickness 0.1524)
				)
			)
		)
		(property "Device Type" "R402H16"
			(at 0.064008 -5.517896 90)
			(unlocked yes)
			(layer "F.Fab")
			(hide yes)
			(effects
				(font
					(size 1.016 1.016)
					(thickness 0.1524)
				)
			)
		)
		(duplicate_pad_numbers_are_jumpers no)
		(fp_line
			(start 0.508 -0.9398)
			(end -0.508 -0.9398)
			(stroke
				(width 0.1524)
				(type default)
			)
			(layer "F.SilkS")
		)
		(fp_line
			(start -0.508 -0.9398)
			(end -0.508 0.9398)
			(stroke
				(width 0.1524)
				(type default)
			)
			(layer "F.SilkS")
		)
		(fp_rect
			(start -0.508 0.9398)
			(end 0.508 -0.9398)
			(stroke
				(width 0)
				(type default)
			)
			(fill no)
			(layer "F.CrtYd")
		)
		(fp_rect
			(start -0.508 0.9398)
			(end 0.508 -0.9398)
			(stroke
				(width 0)
				(type default)
			)
			(fill no)
			(layer "F.Fab")
		)
		(pad "1" smd custom
			(at 0 -0.4445 90)
			(size 0.1397 0.1397)
			(layers "F.Cu" "F.Mask" "F.Paste")
			(net "P3V3_STBY")
			(options
				(clearance outline)
				(anchor circle)
			)
			(primitives
				(gr_poly
					(pts
						(arc
							(start -0.1778 -0.2794)
							(mid -0.249642 -0.249642)
							(end -0.2794 -0.1778)
						)
						(arc
							(start -0.2794 0.1778)
							(mid -0.249642 0.249642)
							(end -0.1778 0.2794)
						)
						(arc
							(start 0.1778 0.2794)
							(mid 0.249642 0.249642)
							(end 0.2794 0.1778)
						)
						(arc
							(start 0.2794 -0.1778)
							(mid 0.249642 -0.249642)
							(end 0.1778 -0.2794)
						)
					)
					(width 0)
					(fill yes)
				)
			)
		)
		(pad "2" smd custom
			(at 0 0.4445 90)
			(size 0.1397 0.1397)
			(layers "F.Cu" "F.Mask" "F.Paste")
			(net "LED_R_4")
			(options
				(clearance outline)
				(anchor circle)
			)
			(primitives
				(gr_poly
					(pts
						(arc
							(start -0.1778 -0.2794)
							(mid -0.249642 -0.249642)
							(end -0.2794 -0.1778)
						)
						(arc
							(start -0.2794 0.1778)
							(mid -0.249642 0.249642)
							(end -0.1778 0.2794)
						)
						(arc
							(start 0.1778 0.2794)
							(mid 0.249642 0.249642)
							(end 0.2794 0.1778)
						)
						(arc
							(start 0.2794 -0.1778)
							(mid 0.249642 -0.249642)
							(end 0.1778 -0.2794)
						)
					)
					(width 0)
					(fill yes)
				)
			)
		)
	)
	(footprint ""
		(layer "F.Cu")
		(at 20.955 -136.7282 90)
		(property "Reference" "R290"
			(at 0 0 90)
			(layer "F.SilkS")
			(hide yes)
			(effects
				(font
					(size 1.27 1.27)
				)
			)
		)
		(property "Value" "0R2J-2-GP"
			(at 0.064008 -3.993896 90)
			(unlocked yes)
			(layer "F.Fab")
			(hide yes)
			(effects
				(font
					(size 1.016 1.016)
					(thickness 0.1524)
				)
			)
		)
		(property "Device Type" "R402H16"
			(at 0.064008 -5.517896 90)
			(unlocked yes)
			(layer "F.Fab")
			(hide yes)
			(effects
				(font
					(size 1.016 1.016)
					(thickness 0.1524)
				)
			)
		)
		(duplicate_pad_numbers_are_jumpers no)
		(fp_line
			(start 0.508 -0.9398)
			(end -0.508 -0.9398)
			(stroke
				(width 0.1524)
				(type default)
			)
			(layer "F.SilkS")
		)
		(fp_line
			(start -0.508 -0.9398)
			(end -0.508 0.9398)
			(stroke
				(width 0.1524)
				(type default)
			)
			(layer "F.SilkS")
		)
		(fp_rect
			(start -0.508 0.9398)
			(end 0.508 -0.9398)
			(stroke
				(width 0)
				(type default)
			)
			(fill no)
			(layer "F.CrtYd")
		)
		(fp_rect
			(start -0.508 0.9398)
			(end 0.508 -0.9398)
			(stroke
				(width 0)
				(type default)
			)
			(fill no)
			(layer "F.Fab")
		)
		(pad "1" smd custom
			(at 0 -0.4445 90)
			(size 0.1397 0.1397)
			(layers "F.Cu" "F.Mask" "F.Paste")
			(net "TRAY_POWER_CRIT_N")
			(options
				(clearance outline)
				(anchor circle)
			)
			(primitives
				(gr_poly
					(pts
						(arc
							(start -0.1778 -0.2794)
							(mid -0.249642 -0.249642)
							(end -0.2794 -0.1778)
						)
						(arc
							(start -0.2794 0.1778)
							(mid -0.249642 0.249642)
							(end -0.1778 0.2794)
						)
						(arc
							(start 0.1778 0.2794)
							(mid 0.249642 0.249642)
							(end 0.2794 0.1778)
						)
						(arc
							(start 0.2794 -0.1778)
							(mid 0.249642 -0.249642)
							(end 0.1778 -0.2794)
						)
					)
					(width 0)
					(fill yes)
				)
			)
		)
		(pad "2" smd custom
			(at 0 0.4445 90)
			(size 0.1397 0.1397)
			(layers "F.Cu" "F.Mask" "F.Paste")
			(net "GPIOR5_R")
			(options
				(clearance outline)
				(anchor circle)
			)
			(primitives
				(gr_poly
					(pts
						(arc
							(start -0.1778 -0.2794)
							(mid -0.249642 -0.249642)
							(end -0.2794 -0.1778)
						)
						(arc
							(start -0.2794 0.1778)
							(mid -0.249642 0.249642)
							(end -0.1778 0.2794)
						)
						(arc
							(start 0.1778 0.2794)
							(mid 0.249642 0.249642)
							(end 0.2794 0.1778)
						)
						(arc
							(start 0.2794 -0.1778)
							(mid 0.249642 -0.249642)
							(end 0.1778 -0.2794)
						)
					)
					(width 0)
					(fill yes)
				)
			)
		)
	)
	(footprint ""
		(layer "F.Cu")
		(at 207.137 -4.7752 180)
		(property "Reference" "R58"
			(at 0 0 180)
			(layer "F.SilkS")
			(hide yes)
			(effects
				(font
					(size 1.27 1.27)
				)
			)
		)
		(property "Value" "4K7R2F-GP"
			(at 0.064008 -3.993896 180)
			(unlocked yes)
			(layer "F.Fab")
			(hide yes)
			(effects
				(font
					(size 1.016 1.016)
					(thickness 0.1524)
				)
			)
		)
		(property "Device Type" "R402H16"
			(at 0.064008 -5.517896 180)
			(unlocked yes)
			(layer "F.Fab")
			(hide yes)
			(effects
				(font
					(size 1.016 1.016)
					(thickness 0.1524)
				)
			)
		)
		(duplicate_pad_numbers_are_jumpers no)
		(fp_line
			(start 0.508 -0.9398)
			(end -0.508 -0.9398)
			(stroke
				(width 0.1524)
				(type default)
			)
			(layer "F.SilkS")
		)
		(fp_line
			(start -0.508 -0.9398)
			(end -0.508 0.9398)
			(stroke
				(width 0.1524)
				(type default)
			)
			(layer "F.SilkS")
		)
		(fp_rect
			(start -0.508 0.9398)
			(end 0.508 -0.9398)
			(stroke
				(width 0)
				(type default)
			)
			(fill no)
			(layer "F.CrtYd")
		)
		(fp_rect
			(start -0.508 0.9398)
			(end 0.508 -0.9398)
			(stroke
				(width 0)
				(type default)
			)
			(fill no)
			(layer "F.Fab")
		)
		(pad "1" smd custom
			(at 0 -0.4445 180)
			(size 0.1397 0.1397)
			(layers "F.Cu" "F.Mask" "F.Paste")
			(net "DUT_VDDO")
			(options
				(clearance outline)
				(anchor circle)
			)
			(primitives
				(gr_poly
					(pts
						(arc
							(start -0.1778 -0.2794)
							(mid -0.249642 -0.249642)
							(end -0.2794 -0.1778)
						)
						(arc
							(start -0.2794 0.1778)
							(mid -0.249642 0.249642)
							(end -0.1778 0.2794)
						)
						(arc
							(start 0.1778 0.2794)
							(mid 0.249642 0.249642)
							(end 0.2794 0.1778)
						)
						(arc
							(start 0.2794 -0.1778)
							(mid 0.249642 -0.249642)
							(end 0.1778 -0.2794)
						)
					)
					(width 0)
					(fill yes)
				)
			)
		)
		(pad "2" smd custom
			(at 0 0.4445 180)
			(size 0.1397 0.1397)
			(layers "F.Cu" "F.Mask" "F.Paste")
			(net "BOOT_RECOVERY_1")
			(options
				(clearance outline)
				(anchor circle)
			)
			(primitives
				(gr_poly
					(pts
						(arc
							(start -0.1778 -0.2794)
							(mid -0.249642 -0.249642)
							(end -0.2794 -0.1778)
						)
						(arc
							(start -0.2794 0.1778)
							(mid -0.249642 0.249642)
							(end -0.1778 0.2794)
						)
						(arc
							(start 0.1778 0.2794)
							(mid 0.249642 0.249642)
							(end 0.2794 0.1778)
						)
						(arc
							(start 0.2794 -0.1778)
							(mid 0.249642 -0.249642)
							(end 0.1778 -0.2794)
						)
					)
					(width 0)
					(fill yes)
				)
			)
		)
	)
	(footprint ""
		(layer "F.Cu")
		(at 10.9982 -81.6356 90)
		(property "Reference" "R399"
			(at 0 0 90)
			(layer "F.SilkS")
			(hide yes)
			(effects
				(font
					(size 1.27 1.27)
				)
			)
		)
		(property "Value" "10KR2F-2-GP"
			(at 0.064008 -3.993896 90)
			(unlocked yes)
			(layer "F.Fab")
			(hide yes)
			(effects
				(font
					(size 1.016 1.016)
					(thickness 0.1524)
				)
			)
		)
		(property "Device Type" "R402H16"
			(at 0.064008 -5.517896 90)
			(unlocked yes)
			(layer "F.Fab")
			(hide yes)
			(effects
				(font
					(size 1.016 1.016)
					(thickness 0.1524)
				)
			)
		)
		(duplicate_pad_numbers_are_jumpers no)
		(fp_line
			(start 0.508 -0.9398)
			(end -0.508 -0.9398)
			(stroke
				(width 0.1524)
				(type default)
			)
			(layer "F.SilkS")
		)
		(fp_line
			(start -0.508 -0.9398)
			(end -0.508 0.9398)
			(stroke
				(width 0.1524)
				(type default)
			)
			(layer "F.SilkS")
		)
		(fp_rect
			(start -0.508 0.9398)
			(end 0.508 -0.9398)
			(stroke
				(width 0)
				(type default)
			)
			(fill no)
			(layer "F.CrtYd")
		)
		(fp_rect
			(start -0.508 0.9398)
			(end 0.508 -0.9398)
			(stroke
				(width 0)
				(type default)
			)
			(fill no)
			(layer "F.Fab")
		)
		(pad "1" smd custom
			(at 0 -0.4445 90)
			(size 0.1397 0.1397)
			(layers "F.Cu" "F.Mask" "F.Paste")
			(net "P3V3_STBY")
			(options
				(clearance outline)
				(anchor circle)
			)
			(primitives
				(gr_poly
					(pts
						(arc
							(start -0.1778 -0.2794)
							(mid -0.249642 -0.249642)
							(end -0.2794 -0.1778)
						)
						(arc
							(start -0.2794 0.1778)
							(mid -0.249642 0.249642)
							(end -0.1778 0.2794)
						)
						(arc
							(start 0.1778 0.2794)
							(mid 0.249642 0.249642)
							(end 0.2794 0.1778)
						)
						(arc
							(start 0.2794 -0.1778)
							(mid 0.249642 -0.249642)
							(end 0.1778 -0.2794)
						)
					)
					(width 0)
					(fill yes)
				)
			)
		)
		(pad "2" smd custom
			(at 0 0.4445 90)
			(size 0.1397 0.1397)
			(layers "F.Cu" "F.Mask" "F.Paste")
			(net "FM_OSC_50M_EN")
			(options
				(clearance outline)
				(anchor circle)
			)
			(primitives
				(gr_poly
					(pts
						(arc
							(start -0.1778 -0.2794)
							(mid -0.249642 -0.249642)
							(end -0.2794 -0.1778)
						)
						(arc
							(start -0.2794 0.1778)
							(mid -0.249642 0.249642)
							(end -0.1778 0.2794)
						)
						(arc
							(start 0.1778 0.2794)
							(mid 0.249642 0.249642)
							(end 0.2794 0.1778)
						)
						(arc
							(start 0.2794 -0.1778)
							(mid 0.249642 -0.249642)
							(end 0.1778 -0.2794)
						)
					)
					(width 0)
					(fill yes)
				)
			)
		)
	)
	(footprint ""
		(layer "F.Cu")
		(at 159.429704 -33.528)
		(property "Reference" "C399"
			(at 0 0 0)
			(layer "F.SilkS")
			(hide yes)
			(effects
				(font
					(size 1.27 1.27)
				)
			)
		)
		(property "Value" "SCD22U10V2KX-1GP"
			(at 1.1811 -2.7051 0)
			(unlocked yes)
			(layer "F.Fab")
			(hide yes)
			(effects
				(font
					(size 1.016 1.016)
					(thickness 0.1524)
				)
			)
		)
		(property "Device Type" "C402H22"
			(at 1.1811 -4.2291 0)
			(unlocked yes)
			(layer "F.Fab")
			(hide yes)
			(effects
				(font
					(size 1.016 1.016)
					(thickness 0.1524)
				)
			)
		)
		(duplicate_pad_numbers_are_jumpers no)
		(fp_rect
			(start -0.4318 0.9525)
			(end 0.4318 -0.9525)
			(stroke
				(width 0)
				(type default)
			)
			(fill no)
			(layer "F.CrtYd")
		)
		(fp_rect
			(start -0.4318 0.9525)
			(end 0.4318 -0.9525)
			(stroke
				(width 0)
				(type default)
			)
			(fill no)
			(layer "F.Fab")
		)
		(pad "1" smd custom
			(at 0 -0.4445)
			(size 0.1524 0.1524)
			(layers "F.Cu" "F.Mask" "F.Paste")
			(net "PCIE_TX_CAP_N89")
			(options
				(clearance outline)
				(anchor circle)
			)
			(primitives
				(gr_poly
					(pts
						(arc
							(start 0.3048 -0.2032)
							(mid 0.275042 -0.275042)
							(end 0.2032 -0.3048)
						)
						(arc
							(start -0.2032 -0.3048)
							(mid -0.275042 -0.275042)
							(end -0.3048 -0.2032)
						)
						(arc
							(start -0.3048 0.2032)
							(mid -0.275042 0.275042)
							(end -0.2032 0.3048)
						)
						(arc
							(start 0.2032 0.3048)
							(mid 0.275042 0.275042)
							(end 0.3048 0.2032)
						)
					)
					(width 0)
					(fill yes)
				)
			)
		)
		(pad "2" smd custom
			(at 0 0.4445)
			(size 0.1524 0.1524)
			(layers "F.Cu" "F.Mask" "F.Paste")
			(net "PCIE_TX_N89")
			(options
				(clearance outline)
				(anchor circle)
			)
			(primitives
				(gr_poly
					(pts
						(arc
							(start 0.3048 -0.2032)
							(mid 0.275042 -0.275042)
							(end 0.2032 -0.3048)
						)
						(arc
							(start -0.2032 -0.3048)
							(mid -0.275042 -0.275042)
							(end -0.3048 -0.2032)
						)
						(arc
							(start -0.3048 0.2032)
							(mid -0.275042 0.275042)
							(end -0.2032 0.3048)
						)
						(arc
							(start 0.2032 0.3048)
							(mid 0.275042 0.275042)
							(end 0.3048 0.2032)
						)
					)
					(width 0)
					(fill yes)
				)
			)
		)
	)
	(footprint ""
		(layer "F.Cu")
		(at 292.227 -57.15 180)
		(property "Reference" "Q39"
			(at 0 0 180)
			(layer "F.SilkS")
			(hide yes)
			(effects
				(font
					(size 1.27 1.27)
				)
			)
		)
		(property "Value" "2N7002K-1-GP"
			(at 0.127 -8.9662 180)
			(unlocked yes)
			(layer "F.Fab")
			(hide yes)
			(effects
				(font
					(size 1.016 1.016)
					(thickness 0.1524)
				)
			)
		)
		(property "Device Type" "SOT23DGS2D4H44"
			(at 0.127 -10.4902 180)
			(unlocked yes)
			(layer "F.Fab")
			(hide yes)
			(effects
				(font
					(size 1.016 1.016)
					(thickness 0.1524)
				)
			)
		)
		(duplicate_pad_numbers_are_jumpers no)
		(fp_line
			(start 1.651 1.778)
			(end 1.651 -1.778)
			(stroke
				(width 0.1524)
				(type default)
			)
			(layer "F.SilkS")
		)
		(fp_line
			(start 1.651 -1.778)
			(end -1.651 -1.778)
			(stroke
				(width 0.1524)
				(type default)
			)
			(layer "F.SilkS")
		)
		(fp_line
			(start -1.651 1.778)
			(end 1.651 1.778)
			(stroke
				(width 0.1524)
				(type default)
			)
			(layer "F.SilkS")
		)
		(fp_line
			(start -1.651 -1.778)
			(end -1.651 1.778)
			(stroke
				(width 0.1524)
				(type default)
			)
			(layer "F.SilkS")
		)
		(fp_poly
			(pts
				(xy -1.778 1.8796) (xy -1.778 -1.8796) (xy 1.778 -1.8796) (xy 1.778 1.8796)
			)
			(stroke
				(width 0)
				(type default)
			)
			(fill no)
			(layer "F.CrtYd")
		)
		(fp_poly
			(pts
				(xy -1.778 1.8796) (xy -1.778 -1.8796) (xy 1.778 -1.8796) (xy 1.778 1.8796)
			)
			(stroke
				(width 0)
				(type default)
			)
			(fill no)
			(layer "F.Fab")
		)
		(pad "D" smd custom
			(at 0 -0.9525 180)
			(size 0.1905 0.1905)
			(layers "F.Cu" "F.Mask" "F.Paste")
			(net "LED_Q_14")
			(options
				(clearance outline)
				(anchor circle)
			)
			(primitives
				(gr_poly
					(pts
						(arc
							(start -0.1778 0.5715)
							(mid -0.321484 0.511984)
							(end -0.381 0.3683)
						)
						(arc
							(start -0.381 -0.3683)
							(mid -0.321484 -0.511984)
							(end -0.1778 -0.5715)
						)
						(arc
							(start 0.1778 -0.5715)
							(mid 0.321484 -0.511984)
							(end 0.381 -0.3683)
						)
						(arc
							(start 0.381 0.3683)
							(mid 0.321484 0.511984)
							(end 0.1778 0.5715)
						)
					)
					(width 0)
					(fill yes)
				)
			)
		)
		(pad "G" smd custom
			(at -0.98425 0.9525 180)
			(size 0.1905 0.1905)
			(layers "F.Cu" "F.Mask" "F.Paste")
			(net "VS6_LED_R")
			(options
				(clearance outline)
				(anchor circle)
			)
			(primitives
				(gr_poly
					(pts
						(arc
							(start -0.1778 0.5715)
							(mid -0.321484 0.511984)
							(end -0.381 0.3683)
						)
						(arc
							(start -0.381 -0.3683)
							(mid -0.321484 -0.511984)
							(end -0.1778 -0.5715)
						)
						(arc
							(start 0.1778 -0.5715)
							(mid 0.321484 -0.511984)
							(end 0.381 -0.3683)
						)
						(arc
							(start 0.381 0.3683)
							(mid 0.321484 0.511984)
							(end 0.1778 0.5715)
						)
					)
					(width 0)
					(fill yes)
				)
			)
		)
		(pad "S" smd custom
			(at 0.98425 0.9525 180)
			(size 0.1905 0.1905)
			(layers "F.Cu" "F.Mask" "F.Paste")
			(net "GND")
			(options
				(clearance outline)
				(anchor circle)
			)
			(primitives
				(gr_poly
					(pts
						(arc
							(start -0.1778 0.5715)
							(mid -0.321484 0.511984)
							(end -0.381 0.3683)
						)
						(arc
							(start -0.381 -0.3683)
							(mid -0.321484 -0.511984)
							(end -0.1778 -0.5715)
						)
						(arc
							(start 0.1778 -0.5715)
							(mid 0.321484 -0.511984)
							(end 0.381 -0.3683)
						)
						(arc
							(start 0.381 0.3683)
							(mid 0.321484 0.511984)
							(end 0.1778 0.5715)
						)
					)
					(width 0)
					(fill yes)
				)
			)
		)
	)
	(footprint ""
		(layer "F.Cu")
		(at 7.597648 -77.895196 90)
		(property "Reference" "R398"
			(at 0 0 90)
			(layer "F.SilkS")
			(hide yes)
			(effects
				(font
					(size 1.27 1.27)
				)
			)
		)
		(property "Value" "10KR2F-2-GP"
			(at 0.064008 -3.993896 90)
			(unlocked yes)
			(layer "F.Fab")
			(hide yes)
			(effects
				(font
					(size 1.016 1.016)
					(thickness 0.1524)
				)
			)
		)
		(property "Device Type" "R402H16"
			(at 0.064008 -5.517896 90)
			(unlocked yes)
			(layer "F.Fab")
			(hide yes)
			(effects
				(font
					(size 1.016 1.016)
					(thickness 0.1524)
				)
			)
		)
		(duplicate_pad_numbers_are_jumpers no)
		(fp_line
			(start 0.508 -0.9398)
			(end -0.508 -0.9398)
			(stroke
				(width 0.1524)
				(type default)
			)
			(layer "F.SilkS")
		)
		(fp_line
			(start -0.508 -0.9398)
			(end -0.508 0.9398)
			(stroke
				(width 0.1524)
				(type default)
			)
			(layer "F.SilkS")
		)
		(fp_rect
			(start -0.508 0.9398)
			(end 0.508 -0.9398)
			(stroke
				(width 0)
				(type default)
			)
			(fill no)
			(layer "F.CrtYd")
		)
		(fp_rect
			(start -0.508 0.9398)
			(end 0.508 -0.9398)
			(stroke
				(width 0)
				(type default)
			)
			(fill no)
			(layer "F.Fab")
		)
		(pad "1" smd custom
			(at 0 -0.4445 90)
			(size 0.1397 0.1397)
			(layers "F.Cu" "F.Mask" "F.Paste")
			(net "P3V3_STBY")
			(options
				(clearance outline)
				(anchor circle)
			)
			(primitives
				(gr_poly
					(pts
						(arc
							(start -0.1778 -0.2794)
							(mid -0.249642 -0.249642)
							(end -0.2794 -0.1778)
						)
						(arc
							(start -0.2794 0.1778)
							(mid -0.249642 0.249642)
							(end -0.1778 0.2794)
						)
						(arc
							(start 0.1778 0.2794)
							(mid 0.249642 0.249642)
							(end 0.2794 0.1778)
						)
						(arc
							(start 0.2794 -0.1778)
							(mid 0.249642 -0.249642)
							(end 0.1778 -0.2794)
						)
					)
					(width 0)
					(fill yes)
				)
			)
		)
		(pad "2" smd custom
			(at 0 0.4445 90)
			(size 0.1397 0.1397)
			(layers "F.Cu" "F.Mask" "F.Paste")
			(net "LAN_SMB_DAT")
			(options
				(clearance outline)
				(anchor circle)
			)
			(primitives
				(gr_poly
					(pts
						(arc
							(start -0.1778 -0.2794)
							(mid -0.249642 -0.249642)
							(end -0.2794 -0.1778)
						)
						(arc
							(start -0.2794 0.1778)
							(mid -0.249642 0.249642)
							(end -0.1778 0.2794)
						)
						(arc
							(start 0.1778 0.2794)
							(mid 0.249642 0.249642)
							(end 0.2794 0.1778)
						)
						(arc
							(start 0.2794 -0.1778)
							(mid 0.249642 -0.249642)
							(end 0.1778 -0.2794)
						)
					)
					(width 0)
					(fill yes)
				)
			)
		)
	)
	(footprint ""
		(layer "F.Cu")
		(at 145.761202 -64.416432 -90)
		(property "Reference" "PC198"
			(at 0 0 270)
			(layer "F.SilkS")
			(hide yes)
			(effects
				(font
					(size 1.27 1.27)
				)
			)
		)
		(property "Value" "SC10U25V5KX-GP"
			(at -0.0762 -6.1214 270)
			(unlocked yes)
			(layer "F.Fab")
			(hide yes)
			(effects
				(font
					(size 1.016 1.016)
					(thickness 0.1524)
				)
			)
		)
		(property "Device Type" "C805H56"
			(at -0.0762 -8.1534 270)
			(unlocked yes)
			(layer "F.Fab")
			(hide yes)
			(effects
				(font
					(size 1.016 1.016)
					(thickness 0.1524)
				)
			)
		)
		(duplicate_pad_numbers_are_jumpers no)
		(fp_line
			(start 0.635 0)
			(end -0.635 0)
			(stroke
				(width 0.508)
				(type default)
			)
			(layer "F.SilkS")
		)
		(fp_rect
			(start -0.9652 1.778)
			(end 0.9652 -1.778)
			(stroke
				(width 0)
				(type default)
			)
			(fill no)
			(layer "F.CrtYd")
		)
		(fp_poly
			(pts
				(xy -0.9652 -1.778) (xy 0.9652 -1.778) (xy 0.9652 1.778) (xy -0.9652 1.778)
			)
			(stroke
				(width 0)
				(type default)
			)
			(fill no)
			(layer "F.Fab")
		)
		(pad "1" smd rect
			(at 0 -0.9652 270)
			(size 1.397 1.143)
			(layers "F.Cu" "F.Mask" "F.Paste")
			(net "P0V9_VIN")
		)
		(pad "2" smd rect
			(at 0 0.9652 270)
			(size 1.397 1.143)
			(layers "F.Cu" "F.Mask" "F.Paste")
			(net "GND")
		)
	)
	(footprint ""
		(layer "F.Cu")
		(at 73.914 -195.6816 180)
		(property "Reference" "R7961"
			(at 0 0 180)
			(layer "F.SilkS")
			(hide yes)
			(effects
				(font
					(size 1.27 1.27)
				)
			)
		)
		(property "Value" "0R2J-2-GP"
			(at 0.064008 -3.993896 180)
			(unlocked yes)
			(layer "F.Fab")
			(hide yes)
			(effects
				(font
					(size 1.016 1.016)
					(thickness 0.1524)
				)
			)
		)
		(property "Device Type" "R402H16"
			(at 0.064008 -5.517896 180)
			(unlocked yes)
			(layer "F.Fab")
			(hide yes)
			(effects
				(font
					(size 1.016 1.016)
					(thickness 0.1524)
				)
			)
		)
		(duplicate_pad_numbers_are_jumpers no)
		(fp_line
			(start 0.508 -0.9398)
			(end -0.508 -0.9398)
			(stroke
				(width 0.1524)
				(type default)
			)
			(layer "F.SilkS")
		)
		(fp_line
			(start -0.508 -0.9398)
			(end -0.508 0.9398)
			(stroke
				(width 0.1524)
				(type default)
			)
			(layer "F.SilkS")
		)
		(fp_rect
			(start -0.508 0.9398)
			(end 0.508 -0.9398)
			(stroke
				(width 0)
				(type default)
			)
			(fill no)
			(layer "F.CrtYd")
		)
		(fp_rect
			(start -0.508 0.9398)
			(end 0.508 -0.9398)
			(stroke
				(width 0)
				(type default)
			)
			(fill no)
			(layer "F.Fab")
		)
		(pad "1" smd custom
			(at 0 -0.4445 180)
			(size 0.1397 0.1397)
			(layers "F.Cu" "F.Mask" "F.Paste")
			(net "SSD_PWREN11")
			(options
				(clearance outline)
				(anchor circle)
			)
			(primitives
				(gr_poly
					(pts
						(arc
							(start -0.1778 -0.2794)
							(mid -0.249642 -0.249642)
							(end -0.2794 -0.1778)
						)
						(arc
							(start -0.2794 0.1778)
							(mid -0.249642 0.249642)
							(end -0.1778 0.2794)
						)
						(arc
							(start 0.1778 0.2794)
							(mid 0.249642 0.249642)
							(end 0.2794 0.1778)
						)
						(arc
							(start 0.2794 -0.1778)
							(mid 0.249642 -0.249642)
							(end 0.1778 -0.2794)
						)
					)
					(width 0)
					(fill yes)
				)
			)
		)
		(pad "2" smd custom
			(at 0 0.4445 180)
			(size 0.1397 0.1397)
			(layers "F.Cu" "F.Mask" "F.Paste")
			(net "SSD_PWREN11_R")
			(options
				(clearance outline)
				(anchor circle)
			)
			(primitives
				(gr_poly
					(pts
						(arc
							(start -0.1778 -0.2794)
							(mid -0.249642 -0.249642)
							(end -0.2794 -0.1778)
						)
						(arc
							(start -0.2794 0.1778)
							(mid -0.249642 0.249642)
							(end -0.1778 0.2794)
						)
						(arc
							(start 0.1778 0.2794)
							(mid 0.249642 0.249642)
							(end 0.2794 0.1778)
						)
						(arc
							(start 0.2794 -0.1778)
							(mid 0.249642 -0.249642)
							(end 0.1778 -0.2794)
						)
					)
					(width 0)
					(fill yes)
				)
			)
		)
	)
	(footprint ""
		(layer "F.Cu")
		(at 22.4536 -52.2224 180)
		(property "Reference" "R560"
			(at 0 0 180)
			(layer "F.SilkS")
			(hide yes)
			(effects
				(font
					(size 1.27 1.27)
				)
			)
		)
		(property "Value" "0R2J-2-GP"
			(at 0.064008 -3.993896 180)
			(unlocked yes)
			(layer "F.Fab")
			(hide yes)
			(effects
				(font
					(size 1.016 1.016)
					(thickness 0.1524)
				)
			)
		)
		(property "Device Type" "R402H16"
			(at 0.064008 -5.517896 180)
			(unlocked yes)
			(layer "F.Fab")
			(hide yes)
			(effects
				(font
					(size 1.016 1.016)
					(thickness 0.1524)
				)
			)
		)
		(duplicate_pad_numbers_are_jumpers no)
		(fp_line
			(start 0.508 -0.9398)
			(end -0.508 -0.9398)
			(stroke
				(width 0.1524)
				(type default)
			)
			(layer "F.SilkS")
		)
		(fp_line
			(start -0.508 -0.9398)
			(end -0.508 0.9398)
			(stroke
				(width 0.1524)
				(type default)
			)
			(layer "F.SilkS")
		)
		(fp_rect
			(start -0.508 0.9398)
			(end 0.508 -0.9398)
			(stroke
				(width 0)
				(type default)
			)
			(fill no)
			(layer "F.CrtYd")
		)
		(fp_rect
			(start -0.508 0.9398)
			(end 0.508 -0.9398)
			(stroke
				(width 0)
				(type default)
			)
			(fill no)
			(layer "F.Fab")
		)
		(pad "1" smd custom
			(at 0 -0.4445 180)
			(size 0.1397 0.1397)
			(layers "F.Cu" "F.Mask" "F.Paste")
			(net "NIC0_MDI0_N3_R")
			(options
				(clearance outline)
				(anchor circle)
			)
			(primitives
				(gr_poly
					(pts
						(arc
							(start -0.1778 -0.2794)
							(mid -0.249642 -0.249642)
							(end -0.2794 -0.1778)
						)
						(arc
							(start -0.2794 0.1778)
							(mid -0.249642 0.249642)
							(end -0.1778 0.2794)
						)
						(arc
							(start 0.1778 0.2794)
							(mid 0.249642 0.249642)
							(end 0.2794 0.1778)
						)
						(arc
							(start 0.2794 -0.1778)
							(mid 0.249642 -0.249642)
							(end 0.1778 -0.2794)
						)
					)
					(width 0)
					(fill yes)
				)
			)
		)
		(pad "2" smd custom
			(at 0 0.4445 180)
			(size 0.1397 0.1397)
			(layers "F.Cu" "F.Mask" "F.Paste")
			(net "NIC0_MDI0_N3")
			(options
				(clearance outline)
				(anchor circle)
			)
			(primitives
				(gr_poly
					(pts
						(arc
							(start -0.1778 -0.2794)
							(mid -0.249642 -0.249642)
							(end -0.2794 -0.1778)
						)
						(arc
							(start -0.2794 0.1778)
							(mid -0.249642 0.249642)
							(end -0.1778 0.2794)
						)
						(arc
							(start 0.1778 0.2794)
							(mid 0.249642 0.249642)
							(end 0.2794 0.1778)
						)
						(arc
							(start 0.2794 -0.1778)
							(mid 0.249642 -0.249642)
							(end 0.1778 -0.2794)
						)
					)
					(width 0)
					(fill yes)
				)
			)
		)
	)
	(footprint ""
		(layer "F.Cu")
		(at 271.966182 -10.902442 180)
		(property "Reference" "R215"
			(at 0 0 180)
			(layer "F.SilkS")
			(hide yes)
			(effects
				(font
					(size 1.27 1.27)
				)
			)
		)
		(property "Value" "4K7R2F-GP"
			(at 0.064008 -3.993896 180)
			(unlocked yes)
			(layer "F.Fab")
			(hide yes)
			(effects
				(font
					(size 1.016 1.016)
					(thickness 0.1524)
				)
			)
		)
		(property "Device Type" "R402H16"
			(at 0.064008 -5.517896 180)
			(unlocked yes)
			(layer "F.Fab")
			(hide yes)
			(effects
				(font
					(size 1.016 1.016)
					(thickness 0.1524)
				)
			)
		)
		(duplicate_pad_numbers_are_jumpers no)
		(fp_line
			(start 0.508 -0.9398)
			(end -0.508 -0.9398)
			(stroke
				(width 0.1524)
				(type default)
			)
			(layer "F.SilkS")
		)
		(fp_line
			(start -0.508 -0.9398)
			(end -0.508 0.9398)
			(stroke
				(width 0.1524)
				(type default)
			)
			(layer "F.SilkS")
		)
		(fp_rect
			(start -0.508 0.9398)
			(end 0.508 -0.9398)
			(stroke
				(width 0)
				(type default)
			)
			(fill no)
			(layer "F.CrtYd")
		)
		(fp_rect
			(start -0.508 0.9398)
			(end 0.508 -0.9398)
			(stroke
				(width 0)
				(type default)
			)
			(fill no)
			(layer "F.Fab")
		)
		(pad "1" smd custom
			(at 0 -0.4445 180)
			(size 0.1397 0.1397)
			(layers "F.Cu" "F.Mask" "F.Paste")
			(net "CLK_P_5_R")
			(options
				(clearance outline)
				(anchor circle)
			)
			(primitives
				(gr_poly
					(pts
						(arc
							(start -0.1778 -0.2794)
							(mid -0.249642 -0.249642)
							(end -0.2794 -0.1778)
						)
						(arc
							(start -0.2794 0.1778)
							(mid -0.249642 0.249642)
							(end -0.1778 0.2794)
						)
						(arc
							(start 0.1778 0.2794)
							(mid 0.249642 0.249642)
							(end 0.2794 0.1778)
						)
						(arc
							(start 0.2794 -0.1778)
							(mid 0.249642 -0.249642)
							(end 0.1778 -0.2794)
						)
					)
					(width 0)
					(fill yes)
				)
			)
		)
		(pad "2" smd custom
			(at 0 0.4445 180)
			(size 0.1397 0.1397)
			(layers "F.Cu" "F.Mask" "F.Paste")
			(net "GND")
			(options
				(clearance outline)
				(anchor circle)
			)
			(primitives
				(gr_poly
					(pts
						(arc
							(start -0.1778 -0.2794)
							(mid -0.249642 -0.249642)
							(end -0.2794 -0.1778)
						)
						(arc
							(start -0.2794 0.1778)
							(mid -0.249642 0.249642)
							(end -0.1778 0.2794)
						)
						(arc
							(start 0.1778 0.2794)
							(mid 0.249642 0.249642)
							(end 0.2794 0.1778)
						)
						(arc
							(start 0.2794 -0.1778)
							(mid 0.249642 -0.249642)
							(end 0.1778 -0.2794)
						)
					)
					(width 0)
					(fill yes)
				)
			)
		)
	)
	(footprint ""
		(layer "F.Cu")
		(at 192.9384 -20.9042 -90)
		(property "Reference" "R699"
			(at 0 0 270)
			(layer "F.SilkS")
			(hide yes)
			(effects
				(font
					(size 1.27 1.27)
				)
			)
		)
		(property "Value" "4K7R2F-GP"
			(at 0.064008 -3.993896 270)
			(unlocked yes)
			(layer "F.Fab")
			(hide yes)
			(effects
				(font
					(size 1.016 1.016)
					(thickness 0.1524)
				)
			)
		)
		(property "Device Type" "R402H16"
			(at 0.064008 -5.517896 270)
			(unlocked yes)
			(layer "F.Fab")
			(hide yes)
			(effects
				(font
					(size 1.016 1.016)
					(thickness 0.1524)
				)
			)
		)
		(duplicate_pad_numbers_are_jumpers no)
		(fp_line
			(start -0.508 -0.9398)
			(end -0.508 0.9398)
			(stroke
				(width 0.1524)
				(type default)
			)
			(layer "F.SilkS")
		)
		(fp_line
			(start 0.508 -0.9398)
			(end -0.508 -0.9398)
			(stroke
				(width 0.1524)
				(type default)
			)
			(layer "F.SilkS")
		)
		(fp_rect
			(start -0.508 0.9398)
			(end 0.508 -0.9398)
			(stroke
				(width 0)
				(type default)
			)
			(fill no)
			(layer "F.CrtYd")
		)
		(fp_rect
			(start -0.508 0.9398)
			(end 0.508 -0.9398)
			(stroke
				(width 0)
				(type default)
			)
			(fill no)
			(layer "F.Fab")
		)
		(pad "1" smd custom
			(at 0 -0.4445 270)
			(size 0.1397 0.1397)
			(layers "F.Cu" "F.Mask" "F.Paste")
			(net "MINISAS_CN15_B_I2C_INT#")
			(options
				(clearance outline)
				(anchor circle)
			)
			(primitives
				(gr_poly
					(pts
						(arc
							(start -0.1778 -0.2794)
							(mid -0.249642 -0.249642)
							(end -0.2794 -0.1778)
						)
						(arc
							(start -0.2794 0.1778)
							(mid -0.249642 0.249642)
							(end -0.1778 0.2794)
						)
						(arc
							(start 0.1778 0.2794)
							(mid 0.249642 0.249642)
							(end 0.2794 0.1778)
						)
						(arc
							(start 0.2794 -0.1778)
							(mid 0.249642 -0.249642)
							(end 0.1778 -0.2794)
						)
					)
					(width 0)
					(fill yes)
				)
			)
		)
		(pad "2" smd custom
			(at 0 0.4445 270)
			(size 0.1397 0.1397)
			(layers "F.Cu" "F.Mask" "F.Paste")
			(net "P3V3_STBY")
			(options
				(clearance outline)
				(anchor circle)
			)
			(primitives
				(gr_poly
					(pts
						(arc
							(start -0.1778 -0.2794)
							(mid -0.249642 -0.249642)
							(end -0.2794 -0.1778)
						)
						(arc
							(start -0.2794 0.1778)
							(mid -0.249642 0.249642)
							(end -0.1778 0.2794)
						)
						(arc
							(start 0.1778 0.2794)
							(mid 0.249642 0.249642)
							(end 0.2794 0.1778)
						)
						(arc
							(start 0.2794 -0.1778)
							(mid 0.249642 -0.249642)
							(end 0.1778 -0.2794)
						)
					)
					(width 0)
					(fill yes)
				)
			)
		)
	)
	(footprint ""
		(layer "F.Cu")
		(at 232.537 -23.241)
		(property "Reference" "R818"
			(at 0 0 0)
			(layer "F.SilkS")
			(hide yes)
			(effects
				(font
					(size 1.27 1.27)
				)
			)
		)
		(property "Value" "4K7R2F-GP"
			(at 0.064008 -3.993896 0)
			(unlocked yes)
			(layer "F.Fab")
			(hide yes)
			(effects
				(font
					(size 1.016 1.016)
					(thickness 0.1524)
				)
			)
		)
		(property "Device Type" "R402H16"
			(at 0.064008 -5.517896 0)
			(unlocked yes)
			(layer "F.Fab")
			(hide yes)
			(effects
				(font
					(size 1.016 1.016)
					(thickness 0.1524)
				)
			)
		)
		(duplicate_pad_numbers_are_jumpers no)
		(fp_line
			(start -0.508 -0.9398)
			(end -0.508 0.9398)
			(stroke
				(width 0.1524)
				(type default)
			)
			(layer "F.SilkS")
		)
		(fp_line
			(start 0.508 -0.9398)
			(end -0.508 -0.9398)
			(stroke
				(width 0.1524)
				(type default)
			)
			(layer "F.SilkS")
		)
		(fp_rect
			(start -0.508 0.9398)
			(end 0.508 -0.9398)
			(stroke
				(width 0)
				(type default)
			)
			(fill no)
			(layer "F.CrtYd")
		)
		(fp_rect
			(start -0.508 0.9398)
			(end 0.508 -0.9398)
			(stroke
				(width 0)
				(type default)
			)
			(fill no)
			(layer "F.Fab")
		)
		(pad "1" smd custom
			(at 0 -0.4445)
			(size 0.1397 0.1397)
			(layers "F.Cu" "F.Mask" "F.Paste")
			(net "GND")
			(options
				(clearance outline)
				(anchor circle)
			)
			(primitives
				(gr_poly
					(pts
						(arc
							(start -0.1778 -0.2794)
							(mid -0.249642 -0.249642)
							(end -0.2794 -0.1778)
						)
						(arc
							(start -0.2794 0.1778)
							(mid -0.249642 0.249642)
							(end -0.1778 0.2794)
						)
						(arc
							(start 0.1778 0.2794)
							(mid 0.249642 0.249642)
							(end 0.2794 0.1778)
						)
						(arc
							(start 0.2794 -0.1778)
							(mid 0.249642 -0.249642)
							(end 0.1778 -0.2794)
						)
					)
					(width 0)
					(fill yes)
				)
			)
		)
		(pad "2" smd custom
			(at 0 0.4445)
			(size 0.1397 0.1397)
			(layers "F.Cu" "F.Mask" "F.Paste")
			(net "BOOTSTRAP9")
			(options
				(clearance outline)
				(anchor circle)
			)
			(primitives
				(gr_poly
					(pts
						(arc
							(start -0.1778 -0.2794)
							(mid -0.249642 -0.249642)
							(end -0.2794 -0.1778)
						)
						(arc
							(start -0.2794 0.1778)
							(mid -0.249642 0.249642)
							(end -0.1778 0.2794)
						)
						(arc
							(start 0.1778 0.2794)
							(mid 0.249642 0.249642)
							(end 0.2794 0.1778)
						)
						(arc
							(start 0.2794 -0.1778)
							(mid 0.249642 -0.249642)
							(end 0.1778 -0.2794)
						)
					)
					(width 0)
					(fill yes)
				)
			)
		)
	)
	(footprint ""
		(layer "F.Cu")
		(at 225.9076 -13.081 90)
		(property "Reference" "C374"
			(at 0 0 90)
			(layer "F.SilkS")
			(hide yes)
			(effects
				(font
					(size 1.27 1.27)
				)
			)
		)
		(property "Value" "SCD1U25V2KX-2-GP"
			(at 1.1811 -2.7051 90)
			(unlocked yes)
			(layer "F.Fab")
			(hide yes)
			(effects
				(font
					(size 1.016 1.016)
					(thickness 0.1524)
				)
			)
		)
		(property "Device Type" "C402H22"
			(at 1.1811 -4.2291 90)
			(unlocked yes)
			(layer "F.Fab")
			(hide yes)
			(effects
				(font
					(size 1.016 1.016)
					(thickness 0.1524)
				)
			)
		)
		(duplicate_pad_numbers_are_jumpers no)
		(fp_rect
			(start -0.4318 0.9525)
			(end 0.4318 -0.9525)
			(stroke
				(width 0)
				(type default)
			)
			(fill no)
			(layer "F.CrtYd")
		)
		(fp_rect
			(start -0.4318 0.9525)
			(end 0.4318 -0.9525)
			(stroke
				(width 0)
				(type default)
			)
			(fill no)
			(layer "F.Fab")
		)
		(pad "1" smd custom
			(at 0 -0.4445 90)
			(size 0.1524 0.1524)
			(layers "F.Cu" "F.Mask" "F.Paste")
			(net "P3V3_STBY")
			(options
				(clearance outline)
				(anchor circle)
			)
			(primitives
				(gr_poly
					(pts
						(arc
							(start 0.3048 -0.2032)
							(mid 0.275042 -0.275042)
							(end 0.2032 -0.3048)
						)
						(arc
							(start -0.2032 -0.3048)
							(mid -0.275042 -0.275042)
							(end -0.3048 -0.2032)
						)
						(arc
							(start -0.3048 0.2032)
							(mid -0.275042 0.275042)
							(end -0.2032 0.3048)
						)
						(arc
							(start 0.2032 0.3048)
							(mid 0.275042 0.275042)
							(end 0.3048 0.2032)
						)
					)
					(width 0)
					(fill yes)
				)
			)
		)
		(pad "2" smd custom
			(at 0 0.4445 90)
			(size 0.1524 0.1524)
			(layers "F.Cu" "F.Mask" "F.Paste")
			(net "GND")
			(options
				(clearance outline)
				(anchor circle)
			)
			(primitives
				(gr_poly
					(pts
						(arc
							(start 0.3048 -0.2032)
							(mid 0.275042 -0.275042)
							(end 0.2032 -0.3048)
						)
						(arc
							(start -0.2032 -0.3048)
							(mid -0.275042 -0.275042)
							(end -0.3048 -0.2032)
						)
						(arc
							(start -0.3048 0.2032)
							(mid -0.275042 0.275042)
							(end -0.2032 0.3048)
						)
						(arc
							(start 0.2032 0.3048)
							(mid 0.275042 0.275042)
							(end 0.3048 0.2032)
						)
					)
					(width 0)
					(fill yes)
				)
			)
		)
	)
	(footprint ""
		(layer "F.Cu")
		(at 51.9684 -63.754 90)
		(property "Reference" "R501"
			(at 0 0 90)
			(layer "F.SilkS")
			(hide yes)
			(effects
				(font
					(size 1.27 1.27)
				)
			)
		)
		(property "Value" "3K3R2F-2-GP"
			(at 0.064008 -3.993896 90)
			(unlocked yes)
			(layer "F.Fab")
			(hide yes)
			(effects
				(font
					(size 1.016 1.016)
					(thickness 0.1524)
				)
			)
		)
		(property "Device Type" "R402H16"
			(at 0.064008 -5.517896 90)
			(unlocked yes)
			(layer "F.Fab")
			(hide yes)
			(effects
				(font
					(size 1.016 1.016)
					(thickness 0.1524)
				)
			)
		)
		(duplicate_pad_numbers_are_jumpers no)
		(fp_line
			(start 0.508 -0.9398)
			(end -0.508 -0.9398)
			(stroke
				(width 0.1524)
				(type default)
			)
			(layer "F.SilkS")
		)
		(fp_line
			(start -0.508 -0.9398)
			(end -0.508 0.9398)
			(stroke
				(width 0.1524)
				(type default)
			)
			(layer "F.SilkS")
		)
		(fp_rect
			(start -0.508 0.9398)
			(end 0.508 -0.9398)
			(stroke
				(width 0)
				(type default)
			)
			(fill no)
			(layer "F.CrtYd")
		)
		(fp_rect
			(start -0.508 0.9398)
			(end 0.508 -0.9398)
			(stroke
				(width 0)
				(type default)
			)
			(fill no)
			(layer "F.Fab")
		)
		(pad "1" smd custom
			(at 0 -0.4445 90)
			(size 0.1397 0.1397)
			(layers "F.Cu" "F.Mask" "F.Paste")
			(net "P3V3_STBY")
			(options
				(clearance outline)
				(anchor circle)
			)
			(primitives
				(gr_poly
					(pts
						(arc
							(start -0.1778 -0.2794)
							(mid -0.249642 -0.249642)
							(end -0.2794 -0.1778)
						)
						(arc
							(start -0.2794 0.1778)
							(mid -0.249642 0.249642)
							(end -0.1778 0.2794)
						)
						(arc
							(start 0.1778 0.2794)
							(mid 0.249642 0.249642)
							(end 0.2794 0.1778)
						)
						(arc
							(start 0.2794 -0.1778)
							(mid 0.249642 -0.249642)
							(end 0.1778 -0.2794)
						)
					)
					(width 0)
					(fill yes)
				)
			)
		)
		(pad "2" smd custom
			(at 0 0.4445 90)
			(size 0.1397 0.1397)
			(layers "F.Cu" "F.Mask" "F.Paste")
			(net "NVM_SO_R")
			(options
				(clearance outline)
				(anchor circle)
			)
			(primitives
				(gr_poly
					(pts
						(arc
							(start -0.1778 -0.2794)
							(mid -0.249642 -0.249642)
							(end -0.2794 -0.1778)
						)
						(arc
							(start -0.2794 0.1778)
							(mid -0.249642 0.249642)
							(end -0.1778 0.2794)
						)
						(arc
							(start 0.1778 0.2794)
							(mid 0.249642 0.249642)
							(end 0.2794 0.1778)
						)
						(arc
							(start 0.2794 -0.1778)
							(mid 0.249642 -0.249642)
							(end 0.1778 -0.2794)
						)
					)
					(width 0)
					(fill yes)
				)
			)
		)
	)
	(footprint ""
		(layer "F.Cu")
		(at 192.405 -30.1752 -90)
		(property "Reference" "R90"
			(at 0 0 270)
			(layer "F.SilkS")
			(hide yes)
			(effects
				(font
					(size 1.27 1.27)
				)
			)
		)
		(property "Value" "0R2J-2-GP"
			(at 0.064008 -3.993896 270)
			(unlocked yes)
			(layer "F.Fab")
			(hide yes)
			(effects
				(font
					(size 1.016 1.016)
					(thickness 0.1524)
				)
			)
		)
		(property "Device Type" "R402H16"
			(at 0.064008 -5.517896 270)
			(unlocked yes)
			(layer "F.Fab")
			(hide yes)
			(effects
				(font
					(size 1.016 1.016)
					(thickness 0.1524)
				)
			)
		)
		(duplicate_pad_numbers_are_jumpers no)
		(fp_line
			(start -0.508 -0.9398)
			(end -0.508 0.9398)
			(stroke
				(width 0.1524)
				(type default)
			)
			(layer "F.SilkS")
		)
		(fp_line
			(start 0.508 -0.9398)
			(end -0.508 -0.9398)
			(stroke
				(width 0.1524)
				(type default)
			)
			(layer "F.SilkS")
		)
		(fp_rect
			(start -0.508 0.9398)
			(end 0.508 -0.9398)
			(stroke
				(width 0)
				(type default)
			)
			(fill no)
			(layer "F.CrtYd")
		)
		(fp_rect
			(start -0.508 0.9398)
			(end 0.508 -0.9398)
			(stroke
				(width 0)
				(type default)
			)
			(fill no)
			(layer "F.Fab")
		)
		(pad "1" smd custom
			(at 0 -0.4445 270)
			(size 0.1397 0.1397)
			(layers "F.Cu" "F.Mask" "F.Paste")
			(net "U55_P0")
			(options
				(clearance outline)
				(anchor circle)
			)
			(primitives
				(gr_poly
					(pts
						(arc
							(start -0.1778 -0.2794)
							(mid -0.249642 -0.249642)
							(end -0.2794 -0.1778)
						)
						(arc
							(start -0.2794 0.1778)
							(mid -0.249642 0.249642)
							(end -0.1778 0.2794)
						)
						(arc
							(start 0.1778 0.2794)
							(mid 0.249642 0.249642)
							(end 0.2794 0.1778)
						)
						(arc
							(start 0.2794 -0.1778)
							(mid 0.249642 -0.249642)
							(end 0.1778 -0.2794)
						)
					)
					(width 0)
					(fill yes)
				)
			)
		)
		(pad "2" smd custom
			(at 0 0.4445 270)
			(size 0.1397 0.1397)
			(layers "F.Cu" "F.Mask" "F.Paste")
			(net "HOST_I2C_RESET_N")
			(options
				(clearance outline)
				(anchor circle)
			)
			(primitives
				(gr_poly
					(pts
						(arc
							(start -0.1778 -0.2794)
							(mid -0.249642 -0.249642)
							(end -0.2794 -0.1778)
						)
						(arc
							(start -0.2794 0.1778)
							(mid -0.249642 0.249642)
							(end -0.1778 0.2794)
						)
						(arc
							(start 0.1778 0.2794)
							(mid 0.249642 0.249642)
							(end 0.2794 0.1778)
						)
						(arc
							(start 0.2794 -0.1778)
							(mid 0.249642 -0.249642)
							(end 0.1778 -0.2794)
						)
					)
					(width 0)
					(fill yes)
				)
			)
		)
	)
	(footprint ""
		(layer "F.Cu")
		(at 329.565 -99.568 180)
		(property "Reference" "R4169"
			(at 0 0 180)
			(layer "F.SilkS")
			(hide yes)
			(effects
				(font
					(size 1.27 1.27)
				)
			)
		)
		(property "Value" "4K7R2F-GP"
			(at 0.064008 -3.993896 180)
			(unlocked yes)
			(layer "F.Fab")
			(hide yes)
			(effects
				(font
					(size 1.016 1.016)
					(thickness 0.1524)
				)
			)
		)
		(property "Device Type" "R402H16"
			(at 0.064008 -5.517896 180)
			(unlocked yes)
			(layer "F.Fab")
			(hide yes)
			(effects
				(font
					(size 1.016 1.016)
					(thickness 0.1524)
				)
			)
		)
		(duplicate_pad_numbers_are_jumpers no)
		(fp_line
			(start 0.508 -0.9398)
			(end -0.508 -0.9398)
			(stroke
				(width 0.1524)
				(type default)
			)
			(layer "F.SilkS")
		)
		(fp_line
			(start -0.508 -0.9398)
			(end -0.508 0.9398)
			(stroke
				(width 0.1524)
				(type default)
			)
			(layer "F.SilkS")
		)
		(fp_rect
			(start -0.508 0.9398)
			(end 0.508 -0.9398)
			(stroke
				(width 0)
				(type default)
			)
			(fill no)
			(layer "F.CrtYd")
		)
		(fp_rect
			(start -0.508 0.9398)
			(end 0.508 -0.9398)
			(stroke
				(width 0)
				(type default)
			)
			(fill no)
			(layer "F.Fab")
		)
		(pad "1" smd custom
			(at 0 -0.4445 180)
			(size 0.1397 0.1397)
			(layers "F.Cu" "F.Mask" "F.Paste")
			(net "VS3_LED")
			(options
				(clearance outline)
				(anchor circle)
			)
			(primitives
				(gr_poly
					(pts
						(arc
							(start -0.1778 -0.2794)
							(mid -0.249642 -0.249642)
							(end -0.2794 -0.1778)
						)
						(arc
							(start -0.2794 0.1778)
							(mid -0.249642 0.249642)
							(end -0.1778 0.2794)
						)
						(arc
							(start 0.1778 0.2794)
							(mid 0.249642 0.249642)
							(end 0.2794 0.1778)
						)
						(arc
							(start 0.2794 -0.1778)
							(mid 0.249642 -0.249642)
							(end 0.1778 -0.2794)
						)
					)
					(width 0)
					(fill yes)
				)
			)
		)
		(pad "2" smd custom
			(at 0 0.4445 180)
			(size 0.1397 0.1397)
			(layers "F.Cu" "F.Mask" "F.Paste")
			(net "P3V3_STBY")
			(options
				(clearance outline)
				(anchor circle)
			)
			(primitives
				(gr_poly
					(pts
						(arc
							(start -0.1778 -0.2794)
							(mid -0.249642 -0.249642)
							(end -0.2794 -0.1778)
						)
						(arc
							(start -0.2794 0.1778)
							(mid -0.249642 0.249642)
							(end -0.1778 0.2794)
						)
						(arc
							(start 0.1778 0.2794)
							(mid 0.249642 0.249642)
							(end 0.2794 0.1778)
						)
						(arc
							(start 0.2794 -0.1778)
							(mid 0.249642 -0.249642)
							(end 0.1778 -0.2794)
						)
					)
					(width 0)
					(fill yes)
				)
			)
		)
	)
	(footprint ""
		(layer "F.Cu")
		(at 329.819 -86.487)
		(property "Reference" "R4176"
			(at 0 0 0)
			(layer "F.SilkS")
			(hide yes)
			(effects
				(font
					(size 1.27 1.27)
				)
			)
		)
		(property "Value" "4K7R2F-GP"
			(at 0.064008 -3.993896 0)
			(unlocked yes)
			(layer "F.Fab")
			(hide yes)
			(effects
				(font
					(size 1.016 1.016)
					(thickness 0.1524)
				)
			)
		)
		(property "Device Type" "R402H16"
			(at 0.064008 -5.517896 0)
			(unlocked yes)
			(layer "F.Fab")
			(hide yes)
			(effects
				(font
					(size 1.016 1.016)
					(thickness 0.1524)
				)
			)
		)
		(duplicate_pad_numbers_are_jumpers no)
		(fp_line
			(start -0.508 -0.9398)
			(end -0.508 0.9398)
			(stroke
				(width 0.1524)
				(type default)
			)
			(layer "F.SilkS")
		)
		(fp_line
			(start 0.508 -0.9398)
			(end -0.508 -0.9398)
			(stroke
				(width 0.1524)
				(type default)
			)
			(layer "F.SilkS")
		)
		(fp_rect
			(start -0.508 0.9398)
			(end 0.508 -0.9398)
			(stroke
				(width 0)
				(type default)
			)
			(fill no)
			(layer "F.CrtYd")
		)
		(fp_rect
			(start -0.508 0.9398)
			(end 0.508 -0.9398)
			(stroke
				(width 0)
				(type default)
			)
			(fill no)
			(layer "F.Fab")
		)
		(pad "1" smd custom
			(at 0 -0.4445)
			(size 0.1397 0.1397)
			(layers "F.Cu" "F.Mask" "F.Paste")
			(net "UPLINK7")
			(options
				(clearance outline)
				(anchor circle)
			)
			(primitives
				(gr_poly
					(pts
						(arc
							(start -0.1778 -0.2794)
							(mid -0.249642 -0.249642)
							(end -0.2794 -0.1778)
						)
						(arc
							(start -0.2794 0.1778)
							(mid -0.249642 0.249642)
							(end -0.1778 0.2794)
						)
						(arc
							(start 0.1778 0.2794)
							(mid 0.249642 0.249642)
							(end 0.2794 0.1778)
						)
						(arc
							(start 0.2794 -0.1778)
							(mid 0.249642 -0.249642)
							(end 0.1778 -0.2794)
						)
					)
					(width 0)
					(fill yes)
				)
			)
		)
		(pad "2" smd custom
			(at 0 0.4445)
			(size 0.1397 0.1397)
			(layers "F.Cu" "F.Mask" "F.Paste")
			(net "P3V3_STBY")
			(options
				(clearance outline)
				(anchor circle)
			)
			(primitives
				(gr_poly
					(pts
						(arc
							(start -0.1778 -0.2794)
							(mid -0.249642 -0.249642)
							(end -0.2794 -0.1778)
						)
						(arc
							(start -0.2794 0.1778)
							(mid -0.249642 0.249642)
							(end -0.1778 0.2794)
						)
						(arc
							(start 0.1778 0.2794)
							(mid 0.249642 0.249642)
							(end 0.2794 0.1778)
						)
						(arc
							(start 0.2794 -0.1778)
							(mid 0.249642 -0.249642)
							(end 0.1778 -0.2794)
						)
					)
					(width 0)
					(fill yes)
				)
			)
		)
	)
	(footprint ""
		(layer "F.Cu")
		(at 21.0058 -134.4422 -90)
		(property "Reference" "R367"
			(at 0 0 270)
			(layer "F.SilkS")
			(hide yes)
			(effects
				(font
					(size 1.27 1.27)
				)
			)
		)
		(property "Value" "3K3R2F-2-GP"
			(at 0.064008 -3.993896 270)
			(unlocked yes)
			(layer "F.Fab")
			(hide yes)
			(effects
				(font
					(size 1.016 1.016)
					(thickness 0.1524)
				)
			)
		)
		(property "Device Type" "R402H16"
			(at 0.064008 -5.517896 270)
			(unlocked yes)
			(layer "F.Fab")
			(hide yes)
			(effects
				(font
					(size 1.016 1.016)
					(thickness 0.1524)
				)
			)
		)
		(duplicate_pad_numbers_are_jumpers no)
		(fp_line
			(start -0.508 -0.9398)
			(end -0.508 0.9398)
			(stroke
				(width 0.1524)
				(type default)
			)
			(layer "F.SilkS")
		)
		(fp_line
			(start 0.508 -0.9398)
			(end -0.508 -0.9398)
			(stroke
				(width 0.1524)
				(type default)
			)
			(layer "F.SilkS")
		)
		(fp_rect
			(start -0.508 0.9398)
			(end 0.508 -0.9398)
			(stroke
				(width 0)
				(type default)
			)
			(fill no)
			(layer "F.CrtYd")
		)
		(fp_rect
			(start -0.508 0.9398)
			(end 0.508 -0.9398)
			(stroke
				(width 0)
				(type default)
			)
			(fill no)
			(layer "F.Fab")
		)
		(pad "1" smd custom
			(at 0 -0.4445 270)
			(size 0.1397 0.1397)
			(layers "F.Cu" "F.Mask" "F.Paste")
			(net "P3V3_STBY")
			(options
				(clearance outline)
				(anchor circle)
			)
			(primitives
				(gr_poly
					(pts
						(arc
							(start -0.1778 -0.2794)
							(mid -0.249642 -0.249642)
							(end -0.2794 -0.1778)
						)
						(arc
							(start -0.2794 0.1778)
							(mid -0.249642 0.249642)
							(end -0.1778 0.2794)
						)
						(arc
							(start 0.1778 0.2794)
							(mid 0.249642 0.249642)
							(end 0.2794 0.1778)
						)
						(arc
							(start 0.2794 -0.1778)
							(mid 0.249642 -0.249642)
							(end 0.1778 -0.2794)
						)
					)
					(width 0)
					(fill yes)
				)
			)
		)
		(pad "2" smd custom
			(at 0 0.4445 270)
			(size 0.1397 0.1397)
			(layers "F.Cu" "F.Mask" "F.Paste")
			(net "ROMA7")
			(options
				(clearance outline)
				(anchor circle)
			)
			(primitives
				(gr_poly
					(pts
						(arc
							(start -0.1778 -0.2794)
							(mid -0.249642 -0.249642)
							(end -0.2794 -0.1778)
						)
						(arc
							(start -0.2794 0.1778)
							(mid -0.249642 0.249642)
							(end -0.1778 0.2794)
						)
						(arc
							(start 0.1778 0.2794)
							(mid 0.249642 0.249642)
							(end 0.2794 0.1778)
						)
						(arc
							(start 0.2794 -0.1778)
							(mid 0.249642 -0.249642)
							(end 0.1778 -0.2794)
						)
					)
					(width 0)
					(fill yes)
				)
			)
		)
	)
	(footprint ""
		(layer "F.Cu")
		(at 158.242 -95.9104)
		(property "Reference" "R100"
			(at 0 0 0)
			(layer "F.SilkS")
			(hide yes)
			(effects
				(font
					(size 1.27 1.27)
				)
			)
		)
		(property "Value" "10KR2F-2-GP"
			(at 0.064008 -3.993896 0)
			(unlocked yes)
			(layer "F.Fab")
			(hide yes)
			(effects
				(font
					(size 1.016 1.016)
					(thickness 0.1524)
				)
			)
		)
		(property "Device Type" "R402H16"
			(at 0.064008 -5.517896 0)
			(unlocked yes)
			(layer "F.Fab")
			(hide yes)
			(effects
				(font
					(size 1.016 1.016)
					(thickness 0.1524)
				)
			)
		)
		(duplicate_pad_numbers_are_jumpers no)
		(fp_line
			(start -0.508 -0.9398)
			(end -0.508 0.9398)
			(stroke
				(width 0.1524)
				(type default)
			)
			(layer "F.SilkS")
		)
		(fp_line
			(start 0.508 -0.9398)
			(end -0.508 -0.9398)
			(stroke
				(width 0.1524)
				(type default)
			)
			(layer "F.SilkS")
		)
		(fp_rect
			(start -0.508 0.9398)
			(end 0.508 -0.9398)
			(stroke
				(width 0)
				(type default)
			)
			(fill no)
			(layer "F.CrtYd")
		)
		(fp_rect
			(start -0.508 0.9398)
			(end 0.508 -0.9398)
			(stroke
				(width 0)
				(type default)
			)
			(fill no)
			(layer "F.Fab")
		)
		(pad "1" smd custom
			(at 0 -0.4445)
			(size 0.1397 0.1397)
			(layers "F.Cu" "F.Mask" "F.Paste")
			(net "GND")
			(options
				(clearance outline)
				(anchor circle)
			)
			(primitives
				(gr_poly
					(pts
						(arc
							(start -0.1778 -0.2794)
							(mid -0.249642 -0.249642)
							(end -0.2794 -0.1778)
						)
						(arc
							(start -0.2794 0.1778)
							(mid -0.249642 0.249642)
							(end -0.1778 0.2794)
						)
						(arc
							(start 0.1778 0.2794)
							(mid 0.249642 0.249642)
							(end 0.2794 0.1778)
						)
						(arc
							(start 0.2794 -0.1778)
							(mid 0.249642 -0.249642)
							(end 0.1778 -0.2794)
						)
					)
					(width 0)
					(fill yes)
				)
			)
		)
		(pad "2" smd custom
			(at 0 0.4445)
			(size 0.1397 0.1397)
			(layers "F.Cu" "F.Mask" "F.Paste")
			(net "CLKGEN_PWGD")
			(options
				(clearance outline)
				(anchor circle)
			)
			(primitives
				(gr_poly
					(pts
						(arc
							(start -0.1778 -0.2794)
							(mid -0.249642 -0.249642)
							(end -0.2794 -0.1778)
						)
						(arc
							(start -0.2794 0.1778)
							(mid -0.249642 0.249642)
							(end -0.1778 0.2794)
						)
						(arc
							(start 0.1778 0.2794)
							(mid 0.249642 0.249642)
							(end 0.2794 0.1778)
						)
						(arc
							(start 0.2794 -0.1778)
							(mid 0.249642 -0.249642)
							(end 0.1778 -0.2794)
						)
					)
					(width 0)
					(fill yes)
				)
			)
		)
	)
	(footprint ""
		(layer "F.Cu")
		(at 74.950066 -195.6689 180)
		(property "Reference" "R7945"
			(at 0 0 180)
			(layer "F.SilkS")
			(hide yes)
			(effects
				(font
					(size 1.27 1.27)
				)
			)
		)
		(property "Value" "0R2J-2-GP"
			(at 0.064008 -3.993896 180)
			(unlocked yes)
			(layer "F.Fab")
			(hide yes)
			(effects
				(font
					(size 1.016 1.016)
					(thickness 0.1524)
				)
			)
		)
		(property "Device Type" "R402H16"
			(at 0.064008 -5.517896 180)
			(unlocked yes)
			(layer "F.Fab")
			(hide yes)
			(effects
				(font
					(size 1.016 1.016)
					(thickness 0.1524)
				)
			)
		)
		(duplicate_pad_numbers_are_jumpers no)
		(fp_line
			(start 0.508 -0.9398)
			(end -0.508 -0.9398)
			(stroke
				(width 0.1524)
				(type default)
			)
			(layer "F.SilkS")
		)
		(fp_line
			(start -0.508 -0.9398)
			(end -0.508 0.9398)
			(stroke
				(width 0.1524)
				(type default)
			)
			(layer "F.SilkS")
		)
		(fp_rect
			(start -0.508 0.9398)
			(end 0.508 -0.9398)
			(stroke
				(width 0)
				(type default)
			)
			(fill no)
			(layer "F.CrtYd")
		)
		(fp_rect
			(start -0.508 0.9398)
			(end 0.508 -0.9398)
			(stroke
				(width 0)
				(type default)
			)
			(fill no)
			(layer "F.Fab")
		)
		(pad "1" smd custom
			(at 0 -0.4445 180)
			(size 0.1397 0.1397)
			(layers "F.Cu" "F.Mask" "F.Paste")
			(net "SSD_ATNLED#11")
			(options
				(clearance outline)
				(anchor circle)
			)
			(primitives
				(gr_poly
					(pts
						(arc
							(start -0.1778 -0.2794)
							(mid -0.249642 -0.249642)
							(end -0.2794 -0.1778)
						)
						(arc
							(start -0.2794 0.1778)
							(mid -0.249642 0.249642)
							(end -0.1778 0.2794)
						)
						(arc
							(start 0.1778 0.2794)
							(mid 0.249642 0.249642)
							(end 0.2794 0.1778)
						)
						(arc
							(start 0.2794 -0.1778)
							(mid 0.249642 -0.249642)
							(end 0.1778 -0.2794)
						)
					)
					(width 0)
					(fill yes)
				)
			)
		)
		(pad "2" smd custom
			(at 0 0.4445 180)
			(size 0.1397 0.1397)
			(layers "F.Cu" "F.Mask" "F.Paste")
			(net "SSD_ATNLED#11_R")
			(options
				(clearance outline)
				(anchor circle)
			)
			(primitives
				(gr_poly
					(pts
						(arc
							(start -0.1778 -0.2794)
							(mid -0.249642 -0.249642)
							(end -0.2794 -0.1778)
						)
						(arc
							(start -0.2794 0.1778)
							(mid -0.249642 0.249642)
							(end -0.1778 0.2794)
						)
						(arc
							(start 0.1778 0.2794)
							(mid 0.249642 0.249642)
							(end 0.2794 0.1778)
						)
						(arc
							(start 0.2794 -0.1778)
							(mid 0.249642 -0.249642)
							(end 0.1778 -0.2794)
						)
					)
					(width 0)
					(fill yes)
				)
			)
		)
	)
	(footprint ""
		(layer "F.Cu")
		(at 36.1442 -77.8256 90)
		(property "Reference" "PC71"
			(at 0 0 90)
			(layer "F.SilkS")
			(hide yes)
			(effects
				(font
					(size 1.27 1.27)
				)
			)
		)
		(property "Value" "SCD1U50V3KX-GP"
			(at 0 -2.8194 90)
			(unlocked yes)
			(layer "F.Fab")
			(hide yes)
			(effects
				(font
					(size 1.016 1.016)
					(thickness 0.1524)
				)
			)
		)
		(property "Device Type" "C603H36"
			(at 0 -4.3434 90)
			(unlocked yes)
			(layer "F.Fab")
			(hide yes)
			(effects
				(font
					(size 1.016 1.016)
					(thickness 0.1524)
				)
			)
		)
		(duplicate_pad_numbers_are_jumpers no)
		(fp_line
			(start 0.508 0)
			(end -0.508 0)
			(stroke
				(width 0.2032)
				(type default)
			)
			(layer "F.SilkS")
		)
		(fp_rect
			(start -0.5842 1.3335)
			(end 0.5842 -1.3335)
			(stroke
				(width 0)
				(type default)
			)
			(fill no)
			(layer "F.CrtYd")
		)
		(fp_rect
			(start -0.5842 1.3335)
			(end 0.5842 -1.3335)
			(stroke
				(width 0)
				(type default)
			)
			(fill no)
			(layer "F.Fab")
		)
		(pad "1" smd custom
			(at 0 -0.762 90)
			(size 0.2159 0.2159)
			(layers "F.Cu" "F.Mask" "F.Paste")
			(net "P5V_STBY_BS_RC")
			(options
				(clearance outline)
				(anchor circle)
			)
			(primitives
				(gr_poly
					(pts
						(arc
							(start -0.3302 -0.4318)
							(mid -0.402042 -0.402042)
							(end -0.4318 -0.3302)
						)
						(arc
							(start -0.4318 0.3302)
							(mid -0.402042 0.402042)
							(end -0.3302 0.4318)
						)
						(arc
							(start 0.3302 0.4318)
							(mid 0.402042 0.402042)
							(end 0.4318 0.3302)
						)
						(arc
							(start 0.4318 -0.3302)
							(mid 0.402042 -0.402042)
							(end 0.3302 -0.4318)
						)
					)
					(width 0)
					(fill yes)
				)
			)
		)
		(pad "2" smd custom
			(at 0 0.762 90)
			(size 0.2159 0.2159)
			(layers "F.Cu" "F.Mask" "F.Paste")
			(net "P5V_STBY_LX")
			(options
				(clearance outline)
				(anchor circle)
			)
			(primitives
				(gr_poly
					(pts
						(arc
							(start -0.3302 -0.4318)
							(mid -0.402042 -0.402042)
							(end -0.4318 -0.3302)
						)
						(arc
							(start -0.4318 0.3302)
							(mid -0.402042 0.402042)
							(end -0.3302 0.4318)
						)
						(arc
							(start 0.3302 0.4318)
							(mid 0.402042 0.402042)
							(end 0.4318 0.3302)
						)
						(arc
							(start 0.4318 -0.3302)
							(mid 0.402042 -0.402042)
							(end 0.3302 -0.4318)
						)
					)
					(width 0)
					(fill yes)
				)
			)
		)
	)
	(footprint ""
		(layer "F.Cu")
		(at 155.921202 -54.256432 -90)
		(property "Reference" "PR179"
			(at 0 0 270)
			(layer "F.SilkS")
			(hide yes)
			(effects
				(font
					(size 1.27 1.27)
				)
			)
		)
		(property "Value" "10KR2F-2-GP"
			(at 0.064008 -3.993896 270)
			(unlocked yes)
			(layer "F.Fab")
			(hide yes)
			(effects
				(font
					(size 1.016 1.016)
					(thickness 0.1524)
				)
			)
		)
		(property "Device Type" "R402H16"
			(at 0.064008 -5.517896 270)
			(unlocked yes)
			(layer "F.Fab")
			(hide yes)
			(effects
				(font
					(size 1.016 1.016)
					(thickness 0.1524)
				)
			)
		)
		(duplicate_pad_numbers_are_jumpers no)
		(fp_line
			(start -0.508 -0.9398)
			(end -0.508 0.9398)
			(stroke
				(width 0.1524)
				(type default)
			)
			(layer "F.SilkS")
		)
		(fp_line
			(start 0.508 -0.9398)
			(end -0.508 -0.9398)
			(stroke
				(width 0.1524)
				(type default)
			)
			(layer "F.SilkS")
		)
		(fp_rect
			(start -0.508 0.9398)
			(end 0.508 -0.9398)
			(stroke
				(width 0)
				(type default)
			)
			(fill no)
			(layer "F.CrtYd")
		)
		(fp_rect
			(start -0.508 0.9398)
			(end 0.508 -0.9398)
			(stroke
				(width 0)
				(type default)
			)
			(fill no)
			(layer "F.Fab")
		)
		(pad "1" smd custom
			(at 0 -0.4445 270)
			(size 0.1397 0.1397)
			(layers "F.Cu" "F.Mask" "F.Paste")
			(net "P0V9_VFB")
			(options
				(clearance outline)
				(anchor circle)
			)
			(primitives
				(gr_poly
					(pts
						(arc
							(start -0.1778 -0.2794)
							(mid -0.249642 -0.249642)
							(end -0.2794 -0.1778)
						)
						(arc
							(start -0.2794 0.1778)
							(mid -0.249642 0.249642)
							(end -0.1778 0.2794)
						)
						(arc
							(start 0.1778 0.2794)
							(mid 0.249642 0.249642)
							(end 0.2794 0.1778)
						)
						(arc
							(start 0.2794 -0.1778)
							(mid 0.249642 -0.249642)
							(end 0.1778 -0.2794)
						)
					)
					(width 0)
					(fill yes)
				)
			)
		)
		(pad "2" smd custom
			(at 0 0.4445 270)
			(size 0.1397 0.1397)
			(layers "F.Cu" "F.Mask" "F.Paste")
			(net "AGND_P0V9")
			(options
				(clearance outline)
				(anchor circle)
			)
			(primitives
				(gr_poly
					(pts
						(arc
							(start -0.1778 -0.2794)
							(mid -0.249642 -0.249642)
							(end -0.2794 -0.1778)
						)
						(arc
							(start -0.2794 0.1778)
							(mid -0.249642 0.249642)
							(end -0.1778 0.2794)
						)
						(arc
							(start 0.1778 0.2794)
							(mid 0.249642 0.249642)
							(end 0.2794 0.1778)
						)
						(arc
							(start 0.2794 -0.1778)
							(mid 0.249642 -0.249642)
							(end 0.1778 -0.2794)
						)
					)
					(width 0)
					(fill yes)
				)
			)
		)
	)
	(footprint ""
		(layer "F.Cu")
		(at 29.337 -116.713 180)
		(property "Reference" "R237"
			(at 0 0 180)
			(layer "F.SilkS")
			(hide yes)
			(effects
				(font
					(size 1.27 1.27)
				)
			)
		)
		(property "Value" "100KR2F-L1-GP"
			(at 0.064008 -3.993896 180)
			(unlocked yes)
			(layer "F.Fab")
			(hide yes)
			(effects
				(font
					(size 1.016 1.016)
					(thickness 0.1524)
				)
			)
		)
		(property "Device Type" "R402H16"
			(at 0.064008 -5.517896 180)
			(unlocked yes)
			(layer "F.Fab")
			(hide yes)
			(effects
				(font
					(size 1.016 1.016)
					(thickness 0.1524)
				)
			)
		)
		(duplicate_pad_numbers_are_jumpers no)
		(fp_line
			(start 0.508 -0.9398)
			(end -0.508 -0.9398)
			(stroke
				(width 0.1524)
				(type default)
			)
			(layer "F.SilkS")
		)
		(fp_line
			(start -0.508 -0.9398)
			(end -0.508 0.9398)
			(stroke
				(width 0.1524)
				(type default)
			)
			(layer "F.SilkS")
		)
		(fp_rect
			(start -0.508 0.9398)
			(end 0.508 -0.9398)
			(stroke
				(width 0)
				(type default)
			)
			(fill no)
			(layer "F.CrtYd")
		)
		(fp_rect
			(start -0.508 0.9398)
			(end 0.508 -0.9398)
			(stroke
				(width 0)
				(type default)
			)
			(fill no)
			(layer "F.Fab")
		)
		(pad "1" smd custom
			(at 0 -0.4445 180)
			(size 0.1397 0.1397)
			(layers "F.Cu" "F.Mask" "F.Paste")
			(net "GND")
			(options
				(clearance outline)
				(anchor circle)
			)
			(primitives
				(gr_poly
					(pts
						(arc
							(start -0.1778 -0.2794)
							(mid -0.249642 -0.249642)
							(end -0.2794 -0.1778)
						)
						(arc
							(start -0.2794 0.1778)
							(mid -0.249642 0.249642)
							(end -0.1778 0.2794)
						)
						(arc
							(start 0.1778 0.2794)
							(mid 0.249642 0.249642)
							(end 0.2794 0.1778)
						)
						(arc
							(start 0.2794 -0.1778)
							(mid 0.249642 -0.249642)
							(end 0.1778 -0.2794)
						)
					)
					(width 0)
					(fill yes)
				)
			)
		)
		(pad "2" smd custom
			(at 0 0.4445 180)
			(size 0.1397 0.1397)
			(layers "F.Cu" "F.Mask" "F.Paste")
			(net "TP_BMC0_LPC_LAD3")
			(options
				(clearance outline)
				(anchor circle)
			)
			(primitives
				(gr_poly
					(pts
						(arc
							(start -0.1778 -0.2794)
							(mid -0.249642 -0.249642)
							(end -0.2794 -0.1778)
						)
						(arc
							(start -0.2794 0.1778)
							(mid -0.249642 0.249642)
							(end -0.1778 0.2794)
						)
						(arc
							(start 0.1778 0.2794)
							(mid 0.249642 0.249642)
							(end 0.2794 0.1778)
						)
						(arc
							(start 0.2794 -0.1778)
							(mid 0.249642 -0.249642)
							(end 0.1778 -0.2794)
						)
					)
					(width 0)
					(fill yes)
				)
			)
		)
	)
	(footprint ""
		(layer "F.Cu")
		(at 17.2974 -66.6242 180)
		(property "Reference" "R474"
			(at 0 0 180)
			(layer "F.SilkS")
			(hide yes)
			(effects
				(font
					(size 1.27 1.27)
				)
			)
		)
		(property "Value" "0R3J-0-U-GP"
			(at -0.0254 -2.5146 180)
			(unlocked yes)
			(layer "F.Fab")
			(hide yes)
			(effects
				(font
					(size 1.016 1.016)
					(thickness 0.1524)
				)
			)
		)
		(property "Device Type" "R603H22"
			(at -0.0254 -4.0386 180)
			(unlocked yes)
			(layer "F.Fab")
			(hide yes)
			(effects
				(font
					(size 1.016 1.016)
					(thickness 0.1524)
				)
			)
		)
		(duplicate_pad_numbers_are_jumpers no)
		(fp_line
			(start 0.2032 0)
			(end 0.4826 0)
			(stroke
				(width 0.2032)
				(type default)
			)
			(layer "F.SilkS")
		)
		(fp_line
			(start -0.4826 0)
			(end -0.2032 0)
			(stroke
				(width 0.2032)
				(type default)
			)
			(layer "F.SilkS")
		)
		(fp_rect
			(start -0.5842 1.3335)
			(end 0.5842 -1.3335)
			(stroke
				(width 0)
				(type default)
			)
			(fill no)
			(layer "F.CrtYd")
		)
		(fp_rect
			(start -0.5842 1.3335)
			(end 0.5842 -1.3335)
			(stroke
				(width 0)
				(type default)
			)
			(fill no)
			(layer "F.Fab")
		)
		(pad "1" smd custom
			(at 0 -0.762 180)
			(size 0.2159 0.2159)
			(layers "F.Cu" "F.Mask" "F.Paste")
			(net "P1V5_I210")
			(options
				(clearance outline)
				(anchor circle)
			)
			(primitives
				(gr_poly
					(pts
						(arc
							(start -0.3302 -0.4318)
							(mid -0.402042 -0.402042)
							(end -0.4318 -0.3302)
						)
						(arc
							(start -0.4318 0.3302)
							(mid -0.402042 0.402042)
							(end -0.3302 0.4318)
						)
						(arc
							(start 0.3302 0.4318)
							(mid 0.402042 0.402042)
							(end 0.4318 0.3302)
						)
						(arc
							(start 0.4318 -0.3302)
							(mid 0.402042 -0.402042)
							(end 0.3302 -0.4318)
						)
					)
					(width 0)
					(fill yes)
				)
			)
		)
		(pad "2" smd custom
			(at 0 0.762 180)
			(size 0.2159 0.2159)
			(layers "F.Cu" "F.Mask" "F.Paste")
			(net "LAN1_56")
			(options
				(clearance outline)
				(anchor circle)
			)
			(primitives
				(gr_poly
					(pts
						(arc
							(start -0.3302 -0.4318)
							(mid -0.402042 -0.402042)
							(end -0.4318 -0.3302)
						)
						(arc
							(start -0.4318 0.3302)
							(mid -0.402042 0.402042)
							(end -0.3302 0.4318)
						)
						(arc
							(start 0.3302 0.4318)
							(mid 0.402042 0.402042)
							(end 0.4318 0.3302)
						)
						(arc
							(start 0.4318 -0.3302)
							(mid 0.402042 -0.402042)
							(end 0.3302 -0.4318)
						)
					)
					(width 0)
					(fill yes)
				)
			)
		)
	)
	(footprint ""
		(layer "F.Cu")
		(at 28.956 -98.7044 -90)
		(property "Reference" "R2943"
			(at 0 0 270)
			(layer "F.SilkS")
			(hide yes)
			(effects
				(font
					(size 1.27 1.27)
				)
			)
		)
		(property "Value" "10KR2F-2-GP"
			(at 0.064008 -3.993896 270)
			(unlocked yes)
			(layer "F.Fab")
			(hide yes)
			(effects
				(font
					(size 1.016 1.016)
					(thickness 0.1524)
				)
			)
		)
		(property "Device Type" "R402H16"
			(at 0.064008 -5.517896 270)
			(unlocked yes)
			(layer "F.Fab")
			(hide yes)
			(effects
				(font
					(size 1.016 1.016)
					(thickness 0.1524)
				)
			)
		)
		(duplicate_pad_numbers_are_jumpers no)
		(fp_line
			(start -0.508 -0.9398)
			(end -0.508 0.9398)
			(stroke
				(width 0.1524)
				(type default)
			)
			(layer "F.SilkS")
		)
		(fp_line
			(start 0.508 -0.9398)
			(end -0.508 -0.9398)
			(stroke
				(width 0.1524)
				(type default)
			)
			(layer "F.SilkS")
		)
		(fp_rect
			(start -0.508 0.9398)
			(end 0.508 -0.9398)
			(stroke
				(width 0)
				(type default)
			)
			(fill no)
			(layer "F.CrtYd")
		)
		(fp_rect
			(start -0.508 0.9398)
			(end 0.508 -0.9398)
			(stroke
				(width 0)
				(type default)
			)
			(fill no)
			(layer "F.Fab")
		)
		(pad "1" smd custom
			(at 0 -0.4445 270)
			(size 0.1397 0.1397)
			(layers "F.Cu" "F.Mask" "F.Paste")
			(net "P3V3_STBY")
			(options
				(clearance outline)
				(anchor circle)
			)
			(primitives
				(gr_poly
					(pts
						(arc
							(start -0.1778 -0.2794)
							(mid -0.249642 -0.249642)
							(end -0.2794 -0.1778)
						)
						(arc
							(start -0.2794 0.1778)
							(mid -0.249642 0.249642)
							(end -0.1778 0.2794)
						)
						(arc
							(start 0.1778 0.2794)
							(mid 0.249642 0.249642)
							(end 0.2794 0.1778)
						)
						(arc
							(start 0.2794 -0.1778)
							(mid 0.249642 -0.249642)
							(end 0.1778 -0.2794)
						)
					)
					(width 0)
					(fill yes)
				)
			)
		)
		(pad "2" smd custom
			(at 0 0.4445 270)
			(size 0.1397 0.1397)
			(layers "F.Cu" "F.Mask" "F.Paste")
			(net "FM_TPM_PRES_RST")
			(options
				(clearance outline)
				(anchor circle)
			)
			(primitives
				(gr_poly
					(pts
						(arc
							(start -0.1778 -0.2794)
							(mid -0.249642 -0.249642)
							(end -0.2794 -0.1778)
						)
						(arc
							(start -0.2794 0.1778)
							(mid -0.249642 0.249642)
							(end -0.1778 0.2794)
						)
						(arc
							(start 0.1778 0.2794)
							(mid 0.249642 0.249642)
							(end 0.2794 0.1778)
						)
						(arc
							(start 0.2794 -0.1778)
							(mid 0.249642 -0.249642)
							(end 0.1778 -0.2794)
						)
					)
					(width 0)
					(fill yes)
				)
			)
		)
	)
	(footprint ""
		(layer "F.Cu")
		(at 117.03939 -37.975286 180)
		(property "Reference" "Q25"
			(at 0 0 180)
			(layer "F.SilkS")
			(hide yes)
			(effects
				(font
					(size 1.27 1.27)
				)
			)
		)
		(property "Value" "2N7002K-1-GP"
			(at 0.127 -8.9662 180)
			(unlocked yes)
			(layer "F.Fab")
			(hide yes)
			(effects
				(font
					(size 1.016 1.016)
					(thickness 0.1524)
				)
			)
		)
		(property "Device Type" "SOT23DGS2D4H44"
			(at 0.127 -10.4902 180)
			(unlocked yes)
			(layer "F.Fab")
			(hide yes)
			(effects
				(font
					(size 1.016 1.016)
					(thickness 0.1524)
				)
			)
		)
		(duplicate_pad_numbers_are_jumpers no)
		(fp_line
			(start 1.651 1.778)
			(end 1.651 -1.778)
			(stroke
				(width 0.1524)
				(type default)
			)
			(layer "F.SilkS")
		)
		(fp_line
			(start 1.651 -1.778)
			(end -1.651 -1.778)
			(stroke
				(width 0.1524)
				(type default)
			)
			(layer "F.SilkS")
		)
		(fp_line
			(start -1.651 1.778)
			(end 1.651 1.778)
			(stroke
				(width 0.1524)
				(type default)
			)
			(layer "F.SilkS")
		)
		(fp_line
			(start -1.651 -1.778)
			(end -1.651 1.778)
			(stroke
				(width 0.1524)
				(type default)
			)
			(layer "F.SilkS")
		)
		(fp_poly
			(pts
				(xy -1.778 1.8796) (xy -1.778 -1.8796) (xy 1.778 -1.8796) (xy 1.778 1.8796)
			)
			(stroke
				(width 0)
				(type default)
			)
			(fill no)
			(layer "F.CrtYd")
		)
		(fp_poly
			(pts
				(xy -1.778 1.8796) (xy -1.778 -1.8796) (xy 1.778 -1.8796) (xy 1.778 1.8796)
			)
			(stroke
				(width 0)
				(type default)
			)
			(fill no)
			(layer "F.Fab")
		)
		(pad "D" smd custom
			(at 0 -0.9525 180)
			(size 0.1905 0.1905)
			(layers "F.Cu" "F.Mask" "F.Paste")
			(net "LED_Q_2")
			(options
				(clearance outline)
				(anchor circle)
			)
			(primitives
				(gr_poly
					(pts
						(arc
							(start -0.1778 0.5715)
							(mid -0.321484 0.511984)
							(end -0.381 0.3683)
						)
						(arc
							(start -0.381 -0.3683)
							(mid -0.321484 -0.511984)
							(end -0.1778 -0.5715)
						)
						(arc
							(start 0.1778 -0.5715)
							(mid 0.321484 -0.511984)
							(end 0.381 -0.3683)
						)
						(arc
							(start 0.381 0.3683)
							(mid 0.321484 0.511984)
							(end 0.1778 0.5715)
						)
					)
					(width 0)
					(fill yes)
				)
			)
		)
		(pad "G" smd custom
			(at -0.98425 0.9525 180)
			(size 0.1905 0.1905)
			(layers "F.Cu" "F.Mask" "F.Paste")
			(net "UPLINK2_R")
			(options
				(clearance outline)
				(anchor circle)
			)
			(primitives
				(gr_poly
					(pts
						(arc
							(start -0.1778 0.5715)
							(mid -0.321484 0.511984)
							(end -0.381 0.3683)
						)
						(arc
							(start -0.381 -0.3683)
							(mid -0.321484 -0.511984)
							(end -0.1778 -0.5715)
						)
						(arc
							(start 0.1778 -0.5715)
							(mid 0.321484 -0.511984)
							(end 0.381 -0.3683)
						)
						(arc
							(start 0.381 0.3683)
							(mid 0.321484 0.511984)
							(end 0.1778 0.5715)
						)
					)
					(width 0)
					(fill yes)
				)
			)
		)
		(pad "S" smd custom
			(at 0.98425 0.9525 180)
			(size 0.1905 0.1905)
			(layers "F.Cu" "F.Mask" "F.Paste")
			(net "GND")
			(options
				(clearance outline)
				(anchor circle)
			)
			(primitives
				(gr_poly
					(pts
						(arc
							(start -0.1778 0.5715)
							(mid -0.321484 0.511984)
							(end -0.381 0.3683)
						)
						(arc
							(start -0.381 -0.3683)
							(mid -0.321484 -0.511984)
							(end -0.1778 -0.5715)
						)
						(arc
							(start 0.1778 -0.5715)
							(mid 0.321484 -0.511984)
							(end 0.381 -0.3683)
						)
						(arc
							(start 0.381 0.3683)
							(mid 0.321484 0.511984)
							(end 0.1778 0.5715)
						)
					)
					(width 0)
					(fill yes)
				)
			)
		)
	)
	(footprint ""
		(layer "F.Cu")
		(at 56.126126 -110.914688)
		(property "Reference" "R328"
			(at 0 0 0)
			(layer "F.SilkS")
			(hide yes)
			(effects
				(font
					(size 1.27 1.27)
				)
			)
		)
		(property "Value" "4K7R2F-GP"
			(at 0.064008 -3.993896 0)
			(unlocked yes)
			(layer "F.Fab")
			(hide yes)
			(effects
				(font
					(size 1.016 1.016)
					(thickness 0.1524)
				)
			)
		)
		(property "Device Type" "R402H16"
			(at 0.064008 -5.517896 0)
			(unlocked yes)
			(layer "F.Fab")
			(hide yes)
			(effects
				(font
					(size 1.016 1.016)
					(thickness 0.1524)
				)
			)
		)
		(duplicate_pad_numbers_are_jumpers no)
		(fp_line
			(start -0.508 -0.9398)
			(end -0.508 0.9398)
			(stroke
				(width 0.1524)
				(type default)
			)
			(layer "F.SilkS")
		)
		(fp_line
			(start 0.508 -0.9398)
			(end -0.508 -0.9398)
			(stroke
				(width 0.1524)
				(type default)
			)
			(layer "F.SilkS")
		)
		(fp_rect
			(start -0.508 0.9398)
			(end 0.508 -0.9398)
			(stroke
				(width 0)
				(type default)
			)
			(fill no)
			(layer "F.CrtYd")
		)
		(fp_rect
			(start -0.508 0.9398)
			(end 0.508 -0.9398)
			(stroke
				(width 0)
				(type default)
			)
			(fill no)
			(layer "F.Fab")
		)
		(pad "1" smd custom
			(at 0 -0.4445)
			(size 0.1397 0.1397)
			(layers "F.Cu" "F.Mask" "F.Paste")
			(net "P3V3_STBY")
			(options
				(clearance outline)
				(anchor circle)
			)
			(primitives
				(gr_poly
					(pts
						(arc
							(start -0.1778 -0.2794)
							(mid -0.249642 -0.249642)
							(end -0.2794 -0.1778)
						)
						(arc
							(start -0.2794 0.1778)
							(mid -0.249642 0.249642)
							(end -0.1778 0.2794)
						)
						(arc
							(start 0.1778 0.2794)
							(mid 0.249642 0.249642)
							(end 0.2794 0.1778)
						)
						(arc
							(start 0.2794 -0.1778)
							(mid 0.249642 -0.249642)
							(end 0.1778 -0.2794)
						)
					)
					(width 0)
					(fill yes)
				)
			)
		)
		(pad "2" smd custom
			(at 0 0.4445)
			(size 0.1397 0.1397)
			(layers "F.Cu" "F.Mask" "F.Paste")
			(net "I2C7_LS_G2")
			(options
				(clearance outline)
				(anchor circle)
			)
			(primitives
				(gr_poly
					(pts
						(arc
							(start -0.1778 -0.2794)
							(mid -0.249642 -0.249642)
							(end -0.2794 -0.1778)
						)
						(arc
							(start -0.2794 0.1778)
							(mid -0.249642 0.249642)
							(end -0.1778 0.2794)
						)
						(arc
							(start 0.1778 0.2794)
							(mid 0.249642 0.249642)
							(end 0.2794 0.1778)
						)
						(arc
							(start 0.2794 -0.1778)
							(mid 0.249642 -0.249642)
							(end 0.1778 -0.2794)
						)
					)
					(width 0)
					(fill yes)
				)
			)
		)
	)
	(footprint ""
		(layer "F.Cu")
		(at 17.486122 -90.103198 -90)
		(property "Reference" "R390"
			(at 0 0 270)
			(layer "F.SilkS")
			(hide yes)
			(effects
				(font
					(size 1.27 1.27)
				)
			)
		)
		(property "Value" "4K99R2F-L-GP"
			(at 0.064008 -3.993896 270)
			(unlocked yes)
			(layer "F.Fab")
			(hide yes)
			(effects
				(font
					(size 1.016 1.016)
					(thickness 0.1524)
				)
			)
		)
		(property "Device Type" "R402H16"
			(at 0.064008 -5.517896 270)
			(unlocked yes)
			(layer "F.Fab")
			(hide yes)
			(effects
				(font
					(size 1.016 1.016)
					(thickness 0.1524)
				)
			)
		)
		(duplicate_pad_numbers_are_jumpers no)
		(fp_line
			(start -0.508 -0.9398)
			(end -0.508 0.9398)
			(stroke
				(width 0.1524)
				(type default)
			)
			(layer "F.SilkS")
		)
		(fp_line
			(start 0.508 -0.9398)
			(end -0.508 -0.9398)
			(stroke
				(width 0.1524)
				(type default)
			)
			(layer "F.SilkS")
		)
		(fp_rect
			(start -0.508 0.9398)
			(end 0.508 -0.9398)
			(stroke
				(width 0)
				(type default)
			)
			(fill no)
			(layer "F.CrtYd")
		)
		(fp_rect
			(start -0.508 0.9398)
			(end 0.508 -0.9398)
			(stroke
				(width 0)
				(type default)
			)
			(fill no)
			(layer "F.Fab")
		)
		(pad "1" smd custom
			(at 0 -0.4445 270)
			(size 0.1397 0.1397)
			(layers "F.Cu" "F.Mask" "F.Paste")
			(net "GND")
			(options
				(clearance outline)
				(anchor circle)
			)
			(primitives
				(gr_poly
					(pts
						(arc
							(start -0.1778 -0.2794)
							(mid -0.249642 -0.249642)
							(end -0.2794 -0.1778)
						)
						(arc
							(start -0.2794 0.1778)
							(mid -0.249642 0.249642)
							(end -0.1778 0.2794)
						)
						(arc
							(start 0.1778 0.2794)
							(mid 0.249642 0.249642)
							(end 0.2794 0.1778)
						)
						(arc
							(start 0.2794 -0.1778)
							(mid 0.249642 -0.249642)
							(end 0.1778 -0.2794)
						)
					)
					(width 0)
					(fill yes)
				)
			)
		)
		(pad "2" smd custom
			(at 0 0.4445 270)
			(size 0.1397 0.1397)
			(layers "F.Cu" "F.Mask" "F.Paste")
			(net "LAN_SE_RSET")
			(options
				(clearance outline)
				(anchor circle)
			)
			(primitives
				(gr_poly
					(pts
						(arc
							(start -0.1778 -0.2794)
							(mid -0.249642 -0.249642)
							(end -0.2794 -0.1778)
						)
						(arc
							(start -0.2794 0.1778)
							(mid -0.249642 0.249642)
							(end -0.1778 0.2794)
						)
						(arc
							(start 0.1778 0.2794)
							(mid 0.249642 0.249642)
							(end 0.2794 0.1778)
						)
						(arc
							(start 0.2794 -0.1778)
							(mid 0.249642 -0.249642)
							(end 0.1778 -0.2794)
						)
					)
					(width 0)
					(fill yes)
				)
			)
		)
	)
	(footprint ""
		(layer "F.Cu")
		(at 346.689172 -42.697908 90)
		(property "Reference" "R7908"
			(at 0 0 90)
			(layer "F.SilkS")
			(hide yes)
			(effects
				(font
					(size 1.27 1.27)
				)
			)
		)
		(property "Value" "0R2J-2-GP"
			(at 0.064008 -3.993896 90)
			(unlocked yes)
			(layer "F.Fab")
			(hide yes)
			(effects
				(font
					(size 1.016 1.016)
					(thickness 0.1524)
				)
			)
		)
		(property "Device Type" "R402H16"
			(at 0.064008 -5.517896 90)
			(unlocked yes)
			(layer "F.Fab")
			(hide yes)
			(effects
				(font
					(size 1.016 1.016)
					(thickness 0.1524)
				)
			)
		)
		(duplicate_pad_numbers_are_jumpers no)
		(fp_line
			(start 0.508 -0.9398)
			(end -0.508 -0.9398)
			(stroke
				(width 0.1524)
				(type default)
			)
			(layer "F.SilkS")
		)
		(fp_line
			(start -0.508 -0.9398)
			(end -0.508 0.9398)
			(stroke
				(width 0.1524)
				(type default)
			)
			(layer "F.SilkS")
		)
		(fp_rect
			(start -0.508 0.9398)
			(end 0.508 -0.9398)
			(stroke
				(width 0)
				(type default)
			)
			(fill no)
			(layer "F.CrtYd")
		)
		(fp_rect
			(start -0.508 0.9398)
			(end 0.508 -0.9398)
			(stroke
				(width 0)
				(type default)
			)
			(fill no)
			(layer "F.Fab")
		)
		(pad "1" smd custom
			(at 0 -0.4445 90)
			(size 0.1397 0.1397)
			(layers "F.Cu" "F.Mask" "F.Paste")
			(net "HB_OUT")
			(options
				(clearance outline)
				(anchor circle)
			)
			(primitives
				(gr_poly
					(pts
						(arc
							(start -0.1778 -0.2794)
							(mid -0.249642 -0.249642)
							(end -0.2794 -0.1778)
						)
						(arc
							(start -0.2794 0.1778)
							(mid -0.249642 0.249642)
							(end -0.1778 0.2794)
						)
						(arc
							(start 0.1778 0.2794)
							(mid 0.249642 0.249642)
							(end 0.2794 0.1778)
						)
						(arc
							(start 0.2794 -0.1778)
							(mid 0.249642 -0.249642)
							(end 0.1778 -0.2794)
						)
					)
					(width 0)
					(fill yes)
				)
			)
		)
		(pad "2" smd custom
			(at 0 0.4445 90)
			(size 0.1397 0.1397)
			(layers "F.Cu" "F.Mask" "F.Paste")
			(net "Q37_G")
			(options
				(clearance outline)
				(anchor circle)
			)
			(primitives
				(gr_poly
					(pts
						(arc
							(start -0.1778 -0.2794)
							(mid -0.249642 -0.249642)
							(end -0.2794 -0.1778)
						)
						(arc
							(start -0.2794 0.1778)
							(mid -0.249642 0.249642)
							(end -0.1778 0.2794)
						)
						(arc
							(start 0.1778 0.2794)
							(mid 0.249642 0.249642)
							(end 0.2794 0.1778)
						)
						(arc
							(start 0.2794 -0.1778)
							(mid 0.249642 -0.249642)
							(end 0.1778 -0.2794)
						)
					)
					(width 0)
					(fill yes)
				)
			)
		)
	)
	(footprint ""
		(layer "F.Cu")
		(at 66.802 -74.9554)
		(property "Reference" "R963"
			(at 0 0 0)
			(layer "F.SilkS")
			(hide yes)
			(effects
				(font
					(size 1.27 1.27)
				)
			)
		)
		(property "Value" "4K7R2F-GP"
			(at 0.064008 -3.993896 0)
			(unlocked yes)
			(layer "F.Fab")
			(hide yes)
			(effects
				(font
					(size 1.016 1.016)
					(thickness 0.1524)
				)
			)
		)
		(property "Device Type" "R402H16"
			(at 0.064008 -5.517896 0)
			(unlocked yes)
			(layer "F.Fab")
			(hide yes)
			(effects
				(font
					(size 1.016 1.016)
					(thickness 0.1524)
				)
			)
		)
		(duplicate_pad_numbers_are_jumpers no)
		(fp_line
			(start -0.508 -0.9398)
			(end -0.508 0.9398)
			(stroke
				(width 0.1524)
				(type default)
			)
			(layer "F.SilkS")
		)
		(fp_line
			(start 0.508 -0.9398)
			(end -0.508 -0.9398)
			(stroke
				(width 0.1524)
				(type default)
			)
			(layer "F.SilkS")
		)
		(fp_rect
			(start -0.508 0.9398)
			(end 0.508 -0.9398)
			(stroke
				(width 0)
				(type default)
			)
			(fill no)
			(layer "F.CrtYd")
		)
		(fp_rect
			(start -0.508 0.9398)
			(end 0.508 -0.9398)
			(stroke
				(width 0)
				(type default)
			)
			(fill no)
			(layer "F.Fab")
		)
		(pad "1" smd custom
			(at 0 -0.4445)
			(size 0.1397 0.1397)
			(layers "F.Cu" "F.Mask" "F.Paste")
			(net "P3V3_STBY")
			(options
				(clearance outline)
				(anchor circle)
			)
			(primitives
				(gr_poly
					(pts
						(arc
							(start -0.1778 -0.2794)
							(mid -0.249642 -0.249642)
							(end -0.2794 -0.1778)
						)
						(arc
							(start -0.2794 0.1778)
							(mid -0.249642 0.249642)
							(end -0.1778 0.2794)
						)
						(arc
							(start 0.1778 0.2794)
							(mid 0.249642 0.249642)
							(end 0.2794 0.1778)
						)
						(arc
							(start 0.2794 -0.1778)
							(mid 0.249642 -0.249642)
							(end 0.1778 -0.2794)
						)
					)
					(width 0)
					(fill yes)
				)
			)
		)
		(pad "2" smd custom
			(at 0 0.4445)
			(size 0.1397 0.1397)
			(layers "F.Cu" "F.Mask" "F.Paste")
			(net "U19_PERST_N")
			(options
				(clearance outline)
				(anchor circle)
			)
			(primitives
				(gr_poly
					(pts
						(arc
							(start -0.1778 -0.2794)
							(mid -0.249642 -0.249642)
							(end -0.2794 -0.1778)
						)
						(arc
							(start -0.2794 0.1778)
							(mid -0.249642 0.249642)
							(end -0.1778 0.2794)
						)
						(arc
							(start 0.1778 0.2794)
							(mid 0.249642 0.249642)
							(end 0.2794 0.1778)
						)
						(arc
							(start 0.2794 -0.1778)
							(mid 0.249642 -0.249642)
							(end 0.1778 -0.2794)
						)
					)
					(width 0)
					(fill yes)
				)
			)
		)
	)
	(footprint ""
		(layer "F.Cu")
		(at 301.60849 -33.540192)
		(property "Reference" "C16"
			(at 0 0 0)
			(layer "F.SilkS")
			(hide yes)
			(effects
				(font
					(size 1.27 1.27)
				)
			)
		)
		(property "Value" "SCD22U10V2KX-1GP"
			(at 1.1811 -2.7051 0)
			(unlocked yes)
			(layer "F.Fab")
			(hide yes)
			(effects
				(font
					(size 1.016 1.016)
					(thickness 0.1524)
				)
			)
		)
		(property "Device Type" "C402H22"
			(at 1.1811 -4.2291 0)
			(unlocked yes)
			(layer "F.Fab")
			(hide yes)
			(effects
				(font
					(size 1.016 1.016)
					(thickness 0.1524)
				)
			)
		)
		(duplicate_pad_numbers_are_jumpers no)
		(fp_rect
			(start -0.4318 0.9525)
			(end 0.4318 -0.9525)
			(stroke
				(width 0)
				(type default)
			)
			(fill no)
			(layer "F.CrtYd")
		)
		(fp_rect
			(start -0.4318 0.9525)
			(end 0.4318 -0.9525)
			(stroke
				(width 0)
				(type default)
			)
			(fill no)
			(layer "F.Fab")
		)
		(pad "1" smd custom
			(at 0 -0.4445)
			(size 0.1524 0.1524)
			(layers "F.Cu" "F.Mask" "F.Paste")
			(net "PCIE_TX_CAP_P6")
			(options
				(clearance outline)
				(anchor circle)
			)
			(primitives
				(gr_poly
					(pts
						(arc
							(start 0.3048 -0.2032)
							(mid 0.275042 -0.275042)
							(end 0.2032 -0.3048)
						)
						(arc
							(start -0.2032 -0.3048)
							(mid -0.275042 -0.275042)
							(end -0.3048 -0.2032)
						)
						(arc
							(start -0.3048 0.2032)
							(mid -0.275042 0.275042)
							(end -0.2032 0.3048)
						)
						(arc
							(start 0.2032 0.3048)
							(mid 0.275042 0.275042)
							(end 0.3048 0.2032)
						)
					)
					(width 0)
					(fill yes)
				)
			)
		)
		(pad "2" smd custom
			(at 0 0.4445)
			(size 0.1524 0.1524)
			(layers "F.Cu" "F.Mask" "F.Paste")
			(net "PCIE_TX_P6")
			(options
				(clearance outline)
				(anchor circle)
			)
			(primitives
				(gr_poly
					(pts
						(arc
							(start 0.3048 -0.2032)
							(mid 0.275042 -0.275042)
							(end 0.2032 -0.3048)
						)
						(arc
							(start -0.2032 -0.3048)
							(mid -0.275042 -0.275042)
							(end -0.3048 -0.2032)
						)
						(arc
							(start -0.3048 0.2032)
							(mid -0.275042 0.275042)
							(end -0.2032 0.3048)
						)
						(arc
							(start 0.2032 0.3048)
							(mid 0.275042 0.275042)
							(end 0.3048 0.2032)
						)
					)
					(width 0)
					(fill yes)
				)
			)
		)
	)
	(footprint ""
		(layer "F.Cu")
		(at 27.559 -75.2856)
		(property "Reference" "R394"
			(at 0 0 0)
			(layer "F.SilkS")
			(hide yes)
			(effects
				(font
					(size 1.27 1.27)
				)
			)
		)
		(property "Value" "10KR2F-2-GP"
			(at 0.064008 -3.993896 0)
			(unlocked yes)
			(layer "F.Fab")
			(hide yes)
			(effects
				(font
					(size 1.016 1.016)
					(thickness 0.1524)
				)
			)
		)
		(property "Device Type" "R402H16"
			(at 0.064008 -5.517896 0)
			(unlocked yes)
			(layer "F.Fab")
			(hide yes)
			(effects
				(font
					(size 1.016 1.016)
					(thickness 0.1524)
				)
			)
		)
		(duplicate_pad_numbers_are_jumpers no)
		(fp_line
			(start -0.508 -0.9398)
			(end -0.508 0.9398)
			(stroke
				(width 0.1524)
				(type default)
			)
			(layer "F.SilkS")
		)
		(fp_line
			(start 0.508 -0.9398)
			(end -0.508 -0.9398)
			(stroke
				(width 0.1524)
				(type default)
			)
			(layer "F.SilkS")
		)
		(fp_rect
			(start -0.508 0.9398)
			(end 0.508 -0.9398)
			(stroke
				(width 0)
				(type default)
			)
			(fill no)
			(layer "F.CrtYd")
		)
		(fp_rect
			(start -0.508 0.9398)
			(end 0.508 -0.9398)
			(stroke
				(width 0)
				(type default)
			)
			(fill no)
			(layer "F.Fab")
		)
		(pad "1" smd custom
			(at 0 -0.4445)
			(size 0.1397 0.1397)
			(layers "F.Cu" "F.Mask" "F.Paste")
			(net "P3V3_STBY")
			(options
				(clearance outline)
				(anchor circle)
			)
			(primitives
				(gr_poly
					(pts
						(arc
							(start -0.1778 -0.2794)
							(mid -0.249642 -0.249642)
							(end -0.2794 -0.1778)
						)
						(arc
							(start -0.2794 0.1778)
							(mid -0.249642 0.249642)
							(end -0.1778 0.2794)
						)
						(arc
							(start 0.1778 0.2794)
							(mid 0.249642 0.249642)
							(end 0.2794 0.1778)
						)
						(arc
							(start 0.2794 -0.1778)
							(mid 0.249642 -0.249642)
							(end 0.1778 -0.2794)
						)
					)
					(width 0)
					(fill yes)
				)
			)
		)
		(pad "2" smd custom
			(at 0 0.4445)
			(size 0.1397 0.1397)
			(layers "F.Cu" "F.Mask" "F.Paste")
			(net "RMII_PHY_BMC_RXD0")
			(options
				(clearance outline)
				(anchor circle)
			)
			(primitives
				(gr_poly
					(pts
						(arc
							(start -0.1778 -0.2794)
							(mid -0.249642 -0.249642)
							(end -0.2794 -0.1778)
						)
						(arc
							(start -0.2794 0.1778)
							(mid -0.249642 0.249642)
							(end -0.1778 0.2794)
						)
						(arc
							(start 0.1778 0.2794)
							(mid 0.249642 0.249642)
							(end 0.2794 0.1778)
						)
						(arc
							(start 0.2794 -0.1778)
							(mid 0.249642 -0.249642)
							(end 0.1778 -0.2794)
						)
					)
					(width 0)
					(fill yes)
				)
			)
		)
	)
	(footprint ""
		(layer "F.Cu")
		(at 69.2658 -129.794 90)
		(property "Reference" "U49"
			(at 0 0 90)
			(layer "F.SilkS")
			(hide yes)
			(effects
				(font
					(size 1.27 1.27)
				)
			)
		)
		(property "Value" "SN74AUP1T97DCKR-GP"
			(at -2.3622 -8.2042 90)
			(unlocked yes)
			(layer "F.Fab")
			(hide yes)
			(effects
				(font
					(size 1.016 1.016)
					(thickness 0.1524)
				)
			)
		)
		(property "Device Type" "SC70-6H44"
			(at -2.3622 -10.1092 90)
			(unlocked yes)
			(layer "F.Fab")
			(hide yes)
			(effects
				(font
					(size 1.016 1.016)
					(thickness 0.1524)
				)
			)
		)
		(duplicate_pad_numbers_are_jumpers no)
		(fp_line
			(start 1.4478 -1.7018)
			(end -1.4478 -1.7018)
			(stroke
				(width 0.1524)
				(type default)
			)
			(layer "F.SilkS")
		)
		(fp_line
			(start -1.4478 -1.7018)
			(end -1.4478 1.7018)
			(stroke
				(width 0.1524)
				(type default)
			)
			(layer "F.SilkS")
		)
		(fp_line
			(start 1.4478 1.7018)
			(end 1.4478 -1.7018)
			(stroke
				(width 0.1524)
				(type default)
			)
			(layer "F.SilkS")
		)
		(fp_line
			(start -1.4478 1.7018)
			(end 1.4478 1.7018)
			(stroke
				(width 0.1524)
				(type default)
			)
			(layer "F.SilkS")
		)
		(fp_line
			(start -0.5715 1.7907)
			(end -1.5494 1.7907)
			(stroke
				(width 0.3302)
				(type default)
			)
			(layer "F.SilkS")
		)
		(fp_line
			(start -1.5494 1.7907)
			(end -1.5494 0.8255)
			(stroke
				(width 0.3302)
				(type default)
			)
			(layer "F.SilkS")
		)
		(fp_poly
			(pts
				(xy -0.6604 1.7272) (xy -1.016 2.0828) (xy -0.3048 2.0828)
			)
			(stroke
				(width 0)
				(type default)
			)
			(fill yes)
			(layer "F.SilkS")
		)
		(fp_poly
			(pts
				(xy -1.524 -1.778) (xy 1.524 -1.778) (xy 1.524 1.778) (xy -1.524 1.778)
			)
			(stroke
				(width 0)
				(type default)
			)
			(fill no)
			(layer "F.CrtYd")
		)
		(fp_poly
			(pts
				(xy -1.524 -1.778) (xy 1.524 -1.778) (xy 1.524 1.778) (xy -1.524 1.778)
			)
			(stroke
				(width 0)
				(type default)
			)
			(fill no)
			(layer "F.Fab")
		)
		(pad "1" smd rect
			(at -0.65024 0.9398 90)
			(size 0.4064 1.016)
			(layers "F.Cu" "F.Mask" "F.Paste")
			(net "BMC_TXD5_R")
		)
		(pad "2" smd rect
			(at 0 0.9398 90)
			(size 0.4064 1.016)
			(layers "F.Cu" "F.Mask" "F.Paste")
			(net "GND")
		)
		(pad "3" smd rect
			(at 0.65024 0.9398 90)
			(size 0.4064 1.016)
			(layers "F.Cu" "F.Mask" "F.Paste")
			(net "GND")
		)
		(pad "4" smd rect
			(at 0.65024 -0.9398 90)
			(size 0.4064 1.016)
			(layers "F.Cu" "F.Mask" "F.Paste")
			(net "BMC_TXD5")
		)
		(pad "5" smd rect
			(at 0 -0.9398 90)
			(size 0.4064 1.016)
			(layers "F.Cu" "F.Mask" "F.Paste")
			(net "P3V3_STBY")
		)
		(pad "6" smd rect
			(at -0.65024 -0.9398 90)
			(size 0.4064 1.016)
			(layers "F.Cu" "F.Mask" "F.Paste")
			(net "GND")
		)
	)
	(footprint ""
		(layer "F.Cu")
		(at 276.606 -0.127 90)
		(property "Reference" "R2915"
			(at 0 0 90)
			(layer "F.SilkS")
			(hide yes)
			(effects
				(font
					(size 1.27 1.27)
				)
			)
		)
		(property "Value" "0R2J-2-GP"
			(at 0.064008 -3.993896 90)
			(unlocked yes)
			(layer "F.Fab")
			(hide yes)
			(effects
				(font
					(size 1.016 1.016)
					(thickness 0.1524)
				)
			)
		)
		(property "Device Type" "R402H16"
			(at 0.064008 -5.517896 90)
			(unlocked yes)
			(layer "F.Fab")
			(hide yes)
			(effects
				(font
					(size 1.016 1.016)
					(thickness 0.1524)
				)
			)
		)
		(duplicate_pad_numbers_are_jumpers no)
		(fp_line
			(start 0.508 -0.9398)
			(end -0.508 -0.9398)
			(stroke
				(width 0.1524)
				(type default)
			)
			(layer "F.SilkS")
		)
		(fp_line
			(start -0.508 -0.9398)
			(end -0.508 0.9398)
			(stroke
				(width 0.1524)
				(type default)
			)
			(layer "F.SilkS")
		)
		(fp_rect
			(start -0.508 0.9398)
			(end 0.508 -0.9398)
			(stroke
				(width 0)
				(type default)
			)
			(fill no)
			(layer "F.CrtYd")
		)
		(fp_rect
			(start -0.508 0.9398)
			(end 0.508 -0.9398)
			(stroke
				(width 0)
				(type default)
			)
			(fill no)
			(layer "F.Fab")
		)
		(pad "1" smd custom
			(at 0 -0.4445 90)
			(size 0.1397 0.1397)
			(layers "F.Cu" "F.Mask" "F.Paste")
			(net "CBL_PRSNT_N_7")
			(options
				(clearance outline)
				(anchor circle)
			)
			(primitives
				(gr_poly
					(pts
						(arc
							(start -0.1778 -0.2794)
							(mid -0.249642 -0.249642)
							(end -0.2794 -0.1778)
						)
						(arc
							(start -0.2794 0.1778)
							(mid -0.249642 0.249642)
							(end -0.1778 0.2794)
						)
						(arc
							(start 0.1778 0.2794)
							(mid 0.249642 0.249642)
							(end 0.2794 0.1778)
						)
						(arc
							(start 0.2794 -0.1778)
							(mid 0.249642 -0.249642)
							(end 0.1778 -0.2794)
						)
					)
					(width 0)
					(fill yes)
				)
			)
		)
		(pad "2" smd custom
			(at 0 0.4445 90)
			(size 0.1397 0.1397)
			(layers "F.Cu" "F.Mask" "F.Paste")
			(net "8644_SDA_R_7")
			(options
				(clearance outline)
				(anchor circle)
			)
			(primitives
				(gr_poly
					(pts
						(arc
							(start -0.1778 -0.2794)
							(mid -0.249642 -0.249642)
							(end -0.2794 -0.1778)
						)
						(arc
							(start -0.2794 0.1778)
							(mid -0.249642 0.249642)
							(end -0.1778 0.2794)
						)
						(arc
							(start 0.1778 0.2794)
							(mid 0.249642 0.249642)
							(end 0.2794 0.1778)
						)
						(arc
							(start 0.2794 -0.1778)
							(mid 0.249642 -0.249642)
							(end 0.1778 -0.2794)
						)
					)
					(width 0)
					(fill yes)
				)
			)
		)
	)
	(footprint ""
		(layer "F.Cu")
		(at 65.4304 -107.315 -90)
		(property "Reference" "R39"
			(at 0 0 270)
			(layer "F.SilkS")
			(hide yes)
			(effects
				(font
					(size 1.27 1.27)
				)
			)
		)
		(property "Value" "0R2J-2-GP"
			(at 0.064008 -3.993896 270)
			(unlocked yes)
			(layer "F.Fab")
			(hide yes)
			(effects
				(font
					(size 1.016 1.016)
					(thickness 0.1524)
				)
			)
		)
		(property "Device Type" "R402H16"
			(at 0.064008 -5.517896 270)
			(unlocked yes)
			(layer "F.Fab")
			(hide yes)
			(effects
				(font
					(size 1.016 1.016)
					(thickness 0.1524)
				)
			)
		)
		(duplicate_pad_numbers_are_jumpers no)
		(fp_line
			(start -0.508 -0.9398)
			(end -0.508 0.9398)
			(stroke
				(width 0.1524)
				(type default)
			)
			(layer "F.SilkS")
		)
		(fp_line
			(start 0.508 -0.9398)
			(end -0.508 -0.9398)
			(stroke
				(width 0.1524)
				(type default)
			)
			(layer "F.SilkS")
		)
		(fp_rect
			(start -0.508 0.9398)
			(end 0.508 -0.9398)
			(stroke
				(width 0)
				(type default)
			)
			(fill no)
			(layer "F.CrtYd")
		)
		(fp_rect
			(start -0.508 0.9398)
			(end 0.508 -0.9398)
			(stroke
				(width 0)
				(type default)
			)
			(fill no)
			(layer "F.Fab")
		)
		(pad "1" smd custom
			(at 0 -0.4445 270)
			(size 0.1397 0.1397)
			(layers "F.Cu" "F.Mask" "F.Paste")
			(net "BMC_I2C11_MINI5_SCL_S")
			(options
				(clearance outline)
				(anchor circle)
			)
			(primitives
				(gr_poly
					(pts
						(arc
							(start -0.1778 -0.2794)
							(mid -0.249642 -0.249642)
							(end -0.2794 -0.1778)
						)
						(arc
							(start -0.2794 0.1778)
							(mid -0.249642 0.249642)
							(end -0.1778 0.2794)
						)
						(arc
							(start 0.1778 0.2794)
							(mid 0.249642 0.249642)
							(end 0.2794 0.1778)
						)
						(arc
							(start 0.2794 -0.1778)
							(mid 0.249642 -0.249642)
							(end 0.1778 -0.2794)
						)
					)
					(width 0)
					(fill yes)
				)
			)
		)
		(pad "2" smd custom
			(at 0 0.4445 270)
			(size 0.1397 0.1397)
			(layers "F.Cu" "F.Mask" "F.Paste")
			(net "BMC_I2C11_MINI5_SCL")
			(options
				(clearance outline)
				(anchor circle)
			)
			(primitives
				(gr_poly
					(pts
						(arc
							(start -0.1778 -0.2794)
							(mid -0.249642 -0.249642)
							(end -0.2794 -0.1778)
						)
						(arc
							(start -0.2794 0.1778)
							(mid -0.249642 0.249642)
							(end -0.1778 0.2794)
						)
						(arc
							(start 0.1778 0.2794)
							(mid 0.249642 0.249642)
							(end 0.2794 0.1778)
						)
						(arc
							(start 0.2794 -0.1778)
							(mid 0.249642 -0.249642)
							(end 0.1778 -0.2794)
						)
					)
					(width 0)
					(fill yes)
				)
			)
		)
	)
	(footprint ""
		(layer "F.Cu")
		(at 242.6716 -17.9578 180)
		(property "Reference" "R822"
			(at 0 0 180)
			(layer "F.SilkS")
			(hide yes)
			(effects
				(font
					(size 1.27 1.27)
				)
			)
		)
		(property "Value" "4K7R2F-GP"
			(at 0.064008 -3.993896 180)
			(unlocked yes)
			(layer "F.Fab")
			(hide yes)
			(effects
				(font
					(size 1.016 1.016)
					(thickness 0.1524)
				)
			)
		)
		(property "Device Type" "R402H16"
			(at 0.064008 -5.517896 180)
			(unlocked yes)
			(layer "F.Fab")
			(hide yes)
			(effects
				(font
					(size 1.016 1.016)
					(thickness 0.1524)
				)
			)
		)
		(duplicate_pad_numbers_are_jumpers no)
		(fp_line
			(start 0.508 -0.9398)
			(end -0.508 -0.9398)
			(stroke
				(width 0.1524)
				(type default)
			)
			(layer "F.SilkS")
		)
		(fp_line
			(start -0.508 -0.9398)
			(end -0.508 0.9398)
			(stroke
				(width 0.1524)
				(type default)
			)
			(layer "F.SilkS")
		)
		(fp_rect
			(start -0.508 0.9398)
			(end 0.508 -0.9398)
			(stroke
				(width 0)
				(type default)
			)
			(fill no)
			(layer "F.CrtYd")
		)
		(fp_rect
			(start -0.508 0.9398)
			(end 0.508 -0.9398)
			(stroke
				(width 0)
				(type default)
			)
			(fill no)
			(layer "F.Fab")
		)
		(pad "1" smd custom
			(at 0 -0.4445 180)
			(size 0.1397 0.1397)
			(layers "F.Cu" "F.Mask" "F.Paste")
			(net "PM8536_HB")
			(options
				(clearance outline)
				(anchor circle)
			)
			(primitives
				(gr_poly
					(pts
						(arc
							(start -0.1778 -0.2794)
							(mid -0.249642 -0.249642)
							(end -0.2794 -0.1778)
						)
						(arc
							(start -0.2794 0.1778)
							(mid -0.249642 0.249642)
							(end -0.1778 0.2794)
						)
						(arc
							(start 0.1778 0.2794)
							(mid 0.249642 0.249642)
							(end 0.2794 0.1778)
						)
						(arc
							(start 0.2794 -0.1778)
							(mid 0.249642 -0.249642)
							(end 0.1778 -0.2794)
						)
					)
					(width 0)
					(fill yes)
				)
			)
		)
		(pad "2" smd custom
			(at 0 0.4445 180)
			(size 0.1397 0.1397)
			(layers "F.Cu" "F.Mask" "F.Paste")
			(net "P3V3_GPIO")
			(options
				(clearance outline)
				(anchor circle)
			)
			(primitives
				(gr_poly
					(pts
						(arc
							(start -0.1778 -0.2794)
							(mid -0.249642 -0.249642)
							(end -0.2794 -0.1778)
						)
						(arc
							(start -0.2794 0.1778)
							(mid -0.249642 0.249642)
							(end -0.1778 0.2794)
						)
						(arc
							(start 0.1778 0.2794)
							(mid 0.249642 0.249642)
							(end 0.2794 0.1778)
						)
						(arc
							(start 0.2794 -0.1778)
							(mid 0.249642 -0.249642)
							(end 0.1778 -0.2794)
						)
					)
					(width 0)
					(fill yes)
				)
			)
		)
	)
	(footprint ""
		(layer "F.Cu")
		(at 47.244 -182.499 180)
		(property "Reference" "R896"
			(at 0 0 180)
			(layer "F.SilkS")
			(hide yes)
			(effects
				(font
					(size 1.27 1.27)
				)
			)
		)
		(property "Value" "10KR2F-2-GP"
			(at 0.064008 -3.993896 180)
			(unlocked yes)
			(layer "F.Fab")
			(hide yes)
			(effects
				(font
					(size 1.016 1.016)
					(thickness 0.1524)
				)
			)
		)
		(property "Device Type" "R402H16"
			(at 0.064008 -5.517896 180)
			(unlocked yes)
			(layer "F.Fab")
			(hide yes)
			(effects
				(font
					(size 1.016 1.016)
					(thickness 0.1524)
				)
			)
		)
		(duplicate_pad_numbers_are_jumpers no)
		(fp_line
			(start 0.508 -0.9398)
			(end -0.508 -0.9398)
			(stroke
				(width 0.1524)
				(type default)
			)
			(layer "F.SilkS")
		)
		(fp_line
			(start -0.508 -0.9398)
			(end -0.508 0.9398)
			(stroke
				(width 0.1524)
				(type default)
			)
			(layer "F.SilkS")
		)
		(fp_rect
			(start -0.508 0.9398)
			(end 0.508 -0.9398)
			(stroke
				(width 0)
				(type default)
			)
			(fill no)
			(layer "F.CrtYd")
		)
		(fp_rect
			(start -0.508 0.9398)
			(end 0.508 -0.9398)
			(stroke
				(width 0)
				(type default)
			)
			(fill no)
			(layer "F.Fab")
		)
		(pad "1" smd custom
			(at 0 -0.4445 180)
			(size 0.1397 0.1397)
			(layers "F.Cu" "F.Mask" "F.Paste")
			(net "I2C8_BUF_READY")
			(options
				(clearance outline)
				(anchor circle)
			)
			(primitives
				(gr_poly
					(pts
						(arc
							(start -0.1778 -0.2794)
							(mid -0.249642 -0.249642)
							(end -0.2794 -0.1778)
						)
						(arc
							(start -0.2794 0.1778)
							(mid -0.249642 0.249642)
							(end -0.1778 0.2794)
						)
						(arc
							(start 0.1778 0.2794)
							(mid 0.249642 0.249642)
							(end 0.2794 0.1778)
						)
						(arc
							(start 0.2794 -0.1778)
							(mid 0.249642 -0.249642)
							(end 0.1778 -0.2794)
						)
					)
					(width 0)
					(fill yes)
				)
			)
		)
		(pad "2" smd custom
			(at 0 0.4445 180)
			(size 0.1397 0.1397)
			(layers "F.Cu" "F.Mask" "F.Paste")
			(net "P3V3_STBY")
			(options
				(clearance outline)
				(anchor circle)
			)
			(primitives
				(gr_poly
					(pts
						(arc
							(start -0.1778 -0.2794)
							(mid -0.249642 -0.249642)
							(end -0.2794 -0.1778)
						)
						(arc
							(start -0.2794 0.1778)
							(mid -0.249642 0.249642)
							(end -0.1778 0.2794)
						)
						(arc
							(start 0.1778 0.2794)
							(mid 0.249642 0.249642)
							(end 0.2794 0.1778)
						)
						(arc
							(start 0.2794 -0.1778)
							(mid 0.249642 -0.249642)
							(end 0.1778 -0.2794)
						)
					)
					(width 0)
					(fill yes)
				)
			)
		)
	)
	(footprint ""
		(layer "F.Cu")
		(at 13.462 -52.3748 180)
		(property "Reference" "R596"
			(at 0 0 180)
			(layer "F.SilkS")
			(hide yes)
			(effects
				(font
					(size 1.27 1.27)
				)
			)
		)
		(property "Value" "0R2J-2-GP"
			(at 0.064008 -3.993896 180)
			(unlocked yes)
			(layer "F.Fab")
			(hide yes)
			(effects
				(font
					(size 1.016 1.016)
					(thickness 0.1524)
				)
			)
		)
		(property "Device Type" "R402H16"
			(at 0.064008 -5.517896 180)
			(unlocked yes)
			(layer "F.Fab")
			(hide yes)
			(effects
				(font
					(size 1.016 1.016)
					(thickness 0.1524)
				)
			)
		)
		(duplicate_pad_numbers_are_jumpers no)
		(fp_line
			(start 0.508 -0.9398)
			(end -0.508 -0.9398)
			(stroke
				(width 0.1524)
				(type default)
			)
			(layer "F.SilkS")
		)
		(fp_line
			(start -0.508 -0.9398)
			(end -0.508 0.9398)
			(stroke
				(width 0.1524)
				(type default)
			)
			(layer "F.SilkS")
		)
		(fp_rect
			(start -0.508 0.9398)
			(end 0.508 -0.9398)
			(stroke
				(width 0)
				(type default)
			)
			(fill no)
			(layer "F.CrtYd")
		)
		(fp_rect
			(start -0.508 0.9398)
			(end 0.508 -0.9398)
			(stroke
				(width 0)
				(type default)
			)
			(fill no)
			(layer "F.Fab")
		)
		(pad "1" smd custom
			(at 0 -0.4445 180)
			(size 0.1397 0.1397)
			(layers "F.Cu" "F.Mask" "F.Paste")
			(net "NIC0_MDI0_N1_R")
			(options
				(clearance outline)
				(anchor circle)
			)
			(primitives
				(gr_poly
					(pts
						(arc
							(start -0.1778 -0.2794)
							(mid -0.249642 -0.249642)
							(end -0.2794 -0.1778)
						)
						(arc
							(start -0.2794 0.1778)
							(mid -0.249642 0.249642)
							(end -0.1778 0.2794)
						)
						(arc
							(start 0.1778 0.2794)
							(mid 0.249642 0.249642)
							(end 0.2794 0.1778)
						)
						(arc
							(start 0.2794 -0.1778)
							(mid 0.249642 -0.249642)
							(end 0.1778 -0.2794)
						)
					)
					(width 0)
					(fill yes)
				)
			)
		)
		(pad "2" smd custom
			(at 0 0.4445 180)
			(size 0.1397 0.1397)
			(layers "F.Cu" "F.Mask" "F.Paste")
			(net "NIC0_MDI0_N1")
			(options
				(clearance outline)
				(anchor circle)
			)
			(primitives
				(gr_poly
					(pts
						(arc
							(start -0.1778 -0.2794)
							(mid -0.249642 -0.249642)
							(end -0.2794 -0.1778)
						)
						(arc
							(start -0.2794 0.1778)
							(mid -0.249642 0.249642)
							(end -0.1778 0.2794)
						)
						(arc
							(start 0.1778 0.2794)
							(mid 0.249642 0.249642)
							(end 0.2794 0.1778)
						)
						(arc
							(start 0.2794 -0.1778)
							(mid 0.249642 -0.249642)
							(end 0.1778 -0.2794)
						)
					)
					(width 0)
					(fill yes)
				)
			)
		)
	)
	(footprint ""
		(layer "F.Cu")
		(at 78.343506 -82.855054 90)
		(property "Reference" "SC1310"
			(at 0 0 90)
			(layer "F.SilkS")
			(hide yes)
			(effects
				(font
					(size 1.27 1.27)
				)
			)
		)
		(property "Value" "SC10U6D3V5KX-4GP"
			(at -0.0762 -6.1214 90)
			(unlocked yes)
			(layer "F.Fab")
			(hide yes)
			(effects
				(font
					(size 1.016 1.016)
					(thickness 0.1524)
				)
			)
		)
		(property "Device Type" "C805H58"
			(at -0.0762 -8.1534 90)
			(unlocked yes)
			(layer "F.Fab")
			(hide yes)
			(effects
				(font
					(size 1.016 1.016)
					(thickness 0.1524)
				)
			)
		)
		(duplicate_pad_numbers_are_jumpers no)
		(fp_line
			(start 0.635 0)
			(end -0.635 0)
			(stroke
				(width 0.508)
				(type default)
			)
			(layer "F.SilkS")
		)
		(fp_rect
			(start -0.9652 1.778)
			(end 0.9652 -1.778)
			(stroke
				(width 0)
				(type default)
			)
			(fill no)
			(layer "F.CrtYd")
		)
		(fp_poly
			(pts
				(xy -0.9652 -1.778) (xy 0.9652 -1.778) (xy 0.9652 1.778) (xy -0.9652 1.778)
			)
			(stroke
				(width 0)
				(type default)
			)
			(fill no)
			(layer "F.Fab")
		)
		(pad "1" smd rect
			(at 0 -0.9652 90)
			(size 1.397 1.143)
			(layers "F.Cu" "F.Mask" "F.Paste")
			(net "HB_A_IN")
		)
		(pad "2" smd rect
			(at 0 0.9652 90)
			(size 1.397 1.143)
			(layers "F.Cu" "F.Mask" "F.Paste")
			(net "GND")
		)
	)
	(footprint ""
		(layer "F.Cu")
		(at 259.85724 -0.514096 -90)
		(property "Reference" "R7982"
			(at 0 0 270)
			(layer "F.SilkS")
			(hide yes)
			(effects
				(font
					(size 1.27 1.27)
				)
			)
		)
		(property "Value" "0R2J-2-GP"
			(at 0.064008 -3.993896 270)
			(unlocked yes)
			(layer "F.Fab")
			(hide yes)
			(effects
				(font
					(size 1.016 1.016)
					(thickness 0.1524)
				)
			)
		)
		(property "Device Type" "R402H16"
			(at 0.064008 -5.517896 270)
			(unlocked yes)
			(layer "F.Fab")
			(hide yes)
			(effects
				(font
					(size 1.016 1.016)
					(thickness 0.1524)
				)
			)
		)
		(duplicate_pad_numbers_are_jumpers no)
		(fp_line
			(start -0.508 -0.9398)
			(end -0.508 0.9398)
			(stroke
				(width 0.1524)
				(type default)
			)
			(layer "F.SilkS")
		)
		(fp_line
			(start 0.508 -0.9398)
			(end -0.508 -0.9398)
			(stroke
				(width 0.1524)
				(type default)
			)
			(layer "F.SilkS")
		)
		(fp_rect
			(start -0.508 0.9398)
			(end 0.508 -0.9398)
			(stroke
				(width 0)
				(type default)
			)
			(fill no)
			(layer "F.CrtYd")
		)
		(fp_rect
			(start -0.508 0.9398)
			(end 0.508 -0.9398)
			(stroke
				(width 0)
				(type default)
			)
			(fill no)
			(layer "F.Fab")
		)
		(pad "1" smd custom
			(at 0 -0.4445 270)
			(size 0.1397 0.1397)
			(layers "F.Cu" "F.Mask" "F.Paste")
			(net "RST_BTN#")
			(options
				(clearance outline)
				(anchor circle)
			)
			(primitives
				(gr_poly
					(pts
						(arc
							(start -0.1778 -0.2794)
							(mid -0.249642 -0.249642)
							(end -0.2794 -0.1778)
						)
						(arc
							(start -0.2794 0.1778)
							(mid -0.249642 0.249642)
							(end -0.1778 0.2794)
						)
						(arc
							(start 0.1778 0.2794)
							(mid 0.249642 0.249642)
							(end 0.2794 0.1778)
						)
						(arc
							(start 0.2794 -0.1778)
							(mid 0.249642 -0.249642)
							(end 0.1778 -0.2794)
						)
					)
					(width 0)
					(fill yes)
				)
			)
		)
		(pad "2" smd custom
			(at 0 0.4445 270)
			(size 0.1397 0.1397)
			(layers "F.Cu" "F.Mask" "F.Paste")
			(net "DP_RST_N")
			(options
				(clearance outline)
				(anchor circle)
			)
			(primitives
				(gr_poly
					(pts
						(arc
							(start -0.1778 -0.2794)
							(mid -0.249642 -0.249642)
							(end -0.2794 -0.1778)
						)
						(arc
							(start -0.2794 0.1778)
							(mid -0.249642 0.249642)
							(end -0.1778 0.2794)
						)
						(arc
							(start 0.1778 0.2794)
							(mid 0.249642 0.249642)
							(end 0.2794 0.1778)
						)
						(arc
							(start 0.2794 -0.1778)
							(mid 0.249642 -0.249642)
							(end 0.1778 -0.2794)
						)
					)
					(width 0)
					(fill yes)
				)
			)
		)
	)
	(footprint ""
		(layer "F.Cu")
		(at 226.390454 -3.778758)
		(property "Reference" "R176"
			(at 0 0 0)
			(layer "F.SilkS")
			(hide yes)
			(effects
				(font
					(size 1.27 1.27)
				)
			)
		)
		(property "Value" "4K7R2F-GP"
			(at 0.064008 -3.993896 0)
			(unlocked yes)
			(layer "F.Fab")
			(hide yes)
			(effects
				(font
					(size 1.016 1.016)
					(thickness 0.1524)
				)
			)
		)
		(property "Device Type" "R402H16"
			(at 0.064008 -5.517896 0)
			(unlocked yes)
			(layer "F.Fab")
			(hide yes)
			(effects
				(font
					(size 1.016 1.016)
					(thickness 0.1524)
				)
			)
		)
		(duplicate_pad_numbers_are_jumpers no)
		(fp_line
			(start -0.508 -0.9398)
			(end -0.508 0.9398)
			(stroke
				(width 0.1524)
				(type default)
			)
			(layer "F.SilkS")
		)
		(fp_line
			(start 0.508 -0.9398)
			(end -0.508 -0.9398)
			(stroke
				(width 0.1524)
				(type default)
			)
			(layer "F.SilkS")
		)
		(fp_rect
			(start -0.508 0.9398)
			(end 0.508 -0.9398)
			(stroke
				(width 0)
				(type default)
			)
			(fill no)
			(layer "F.CrtYd")
		)
		(fp_rect
			(start -0.508 0.9398)
			(end 0.508 -0.9398)
			(stroke
				(width 0)
				(type default)
			)
			(fill no)
			(layer "F.Fab")
		)
		(pad "1" smd custom
			(at 0 -0.4445)
			(size 0.1397 0.1397)
			(layers "F.Cu" "F.Mask" "F.Paste")
			(net "UART_SWITCH_R")
			(options
				(clearance outline)
				(anchor circle)
			)
			(primitives
				(gr_poly
					(pts
						(arc
							(start -0.1778 -0.2794)
							(mid -0.249642 -0.249642)
							(end -0.2794 -0.1778)
						)
						(arc
							(start -0.2794 0.1778)
							(mid -0.249642 0.249642)
							(end -0.1778 0.2794)
						)
						(arc
							(start 0.1778 0.2794)
							(mid 0.249642 0.249642)
							(end 0.2794 0.1778)
						)
						(arc
							(start 0.2794 -0.1778)
							(mid 0.249642 -0.249642)
							(end 0.1778 -0.2794)
						)
					)
					(width 0)
					(fill yes)
				)
			)
		)
		(pad "2" smd custom
			(at 0 0.4445)
			(size 0.1397 0.1397)
			(layers "F.Cu" "F.Mask" "F.Paste")
			(net "GND")
			(options
				(clearance outline)
				(anchor circle)
			)
			(primitives
				(gr_poly
					(pts
						(arc
							(start -0.1778 -0.2794)
							(mid -0.249642 -0.249642)
							(end -0.2794 -0.1778)
						)
						(arc
							(start -0.2794 0.1778)
							(mid -0.249642 0.249642)
							(end -0.1778 0.2794)
						)
						(arc
							(start 0.1778 0.2794)
							(mid 0.249642 0.249642)
							(end 0.2794 0.1778)
						)
						(arc
							(start 0.2794 -0.1778)
							(mid 0.249642 -0.249642)
							(end 0.1778 -0.2794)
						)
					)
					(width 0)
					(fill yes)
				)
			)
		)
	)
	(footprint ""
		(layer "F.Cu")
		(at 20.955 -141.859 -90)
		(property "Reference" "R324"
			(at 0 0 270)
			(layer "F.SilkS")
			(hide yes)
			(effects
				(font
					(size 1.27 1.27)
				)
			)
		)
		(property "Value" "10KR2F-2-GP"
			(at 0.064008 -3.993896 270)
			(unlocked yes)
			(layer "F.Fab")
			(hide yes)
			(effects
				(font
					(size 1.016 1.016)
					(thickness 0.1524)
				)
			)
		)
		(property "Device Type" "R402H16"
			(at 0.064008 -5.517896 270)
			(unlocked yes)
			(layer "F.Fab")
			(hide yes)
			(effects
				(font
					(size 1.016 1.016)
					(thickness 0.1524)
				)
			)
		)
		(duplicate_pad_numbers_are_jumpers no)
		(fp_line
			(start -0.508 -0.9398)
			(end -0.508 0.9398)
			(stroke
				(width 0.1524)
				(type default)
			)
			(layer "F.SilkS")
		)
		(fp_line
			(start 0.508 -0.9398)
			(end -0.508 -0.9398)
			(stroke
				(width 0.1524)
				(type default)
			)
			(layer "F.SilkS")
		)
		(fp_rect
			(start -0.508 0.9398)
			(end 0.508 -0.9398)
			(stroke
				(width 0)
				(type default)
			)
			(fill no)
			(layer "F.CrtYd")
		)
		(fp_rect
			(start -0.508 0.9398)
			(end 0.508 -0.9398)
			(stroke
				(width 0)
				(type default)
			)
			(fill no)
			(layer "F.Fab")
		)
		(pad "1" smd custom
			(at 0 -0.4445 270)
			(size 0.1397 0.1397)
			(layers "F.Cu" "F.Mask" "F.Paste")
			(net "PECI0_R")
			(options
				(clearance outline)
				(anchor circle)
			)
			(primitives
				(gr_poly
					(pts
						(arc
							(start -0.1778 -0.2794)
							(mid -0.249642 -0.249642)
							(end -0.2794 -0.1778)
						)
						(arc
							(start -0.2794 0.1778)
							(mid -0.249642 0.249642)
							(end -0.1778 0.2794)
						)
						(arc
							(start 0.1778 0.2794)
							(mid 0.249642 0.249642)
							(end 0.2794 0.1778)
						)
						(arc
							(start 0.2794 -0.1778)
							(mid 0.249642 -0.249642)
							(end 0.1778 -0.2794)
						)
					)
					(width 0)
					(fill yes)
				)
			)
		)
		(pad "2" smd custom
			(at 0 0.4445 270)
			(size 0.1397 0.1397)
			(layers "F.Cu" "F.Mask" "F.Paste")
			(net "GND")
			(options
				(clearance outline)
				(anchor circle)
			)
			(primitives
				(gr_poly
					(pts
						(arc
							(start -0.1778 -0.2794)
							(mid -0.249642 -0.249642)
							(end -0.2794 -0.1778)
						)
						(arc
							(start -0.2794 0.1778)
							(mid -0.249642 0.249642)
							(end -0.1778 0.2794)
						)
						(arc
							(start 0.1778 0.2794)
							(mid 0.249642 0.249642)
							(end 0.2794 0.1778)
						)
						(arc
							(start 0.2794 -0.1778)
							(mid 0.249642 -0.249642)
							(end 0.1778 -0.2794)
						)
					)
					(width 0)
					(fill yes)
				)
			)
		)
	)
	(footprint ""
		(layer "F.Cu")
		(at 28.1178 -198.7042)
		(property "Reference" "Q23"
			(at 0 0 0)
			(layer "F.SilkS")
			(hide yes)
			(effects
				(font
					(size 1.27 1.27)
				)
			)
		)
		(property "Value" "PSMN0R9-25YLC-GP"
			(at -4.2799 -0.4572 0)
			(unlocked yes)
			(layer "F.Fab")
			(hide yes)
			(effects
				(font
					(size 1.016 1.016)
					(thickness 0.1524)
				)
			)
		)
		(property "Device Type" "LFPAK-5PH48-U"
			(at -4.2799 -1.9812 0)
			(unlocked yes)
			(layer "F.Fab")
			(hide yes)
			(effects
				(font
					(size 1.016 1.016)
					(thickness 0.1524)
				)
			)
		)
		(duplicate_pad_numbers_are_jumpers no)
		(fp_line
			(start -2.7559 -6.5532)
			(end -2.7559 1.0668)
			(stroke
				(width 0.1524)
				(type default)
			)
			(layer "F.SilkS")
		)
		(fp_line
			(start -2.7559 1.0668)
			(end 2.7559 1.0668)
			(stroke
				(width 0.1524)
				(type default)
			)
			(layer "F.SilkS")
		)
		(fp_line
			(start -1.7272 1.1684)
			(end -2.1082 1.1684)
			(stroke
				(width 0.3302)
				(type default)
			)
			(layer "F.SilkS")
		)
		(fp_line
			(start 2.7559 -6.5532)
			(end -2.7559 -6.5532)
			(stroke
				(width 0.1524)
				(type default)
			)
			(layer "F.SilkS")
		)
		(fp_line
			(start 2.7559 1.0668)
			(end 2.7559 -6.5532)
			(stroke
				(width 0.1524)
				(type default)
			)
			(layer "F.SilkS")
		)
		(fp_poly
			(pts
				(xy -2.3368 1.5748) (xy -1.905 1.143) (xy -1.4732 1.5748)
			)
			(stroke
				(width 0)
				(type default)
			)
			(fill yes)
			(layer "F.SilkS")
		)
		(fp_poly
			(pts
				(xy -2.5019 -4.02971) (xy -0.3302 -4.02971) (xy -0.3302 -6.30301) (xy -2.5019 -6.30301)
			)
			(stroke
				(width 0)
				(type default)
			)
			(fill yes)
			(layer "F.Paste")
		)
		(fp_poly
			(pts
				(xy -2.5019 -1.09601) (xy -0.3302 -1.09601) (xy -0.3302 -3.36931) (xy -2.5019 -3.36931)
			)
			(stroke
				(width 0)
				(type default)
			)
			(fill yes)
			(layer "F.Paste")
		)
		(fp_poly
			(pts
				(xy 0.3302 -4.02971) (xy 2.5019 -4.02971) (xy 2.5019 -6.30301) (xy 0.3302 -6.30301)
			)
			(stroke
				(width 0)
				(type default)
			)
			(fill yes)
			(layer "F.Paste")
		)
		(fp_poly
			(pts
				(xy 0.3302 -1.09601) (xy 2.5019 -1.09601) (xy 2.5019 -3.36931) (xy 0.3302 -3.36931)
			)
			(stroke
				(width 0)
				(type default)
			)
			(fill yes)
			(layer "F.Paste")
		)
		(fp_rect
			(start -2.4511 0.3048)
			(end 2.4511 -5.6896)
			(stroke
				(width 0)
				(type default)
			)
			(fill no)
			(layer "F.CrtYd")
		)
		(fp_poly
			(pts
				(xy -3.0099 1.3208) (xy -3.0099 -6.8072) (xy 3.0099 -6.8072) (xy 3.0099 -1.016) (xy 2.4511 -1.016)
				(xy 2.4511 -5.6896) (xy -2.4511 -5.6896) (xy -2.4511 0.3048) (xy 2.4511 0.3048) (xy 2.4511 -1.0033)
				(xy 3.0099 -1.0033) (xy 3.0099 1.3208)
			)
			(stroke
				(width 0)
				(type default)
			)
			(fill no)
			(layer "F.CrtYd")
		)
		(fp_rect
			(start -3.0099 1.3208)
			(end 3.0099 -6.8072)
			(stroke
				(width 0)
				(type default)
			)
			(fill no)
			(layer "F.Fab")
		)
		(pad "1" smd rect
			(at -1.905 0)
			(size 0.762 1.6256)
			(layers "F.Cu" "F.Mask" "F.Paste")
			(net "P12V")
		)
		(pad "2" smd rect
			(at -0.635 0)
			(size 0.762 1.6256)
			(layers "F.Cu" "F.Mask" "F.Paste")
			(net "P12V")
		)
		(pad "3" smd rect
			(at 0.635 0)
			(size 0.762 1.6256)
			(layers "F.Cu" "F.Mask" "F.Paste")
			(net "P12V")
		)
		(pad "4" smd rect
			(at 1.905 0)
			(size 0.762 1.6256)
			(layers "F.Cu" "F.Mask" "F.Paste")
			(net "MB0_12V_CTRL_GATE1")
		)
		(pad "5" smd rect
			(at 0 -3.69951)
			(size 5.0038 5.207)
			(layers "F.Cu" "F.Mask" "F.Paste")
			(net "MB0_P12V_MAIN_R")
		)
	)
	(footprint ""
		(layer "F.Cu")
		(at 26.4668 -173.2026 -90)
		(property "Reference" "PR34"
			(at 0 0 270)
			(layer "F.SilkS")
			(hide yes)
			(effects
				(font
					(size 1.27 1.27)
				)
			)
		)
		(property "Value" "10KR2F-2-GP"
			(at 0.064008 -3.993896 270)
			(unlocked yes)
			(layer "F.Fab")
			(hide yes)
			(effects
				(font
					(size 1.016 1.016)
					(thickness 0.1524)
				)
			)
		)
		(property "Device Type" "R402H16"
			(at 0.064008 -5.517896 270)
			(unlocked yes)
			(layer "F.Fab")
			(hide yes)
			(effects
				(font
					(size 1.016 1.016)
					(thickness 0.1524)
				)
			)
		)
		(duplicate_pad_numbers_are_jumpers no)
		(fp_line
			(start -0.508 -0.9398)
			(end -0.508 0.9398)
			(stroke
				(width 0.1524)
				(type default)
			)
			(layer "F.SilkS")
		)
		(fp_line
			(start 0.508 -0.9398)
			(end -0.508 -0.9398)
			(stroke
				(width 0.1524)
				(type default)
			)
			(layer "F.SilkS")
		)
		(fp_rect
			(start -0.508 0.9398)
			(end 0.508 -0.9398)
			(stroke
				(width 0)
				(type default)
			)
			(fill no)
			(layer "F.CrtYd")
		)
		(fp_rect
			(start -0.508 0.9398)
			(end 0.508 -0.9398)
			(stroke
				(width 0)
				(type default)
			)
			(fill no)
			(layer "F.Fab")
		)
		(pad "1" smd custom
			(at 0 -0.4445 270)
			(size 0.1397 0.1397)
			(layers "F.Cu" "F.Mask" "F.Paste")
			(net "GND")
			(options
				(clearance outline)
				(anchor circle)
			)
			(primitives
				(gr_poly
					(pts
						(arc
							(start -0.1778 -0.2794)
							(mid -0.249642 -0.249642)
							(end -0.2794 -0.1778)
						)
						(arc
							(start -0.2794 0.1778)
							(mid -0.249642 0.249642)
							(end -0.1778 0.2794)
						)
						(arc
							(start 0.1778 0.2794)
							(mid 0.249642 0.249642)
							(end 0.2794 0.1778)
						)
						(arc
							(start 0.2794 -0.1778)
							(mid 0.249642 -0.249642)
							(end 0.1778 -0.2794)
						)
					)
					(width 0)
					(fill yes)
				)
			)
		)
		(pad "2" smd custom
			(at 0 0.4445 270)
			(size 0.1397 0.1397)
			(layers "F.Cu" "F.Mask" "F.Paste")
			(net "PCIE_MATED#_A")
			(options
				(clearance outline)
				(anchor circle)
			)
			(primitives
				(gr_poly
					(pts
						(arc
							(start -0.1778 -0.2794)
							(mid -0.249642 -0.249642)
							(end -0.2794 -0.1778)
						)
						(arc
							(start -0.2794 0.1778)
							(mid -0.249642 0.249642)
							(end -0.1778 0.2794)
						)
						(arc
							(start 0.1778 0.2794)
							(mid 0.249642 0.249642)
							(end 0.2794 0.1778)
						)
						(arc
							(start 0.2794 -0.1778)
							(mid 0.249642 -0.249642)
							(end 0.1778 -0.2794)
						)
					)
					(width 0)
					(fill yes)
				)
			)
		)
	)
	(footprint ""
		(layer "F.Cu")
		(at 259.08 -26.289 180)
		(property "Reference" "R742"
			(at 0 0 180)
			(layer "F.SilkS")
			(hide yes)
			(effects
				(font
					(size 1.27 1.27)
				)
			)
		)
		(property "Value" "4K7R2F-GP"
			(at 0.064008 -3.993896 180)
			(unlocked yes)
			(layer "F.Fab")
			(hide yes)
			(effects
				(font
					(size 1.016 1.016)
					(thickness 0.1524)
				)
			)
		)
		(property "Device Type" "R402H16"
			(at 0.064008 -5.517896 180)
			(unlocked yes)
			(layer "F.Fab")
			(hide yes)
			(effects
				(font
					(size 1.016 1.016)
					(thickness 0.1524)
				)
			)
		)
		(duplicate_pad_numbers_are_jumpers no)
		(fp_line
			(start 0.508 -0.9398)
			(end -0.508 -0.9398)
			(stroke
				(width 0.1524)
				(type default)
			)
			(layer "F.SilkS")
		)
		(fp_line
			(start -0.508 -0.9398)
			(end -0.508 0.9398)
			(stroke
				(width 0.1524)
				(type default)
			)
			(layer "F.SilkS")
		)
		(fp_rect
			(start -0.508 0.9398)
			(end 0.508 -0.9398)
			(stroke
				(width 0)
				(type default)
			)
			(fill no)
			(layer "F.CrtYd")
		)
		(fp_rect
			(start -0.508 0.9398)
			(end 0.508 -0.9398)
			(stroke
				(width 0)
				(type default)
			)
			(fill no)
			(layer "F.Fab")
		)
		(pad "1" smd custom
			(at 0 -0.4445 180)
			(size 0.1397 0.1397)
			(layers "F.Cu" "F.Mask" "F.Paste")
			(net "P3V3_GPIO")
			(options
				(clearance outline)
				(anchor circle)
			)
			(primitives
				(gr_poly
					(pts
						(arc
							(start -0.1778 -0.2794)
							(mid -0.249642 -0.249642)
							(end -0.2794 -0.1778)
						)
						(arc
							(start -0.2794 0.1778)
							(mid -0.249642 0.249642)
							(end -0.1778 0.2794)
						)
						(arc
							(start 0.1778 0.2794)
							(mid 0.249642 0.249642)
							(end 0.2794 0.1778)
						)
						(arc
							(start 0.2794 -0.1778)
							(mid 0.249642 -0.249642)
							(end 0.1778 -0.2794)
						)
					)
					(width 0)
					(fill yes)
				)
			)
		)
		(pad "2" smd custom
			(at 0 0.4445 180)
			(size 0.1397 0.1397)
			(layers "F.Cu" "F.Mask" "F.Paste")
			(net "IOEXP_INT#_1")
			(options
				(clearance outline)
				(anchor circle)
			)
			(primitives
				(gr_poly
					(pts
						(arc
							(start -0.1778 -0.2794)
							(mid -0.249642 -0.249642)
							(end -0.2794 -0.1778)
						)
						(arc
							(start -0.2794 0.1778)
							(mid -0.249642 0.249642)
							(end -0.1778 0.2794)
						)
						(arc
							(start 0.1778 0.2794)
							(mid 0.249642 0.249642)
							(end 0.2794 0.1778)
						)
						(arc
							(start 0.2794 -0.1778)
							(mid 0.249642 -0.249642)
							(end 0.1778 -0.2794)
						)
					)
					(width 0)
					(fill yes)
				)
			)
		)
	)
	(footprint ""
		(layer "F.Cu")
		(at 243.098574 -16.414496 -90)
		(property "Reference" "R494"
			(at 0 0 270)
			(layer "F.SilkS")
			(hide yes)
			(effects
				(font
					(size 1.27 1.27)
				)
			)
		)
		(property "Value" "0R2J-2-GP"
			(at 0.064008 -3.993896 270)
			(unlocked yes)
			(layer "F.Fab")
			(hide yes)
			(effects
				(font
					(size 1.016 1.016)
					(thickness 0.1524)
				)
			)
		)
		(property "Device Type" "R402H16"
			(at 0.064008 -5.517896 270)
			(unlocked yes)
			(layer "F.Fab")
			(hide yes)
			(effects
				(font
					(size 1.016 1.016)
					(thickness 0.1524)
				)
			)
		)
		(duplicate_pad_numbers_are_jumpers no)
		(fp_line
			(start -0.508 -0.9398)
			(end -0.508 0.9398)
			(stroke
				(width 0.1524)
				(type default)
			)
			(layer "F.SilkS")
		)
		(fp_line
			(start 0.508 -0.9398)
			(end -0.508 -0.9398)
			(stroke
				(width 0.1524)
				(type default)
			)
			(layer "F.SilkS")
		)
		(fp_rect
			(start -0.508 0.9398)
			(end 0.508 -0.9398)
			(stroke
				(width 0)
				(type default)
			)
			(fill no)
			(layer "F.CrtYd")
		)
		(fp_rect
			(start -0.508 0.9398)
			(end 0.508 -0.9398)
			(stroke
				(width 0)
				(type default)
			)
			(fill no)
			(layer "F.Fab")
		)
		(pad "1" smd custom
			(at 0 -0.4445 270)
			(size 0.1397 0.1397)
			(layers "F.Cu" "F.Mask" "F.Paste")
			(net "PM8536_HB")
			(options
				(clearance outline)
				(anchor circle)
			)
			(primitives
				(gr_poly
					(pts
						(arc
							(start -0.1778 -0.2794)
							(mid -0.249642 -0.249642)
							(end -0.2794 -0.1778)
						)
						(arc
							(start -0.2794 0.1778)
							(mid -0.249642 0.249642)
							(end -0.1778 0.2794)
						)
						(arc
							(start 0.1778 0.2794)
							(mid 0.249642 0.249642)
							(end 0.2794 0.1778)
						)
						(arc
							(start 0.2794 -0.1778)
							(mid 0.249642 -0.249642)
							(end 0.1778 -0.2794)
						)
					)
					(width 0)
					(fill yes)
				)
			)
		)
		(pad "2" smd custom
			(at 0 0.4445 270)
			(size 0.1397 0.1397)
			(layers "F.Cu" "F.Mask" "F.Paste")
			(net "Q22_G")
			(options
				(clearance outline)
				(anchor circle)
			)
			(primitives
				(gr_poly
					(pts
						(arc
							(start -0.1778 -0.2794)
							(mid -0.249642 -0.249642)
							(end -0.2794 -0.1778)
						)
						(arc
							(start -0.2794 0.1778)
							(mid -0.249642 0.249642)
							(end -0.1778 0.2794)
						)
						(arc
							(start 0.1778 0.2794)
							(mid 0.249642 0.249642)
							(end 0.2794 0.1778)
						)
						(arc
							(start 0.2794 -0.1778)
							(mid 0.249642 -0.249642)
							(end 0.1778 -0.2794)
						)
					)
					(width 0)
					(fill yes)
				)
			)
		)
	)
	(footprint ""
		(layer "F.Cu")
		(at 21.9964 -149.9362 -90)
		(property "Reference" "C264"
			(at 0 0 270)
			(layer "F.SilkS")
			(hide yes)
			(effects
				(font
					(size 1.27 1.27)
				)
			)
		)
		(property "Value" "SC1U10V2KX-4-GP"
			(at 1.1811 -2.7051 270)
			(unlocked yes)
			(layer "F.Fab")
			(hide yes)
			(effects
				(font
					(size 1.016 1.016)
					(thickness 0.1524)
				)
			)
		)
		(property "Device Type" "C402H22"
			(at 1.1811 -4.2291 270)
			(unlocked yes)
			(layer "F.Fab")
			(hide yes)
			(effects
				(font
					(size 1.016 1.016)
					(thickness 0.1524)
				)
			)
		)
		(duplicate_pad_numbers_are_jumpers no)
		(fp_rect
			(start -0.4318 0.9525)
			(end 0.4318 -0.9525)
			(stroke
				(width 0)
				(type default)
			)
			(fill no)
			(layer "F.CrtYd")
		)
		(fp_rect
			(start -0.4318 0.9525)
			(end 0.4318 -0.9525)
			(stroke
				(width 0)
				(type default)
			)
			(fill no)
			(layer "F.Fab")
		)
		(pad "1" smd custom
			(at 0 -0.4445 270)
			(size 0.1524 0.1524)
			(layers "F.Cu" "F.Mask" "F.Paste")
			(net "U80_B")
			(options
				(clearance outline)
				(anchor circle)
			)
			(primitives
				(gr_poly
					(pts
						(arc
							(start 0.3048 -0.2032)
							(mid 0.275042 -0.275042)
							(end 0.2032 -0.3048)
						)
						(arc
							(start -0.2032 -0.3048)
							(mid -0.275042 -0.275042)
							(end -0.3048 -0.2032)
						)
						(arc
							(start -0.3048 0.2032)
							(mid -0.275042 0.275042)
							(end -0.2032 0.3048)
						)
						(arc
							(start 0.2032 0.3048)
							(mid 0.275042 0.275042)
							(end 0.3048 0.2032)
						)
					)
					(width 0)
					(fill yes)
				)
			)
		)
		(pad "2" smd custom
			(at 0 0.4445 270)
			(size 0.1524 0.1524)
			(layers "F.Cu" "F.Mask" "F.Paste")
			(net "GND")
			(options
				(clearance outline)
				(anchor circle)
			)
			(primitives
				(gr_poly
					(pts
						(arc
							(start 0.3048 -0.2032)
							(mid 0.275042 -0.275042)
							(end 0.2032 -0.3048)
						)
						(arc
							(start -0.2032 -0.3048)
							(mid -0.275042 -0.275042)
							(end -0.3048 -0.2032)
						)
						(arc
							(start -0.3048 0.2032)
							(mid -0.275042 0.275042)
							(end -0.2032 0.3048)
						)
						(arc
							(start 0.2032 0.3048)
							(mid 0.275042 0.275042)
							(end 0.3048 0.2032)
						)
					)
					(width 0)
					(fill yes)
				)
			)
		)
	)
	(footprint ""
		(layer "F.Cu")
		(at 16.764 -152.4)
		(property "Reference" "R489"
			(at 0 0 0)
			(layer "F.SilkS")
			(hide yes)
			(effects
				(font
					(size 1.27 1.27)
				)
			)
		)
		(property "Value" "4K7R2F-GP"
			(at 0.064008 -3.993896 0)
			(unlocked yes)
			(layer "F.Fab")
			(hide yes)
			(effects
				(font
					(size 1.016 1.016)
					(thickness 0.1524)
				)
			)
		)
		(property "Device Type" "R402H16"
			(at 0.064008 -5.517896 0)
			(unlocked yes)
			(layer "F.Fab")
			(hide yes)
			(effects
				(font
					(size 1.016 1.016)
					(thickness 0.1524)
				)
			)
		)
		(duplicate_pad_numbers_are_jumpers no)
		(fp_line
			(start -0.508 -0.9398)
			(end -0.508 0.9398)
			(stroke
				(width 0.1524)
				(type default)
			)
			(layer "F.SilkS")
		)
		(fp_line
			(start 0.508 -0.9398)
			(end -0.508 -0.9398)
			(stroke
				(width 0.1524)
				(type default)
			)
			(layer "F.SilkS")
		)
		(fp_rect
			(start -0.508 0.9398)
			(end 0.508 -0.9398)
			(stroke
				(width 0)
				(type default)
			)
			(fill no)
			(layer "F.CrtYd")
		)
		(fp_rect
			(start -0.508 0.9398)
			(end 0.508 -0.9398)
			(stroke
				(width 0)
				(type default)
			)
			(fill no)
			(layer "F.Fab")
		)
		(pad "1" smd custom
			(at 0 -0.4445)
			(size 0.1397 0.1397)
			(layers "F.Cu" "F.Mask" "F.Paste")
			(net "P1V53_STBY")
			(options
				(clearance outline)
				(anchor circle)
			)
			(primitives
				(gr_poly
					(pts
						(arc
							(start -0.1778 -0.2794)
							(mid -0.249642 -0.249642)
							(end -0.2794 -0.1778)
						)
						(arc
							(start -0.2794 0.1778)
							(mid -0.249642 0.249642)
							(end -0.1778 0.2794)
						)
						(arc
							(start 0.1778 0.2794)
							(mid 0.249642 0.249642)
							(end 0.2794 0.1778)
						)
						(arc
							(start 0.2794 -0.1778)
							(mid 0.249642 -0.249642)
							(end 0.1778 -0.2794)
						)
					)
					(width 0)
					(fill yes)
				)
			)
		)
		(pad "2" smd custom
			(at 0 0.4445)
			(size 0.1397 0.1397)
			(layers "F.Cu" "F.Mask" "F.Paste")
			(net "BMC_DDR3_RST_N")
			(options
				(clearance outline)
				(anchor circle)
			)
			(primitives
				(gr_poly
					(pts
						(arc
							(start -0.1778 -0.2794)
							(mid -0.249642 -0.249642)
							(end -0.2794 -0.1778)
						)
						(arc
							(start -0.2794 0.1778)
							(mid -0.249642 0.249642)
							(end -0.1778 0.2794)
						)
						(arc
							(start 0.1778 0.2794)
							(mid 0.249642 0.249642)
							(end 0.2794 0.1778)
						)
						(arc
							(start 0.2794 -0.1778)
							(mid 0.249642 -0.249642)
							(end 0.1778 -0.2794)
						)
					)
					(width 0)
					(fill yes)
				)
			)
		)
	)
	(footprint ""
		(layer "F.Cu")
		(at 51.181 -145.296128)
		(property "Reference" "SR943"
			(at 0 0 0)
			(layer "F.SilkS")
			(hide yes)
			(effects
				(font
					(size 1.27 1.27)
				)
			)
		)
		(property "Value" "4K75R2F-1-GP"
			(at 0.064008 -3.993896 0)
			(unlocked yes)
			(layer "F.Fab")
			(hide yes)
			(effects
				(font
					(size 1.016 1.016)
					(thickness 0.1524)
				)
			)
		)
		(property "Device Type" "R402H16"
			(at 0.064008 -5.517896 0)
			(unlocked yes)
			(layer "F.Fab")
			(hide yes)
			(effects
				(font
					(size 1.016 1.016)
					(thickness 0.1524)
				)
			)
		)
		(duplicate_pad_numbers_are_jumpers no)
		(fp_line
			(start -0.508 -0.9398)
			(end -0.508 0.9398)
			(stroke
				(width 0.1524)
				(type default)
			)
			(layer "F.SilkS")
		)
		(fp_line
			(start 0.508 -0.9398)
			(end -0.508 -0.9398)
			(stroke
				(width 0.1524)
				(type default)
			)
			(layer "F.SilkS")
		)
		(fp_rect
			(start -0.508 0.9398)
			(end 0.508 -0.9398)
			(stroke
				(width 0)
				(type default)
			)
			(fill no)
			(layer "F.CrtYd")
		)
		(fp_rect
			(start -0.508 0.9398)
			(end 0.508 -0.9398)
			(stroke
				(width 0)
				(type default)
			)
			(fill no)
			(layer "F.Fab")
		)
		(pad "1" smd custom
			(at 0 -0.4445)
			(size 0.1397 0.1397)
			(layers "F.Cu" "F.Mask" "F.Paste")
			(net "P3V3_STBY")
			(options
				(clearance outline)
				(anchor circle)
			)
			(primitives
				(gr_poly
					(pts
						(arc
							(start -0.1778 -0.2794)
							(mid -0.249642 -0.249642)
							(end -0.2794 -0.1778)
						)
						(arc
							(start -0.2794 0.1778)
							(mid -0.249642 0.249642)
							(end -0.1778 0.2794)
						)
						(arc
							(start 0.1778 0.2794)
							(mid 0.249642 0.249642)
							(end 0.2794 0.1778)
						)
						(arc
							(start 0.2794 -0.1778)
							(mid 0.249642 -0.249642)
							(end 0.1778 -0.2794)
						)
					)
					(width 0)
					(fill yes)
				)
			)
		)
		(pad "2" smd custom
			(at 0 0.4445)
			(size 0.1397 0.1397)
			(layers "F.Cu" "F.Mask" "F.Paste")
			(net "BMC_FW_DET_BOARD_VER_1")
			(options
				(clearance outline)
				(anchor circle)
			)
			(primitives
				(gr_poly
					(pts
						(arc
							(start -0.1778 -0.2794)
							(mid -0.249642 -0.249642)
							(end -0.2794 -0.1778)
						)
						(arc
							(start -0.2794 0.1778)
							(mid -0.249642 0.249642)
							(end -0.1778 0.2794)
						)
						(arc
							(start 0.1778 0.2794)
							(mid 0.249642 0.249642)
							(end 0.2794 0.1778)
						)
						(arc
							(start 0.2794 -0.1778)
							(mid 0.249642 -0.249642)
							(end 0.1778 -0.2794)
						)
					)
					(width 0)
					(fill yes)
				)
			)
		)
	)
	(footprint ""
		(layer "F.Cu")
		(at 18.796 -143.002)
		(property "Reference" "C201"
			(at 0 0 0)
			(layer "F.SilkS")
			(hide yes)
			(effects
				(font
					(size 1.27 1.27)
				)
			)
		)
		(property "Value" "SC1U10V2KX-4-GP"
			(at 1.1811 -2.7051 0)
			(unlocked yes)
			(layer "F.Fab")
			(hide yes)
			(effects
				(font
					(size 1.016 1.016)
					(thickness 0.1524)
				)
			)
		)
		(property "Device Type" "C402H22"
			(at 1.1811 -4.2291 0)
			(unlocked yes)
			(layer "F.Fab")
			(hide yes)
			(effects
				(font
					(size 1.016 1.016)
					(thickness 0.1524)
				)
			)
		)
		(duplicate_pad_numbers_are_jumpers no)
		(fp_rect
			(start -0.4318 0.9525)
			(end 0.4318 -0.9525)
			(stroke
				(width 0)
				(type default)
			)
			(fill no)
			(layer "F.CrtYd")
		)
		(fp_rect
			(start -0.4318 0.9525)
			(end 0.4318 -0.9525)
			(stroke
				(width 0)
				(type default)
			)
			(fill no)
			(layer "F.Fab")
		)
		(pad "1" smd custom
			(at 0 -0.4445)
			(size 0.1524 0.1524)
			(layers "F.Cu" "F.Mask" "F.Paste")
			(net "V1PLLAV12")
			(options
				(clearance outline)
				(anchor circle)
			)
			(primitives
				(gr_poly
					(pts
						(arc
							(start 0.3048 -0.2032)
							(mid 0.275042 -0.275042)
							(end 0.2032 -0.3048)
						)
						(arc
							(start -0.2032 -0.3048)
							(mid -0.275042 -0.275042)
							(end -0.3048 -0.2032)
						)
						(arc
							(start -0.3048 0.2032)
							(mid -0.275042 0.275042)
							(end -0.2032 0.3048)
						)
						(arc
							(start 0.2032 0.3048)
							(mid 0.275042 0.275042)
							(end 0.3048 0.2032)
						)
					)
					(width 0)
					(fill yes)
				)
			)
		)
		(pad "2" smd custom
			(at 0 0.4445)
			(size 0.1524 0.1524)
			(layers "F.Cu" "F.Mask" "F.Paste")
			(net "GND")
			(options
				(clearance outline)
				(anchor circle)
			)
			(primitives
				(gr_poly
					(pts
						(arc
							(start 0.3048 -0.2032)
							(mid 0.275042 -0.275042)
							(end 0.2032 -0.3048)
						)
						(arc
							(start -0.2032 -0.3048)
							(mid -0.275042 -0.275042)
							(end -0.3048 -0.2032)
						)
						(arc
							(start -0.3048 0.2032)
							(mid -0.275042 0.275042)
							(end -0.2032 0.3048)
						)
						(arc
							(start 0.2032 0.3048)
							(mid 0.275042 0.275042)
							(end 0.3048 0.2032)
						)
					)
					(width 0)
					(fill yes)
				)
			)
		)
	)
	(footprint ""
		(layer "F.Cu")
		(at 301.99203 -212.420454 180)
		(property "Reference" "C74"
			(at 0 0 180)
			(layer "F.SilkS")
			(hide yes)
			(effects
				(font
					(size 1.27 1.27)
				)
			)
		)
		(property "Value" "SCD22U10V2KX-1GP"
			(at 1.1811 -2.7051 180)
			(unlocked yes)
			(layer "F.Fab")
			(hide yes)
			(effects
				(font
					(size 1.016 1.016)
					(thickness 0.1524)
				)
			)
		)
		(property "Device Type" "C402H22"
			(at 1.1811 -4.2291 180)
			(unlocked yes)
			(layer "F.Fab")
			(hide yes)
			(effects
				(font
					(size 1.016 1.016)
					(thickness 0.1524)
				)
			)
		)
		(duplicate_pad_numbers_are_jumpers no)
		(fp_rect
			(start -0.4318 0.9525)
			(end 0.4318 -0.9525)
			(stroke
				(width 0)
				(type default)
			)
			(fill no)
			(layer "F.CrtYd")
		)
		(fp_rect
			(start -0.4318 0.9525)
			(end 0.4318 -0.9525)
			(stroke
				(width 0)
				(type default)
			)
			(fill no)
			(layer "F.Fab")
		)
		(pad "1" smd custom
			(at 0 -0.4445 180)
			(size 0.1524 0.1524)
			(layers "F.Cu" "F.Mask" "F.Paste")
			(net "PCIE_TX_CAP_P26")
			(options
				(clearance outline)
				(anchor circle)
			)
			(primitives
				(gr_poly
					(pts
						(arc
							(start 0.3048 -0.2032)
							(mid 0.275042 -0.275042)
							(end 0.2032 -0.3048)
						)
						(arc
							(start -0.2032 -0.3048)
							(mid -0.275042 -0.275042)
							(end -0.3048 -0.2032)
						)
						(arc
							(start -0.3048 0.2032)
							(mid -0.275042 0.275042)
							(end -0.2032 0.3048)
						)
						(arc
							(start 0.2032 0.3048)
							(mid 0.275042 0.275042)
							(end 0.3048 0.2032)
						)
					)
					(width 0)
					(fill yes)
				)
			)
		)
		(pad "2" smd custom
			(at 0 0.4445 180)
			(size 0.1524 0.1524)
			(layers "F.Cu" "F.Mask" "F.Paste")
			(net "PCIE_TX_P26")
			(options
				(clearance outline)
				(anchor circle)
			)
			(primitives
				(gr_poly
					(pts
						(arc
							(start 0.3048 -0.2032)
							(mid 0.275042 -0.275042)
							(end 0.2032 -0.3048)
						)
						(arc
							(start -0.2032 -0.3048)
							(mid -0.275042 -0.275042)
							(end -0.3048 -0.2032)
						)
						(arc
							(start -0.3048 0.2032)
							(mid -0.275042 0.275042)
							(end -0.2032 0.3048)
						)
						(arc
							(start 0.2032 0.3048)
							(mid 0.275042 0.275042)
							(end 0.3048 0.2032)
						)
					)
					(width 0)
					(fill yes)
				)
			)
		)
	)
	(footprint ""
		(layer "F.Cu")
		(at 339.598 -66.8655 90)
		(property "Reference" "PU3"
			(at 0 0 90)
			(layer "F.SilkS")
			(hide yes)
			(effects
				(font
					(size 1.27 1.27)
				)
			)
		)
		(property "Value" "TPS53355ADQPR-GP"
			(at 4.7498 -5.6896 90)
			(unlocked yes)
			(layer "F.Fab")
			(hide yes)
			(effects
				(font
					(size 1.016 1.016)
					(thickness 0.1524)
				)
			)
		)
		(property "Device Type" "QFN22G6050-G6133H60"
			(at 4.7498 -7.2136 90)
			(unlocked yes)
			(layer "F.Fab")
			(hide yes)
			(effects
				(font
					(size 1.016 1.016)
					(thickness 0.1524)
				)
			)
		)
		(duplicate_pad_numbers_are_jumpers no)
		(fp_line
			(start -2.286 -3.5179)
			(end -3.556 -3.5179)
			(stroke
				(width 0.1524)
				(type default)
			)
			(layer "F.SilkS")
		)
		(fp_line
			(start -3.556 -3.5179)
			(end -3.556 -2.2479)
			(stroke
				(width 0.1524)
				(type default)
			)
			(layer "F.SilkS")
		)
		(fp_line
			(start 0.500126 -3.262122)
			(end 0.500126 -3.770122)
			(stroke
				(width 0.1524)
				(type default)
			)
			(layer "F.SilkS")
		)
		(fp_line
			(start -1.999996 -3.262122)
			(end -1.999996 -4.024122)
			(stroke
				(width 0.1524)
				(type default)
			)
			(layer "F.SilkS")
		)
		(fp_line
			(start -3.556 2.2479)
			(end -3.556 3.5179)
			(stroke
				(width 0.1524)
				(type default)
			)
			(layer "F.SilkS")
		)
		(fp_line
			(start 1.500124 3.262122)
			(end 1.500124 4.024122)
			(stroke
				(width 0.1524)
				(type default)
			)
			(layer "F.SilkS")
		)
		(fp_line
			(start -0.999998 3.262122)
			(end -0.999998 3.770122)
			(stroke
				(width 0.1524)
				(type default)
			)
			(layer "F.SilkS")
		)
		(fp_line
			(start 3.556 3.5179)
			(end 3.556 2.2479)
			(stroke
				(width 0.1524)
				(type default)
			)
			(layer "F.SilkS")
		)
		(fp_line
			(start 2.286 3.5179)
			(end 3.556 3.5179)
			(stroke
				(width 0.1524)
				(type default)
			)
			(layer "F.SilkS")
		)
		(fp_line
			(start -3.556 3.5179)
			(end -2.286 3.5179)
			(stroke
				(width 0.1524)
				(type default)
			)
			(layer "F.SilkS")
		)
		(fp_poly
			(pts
				(xy 3.556 -3.5179) (xy 2.5273 -3.5179) (xy 3.556 -2.4892)
			)
			(stroke
				(width 0)
				(type default)
			)
			(fill yes)
			(layer "F.SilkS")
		)
		(fp_rect
			(start -2.9972 2.5019)
			(end 2.9972 -2.5019)
			(stroke
				(width 0)
				(type default)
			)
			(fill no)
			(layer "F.CrtYd")
		)
		(fp_poly
			(pts
				(xy 3.556 -2.5019) (xy -2.9972 -2.5019) (xy -2.9972 2.5019) (xy 2.9972 2.5019) (xy 2.9972 -2.4892)
				(xy 3.556 -2.4892) (xy 3.556 3.5179) (xy -3.556 3.5179) (xy -3.556 -3.5179) (xy 3.556 -3.5179)
			)
			(stroke
				(width 0)
				(type default)
			)
			(fill no)
			(layer "F.CrtYd")
		)
		(fp_rect
			(start -3.556 3.5179)
			(end 3.556 -3.5179)
			(stroke
				(width 0)
				(type default)
			)
			(fill no)
			(layer "F.Fab")
		)
		(pad "1" smd rect
			(at 2.500122 -2.449322 90)
			(size 0.3048 1.1176)
			(layers "F.Cu" "F.Mask" "F.Paste")
			(net "P0V9_E_VFB")
		)
		(pad "2" smd rect
			(at 1.999996 -2.449322 90)
			(size 0.3048 1.1176)
			(layers "F.Cu" "F.Mask" "F.Paste")
			(net "P0V9_E_EN")
		)
		(pad "3" smd rect
			(at 1.500124 -2.449322 90)
			(size 0.3048 1.1176)
			(layers "F.Cu" "F.Mask" "F.Paste")
			(net "P0V9_E_PG")
		)
		(pad "4" smd rect
			(at 0.999998 -2.449322 90)
			(size 0.3048 1.1176)
			(layers "F.Cu" "F.Mask" "F.Paste")
			(net "P0V9_E_VBST")
		)
		(pad "5" smd rect
			(at 0.500126 -2.449322 90)
			(size 0.3048 1.1176)
			(layers "F.Cu" "F.Mask" "F.Paste")
			(net "Net_2121")
		)
		(pad "6" smd rect
			(at 0 -2.449322 90)
			(size 0.3048 1.1176)
			(layers "F.Cu" "F.Mask" "F.Paste")
			(net "P0V9_E_LX")
		)
		(pad "7" smd rect
			(at -0.500126 -2.449322 90)
			(size 0.3048 1.1176)
			(layers "F.Cu" "F.Mask" "F.Paste")
			(net "P0V9_E_LX")
		)
		(pad "8" smd rect
			(at -0.999998 -2.449322 90)
			(size 0.3048 1.1176)
			(layers "F.Cu" "F.Mask" "F.Paste")
			(net "P0V9_E_LX")
		)
		(pad "9" smd rect
			(at -1.500124 -2.449322 90)
			(size 0.3048 1.1176)
			(layers "F.Cu" "F.Mask" "F.Paste")
			(net "P0V9_E_LX")
		)
		(pad "10" smd rect
			(at -1.999996 -2.449322 90)
			(size 0.3048 1.1176)
			(layers "F.Cu" "F.Mask" "F.Paste")
			(net "P0V9_E_LX")
		)
		(pad "11" smd rect
			(at -2.500122 -2.449322 90)
			(size 0.3048 1.1176)
			(layers "F.Cu" "F.Mask" "F.Paste")
			(net "P0V9_E_LX")
		)
		(pad "12" smd rect
			(at -2.500122 2.449322 90)
			(size 0.3048 1.1176)
			(layers "F.Cu" "F.Mask" "F.Paste")
			(net "P0V9_E_VIN")
		)
		(pad "13" smd rect
			(at -1.999996 2.449322 90)
			(size 0.3048 1.1176)
			(layers "F.Cu" "F.Mask" "F.Paste")
			(net "P0V9_E_VIN")
		)
		(pad "14" smd rect
			(at -1.500124 2.449322 90)
			(size 0.3048 1.1176)
			(layers "F.Cu" "F.Mask" "F.Paste")
			(net "P0V9_E_VIN")
		)
		(pad "15" smd rect
			(at -0.999998 2.449322 90)
			(size 0.3048 1.1176)
			(layers "F.Cu" "F.Mask" "F.Paste")
			(net "P0V9_E_VIN")
		)
		(pad "16" smd rect
			(at -0.500126 2.449322 90)
			(size 0.3048 1.1176)
			(layers "F.Cu" "F.Mask" "F.Paste")
			(net "P0V9_E_VIN")
		)
		(pad "17" smd rect
			(at 0 2.449322 90)
			(size 0.3048 1.1176)
			(layers "F.Cu" "F.Mask" "F.Paste")
			(net "P0V9_E_VIN")
		)
		(pad "18" smd rect
			(at 0.500126 2.449322 90)
			(size 0.3048 1.1176)
			(layers "F.Cu" "F.Mask" "F.Paste")
			(net "P0V9_E_VREG")
		)
		(pad "19" smd rect
			(at 0.999998 2.449322 90)
			(size 0.3048 1.1176)
			(layers "F.Cu" "F.Mask" "F.Paste")
			(net "P0V9_E_VDD")
		)
		(pad "20" smd rect
			(at 1.500124 2.449322 90)
			(size 0.3048 1.1176)
			(layers "F.Cu" "F.Mask" "F.Paste")
			(net "P0V9_E_MODE")
		)
		(pad "21" smd rect
			(at 1.999996 2.449322 90)
			(size 0.3048 1.1176)
			(layers "F.Cu" "F.Mask" "F.Paste")
			(net "P0V9_E_TRIP")
		)
		(pad "22" smd rect
			(at 2.500122 2.449322 90)
			(size 0.3048 1.1176)
			(layers "F.Cu" "F.Mask" "F.Paste")
			(net "P0V9_E_RF")
		)
		(pad "23" smd custom
			(at 0 0 90)
			(size 0.83185 0.83185)
			(layers "F.Cu" "F.Mask" "F.Paste")
			(net "GND")
			(options
				(clearance outline)
				(anchor circle)
			)
			(primitives
				(gr_poly
					(pts
						(xy -2.7813 1.6637) (xy -2.7813 1.2954) (xy -3.048 1.2954) (xy -3.048 0.9525) (xy -2.7813 0.9525)
						(xy -2.7813 -0.9525) (xy -3.048 -0.9525) (xy -3.048 -1.2954) (xy -2.7813 -1.2954) (xy -2.7813 -1.6637)
						(xy 2.7813 -1.6637) (xy 2.7813 -1.2954) (xy 3.048 -1.2954) (xy 3.048 -0.9525) (xy 2.7813 -0.9525)
						(xy 2.7813 0.9525) (xy 3.048 0.9525) (xy 3.048 1.2954) (xy 2.7813 1.2954) (xy 2.7813 1.6637)
					)
					(width 0)
					(fill yes)
				)
			)
		)
	)
	(footprint ""
		(layer "F.Cu")
		(at 70.715124 -183.235092 180)
		(property "Reference" "R516"
			(at 0 0 180)
			(layer "F.SilkS")
			(hide yes)
			(effects
				(font
					(size 1.27 1.27)
				)
			)
		)
		(property "Value" "10KR2F-2-GP"
			(at 0.064008 -3.993896 180)
			(unlocked yes)
			(layer "F.Fab")
			(hide yes)
			(effects
				(font
					(size 1.016 1.016)
					(thickness 0.1524)
				)
			)
		)
		(property "Device Type" "R402H16"
			(at 0.064008 -5.517896 180)
			(unlocked yes)
			(layer "F.Fab")
			(hide yes)
			(effects
				(font
					(size 1.016 1.016)
					(thickness 0.1524)
				)
			)
		)
		(duplicate_pad_numbers_are_jumpers no)
		(fp_line
			(start 0.508 -0.9398)
			(end -0.508 -0.9398)
			(stroke
				(width 0.1524)
				(type default)
			)
			(layer "F.SilkS")
		)
		(fp_line
			(start -0.508 -0.9398)
			(end -0.508 0.9398)
			(stroke
				(width 0.1524)
				(type default)
			)
			(layer "F.SilkS")
		)
		(fp_rect
			(start -0.508 0.9398)
			(end 0.508 -0.9398)
			(stroke
				(width 0)
				(type default)
			)
			(fill no)
			(layer "F.CrtYd")
		)
		(fp_rect
			(start -0.508 0.9398)
			(end 0.508 -0.9398)
			(stroke
				(width 0)
				(type default)
			)
			(fill no)
			(layer "F.Fab")
		)
		(pad "1" smd custom
			(at 0 -0.4445 180)
			(size 0.1397 0.1397)
			(layers "F.Cu" "F.Mask" "F.Paste")
			(net "GND")
			(options
				(clearance outline)
				(anchor circle)
			)
			(primitives
				(gr_poly
					(pts
						(arc
							(start -0.1778 -0.2794)
							(mid -0.249642 -0.249642)
							(end -0.2794 -0.1778)
						)
						(arc
							(start -0.2794 0.1778)
							(mid -0.249642 0.249642)
							(end -0.1778 0.2794)
						)
						(arc
							(start 0.1778 0.2794)
							(mid 0.249642 0.249642)
							(end 0.2794 0.1778)
						)
						(arc
							(start 0.2794 -0.1778)
							(mid 0.249642 -0.249642)
							(end 0.1778 -0.2794)
						)
					)
					(width 0)
					(fill yes)
				)
			)
		)
		(pad "2" smd custom
			(at 0 0.4445 180)
			(size 0.1397 0.1397)
			(layers "F.Cu" "F.Mask" "F.Paste")
			(net "IOEXP1_AD2")
			(options
				(clearance outline)
				(anchor circle)
			)
			(primitives
				(gr_poly
					(pts
						(arc
							(start -0.1778 -0.2794)
							(mid -0.249642 -0.249642)
							(end -0.2794 -0.1778)
						)
						(arc
							(start -0.2794 0.1778)
							(mid -0.249642 0.249642)
							(end -0.1778 0.2794)
						)
						(arc
							(start 0.1778 0.2794)
							(mid 0.249642 0.249642)
							(end 0.2794 0.1778)
						)
						(arc
							(start 0.2794 -0.1778)
							(mid 0.249642 -0.249642)
							(end 0.1778 -0.2794)
						)
					)
					(width 0)
					(fill yes)
				)
			)
		)
	)
	(footprint ""
		(layer "F.Cu")
		(at 120.5738 -99.8982 90)
		(property "Reference" "R429"
			(at 0 0 90)
			(layer "F.SilkS")
			(hide yes)
			(effects
				(font
					(size 1.27 1.27)
				)
			)
		)
		(property "Value" "2KR2F-3-GP"
			(at 0.064008 -3.993896 90)
			(unlocked yes)
			(layer "F.Fab")
			(hide yes)
			(effects
				(font
					(size 1.016 1.016)
					(thickness 0.1524)
				)
			)
		)
		(property "Device Type" "R402H16"
			(at 0.064008 -5.517896 90)
			(unlocked yes)
			(layer "F.Fab")
			(hide yes)
			(effects
				(font
					(size 1.016 1.016)
					(thickness 0.1524)
				)
			)
		)
		(duplicate_pad_numbers_are_jumpers no)
		(fp_line
			(start 0.508 -0.9398)
			(end -0.508 -0.9398)
			(stroke
				(width 0.1524)
				(type default)
			)
			(layer "F.SilkS")
		)
		(fp_line
			(start -0.508 -0.9398)
			(end -0.508 0.9398)
			(stroke
				(width 0.1524)
				(type default)
			)
			(layer "F.SilkS")
		)
		(fp_rect
			(start -0.508 0.9398)
			(end 0.508 -0.9398)
			(stroke
				(width 0)
				(type default)
			)
			(fill no)
			(layer "F.CrtYd")
		)
		(fp_rect
			(start -0.508 0.9398)
			(end 0.508 -0.9398)
			(stroke
				(width 0)
				(type default)
			)
			(fill no)
			(layer "F.Fab")
		)
		(pad "1" smd custom
			(at 0 -0.4445 90)
			(size 0.1397 0.1397)
			(layers "F.Cu" "F.Mask" "F.Paste")
			(net "P3V3_STBY")
			(options
				(clearance outline)
				(anchor circle)
			)
			(primitives
				(gr_poly
					(pts
						(arc
							(start -0.1778 -0.2794)
							(mid -0.249642 -0.249642)
							(end -0.2794 -0.1778)
						)
						(arc
							(start -0.2794 0.1778)
							(mid -0.249642 0.249642)
							(end -0.1778 0.2794)
						)
						(arc
							(start 0.1778 0.2794)
							(mid 0.249642 0.249642)
							(end 0.2794 0.1778)
						)
						(arc
							(start 0.2794 -0.1778)
							(mid 0.249642 -0.249642)
							(end 0.1778 -0.2794)
						)
					)
					(width 0)
					(fill yes)
				)
			)
		)
		(pad "2" smd custom
			(at 0 0.4445 90)
			(size 0.1397 0.1397)
			(layers "F.Cu" "F.Mask" "F.Paste")
			(net "BUF_I2C_SDA_2_R")
			(options
				(clearance outline)
				(anchor circle)
			)
			(primitives
				(gr_poly
					(pts
						(arc
							(start -0.1778 -0.2794)
							(mid -0.249642 -0.249642)
							(end -0.2794 -0.1778)
						)
						(arc
							(start -0.2794 0.1778)
							(mid -0.249642 0.249642)
							(end -0.1778 0.2794)
						)
						(arc
							(start 0.1778 0.2794)
							(mid 0.249642 0.249642)
							(end 0.2794 0.1778)
						)
						(arc
							(start 0.2794 -0.1778)
							(mid 0.249642 -0.249642)
							(end 0.1778 -0.2794)
						)
					)
					(width 0)
					(fill yes)
				)
			)
		)
	)
	(footprint ""
		(layer "F.Cu")
		(at 69.465952 -148.75891 90)
		(property "Reference" "U16"
			(at 0 0 90)
			(layer "F.SilkS")
			(hide yes)
			(effects
				(font
					(size 1.27 1.27)
				)
			)
		)
		(property "Value" "24LC64-I-SN-GP"
			(at -3.707384 -1.5367 90)
			(unlocked yes)
			(layer "F.Fab")
			(hide yes)
			(effects
				(font
					(size 1.016 1.016)
					(thickness 0.1524)
				)
			)
		)
		(property "Device Type" "SOIC8H69"
			(at -3.707384 -3.0607 90)
			(unlocked yes)
			(layer "F.Fab")
			(hide yes)
			(effects
				(font
					(size 1.016 1.016)
					(thickness 0.1524)
				)
			)
		)
		(duplicate_pad_numbers_are_jumpers no)
		(fp_line
			(start 2.1336 -1.4224)
			(end -2.7432 -1.4224)
			(stroke
				(width 0.1524)
				(type default)
			)
			(layer "F.SilkS")
		)
		(fp_line
			(start -2.7432 -1.4224)
			(end -2.7432 1.4224)
			(stroke
				(width 0.1524)
				(type default)
			)
			(layer "F.SilkS")
		)
		(fp_line
			(start -2.7178 -0.508)
			(end -2.1844 -0.0508)
			(stroke
				(width 0.1524)
				(type default)
			)
			(layer "F.SilkS")
		)
		(fp_line
			(start -2.1844 -0.0508)
			(end -2.7178 0.508)
			(stroke
				(width 0.1524)
				(type default)
			)
			(layer "F.SilkS")
		)
		(fp_line
			(start 2.1336 1.4224)
			(end 2.1336 -1.4224)
			(stroke
				(width 0.1524)
				(type default)
			)
			(layer "F.SilkS")
		)
		(fp_line
			(start -2.7432 1.4224)
			(end 2.1336 1.4224)
			(stroke
				(width 0.1524)
				(type default)
			)
			(layer "F.SilkS")
		)
		(fp_line
			(start -2.7432 1.4224)
			(end -2.6416 1.4224)
			(stroke
				(width 0.1524)
				(type default)
			)
			(layer "F.SilkS")
		)
		(fp_line
			(start -2.6289 3.4417)
			(end -2.6289 1.4732)
			(stroke
				(width 0.381)
				(type default)
			)
			(layer "F.SilkS")
		)
		(fp_poly
			(pts
				(xy -2.2098 -1.4224) (xy -2.2098 1.4224) (xy 2.2098 1.4224) (xy 2.2098 -1.4224)
			)
			(stroke
				(width 0)
				(type default)
			)
			(fill yes)
			(layer "F.SilkS")
		)
		(fp_rect
			(start -2.450084 2.999994)
			(end 2.450084 -2.999994)
			(stroke
				(width 0)
				(type default)
			)
			(fill no)
			(layer "F.CrtYd")
		)
		(fp_poly
			(pts
				(xy -2.8194 3.6322) (xy -2.8194 -3.6322) (xy 2.8194 -3.6322) (xy 2.8194 1.18364) (xy 2.450084 1.18364)
				(xy 2.450084 -2.999994) (xy -2.450084 -2.999994) (xy -2.450084 2.999994) (xy 2.450084 2.999994)
				(xy 2.450084 1.18618) (xy 2.8194 1.18618) (xy 2.8194 3.6322)
			)
			(stroke
				(width 0)
				(type default)
			)
			(fill no)
			(layer "F.CrtYd")
		)
		(fp_rect
			(start -2.8194 3.6322)
			(end 2.8194 -3.6322)
			(stroke
				(width 0)
				(type default)
			)
			(fill no)
			(layer "F.Fab")
		)
		(pad "1" smd rect
			(at -1.905 2.54 90)
			(size 0.635 1.651)
			(layers "F.Cu" "F.Mask" "F.Paste")
			(net "EEPROM_A0_R")
		)
		(pad "2" smd rect
			(at -0.635 2.54 90)
			(size 0.635 1.651)
			(layers "F.Cu" "F.Mask" "F.Paste")
			(net "EEPROM_A1_R")
		)
		(pad "3" smd rect
			(at 0.635 2.54 90)
			(size 0.635 1.651)
			(layers "F.Cu" "F.Mask" "F.Paste")
			(net "EEPROM_A2_R")
		)
		(pad "4" smd rect
			(at 1.905 2.54 90)
			(size 0.635 1.651)
			(layers "F.Cu" "F.Mask" "F.Paste")
			(net "GND")
		)
		(pad "5" smd rect
			(at 1.905 -2.54 90)
			(size 0.635 1.651)
			(layers "F.Cu" "F.Mask" "F.Paste")
			(net "EEPROM_SDA")
		)
		(pad "6" smd rect
			(at 0.635 -2.54 90)
			(size 0.635 1.651)
			(layers "F.Cu" "F.Mask" "F.Paste")
			(net "EEPROM_SCL")
		)
		(pad "7" smd rect
			(at -0.635 -2.54 90)
			(size 0.635 1.651)
			(layers "F.Cu" "F.Mask" "F.Paste")
			(net "EEPROM_WP")
		)
		(pad "8" smd rect
			(at -1.905 -2.54 90)
			(size 0.635 1.651)
			(layers "F.Cu" "F.Mask" "F.Paste")
			(net "P3V3_STBY")
		)
	)
	(footprint ""
		(layer "F.Cu")
		(at 31.9786 -180.5432 90)
		(property "Reference" "C243"
			(at 0 0 90)
			(layer "F.SilkS")
			(hide yes)
			(effects
				(font
					(size 1.27 1.27)
				)
			)
		)
		(property "Value" "SCD1U16V2KX-3GP"
			(at 1.1811 -2.7051 90)
			(unlocked yes)
			(layer "F.Fab")
			(hide yes)
			(effects
				(font
					(size 1.016 1.016)
					(thickness 0.1524)
				)
			)
		)
		(property "Device Type" "C402H22"
			(at 1.1811 -4.2291 90)
			(unlocked yes)
			(layer "F.Fab")
			(hide yes)
			(effects
				(font
					(size 1.016 1.016)
					(thickness 0.1524)
				)
			)
		)
		(duplicate_pad_numbers_are_jumpers no)
		(fp_rect
			(start -0.4318 0.9525)
			(end 0.4318 -0.9525)
			(stroke
				(width 0)
				(type default)
			)
			(fill no)
			(layer "F.CrtYd")
		)
		(fp_rect
			(start -0.4318 0.9525)
			(end 0.4318 -0.9525)
			(stroke
				(width 0)
				(type default)
			)
			(fill no)
			(layer "F.Fab")
		)
		(pad "1" smd custom
			(at 0 -0.4445 90)
			(size 0.1524 0.1524)
			(layers "F.Cu" "F.Mask" "F.Paste")
			(net "P3V3_STBY")
			(options
				(clearance outline)
				(anchor circle)
			)
			(primitives
				(gr_poly
					(pts
						(arc
							(start 0.3048 -0.2032)
							(mid 0.275042 -0.275042)
							(end 0.2032 -0.3048)
						)
						(arc
							(start -0.2032 -0.3048)
							(mid -0.275042 -0.275042)
							(end -0.3048 -0.2032)
						)
						(arc
							(start -0.3048 0.2032)
							(mid -0.275042 0.275042)
							(end -0.2032 0.3048)
						)
						(arc
							(start 0.2032 0.3048)
							(mid 0.275042 0.275042)
							(end 0.3048 0.2032)
						)
					)
					(width 0)
					(fill yes)
				)
			)
		)
		(pad "2" smd custom
			(at 0 0.4445 90)
			(size 0.1524 0.1524)
			(layers "F.Cu" "F.Mask" "F.Paste")
			(net "GND")
			(options
				(clearance outline)
				(anchor circle)
			)
			(primitives
				(gr_poly
					(pts
						(arc
							(start 0.3048 -0.2032)
							(mid 0.275042 -0.275042)
							(end 0.2032 -0.3048)
						)
						(arc
							(start -0.2032 -0.3048)
							(mid -0.275042 -0.275042)
							(end -0.3048 -0.2032)
						)
						(arc
							(start -0.3048 0.2032)
							(mid -0.275042 0.275042)
							(end -0.2032 0.3048)
						)
						(arc
							(start 0.2032 0.3048)
							(mid 0.275042 0.275042)
							(end 0.3048 0.2032)
						)
					)
					(width 0)
					(fill yes)
				)
			)
		)
	)
	(footprint ""
		(layer "F.Cu")
		(at 121.4628 -96.0882 90)
		(property "Reference" "U24"
			(at 0 0 90)
			(layer "F.SilkS")
			(hide yes)
			(effects
				(font
					(size 1.27 1.27)
				)
			)
		)
		(property "Value" "PCA9511ADP-T-GP"
			(at 0 -13.1572 90)
			(unlocked yes)
			(layer "F.Fab")
			(hide yes)
			(effects
				(font
					(size 1.016 1.016)
					(thickness 0.1524)
				)
			)
		)
		(property "Device Type" "SSOIC8-2H44"
			(at 0 -15.1892 90)
			(unlocked yes)
			(layer "F.Fab")
			(hide yes)
			(effects
				(font
					(size 1.016 1.016)
					(thickness 0.1524)
				)
			)
		)
		(duplicate_pad_numbers_are_jumpers no)
		(fp_line
			(start 1.0922 -1.016)
			(end 1.0922 1.016)
			(stroke
				(width 0.1524)
				(type default)
			)
			(layer "F.SilkS")
		)
		(fp_line
			(start -1.9304 -1.016)
			(end 1.0922 -1.016)
			(stroke
				(width 0.1524)
				(type default)
			)
			(layer "F.SilkS")
		)
		(fp_line
			(start -1.524 0)
			(end -1.9304 -0.4064)
			(stroke
				(width 0.1524)
				(type default)
			)
			(layer "F.SilkS")
		)
		(fp_line
			(start -1.524 0)
			(end -1.9304 0.4064)
			(stroke
				(width 0.1524)
				(type default)
			)
			(layer "F.SilkS")
		)
		(fp_line
			(start 1.0922 1.016)
			(end -1.9304 1.016)
			(stroke
				(width 0.1524)
				(type default)
			)
			(layer "F.SilkS")
		)
		(fp_line
			(start -1.9304 1.016)
			(end -1.9304 -1.016)
			(stroke
				(width 0.1524)
				(type default)
			)
			(layer "F.SilkS")
		)
		(fp_line
			(start -1.7018 1.0414)
			(end -1.7018 2.9718)
			(stroke
				(width 0.635)
				(type default)
			)
			(layer "F.SilkS")
		)
		(fp_poly
			(pts
				(xy -1.1938 -1.016) (xy 1.0922 -1.016) (xy 1.0922 1.016) (xy -1.1938 1.016)
			)
			(stroke
				(width 0)
				(type default)
			)
			(fill yes)
			(layer "F.SilkS")
		)
		(fp_rect
			(start -2.0066 3.3401)
			(end 2.0066 -3.3401)
			(stroke
				(width 0)
				(type default)
			)
			(fill no)
			(layer "F.CrtYd")
		)
		(fp_poly
			(pts
				(xy -2.0066 -3.3401) (xy 2.0066 -3.3401) (xy 2.0066 3.3401) (xy -2.0066 3.3401)
			)
			(stroke
				(width 0)
				(type default)
			)
			(fill no)
			(layer "F.Fab")
		)
		(pad "1" smd rect
			(at -0.97536 2.0701 90)
			(size 0.4064 1.524)
			(layers "F.Cu" "F.Mask" "F.Paste")
			(net "I2C10_BUFF_EN")
		)
		(pad "2" smd rect
			(at -0.32512 2.0701 90)
			(size 0.4064 1.524)
			(layers "F.Cu" "F.Mask" "F.Paste")
			(net "BMC_I2C10_8536_SCL_R")
		)
		(pad "3" smd rect
			(at 0.32512 2.0701 90)
			(size 0.4064 1.524)
			(layers "F.Cu" "F.Mask" "F.Paste")
			(net "BUF_I2C_SCL_2_R")
		)
		(pad "4" smd rect
			(at 0.97536 2.0701 90)
			(size 0.4064 1.524)
			(layers "F.Cu" "F.Mask" "F.Paste")
			(net "GND")
		)
		(pad "5" smd rect
			(at 0.97536 -2.0701 90)
			(size 0.4064 1.524)
			(layers "F.Cu" "F.Mask" "F.Paste")
			(net "I2C10_BUF_READY")
		)
		(pad "6" smd rect
			(at 0.32512 -2.0701 90)
			(size 0.4064 1.524)
			(layers "F.Cu" "F.Mask" "F.Paste")
			(net "BUF_I2C_SDA_2_R")
		)
		(pad "7" smd rect
			(at -0.32512 -2.0701 90)
			(size 0.4064 1.524)
			(layers "F.Cu" "F.Mask" "F.Paste")
			(net "BMC_I2C10_8536_SDA_R")
		)
		(pad "8" smd rect
			(at -0.97536 -2.0701 90)
			(size 0.4064 1.524)
			(layers "F.Cu" "F.Mask" "F.Paste")
			(net "P3V3_STBY")
		)
	)
	(footprint ""
		(layer "F.Cu")
		(at 184.10428 -4.25196)
		(property "Reference" "R2954"
			(at 0 0 0)
			(layer "F.SilkS")
			(hide yes)
			(effects
				(font
					(size 1.27 1.27)
				)
			)
		)
		(property "Value" "0R2J-2-GP"
			(at 0.064008 -3.993896 0)
			(unlocked yes)
			(layer "F.Fab")
			(hide yes)
			(effects
				(font
					(size 1.016 1.016)
					(thickness 0.1524)
				)
			)
		)
		(property "Device Type" "R402H16"
			(at 0.064008 -5.517896 0)
			(unlocked yes)
			(layer "F.Fab")
			(hide yes)
			(effects
				(font
					(size 1.016 1.016)
					(thickness 0.1524)
				)
			)
		)
		(duplicate_pad_numbers_are_jumpers no)
		(fp_line
			(start -0.508 -0.9398)
			(end -0.508 0.9398)
			(stroke
				(width 0.1524)
				(type default)
			)
			(layer "F.SilkS")
		)
		(fp_line
			(start 0.508 -0.9398)
			(end -0.508 -0.9398)
			(stroke
				(width 0.1524)
				(type default)
			)
			(layer "F.SilkS")
		)
		(fp_rect
			(start -0.508 0.9398)
			(end 0.508 -0.9398)
			(stroke
				(width 0)
				(type default)
			)
			(fill no)
			(layer "F.CrtYd")
		)
		(fp_rect
			(start -0.508 0.9398)
			(end 0.508 -0.9398)
			(stroke
				(width 0)
				(type default)
			)
			(fill no)
			(layer "F.Fab")
		)
		(pad "1" smd custom
			(at 0 -0.4445)
			(size 0.1397 0.1397)
			(layers "F.Cu" "F.Mask" "F.Paste")
			(net "HOST2_RST_N")
			(options
				(clearance outline)
				(anchor circle)
			)
			(primitives
				(gr_poly
					(pts
						(arc
							(start -0.1778 -0.2794)
							(mid -0.249642 -0.249642)
							(end -0.2794 -0.1778)
						)
						(arc
							(start -0.2794 0.1778)
							(mid -0.249642 0.249642)
							(end -0.1778 0.2794)
						)
						(arc
							(start 0.1778 0.2794)
							(mid 0.249642 0.249642)
							(end 0.2794 0.1778)
						)
						(arc
							(start 0.2794 -0.1778)
							(mid 0.249642 -0.249642)
							(end 0.1778 -0.2794)
						)
					)
					(width 0)
					(fill yes)
				)
			)
		)
		(pad "2" smd custom
			(at 0 0.4445)
			(size 0.1397 0.1397)
			(layers "F.Cu" "F.Mask" "F.Paste")
			(net "HOST2_RST_N_C")
			(options
				(clearance outline)
				(anchor circle)
			)
			(primitives
				(gr_poly
					(pts
						(arc
							(start -0.1778 -0.2794)
							(mid -0.249642 -0.249642)
							(end -0.2794 -0.1778)
						)
						(arc
							(start -0.2794 0.1778)
							(mid -0.249642 0.249642)
							(end -0.1778 0.2794)
						)
						(arc
							(start 0.1778 0.2794)
							(mid 0.249642 0.249642)
							(end 0.2794 0.1778)
						)
						(arc
							(start 0.2794 -0.1778)
							(mid 0.249642 -0.249642)
							(end 0.1778 -0.2794)
						)
					)
					(width 0)
					(fill yes)
				)
			)
		)
	)
	(footprint ""
		(layer "F.Cu")
		(at 118.23319 -48.43272 90)
		(property "Reference" "JP6"
			(at 0 0 90)
			(layer "F.SilkS")
			(hide yes)
			(effects
				(font
					(size 1.27 1.27)
				)
			)
		)
		(property "Value" "PIN-CON3-S-GP"
			(at -5.588 -5.3086 90)
			(unlocked yes)
			(layer "F.Fab")
			(hide yes)
			(effects
				(font
					(size 1.016 1.016)
					(thickness 0.1524)
				)
			)
		)
		(property "Device Type" "21S-91-03GB01"
			(at -5.588 -6.8326 90)
			(unlocked yes)
			(layer "F.Fab")
			(hide yes)
			(effects
				(font
					(size 1.016 1.016)
					(thickness 0.1524)
				)
			)
		)
		(duplicate_pad_numbers_are_jumpers no)
		(fp_line
			(start -4.0132 -1.6256)
			(end -2.7432 -1.6256)
			(stroke
				(width 0.4064)
				(type default)
			)
			(layer "F.SilkS")
		)
		(fp_line
			(start 3.8862 -1.4986)
			(end -3.8862 -1.4986)
			(stroke
				(width 0.1524)
				(type default)
			)
			(layer "F.SilkS")
		)
		(fp_line
			(start -3.8862 -1.4986)
			(end -3.8862 1.4986)
			(stroke
				(width 0.1524)
				(type default)
			)
			(layer "F.SilkS")
		)
		(fp_line
			(start -4.0132 -0.3556)
			(end -4.0132 -1.6256)
			(stroke
				(width 0.4064)
				(type default)
			)
			(layer "F.SilkS")
		)
		(fp_line
			(start 3.8862 1.4986)
			(end 3.8862 -1.4986)
			(stroke
				(width 0.1524)
				(type default)
			)
			(layer "F.SilkS")
		)
		(fp_line
			(start -3.8862 1.4986)
			(end 3.8862 1.4986)
			(stroke
				(width 0.1524)
				(type default)
			)
			(layer "F.SilkS")
		)
		(fp_circle
			(center 2.54 0)
			(end 2.54 1.0668)
			(stroke
				(width 0.3048)
				(type default)
			)
			(fill no)
			(layer "F.SilkS")
		)
		(fp_circle
			(center 0 0)
			(end 0 1.0668)
			(stroke
				(width 0.3048)
				(type default)
			)
			(fill no)
			(layer "F.SilkS")
		)
		(fp_circle
			(center -2.54 0)
			(end -2.54 1.0668)
			(stroke
				(width 0.3048)
				(type default)
			)
			(fill no)
			(layer "F.SilkS")
		)
		(fp_rect
			(start -3.6322 1.2446)
			(end 3.6322 -1.2446)
			(stroke
				(width 0)
				(type default)
			)
			(fill no)
			(layer "F.CrtYd")
		)
		(fp_poly
			(pts
				(xy 4.1402 -1.2446) (xy -3.6322 -1.2446) (xy -3.6322 1.2446) (xy 3.6322 1.2446) (xy 3.6322 -1.2319)
				(xy 4.1402 -1.2319) (xy 4.1402 1.7526) (xy -4.1402 1.7526) (xy -4.1402 -1.7526) (xy 4.1402 -1.7526)
			)
			(stroke
				(width 0)
				(type default)
			)
			(fill no)
			(layer "F.CrtYd")
		)
		(fp_rect
			(start -4.1402 1.7526)
			(end 4.1402 -1.7526)
			(stroke
				(width 0)
				(type default)
			)
			(fill no)
			(layer "F.Fab")
		)
		(pad "1" thru_hole circle
			(at -2.54 0 90)
			(size 1.4224 1.4224)
			(drill 1.016)
			(layers "*.Cu" "*.Mask")
			(remove_unused_layers no)
			(net "BMC_ADD2_PWR")
			(clearance 0.1524)
			(thermal_gap 0.1524)
		)
		(pad "2" thru_hole circle
			(at 0 0 90)
			(size 1.4224 1.4224)
			(drill 1.016)
			(layers "*.Cu" "*.Mask")
			(remove_unused_layers no)
			(net "BMC_ADD2")
			(clearance 0.1524)
			(thermal_gap 0.1524)
		)
		(pad "3" thru_hole circle
			(at 2.54 0 90)
			(size 1.4224 1.4224)
			(drill 1.016)
			(layers "*.Cu" "*.Mask")
			(remove_unused_layers no)
			(net "BMC_ADD2_GND")
			(clearance 0.1524)
			(thermal_gap 0.1524)
		)
	)
	(footprint ""
		(layer "F.Cu")
		(at 218.797124 -203.047092)
		(property "Reference" "R7919"
			(at 0 0 0)
			(layer "F.SilkS")
			(hide yes)
			(effects
				(font
					(size 1.27 1.27)
				)
			)
		)
		(property "Value" "0R2J-2-GP"
			(at 0.064008 -3.993896 0)
			(unlocked yes)
			(layer "F.Fab")
			(hide yes)
			(effects
				(font
					(size 1.016 1.016)
					(thickness 0.1524)
				)
			)
		)
		(property "Device Type" "R402H16"
			(at 0.064008 -5.517896 0)
			(unlocked yes)
			(layer "F.Fab")
			(hide yes)
			(effects
				(font
					(size 1.016 1.016)
					(thickness 0.1524)
				)
			)
		)
		(duplicate_pad_numbers_are_jumpers no)
		(fp_line
			(start -0.508 -0.9398)
			(end -0.508 0.9398)
			(stroke
				(width 0.1524)
				(type default)
			)
			(layer "F.SilkS")
		)
		(fp_line
			(start 0.508 -0.9398)
			(end -0.508 -0.9398)
			(stroke
				(width 0.1524)
				(type default)
			)
			(layer "F.SilkS")
		)
		(fp_rect
			(start -0.508 0.9398)
			(end 0.508 -0.9398)
			(stroke
				(width 0)
				(type default)
			)
			(fill no)
			(layer "F.CrtYd")
		)
		(fp_rect
			(start -0.508 0.9398)
			(end 0.508 -0.9398)
			(stroke
				(width 0)
				(type default)
			)
			(fill no)
			(layer "F.Fab")
		)
		(pad "1" smd custom
			(at 0 -0.4445)
			(size 0.1397 0.1397)
			(layers "F.Cu" "F.Mask" "F.Paste")
			(net "TWI_SCL1")
			(options
				(clearance outline)
				(anchor circle)
			)
			(primitives
				(gr_poly
					(pts
						(arc
							(start -0.1778 -0.2794)
							(mid -0.249642 -0.249642)
							(end -0.2794 -0.1778)
						)
						(arc
							(start -0.2794 0.1778)
							(mid -0.249642 0.249642)
							(end -0.1778 0.2794)
						)
						(arc
							(start 0.1778 0.2794)
							(mid 0.249642 0.249642)
							(end 0.2794 0.1778)
						)
						(arc
							(start 0.2794 -0.1778)
							(mid 0.249642 -0.249642)
							(end 0.1778 -0.2794)
						)
					)
					(width 0)
					(fill yes)
				)
			)
		)
		(pad "2" smd custom
			(at 0 0.4445)
			(size 0.1397 0.1397)
			(layers "F.Cu" "F.Mask" "F.Paste")
			(net "I2C_GPIO_SCL_3")
			(options
				(clearance outline)
				(anchor circle)
			)
			(primitives
				(gr_poly
					(pts
						(arc
							(start -0.1778 -0.2794)
							(mid -0.249642 -0.249642)
							(end -0.2794 -0.1778)
						)
						(arc
							(start -0.2794 0.1778)
							(mid -0.249642 0.249642)
							(end -0.1778 0.2794)
						)
						(arc
							(start 0.1778 0.2794)
							(mid 0.249642 0.249642)
							(end 0.2794 0.1778)
						)
						(arc
							(start 0.2794 -0.1778)
							(mid 0.249642 -0.249642)
							(end 0.1778 -0.2794)
						)
					)
					(width 0)
					(fill yes)
				)
			)
		)
	)
	(footprint ""
		(layer "F.Cu")
		(at 21.0312 -187.0456 90)
		(property "Reference" "PC1083"
			(at 0 0 90)
			(layer "F.SilkS")
			(hide yes)
			(effects
				(font
					(size 1.27 1.27)
				)
			)
		)
		(property "Value" "SC1U25V3KX-GP"
			(at 0 -2.8194 90)
			(unlocked yes)
			(layer "F.Fab")
			(hide yes)
			(effects
				(font
					(size 1.016 1.016)
					(thickness 0.1524)
				)
			)
		)
		(property "Device Type" "C603H36"
			(at 0 -4.3434 90)
			(unlocked yes)
			(layer "F.Fab")
			(hide yes)
			(effects
				(font
					(size 1.016 1.016)
					(thickness 0.1524)
				)
			)
		)
		(duplicate_pad_numbers_are_jumpers no)
		(fp_line
			(start 0.508 0)
			(end -0.508 0)
			(stroke
				(width 0.2032)
				(type default)
			)
			(layer "F.SilkS")
		)
		(fp_rect
			(start -0.5842 1.3335)
			(end 0.5842 -1.3335)
			(stroke
				(width 0)
				(type default)
			)
			(fill no)
			(layer "F.CrtYd")
		)
		(fp_rect
			(start -0.5842 1.3335)
			(end 0.5842 -1.3335)
			(stroke
				(width 0)
				(type default)
			)
			(fill no)
			(layer "F.Fab")
		)
		(pad "1" smd custom
			(at 0 -0.762 90)
			(size 0.2159 0.2159)
			(layers "F.Cu" "F.Mask" "F.Paste")
			(net "MB0_VCC")
			(options
				(clearance outline)
				(anchor circle)
			)
			(primitives
				(gr_poly
					(pts
						(arc
							(start -0.3302 -0.4318)
							(mid -0.402042 -0.402042)
							(end -0.4318 -0.3302)
						)
						(arc
							(start -0.4318 0.3302)
							(mid -0.402042 0.402042)
							(end -0.3302 0.4318)
						)
						(arc
							(start 0.3302 0.4318)
							(mid 0.402042 0.402042)
							(end 0.4318 0.3302)
						)
						(arc
							(start 0.4318 -0.3302)
							(mid 0.402042 -0.402042)
							(end 0.3302 -0.4318)
						)
					)
					(width 0)
					(fill yes)
				)
			)
		)
		(pad "2" smd custom
			(at 0 0.762 90)
			(size 0.2159 0.2159)
			(layers "F.Cu" "F.Mask" "F.Paste")
			(net "AGND_CURRENT_MON")
			(options
				(clearance outline)
				(anchor circle)
			)
			(primitives
				(gr_poly
					(pts
						(arc
							(start -0.3302 -0.4318)
							(mid -0.402042 -0.402042)
							(end -0.4318 -0.3302)
						)
						(arc
							(start -0.4318 0.3302)
							(mid -0.402042 0.402042)
							(end -0.3302 0.4318)
						)
						(arc
							(start 0.3302 0.4318)
							(mid 0.402042 0.402042)
							(end 0.4318 0.3302)
						)
						(arc
							(start 0.4318 -0.3302)
							(mid 0.402042 -0.402042)
							(end 0.3302 -0.4318)
						)
					)
					(width 0)
					(fill yes)
				)
			)
		)
	)
	(footprint ""
		(layer "F.Cu")
		(at 158.334202 -58.447432)
		(property "Reference" "PR178"
			(at 0 0 0)
			(layer "F.SilkS")
			(hide yes)
			(effects
				(font
					(size 1.27 1.27)
				)
			)
		)
		(property "Value" "51KR2F-L-GP"
			(at 0.064008 -3.993896 0)
			(unlocked yes)
			(layer "F.Fab")
			(hide yes)
			(effects
				(font
					(size 1.016 1.016)
					(thickness 0.1524)
				)
			)
		)
		(property "Device Type" "R402H16"
			(at 0.064008 -5.517896 0)
			(unlocked yes)
			(layer "F.Fab")
			(hide yes)
			(effects
				(font
					(size 1.016 1.016)
					(thickness 0.1524)
				)
			)
		)
		(duplicate_pad_numbers_are_jumpers no)
		(fp_line
			(start -0.508 -0.9398)
			(end -0.508 0.9398)
			(stroke
				(width 0.1524)
				(type default)
			)
			(layer "F.SilkS")
		)
		(fp_line
			(start 0.508 -0.9398)
			(end -0.508 -0.9398)
			(stroke
				(width 0.1524)
				(type default)
			)
			(layer "F.SilkS")
		)
		(fp_rect
			(start -0.508 0.9398)
			(end 0.508 -0.9398)
			(stroke
				(width 0)
				(type default)
			)
			(fill no)
			(layer "F.CrtYd")
		)
		(fp_rect
			(start -0.508 0.9398)
			(end 0.508 -0.9398)
			(stroke
				(width 0)
				(type default)
			)
			(fill no)
			(layer "F.Fab")
		)
		(pad "1" smd custom
			(at 0 -0.4445)
			(size 0.1397 0.1397)
			(layers "F.Cu" "F.Mask" "F.Paste")
			(net "P0V9_EN")
			(options
				(clearance outline)
				(anchor circle)
			)
			(primitives
				(gr_poly
					(pts
						(arc
							(start -0.1778 -0.2794)
							(mid -0.249642 -0.249642)
							(end -0.2794 -0.1778)
						)
						(arc
							(start -0.2794 0.1778)
							(mid -0.249642 0.249642)
							(end -0.1778 0.2794)
						)
						(arc
							(start 0.1778 0.2794)
							(mid 0.249642 0.249642)
							(end 0.2794 0.1778)
						)
						(arc
							(start 0.2794 -0.1778)
							(mid 0.249642 -0.249642)
							(end 0.1778 -0.2794)
						)
					)
					(width 0)
					(fill yes)
				)
			)
		)
		(pad "2" smd custom
			(at 0 0.4445)
			(size 0.1397 0.1397)
			(layers "F.Cu" "F.Mask" "F.Paste")
			(net "GND")
			(options
				(clearance outline)
				(anchor circle)
			)
			(primitives
				(gr_poly
					(pts
						(arc
							(start -0.1778 -0.2794)
							(mid -0.249642 -0.249642)
							(end -0.2794 -0.1778)
						)
						(arc
							(start -0.2794 0.1778)
							(mid -0.249642 0.249642)
							(end -0.1778 0.2794)
						)
						(arc
							(start 0.1778 0.2794)
							(mid 0.249642 0.249642)
							(end 0.2794 0.1778)
						)
						(arc
							(start 0.2794 -0.1778)
							(mid 0.249642 -0.249642)
							(end 0.1778 -0.2794)
						)
					)
					(width 0)
					(fill yes)
				)
			)
		)
	)
	(footprint ""
		(layer "F.Cu")
		(at 123.928124 -196.443092 180)
		(property "Reference" "R548"
			(at 0 0 180)
			(layer "F.SilkS")
			(hide yes)
			(effects
				(font
					(size 1.27 1.27)
				)
			)
		)
		(property "Value" "10KR2F-2-GP"
			(at 0.064008 -3.993896 180)
			(unlocked yes)
			(layer "F.Fab")
			(hide yes)
			(effects
				(font
					(size 1.016 1.016)
					(thickness 0.1524)
				)
			)
		)
		(property "Device Type" "R402H16"
			(at 0.064008 -5.517896 180)
			(unlocked yes)
			(layer "F.Fab")
			(hide yes)
			(effects
				(font
					(size 1.016 1.016)
					(thickness 0.1524)
				)
			)
		)
		(duplicate_pad_numbers_are_jumpers no)
		(fp_line
			(start 0.508 -0.9398)
			(end -0.508 -0.9398)
			(stroke
				(width 0.1524)
				(type default)
			)
			(layer "F.SilkS")
		)
		(fp_line
			(start -0.508 -0.9398)
			(end -0.508 0.9398)
			(stroke
				(width 0.1524)
				(type default)
			)
			(layer "F.SilkS")
		)
		(fp_rect
			(start -0.508 0.9398)
			(end 0.508 -0.9398)
			(stroke
				(width 0)
				(type default)
			)
			(fill no)
			(layer "F.CrtYd")
		)
		(fp_rect
			(start -0.508 0.9398)
			(end 0.508 -0.9398)
			(stroke
				(width 0)
				(type default)
			)
			(fill no)
			(layer "F.Fab")
		)
		(pad "1" smd custom
			(at 0 -0.4445 180)
			(size 0.1397 0.1397)
			(layers "F.Cu" "F.Mask" "F.Paste")
			(net "GND")
			(options
				(clearance outline)
				(anchor circle)
			)
			(primitives
				(gr_poly
					(pts
						(arc
							(start -0.1778 -0.2794)
							(mid -0.249642 -0.249642)
							(end -0.2794 -0.1778)
						)
						(arc
							(start -0.2794 0.1778)
							(mid -0.249642 0.249642)
							(end -0.1778 0.2794)
						)
						(arc
							(start 0.1778 0.2794)
							(mid 0.249642 0.249642)
							(end 0.2794 0.1778)
						)
						(arc
							(start 0.2794 -0.1778)
							(mid 0.249642 -0.249642)
							(end 0.1778 -0.2794)
						)
					)
					(width 0)
					(fill yes)
				)
			)
		)
		(pad "2" smd custom
			(at 0 0.4445 180)
			(size 0.1397 0.1397)
			(layers "F.Cu" "F.Mask" "F.Paste")
			(net "IOEXP2_AD1")
			(options
				(clearance outline)
				(anchor circle)
			)
			(primitives
				(gr_poly
					(pts
						(arc
							(start -0.1778 -0.2794)
							(mid -0.249642 -0.249642)
							(end -0.2794 -0.1778)
						)
						(arc
							(start -0.2794 0.1778)
							(mid -0.249642 0.249642)
							(end -0.1778 0.2794)
						)
						(arc
							(start 0.1778 0.2794)
							(mid 0.249642 0.249642)
							(end 0.2794 0.1778)
						)
						(arc
							(start 0.2794 -0.1778)
							(mid 0.249642 -0.249642)
							(end 0.1778 -0.2794)
						)
					)
					(width 0)
					(fill yes)
				)
			)
		)
	)
	(footprint ""
		(layer "F.Cu")
		(at 51.181 -195.58 90)
		(property "Reference" "U31"
			(at 0 0 90)
			(layer "F.SilkS")
			(hide yes)
			(effects
				(font
					(size 1.27 1.27)
				)
			)
		)
		(property "Value" "PCA9511ADP-T-GP"
			(at 0 -13.1572 90)
			(unlocked yes)
			(layer "F.Fab")
			(hide yes)
			(effects
				(font
					(size 1.016 1.016)
					(thickness 0.1524)
				)
			)
		)
		(property "Device Type" "SSOIC8-2H44"
			(at 0 -15.1892 90)
			(unlocked yes)
			(layer "F.Fab")
			(hide yes)
			(effects
				(font
					(size 1.016 1.016)
					(thickness 0.1524)
				)
			)
		)
		(duplicate_pad_numbers_are_jumpers no)
		(fp_line
			(start 1.0922 -1.016)
			(end 1.0922 1.016)
			(stroke
				(width 0.1524)
				(type default)
			)
			(layer "F.SilkS")
		)
		(fp_line
			(start -1.9304 -1.016)
			(end 1.0922 -1.016)
			(stroke
				(width 0.1524)
				(type default)
			)
			(layer "F.SilkS")
		)
		(fp_line
			(start -1.524 0)
			(end -1.9304 -0.4064)
			(stroke
				(width 0.1524)
				(type default)
			)
			(layer "F.SilkS")
		)
		(fp_line
			(start -1.524 0)
			(end -1.9304 0.4064)
			(stroke
				(width 0.1524)
				(type default)
			)
			(layer "F.SilkS")
		)
		(fp_line
			(start 1.0922 1.016)
			(end -1.9304 1.016)
			(stroke
				(width 0.1524)
				(type default)
			)
			(layer "F.SilkS")
		)
		(fp_line
			(start -1.9304 1.016)
			(end -1.9304 -1.016)
			(stroke
				(width 0.1524)
				(type default)
			)
			(layer "F.SilkS")
		)
		(fp_line
			(start -1.7018 1.0414)
			(end -1.7018 2.9718)
			(stroke
				(width 0.635)
				(type default)
			)
			(layer "F.SilkS")
		)
		(fp_poly
			(pts
				(xy -1.1938 -1.016) (xy 1.0922 -1.016) (xy 1.0922 1.016) (xy -1.1938 1.016)
			)
			(stroke
				(width 0)
				(type default)
			)
			(fill yes)
			(layer "F.SilkS")
		)
		(fp_rect
			(start -2.0066 3.3401)
			(end 2.0066 -3.3401)
			(stroke
				(width 0)
				(type default)
			)
			(fill no)
			(layer "F.CrtYd")
		)
		(fp_poly
			(pts
				(xy -2.0066 -3.3401) (xy 2.0066 -3.3401) (xy 2.0066 3.3401) (xy -2.0066 3.3401)
			)
			(stroke
				(width 0)
				(type default)
			)
			(fill no)
			(layer "F.Fab")
		)
		(pad "1" smd rect
			(at -0.97536 2.0701 90)
			(size 0.4064 1.524)
			(layers "F.Cu" "F.Mask" "F.Paste")
			(net "I2C7_BUFF_EN")
		)
		(pad "2" smd rect
			(at -0.32512 2.0701 90)
			(size 0.4064 1.524)
			(layers "F.Cu" "F.Mask" "F.Paste")
			(net "BMC_I2C7_B_DBP_SCL_R")
		)
		(pad "3" smd rect
			(at 0.32512 2.0701 90)
			(size 0.4064 1.524)
			(layers "F.Cu" "F.Mask" "F.Paste")
			(net "BUF_I2C7_B_DBP_SCL_R")
		)
		(pad "4" smd rect
			(at 0.97536 2.0701 90)
			(size 0.4064 1.524)
			(layers "F.Cu" "F.Mask" "F.Paste")
			(net "GND")
		)
		(pad "5" smd rect
			(at 0.97536 -2.0701 90)
			(size 0.4064 1.524)
			(layers "F.Cu" "F.Mask" "F.Paste")
			(net "I2C7_BUF_READY")
		)
		(pad "6" smd rect
			(at 0.32512 -2.0701 90)
			(size 0.4064 1.524)
			(layers "F.Cu" "F.Mask" "F.Paste")
			(net "BUF_I2C7_B_DPB_SDA_R")
		)
		(pad "7" smd rect
			(at -0.32512 -2.0701 90)
			(size 0.4064 1.524)
			(layers "F.Cu" "F.Mask" "F.Paste")
			(net "BMC_I2C7_B_DPB_SDA_R")
		)
		(pad "8" smd rect
			(at -0.97536 -2.0701 90)
			(size 0.4064 1.524)
			(layers "F.Cu" "F.Mask" "F.Paste")
			(net "P3V3_STBY")
		)
	)
	(footprint ""
		(layer "F.Cu")
		(at 75.180952 -148.12391 90)
		(property "Reference" "R198"
			(at 0 0 90)
			(layer "F.SilkS")
			(hide yes)
			(effects
				(font
					(size 1.27 1.27)
				)
			)
		)
		(property "Value" "8K2R2J-3-GP"
			(at 0.064008 -3.993896 90)
			(unlocked yes)
			(layer "F.Fab")
			(hide yes)
			(effects
				(font
					(size 1.016 1.016)
					(thickness 0.1524)
				)
			)
		)
		(property "Device Type" "R402H16"
			(at 0.064008 -5.517896 90)
			(unlocked yes)
			(layer "F.Fab")
			(hide yes)
			(effects
				(font
					(size 1.016 1.016)
					(thickness 0.1524)
				)
			)
		)
		(duplicate_pad_numbers_are_jumpers no)
		(fp_line
			(start 0.508 -0.9398)
			(end -0.508 -0.9398)
			(stroke
				(width 0.1524)
				(type default)
			)
			(layer "F.SilkS")
		)
		(fp_line
			(start -0.508 -0.9398)
			(end -0.508 0.9398)
			(stroke
				(width 0.1524)
				(type default)
			)
			(layer "F.SilkS")
		)
		(fp_rect
			(start -0.508 0.9398)
			(end 0.508 -0.9398)
			(stroke
				(width 0)
				(type default)
			)
			(fill no)
			(layer "F.CrtYd")
		)
		(fp_rect
			(start -0.508 0.9398)
			(end 0.508 -0.9398)
			(stroke
				(width 0)
				(type default)
			)
			(fill no)
			(layer "F.Fab")
		)
		(pad "1" smd custom
			(at 0 -0.4445 90)
			(size 0.1397 0.1397)
			(layers "F.Cu" "F.Mask" "F.Paste")
			(net "EEPROM_A1_R")
			(options
				(clearance outline)
				(anchor circle)
			)
			(primitives
				(gr_poly
					(pts
						(arc
							(start -0.1778 -0.2794)
							(mid -0.249642 -0.249642)
							(end -0.2794 -0.1778)
						)
						(arc
							(start -0.2794 0.1778)
							(mid -0.249642 0.249642)
							(end -0.1778 0.2794)
						)
						(arc
							(start 0.1778 0.2794)
							(mid 0.249642 0.249642)
							(end 0.2794 0.1778)
						)
						(arc
							(start 0.2794 -0.1778)
							(mid 0.249642 -0.249642)
							(end 0.1778 -0.2794)
						)
					)
					(width 0)
					(fill yes)
				)
			)
		)
		(pad "2" smd custom
			(at 0 0.4445 90)
			(size 0.1397 0.1397)
			(layers "F.Cu" "F.Mask" "F.Paste")
			(net "GND")
			(options
				(clearance outline)
				(anchor circle)
			)
			(primitives
				(gr_poly
					(pts
						(arc
							(start -0.1778 -0.2794)
							(mid -0.249642 -0.249642)
							(end -0.2794 -0.1778)
						)
						(arc
							(start -0.2794 0.1778)
							(mid -0.249642 0.249642)
							(end -0.1778 0.2794)
						)
						(arc
							(start 0.1778 0.2794)
							(mid 0.249642 0.249642)
							(end 0.2794 0.1778)
						)
						(arc
							(start 0.2794 -0.1778)
							(mid 0.249642 -0.249642)
							(end 0.1778 -0.2794)
						)
					)
					(width 0)
					(fill yes)
				)
			)
		)
	)
	(footprint ""
		(layer "F.Cu")
		(at 218.885008 -4.064)
		(property "Reference" "SC1116"
			(at 0 0 0)
			(layer "F.SilkS")
			(hide yes)
			(effects
				(font
					(size 1.27 1.27)
				)
			)
		)
		(property "Value" "SCD1U16V2KX-3GP"
			(at 1.1811 -2.7051 0)
			(unlocked yes)
			(layer "F.Fab")
			(hide yes)
			(effects
				(font
					(size 1.016 1.016)
					(thickness 0.1524)
				)
			)
		)
		(property "Device Type" "C402H22"
			(at 1.1811 -4.2291 0)
			(unlocked yes)
			(layer "F.Fab")
			(hide yes)
			(effects
				(font
					(size 1.016 1.016)
					(thickness 0.1524)
				)
			)
		)
		(duplicate_pad_numbers_are_jumpers no)
		(fp_rect
			(start -0.4318 0.9525)
			(end 0.4318 -0.9525)
			(stroke
				(width 0)
				(type default)
			)
			(fill no)
			(layer "F.CrtYd")
		)
		(fp_rect
			(start -0.4318 0.9525)
			(end 0.4318 -0.9525)
			(stroke
				(width 0)
				(type default)
			)
			(fill no)
			(layer "F.Fab")
		)
		(pad "1" smd custom
			(at 0 -0.4445)
			(size 0.1524 0.1524)
			(layers "F.Cu" "F.Mask" "F.Paste")
			(net "P3V3_STBY")
			(options
				(clearance outline)
				(anchor circle)
			)
			(primitives
				(gr_poly
					(pts
						(arc
							(start 0.3048 -0.2032)
							(mid 0.275042 -0.275042)
							(end 0.2032 -0.3048)
						)
						(arc
							(start -0.2032 -0.3048)
							(mid -0.275042 -0.275042)
							(end -0.3048 -0.2032)
						)
						(arc
							(start -0.3048 0.2032)
							(mid -0.275042 0.275042)
							(end -0.2032 0.3048)
						)
						(arc
							(start 0.2032 0.3048)
							(mid 0.275042 0.275042)
							(end 0.3048 0.2032)
						)
					)
					(width 0)
					(fill yes)
				)
			)
		)
		(pad "2" smd custom
			(at 0 0.4445)
			(size 0.1524 0.1524)
			(layers "F.Cu" "F.Mask" "F.Paste")
			(net "GND")
			(options
				(clearance outline)
				(anchor circle)
			)
			(primitives
				(gr_poly
					(pts
						(arc
							(start 0.3048 -0.2032)
							(mid 0.275042 -0.275042)
							(end 0.2032 -0.3048)
						)
						(arc
							(start -0.2032 -0.3048)
							(mid -0.275042 -0.275042)
							(end -0.3048 -0.2032)
						)
						(arc
							(start -0.3048 0.2032)
							(mid -0.275042 0.275042)
							(end -0.2032 0.3048)
						)
						(arc
							(start 0.2032 0.3048)
							(mid 0.275042 0.275042)
							(end 0.3048 0.2032)
						)
					)
					(width 0)
					(fill yes)
				)
			)
		)
	)
	(footprint ""
		(layer "F.Cu")
		(at 53.721 -132.461 -90)
		(property "Reference" "R320"
			(at 0 0 270)
			(layer "F.SilkS")
			(hide yes)
			(effects
				(font
					(size 1.27 1.27)
				)
			)
		)
		(property "Value" "0R2J-2-GP"
			(at 0.064008 -3.993896 270)
			(unlocked yes)
			(layer "F.Fab")
			(hide yes)
			(effects
				(font
					(size 1.016 1.016)
					(thickness 0.1524)
				)
			)
		)
		(property "Device Type" "R402H16"
			(at 0.064008 -5.517896 270)
			(unlocked yes)
			(layer "F.Fab")
			(hide yes)
			(effects
				(font
					(size 1.016 1.016)
					(thickness 0.1524)
				)
			)
		)
		(duplicate_pad_numbers_are_jumpers no)
		(fp_line
			(start -0.508 -0.9398)
			(end -0.508 0.9398)
			(stroke
				(width 0.1524)
				(type default)
			)
			(layer "F.SilkS")
		)
		(fp_line
			(start 0.508 -0.9398)
			(end -0.508 -0.9398)
			(stroke
				(width 0.1524)
				(type default)
			)
			(layer "F.SilkS")
		)
		(fp_rect
			(start -0.508 0.9398)
			(end 0.508 -0.9398)
			(stroke
				(width 0)
				(type default)
			)
			(fill no)
			(layer "F.CrtYd")
		)
		(fp_rect
			(start -0.508 0.9398)
			(end 0.508 -0.9398)
			(stroke
				(width 0)
				(type default)
			)
			(fill no)
			(layer "F.Fab")
		)
		(pad "1" smd custom
			(at 0 -0.4445 270)
			(size 0.1397 0.1397)
			(layers "F.Cu" "F.Mask" "F.Paste")
			(net "ADC_P1V53V")
			(options
				(clearance outline)
				(anchor circle)
			)
			(primitives
				(gr_poly
					(pts
						(arc
							(start -0.1778 -0.2794)
							(mid -0.249642 -0.249642)
							(end -0.2794 -0.1778)
						)
						(arc
							(start -0.2794 0.1778)
							(mid -0.249642 0.249642)
							(end -0.1778 0.2794)
						)
						(arc
							(start 0.1778 0.2794)
							(mid 0.249642 0.249642)
							(end 0.2794 0.1778)
						)
						(arc
							(start 0.2794 -0.1778)
							(mid 0.249642 -0.249642)
							(end 0.1778 -0.2794)
						)
					)
					(width 0)
					(fill yes)
				)
			)
		)
		(pad "2" smd custom
			(at 0 0.4445 270)
			(size 0.1397 0.1397)
			(layers "F.Cu" "F.Mask" "F.Paste")
			(net "ADC_P1V53_BMC")
			(options
				(clearance outline)
				(anchor circle)
			)
			(primitives
				(gr_poly
					(pts
						(arc
							(start -0.1778 -0.2794)
							(mid -0.249642 -0.249642)
							(end -0.2794 -0.1778)
						)
						(arc
							(start -0.2794 0.1778)
							(mid -0.249642 0.249642)
							(end -0.1778 0.2794)
						)
						(arc
							(start 0.1778 0.2794)
							(mid 0.249642 0.249642)
							(end 0.2794 0.1778)
						)
						(arc
							(start 0.2794 -0.1778)
							(mid 0.249642 -0.249642)
							(end 0.1778 -0.2794)
						)
					)
					(width 0)
					(fill yes)
				)
			)
		)
	)
	(footprint ""
		(layer "F.Cu")
		(at 52.671726 -37.968936)
		(property "Reference" "R618"
			(at 0 0 0)
			(layer "F.SilkS")
			(hide yes)
			(effects
				(font
					(size 1.27 1.27)
				)
			)
		)
		(property "Value" "47KR2F-GP"
			(at 0.064008 -3.993896 0)
			(unlocked yes)
			(layer "F.Fab")
			(hide yes)
			(effects
				(font
					(size 1.016 1.016)
					(thickness 0.1524)
				)
			)
		)
		(property "Device Type" "R402H16"
			(at 0.064008 -5.517896 0)
			(unlocked yes)
			(layer "F.Fab")
			(hide yes)
			(effects
				(font
					(size 1.016 1.016)
					(thickness 0.1524)
				)
			)
		)
		(duplicate_pad_numbers_are_jumpers no)
		(fp_line
			(start -0.508 -0.9398)
			(end -0.508 0.9398)
			(stroke
				(width 0.1524)
				(type default)
			)
			(layer "F.SilkS")
		)
		(fp_line
			(start 0.508 -0.9398)
			(end -0.508 -0.9398)
			(stroke
				(width 0.1524)
				(type default)
			)
			(layer "F.SilkS")
		)
		(fp_rect
			(start -0.508 0.9398)
			(end 0.508 -0.9398)
			(stroke
				(width 0)
				(type default)
			)
			(fill no)
			(layer "F.CrtYd")
		)
		(fp_rect
			(start -0.508 0.9398)
			(end 0.508 -0.9398)
			(stroke
				(width 0)
				(type default)
			)
			(fill no)
			(layer "F.Fab")
		)
		(pad "1" smd custom
			(at 0 -0.4445)
			(size 0.1397 0.1397)
			(layers "F.Cu" "F.Mask" "F.Paste")
			(net "P12V_PCIE")
			(options
				(clearance outline)
				(anchor circle)
			)
			(primitives
				(gr_poly
					(pts
						(arc
							(start -0.1778 -0.2794)
							(mid -0.249642 -0.249642)
							(end -0.2794 -0.1778)
						)
						(arc
							(start -0.2794 0.1778)
							(mid -0.249642 0.249642)
							(end -0.1778 0.2794)
						)
						(arc
							(start 0.1778 0.2794)
							(mid 0.249642 0.249642)
							(end 0.2794 0.1778)
						)
						(arc
							(start 0.2794 -0.1778)
							(mid 0.249642 -0.249642)
							(end 0.1778 -0.2794)
						)
					)
					(width 0)
					(fill yes)
				)
			)
		)
		(pad "2" smd custom
			(at 0 0.4445)
			(size 0.1397 0.1397)
			(layers "F.Cu" "F.Mask" "F.Paste")
			(net "Q42_D")
			(options
				(clearance outline)
				(anchor circle)
			)
			(primitives
				(gr_poly
					(pts
						(arc
							(start -0.1778 -0.2794)
							(mid -0.249642 -0.249642)
							(end -0.2794 -0.1778)
						)
						(arc
							(start -0.2794 0.1778)
							(mid -0.249642 0.249642)
							(end -0.1778 0.2794)
						)
						(arc
							(start 0.1778 0.2794)
							(mid 0.249642 0.249642)
							(end 0.2794 0.1778)
						)
						(arc
							(start 0.2794 -0.1778)
							(mid 0.249642 -0.249642)
							(end 0.1778 -0.2794)
						)
					)
					(width 0)
					(fill yes)
				)
			)
		)
	)
	(footprint ""
		(layer "F.Cu")
		(at 181.61 -29.845 -90)
		(property "Reference" "C403"
			(at 0 0 270)
			(layer "F.SilkS")
			(hide yes)
			(effects
				(font
					(size 1.27 1.27)
				)
			)
		)
		(property "Value" "SCD22U10V2KX-1GP"
			(at 1.1811 -2.7051 270)
			(unlocked yes)
			(layer "F.Fab")
			(hide yes)
			(effects
				(font
					(size 1.016 1.016)
					(thickness 0.1524)
				)
			)
		)
		(property "Device Type" "C402H22"
			(at 1.1811 -4.2291 270)
			(unlocked yes)
			(layer "F.Fab")
			(hide yes)
			(effects
				(font
					(size 1.016 1.016)
					(thickness 0.1524)
				)
			)
		)
		(duplicate_pad_numbers_are_jumpers no)
		(fp_rect
			(start -0.4318 0.9525)
			(end 0.4318 -0.9525)
			(stroke
				(width 0)
				(type default)
			)
			(fill no)
			(layer "F.CrtYd")
		)
		(fp_rect
			(start -0.4318 0.9525)
			(end 0.4318 -0.9525)
			(stroke
				(width 0)
				(type default)
			)
			(fill no)
			(layer "F.Fab")
		)
		(pad "1" smd custom
			(at 0 -0.4445 270)
			(size 0.1524 0.1524)
			(layers "F.Cu" "F.Mask" "F.Paste")
			(net "PCIE_TX_CAP_P91")
			(options
				(clearance outline)
				(anchor circle)
			)
			(primitives
				(gr_poly
					(pts
						(arc
							(start 0.3048 -0.2032)
							(mid 0.275042 -0.275042)
							(end 0.2032 -0.3048)
						)
						(arc
							(start -0.2032 -0.3048)
							(mid -0.275042 -0.275042)
							(end -0.3048 -0.2032)
						)
						(arc
							(start -0.3048 0.2032)
							(mid -0.275042 0.275042)
							(end -0.2032 0.3048)
						)
						(arc
							(start 0.2032 0.3048)
							(mid 0.275042 0.275042)
							(end 0.3048 0.2032)
						)
					)
					(width 0)
					(fill yes)
				)
			)
		)
		(pad "2" smd custom
			(at 0 0.4445 270)
			(size 0.1524 0.1524)
			(layers "F.Cu" "F.Mask" "F.Paste")
			(net "PCIE_TX_P91")
			(options
				(clearance outline)
				(anchor circle)
			)
			(primitives
				(gr_poly
					(pts
						(arc
							(start 0.3048 -0.2032)
							(mid 0.275042 -0.275042)
							(end 0.2032 -0.3048)
						)
						(arc
							(start -0.2032 -0.3048)
							(mid -0.275042 -0.275042)
							(end -0.3048 -0.2032)
						)
						(arc
							(start -0.3048 0.2032)
							(mid -0.275042 0.275042)
							(end -0.2032 0.3048)
						)
						(arc
							(start 0.2032 0.3048)
							(mid 0.275042 0.275042)
							(end 0.3048 0.2032)
						)
					)
					(width 0)
					(fill yes)
				)
			)
		)
	)
	(footprint ""
		(layer "F.Cu")
		(at 157.877002 -54.256432 90)
		(property "Reference" "C268"
			(at 0 0 90)
			(layer "F.SilkS")
			(hide yes)
			(effects
				(font
					(size 1.27 1.27)
				)
			)
		)
		(property "Value" "SC100P50V2JN-3GP"
			(at 1.1811 -2.7051 90)
			(unlocked yes)
			(layer "F.Fab")
			(hide yes)
			(effects
				(font
					(size 1.016 1.016)
					(thickness 0.1524)
				)
			)
		)
		(property "Device Type" "C402H22"
			(at 1.1811 -4.2291 90)
			(unlocked yes)
			(layer "F.Fab")
			(hide yes)
			(effects
				(font
					(size 1.016 1.016)
					(thickness 0.1524)
				)
			)
		)
		(duplicate_pad_numbers_are_jumpers no)
		(fp_rect
			(start -0.4318 0.9525)
			(end 0.4318 -0.9525)
			(stroke
				(width 0)
				(type default)
			)
			(fill no)
			(layer "F.CrtYd")
		)
		(fp_rect
			(start -0.4318 0.9525)
			(end 0.4318 -0.9525)
			(stroke
				(width 0)
				(type default)
			)
			(fill no)
			(layer "F.Fab")
		)
		(pad "1" smd custom
			(at 0 -0.4445 90)
			(size 0.1524 0.1524)
			(layers "F.Cu" "F.Mask" "F.Paste")
			(net "P0V9_VFB")
			(options
				(clearance outline)
				(anchor circle)
			)
			(primitives
				(gr_poly
					(pts
						(arc
							(start 0.3048 -0.2032)
							(mid 0.275042 -0.275042)
							(end 0.2032 -0.3048)
						)
						(arc
							(start -0.2032 -0.3048)
							(mid -0.275042 -0.275042)
							(end -0.3048 -0.2032)
						)
						(arc
							(start -0.3048 0.2032)
							(mid -0.275042 0.275042)
							(end -0.2032 0.3048)
						)
						(arc
							(start 0.2032 0.3048)
							(mid 0.275042 0.275042)
							(end 0.3048 0.2032)
						)
					)
					(width 0)
					(fill yes)
				)
			)
		)
		(pad "2" smd custom
			(at 0 0.4445 90)
			(size 0.1524 0.1524)
			(layers "F.Cu" "F.Mask" "F.Paste")
			(net "P0V9_VFB_R")
			(options
				(clearance outline)
				(anchor circle)
			)
			(primitives
				(gr_poly
					(pts
						(arc
							(start 0.3048 -0.2032)
							(mid 0.275042 -0.275042)
							(end 0.2032 -0.3048)
						)
						(arc
							(start -0.2032 -0.3048)
							(mid -0.275042 -0.275042)
							(end -0.3048 -0.2032)
						)
						(arc
							(start -0.3048 0.2032)
							(mid -0.275042 0.275042)
							(end -0.2032 0.3048)
						)
						(arc
							(start 0.2032 0.3048)
							(mid 0.275042 0.275042)
							(end 0.3048 0.2032)
						)
					)
					(width 0)
					(fill yes)
				)
			)
		)
	)
	(footprint ""
		(layer "F.Cu")
		(at 44.3738 -184.8866 90)
		(property "Reference" "C689"
			(at 0 0 90)
			(layer "F.SilkS")
			(hide yes)
			(effects
				(font
					(size 1.27 1.27)
				)
			)
		)
		(property "Value" "SC220P50V3JN-GP"
			(at 0 -2.8194 90)
			(unlocked yes)
			(layer "F.Fab")
			(hide yes)
			(effects
				(font
					(size 1.016 1.016)
					(thickness 0.1524)
				)
			)
		)
		(property "Device Type" "C603H36"
			(at 0 -4.3434 90)
			(unlocked yes)
			(layer "F.Fab")
			(hide yes)
			(effects
				(font
					(size 1.016 1.016)
					(thickness 0.1524)
				)
			)
		)
		(duplicate_pad_numbers_are_jumpers no)
		(fp_line
			(start 0.508 0)
			(end -0.508 0)
			(stroke
				(width 0.2032)
				(type default)
			)
			(layer "F.SilkS")
		)
		(fp_rect
			(start -0.5842 1.3335)
			(end 0.5842 -1.3335)
			(stroke
				(width 0)
				(type default)
			)
			(fill no)
			(layer "F.CrtYd")
		)
		(fp_rect
			(start -0.5842 1.3335)
			(end 0.5842 -1.3335)
			(stroke
				(width 0)
				(type default)
			)
			(fill no)
			(layer "F.Fab")
		)
		(pad "1" smd custom
			(at 0 -0.762 90)
			(size 0.2159 0.2159)
			(layers "F.Cu" "F.Mask" "F.Paste")
			(net "BMC_I2C9_CLKBUF2_SCL_R")
			(options
				(clearance outline)
				(anchor circle)
			)
			(primitives
				(gr_poly
					(pts
						(arc
							(start -0.3302 -0.4318)
							(mid -0.402042 -0.402042)
							(end -0.4318 -0.3302)
						)
						(arc
							(start -0.4318 0.3302)
							(mid -0.402042 0.402042)
							(end -0.3302 0.4318)
						)
						(arc
							(start 0.3302 0.4318)
							(mid 0.402042 0.402042)
							(end 0.4318 0.3302)
						)
						(arc
							(start 0.4318 -0.3302)
							(mid 0.402042 -0.402042)
							(end 0.3302 -0.4318)
						)
					)
					(width 0)
					(fill yes)
				)
			)
		)
		(pad "2" smd custom
			(at 0 0.762 90)
			(size 0.2159 0.2159)
			(layers "F.Cu" "F.Mask" "F.Paste")
			(net "GND")
			(options
				(clearance outline)
				(anchor circle)
			)
			(primitives
				(gr_poly
					(pts
						(arc
							(start -0.3302 -0.4318)
							(mid -0.402042 -0.402042)
							(end -0.4318 -0.3302)
						)
						(arc
							(start -0.4318 0.3302)
							(mid -0.402042 0.402042)
							(end -0.3302 0.4318)
						)
						(arc
							(start 0.3302 0.4318)
							(mid 0.402042 0.402042)
							(end 0.4318 0.3302)
						)
						(arc
							(start 0.4318 -0.3302)
							(mid 0.402042 -0.402042)
							(end 0.3302 -0.4318)
						)
					)
					(width 0)
					(fill yes)
				)
			)
		)
	)
	(footprint ""
		(layer "F.Cu")
		(at 71.749412 -195.689474)
		(property "Reference" "R453"
			(at 0 0 0)
			(layer "F.SilkS")
			(hide yes)
			(effects
				(font
					(size 1.27 1.27)
				)
			)
		)
		(property "Value" "10KR2F-2-GP"
			(at 0.064008 -3.993896 0)
			(unlocked yes)
			(layer "F.Fab")
			(hide yes)
			(effects
				(font
					(size 1.016 1.016)
					(thickness 0.1524)
				)
			)
		)
		(property "Device Type" "R402H16"
			(at 0.064008 -5.517896 0)
			(unlocked yes)
			(layer "F.Fab")
			(hide yes)
			(effects
				(font
					(size 1.016 1.016)
					(thickness 0.1524)
				)
			)
		)
		(duplicate_pad_numbers_are_jumpers no)
		(fp_line
			(start -0.508 -0.9398)
			(end -0.508 0.9398)
			(stroke
				(width 0.1524)
				(type default)
			)
			(layer "F.SilkS")
		)
		(fp_line
			(start 0.508 -0.9398)
			(end -0.508 -0.9398)
			(stroke
				(width 0.1524)
				(type default)
			)
			(layer "F.SilkS")
		)
		(fp_rect
			(start -0.508 0.9398)
			(end 0.508 -0.9398)
			(stroke
				(width 0)
				(type default)
			)
			(fill no)
			(layer "F.CrtYd")
		)
		(fp_rect
			(start -0.508 0.9398)
			(end 0.508 -0.9398)
			(stroke
				(width 0)
				(type default)
			)
			(fill no)
			(layer "F.Fab")
		)
		(pad "1" smd custom
			(at 0 -0.4445)
			(size 0.1397 0.1397)
			(layers "F.Cu" "F.Mask" "F.Paste")
			(net "GND")
			(options
				(clearance outline)
				(anchor circle)
			)
			(primitives
				(gr_poly
					(pts
						(arc
							(start -0.1778 -0.2794)
							(mid -0.249642 -0.249642)
							(end -0.2794 -0.1778)
						)
						(arc
							(start -0.2794 0.1778)
							(mid -0.249642 0.249642)
							(end -0.1778 0.2794)
						)
						(arc
							(start 0.1778 0.2794)
							(mid 0.249642 0.249642)
							(end 0.2794 0.1778)
						)
						(arc
							(start 0.2794 -0.1778)
							(mid 0.249642 -0.249642)
							(end 0.1778 -0.2794)
						)
					)
					(width 0)
					(fill yes)
				)
			)
		)
		(pad "2" smd custom
			(at 0 0.4445)
			(size 0.1397 0.1397)
			(layers "F.Cu" "F.Mask" "F.Paste")
			(net "IOEXP1_AD0")
			(options
				(clearance outline)
				(anchor circle)
			)
			(primitives
				(gr_poly
					(pts
						(arc
							(start -0.1778 -0.2794)
							(mid -0.249642 -0.249642)
							(end -0.2794 -0.1778)
						)
						(arc
							(start -0.2794 0.1778)
							(mid -0.249642 0.249642)
							(end -0.1778 0.2794)
						)
						(arc
							(start 0.1778 0.2794)
							(mid 0.249642 0.249642)
							(end 0.2794 0.1778)
						)
						(arc
							(start 0.2794 -0.1778)
							(mid 0.249642 -0.249642)
							(end 0.1778 -0.2794)
						)
					)
					(width 0)
					(fill yes)
				)
			)
		)
	)
	(footprint ""
		(layer "F.Cu")
		(at 32.418782 -112.19307)
		(property "Reference" "TP308"
			(at 0 0 0)
			(layer "F.SilkS")
			(hide yes)
			(effects
				(font
					(size 1.27 1.27)
				)
			)
		)
		(property "Value" "TPAD28-2-GP"
			(at -0.0127 -1.6637 0)
			(unlocked yes)
			(layer "F.Fab")
			(hide yes)
			(effects
				(font
					(size 1.016 1.016)
					(thickness 0.1524)
				)
			)
		)
		(property "Device Type" "TPAD28"
			(at -0.0127 -3.1877 0)
			(unlocked yes)
			(layer "F.Fab")
			(hide yes)
			(effects
				(font
					(size 1.016 1.016)
					(thickness 0.1524)
				)
			)
		)
		(duplicate_pad_numbers_are_jumpers no)
		(fp_poly
			(pts
				(arc
					(start 0.3556 0)
					(mid -0.3556 0)
					(end 0.3556 0)
				)
			)
			(stroke
				(width 0)
				(type default)
			)
			(fill no)
			(layer "F.CrtYd")
		)
		(fp_poly
			(pts
				(arc
					(start 0.6096 0)
					(mid -0.6096 0)
					(end 0.6096 0)
				)
			)
			(stroke
				(width 0)
				(type default)
			)
			(fill no)
			(layer "F.Fab")
		)
		(pad "1" smd circle
			(at 0 0)
			(size 0.7112 0.7112)
			(layers "F.Cu" "F.Mask" "F.Paste")
			(net "TP_GPIOD7")
		)
	)
	(footprint ""
		(layer "F.Cu")
		(at 152.634442 -9.53008)
		(property "Reference" "CN15"
			(at 0 0 0)
			(layer "F.SilkS")
			(hide yes)
			(effects
				(font
					(size 1.27 1.27)
				)
			)
		)
		(property "Value" "MLX-CONN144-12R-3-GP-U2"
			(at -33.7693 -12.9032 0)
			(unlocked yes)
			(layer "F.Fab")
			(hide yes)
			(effects
				(font
					(size 1.016 1.016)
					(thickness 0.1524)
				)
			)
		)
		(property "Device Type" "PREFIT-144P-459383U2H519"
			(at -33.7693 -14.4272 0)
			(unlocked yes)
			(layer "F.Fab")
			(hide yes)
			(effects
				(font
					(size 1.016 1.016)
					(thickness 0.1524)
				)
			)
		)
		(duplicate_pad_numbers_are_jumpers no)
		(fp_line
			(start -23.1775 -18.2118)
			(end 23.1775 -18.2118)
			(stroke
				(width 0.1524)
				(type default)
			)
			(layer "F.SilkS")
		)
		(fp_line
			(start -23.1775 20.6248)
			(end -23.1775 -18.2118)
			(stroke
				(width 0.1524)
				(type default)
			)
			(layer "F.SilkS")
		)
		(fp_line
			(start 23.1775 -18.2118)
			(end 23.1775 20.6248)
			(stroke
				(width 0.1524)
				(type default)
			)
			(layer "F.SilkS")
		)
		(fp_line
			(start 23.1775 14.489938)
			(end -23.1775 14.489938)
			(stroke
				(width 0.1524)
				(type default)
			)
			(layer "F.SilkS")
		)
		(fp_line
			(start 23.1775 20.6248)
			(end -23.1775 20.6248)
			(stroke
				(width 0.1524)
				(type default)
			)
			(layer "F.SilkS")
		)
		(fp_poly
			(pts
				(xy -23.1775 14.489938) (xy -23.1775 -18.2118) (xy 23.1775 -18.2118) (xy 23.1775 14.489938)
			)
			(stroke
				(width 0)
				(type default)
			)
			(fill yes)
			(layer "F.SilkS")
		)
		(fp_poly
			(pts
				(arc
					(start -21.745956 11.1252)
					(mid -21.999956 11.3792)
					(end -22.253956 11.1252)
				)
				(arc
					(start -22.253956 10.6172)
					(mid -21.999956 10.3632)
					(end -21.745956 10.6172)
				)
			)
			(stroke
				(width 0)
				(type default)
			)
			(fill yes)
			(layer "F.SilkS")
		)
		(fp_poly
			(pts
				(arc
					(start -19.246088 11.1252)
					(mid -19.500088 11.3792)
					(end -19.754088 11.1252)
				)
				(arc
					(start -19.754088 10.6172)
					(mid -19.500088 10.3632)
					(end -19.246088 10.6172)
				)
			)
			(stroke
				(width 0)
				(type default)
			)
			(fill yes)
			(layer "F.SilkS")
		)
		(fp_poly
			(pts
				(arc
					(start -18.496026 11.1252)
					(mid -18.750026 11.3792)
					(end -19.004026 11.1252)
				)
				(arc
					(start -19.004026 10.6172)
					(mid -18.750026 10.3632)
					(end -18.496026 10.6172)
				)
			)
			(stroke
				(width 0)
				(type default)
			)
			(fill yes)
			(layer "F.SilkS")
		)
		(fp_poly
			(pts
				(arc
					(start -17.745964 11.1252)
					(mid -17.999964 11.3792)
					(end -18.253964 11.1252)
				)
				(arc
					(start -18.253964 10.6172)
					(mid -17.999964 10.3632)
					(end -17.745964 10.6172)
				)
			)
			(stroke
				(width 0)
				(type default)
			)
			(fill yes)
			(layer "F.SilkS")
		)
		(fp_poly
			(pts
				(arc
					(start -16.995902 11.1252)
					(mid -17.249902 11.3792)
					(end -17.503902 11.1252)
				)
				(arc
					(start -17.503902 10.6172)
					(mid -17.249902 10.3632)
					(end -16.995902 10.6172)
				)
			)
			(stroke
				(width 0)
				(type default)
			)
			(fill yes)
			(layer "F.SilkS")
		)
		(fp_poly
			(pts
				(arc
					(start -16.256 -17.272)
					(mid -16.51 -17.526)
					(end -16.256 -17.78)
				)
				(arc
					(start -15.24 -17.78)
					(mid -14.986 -17.526)
					(end -15.24 -17.272)
				)
			)
			(stroke
				(width 0)
				(type default)
			)
			(fill yes)
			(layer "F.SilkS")
		)
		(fp_poly
			(pts
				(arc
					(start -16.24584 11.1252)
					(mid -16.49984 11.3792)
					(end -16.75384 11.1252)
				)
				(arc
					(start -16.75384 10.6172)
					(mid -16.49984 10.3632)
					(end -16.24584 10.6172)
				)
			)
			(stroke
				(width 0)
				(type default)
			)
			(fill yes)
			(layer "F.SilkS")
		)
		(fp_poly
			(pts
				(arc
					(start -15.495778 11.1252)
					(mid -15.749778 11.3792)
					(end -16.003778 11.1252)
				)
				(arc
					(start -16.003778 10.6172)
					(mid -15.749778 10.3632)
					(end -15.495778 10.6172)
				)
			)
			(stroke
				(width 0)
				(type default)
			)
			(fill yes)
			(layer "F.SilkS")
		)
		(fp_poly
			(pts
				(arc
					(start -14.745716 11.1252)
					(mid -14.999716 11.3792)
					(end -15.253716 11.1252)
				)
				(arc
					(start -15.253716 10.6172)
					(mid -14.999716 10.3632)
					(end -14.745716 10.6172)
				)
			)
			(stroke
				(width 0)
				(type default)
			)
			(fill yes)
			(layer "F.SilkS")
		)
		(fp_poly
			(pts
				(arc
					(start -13.995654 11.1252)
					(mid -14.249654 11.3792)
					(end -14.503654 11.1252)
				)
				(arc
					(start -14.503654 10.6172)
					(mid -14.249654 10.3632)
					(end -13.995654 10.6172)
				)
			)
			(stroke
				(width 0)
				(type default)
			)
			(fill yes)
			(layer "F.SilkS")
		)
		(fp_poly
			(pts
				(arc
					(start -13.245592 11.1252)
					(mid -13.499592 11.3792)
					(end -13.753592 11.1252)
				)
				(arc
					(start -13.753592 10.6172)
					(mid -13.499592 10.3632)
					(end -13.245592 10.6172)
				)
			)
			(stroke
				(width 0)
				(type default)
			)
			(fill yes)
			(layer "F.SilkS")
		)
		(fp_poly
			(pts
				(arc
					(start -10.745978 11.1252)
					(mid -10.999978 11.3792)
					(end -11.253978 11.1252)
				)
				(arc
					(start -11.253978 10.6172)
					(mid -10.999978 10.3632)
					(end -10.745978 10.6172)
				)
			)
			(stroke
				(width 0)
				(type default)
			)
			(fill yes)
			(layer "F.SilkS")
		)
		(fp_poly
			(pts
				(arc
					(start -8.24611 11.1252)
					(mid -8.50011 11.3792)
					(end -8.75411 11.1252)
				)
				(arc
					(start -8.75411 10.6172)
					(mid -8.50011 10.3632)
					(end -8.24611 10.6172)
				)
			)
			(stroke
				(width 0)
				(type default)
			)
			(fill yes)
			(layer "F.SilkS")
		)
		(fp_poly
			(pts
				(arc
					(start -7.496048 11.1252)
					(mid -7.750048 11.3792)
					(end -8.004048 11.1252)
				)
				(arc
					(start -8.004048 10.6172)
					(mid -7.750048 10.3632)
					(end -7.496048 10.6172)
				)
			)
			(stroke
				(width 0)
				(type default)
			)
			(fill yes)
			(layer "F.SilkS")
		)
		(fp_poly
			(pts
				(arc
					(start -6.745986 11.1252)
					(mid -6.999986 11.3792)
					(end -7.253986 11.1252)
				)
				(arc
					(start -7.253986 10.6172)
					(mid -6.999986 10.3632)
					(end -6.745986 10.6172)
				)
			)
			(stroke
				(width 0)
				(type default)
			)
			(fill yes)
			(layer "F.SilkS")
		)
		(fp_poly
			(pts
				(arc
					(start -5.995924 11.1252)
					(mid -6.249924 11.3792)
					(end -6.503924 11.1252)
				)
				(arc
					(start -6.503924 10.6172)
					(mid -6.249924 10.3632)
					(end -5.995924 10.6172)
				)
			)
			(stroke
				(width 0)
				(type default)
			)
			(fill yes)
			(layer "F.SilkS")
		)
		(fp_poly
			(pts
				(arc
					(start -5.334 -17.272)
					(mid -5.588 -17.526)
					(end -5.334 -17.78)
				)
				(arc
					(start -4.318 -17.78)
					(mid -4.064 -17.526)
					(end -4.318 -17.272)
				)
			)
			(stroke
				(width 0)
				(type default)
			)
			(fill yes)
			(layer "F.SilkS")
		)
		(fp_poly
			(pts
				(arc
					(start -5.245862 11.1252)
					(mid -5.499862 11.3792)
					(end -5.753862 11.1252)
				)
				(arc
					(start -5.753862 10.6172)
					(mid -5.499862 10.3632)
					(end -5.245862 10.6172)
				)
			)
			(stroke
				(width 0)
				(type default)
			)
			(fill yes)
			(layer "F.SilkS")
		)
		(fp_poly
			(pts
				(arc
					(start -4.4958 11.1252)
					(mid -4.7498 11.3792)
					(end -5.0038 11.1252)
				)
				(arc
					(start -5.0038 10.6172)
					(mid -4.7498 10.3632)
					(end -4.4958 10.6172)
				)
			)
			(stroke
				(width 0)
				(type default)
			)
			(fill yes)
			(layer "F.SilkS")
		)
		(fp_poly
			(pts
				(arc
					(start -3.745738 11.1252)
					(mid -3.999738 11.3792)
					(end -4.253738 11.1252)
				)
				(arc
					(start -4.253738 10.6172)
					(mid -3.999738 10.3632)
					(end -3.745738 10.6172)
				)
			)
			(stroke
				(width 0)
				(type default)
			)
			(fill yes)
			(layer "F.SilkS")
		)
		(fp_poly
			(pts
				(arc
					(start -2.995676 11.1252)
					(mid -3.249676 11.3792)
					(end -3.503676 11.1252)
				)
				(arc
					(start -3.503676 10.6172)
					(mid -3.249676 10.3632)
					(end -2.995676 10.6172)
				)
			)
			(stroke
				(width 0)
				(type default)
			)
			(fill yes)
			(layer "F.SilkS")
		)
		(fp_poly
			(pts
				(arc
					(start -2.245614 11.1252)
					(mid -2.499614 11.3792)
					(end -2.753614 11.1252)
				)
				(arc
					(start -2.753614 10.6172)
					(mid -2.499614 10.3632)
					(end -2.245614 10.6172)
				)
			)
			(stroke
				(width 0)
				(type default)
			)
			(fill yes)
			(layer "F.SilkS")
		)
		(fp_poly
			(pts
				(arc
					(start 0.254 11.1252)
					(mid 0 11.3792)
					(end -0.254 11.1252)
				)
				(arc
					(start -0.254 10.6172)
					(mid 0 10.3632)
					(end 0.254 10.6172)
				)
			)
			(stroke
				(width 0)
				(type default)
			)
			(fill yes)
			(layer "F.SilkS")
		)
		(fp_poly
			(pts
				(arc
					(start 2.753868 11.1252)
					(mid 2.499868 11.3792)
					(end 2.245868 11.1252)
				)
				(arc
					(start 2.245868 10.6172)
					(mid 2.499868 10.3632)
					(end 2.753868 10.6172)
				)
			)
			(stroke
				(width 0)
				(type default)
			)
			(fill yes)
			(layer "F.SilkS")
		)
		(fp_poly
			(pts
				(arc
					(start 3.50393 11.1252)
					(mid 3.24993 11.3792)
					(end 2.99593 11.1252)
				)
				(arc
					(start 2.99593 10.6172)
					(mid 3.24993 10.3632)
					(end 3.50393 10.6172)
				)
			)
			(stroke
				(width 0)
				(type default)
			)
			(fill yes)
			(layer "F.SilkS")
		)
		(fp_poly
			(pts
				(arc
					(start 4.253992 11.1252)
					(mid 3.999992 11.3792)
					(end 3.745992 11.1252)
				)
				(arc
					(start 3.745992 10.6172)
					(mid 3.999992 10.3632)
					(end 4.253992 10.6172)
				)
			)
			(stroke
				(width 0)
				(type default)
			)
			(fill yes)
			(layer "F.SilkS")
		)
		(fp_poly
			(pts
				(arc
					(start 5.004054 11.1252)
					(mid 4.750054 11.3792)
					(end 4.496054 11.1252)
				)
				(arc
					(start 4.496054 10.6172)
					(mid 4.750054 10.3632)
					(end 5.004054 10.6172)
				)
			)
			(stroke
				(width 0)
				(type default)
			)
			(fill yes)
			(layer "F.SilkS")
		)
		(fp_poly
			(pts
				(arc
					(start 5.754116 11.1252)
					(mid 5.500116 11.3792)
					(end 5.246116 11.1252)
				)
				(arc
					(start 5.246116 10.6172)
					(mid 5.500116 10.3632)
					(end 5.754116 10.6172)
				)
			)
			(stroke
				(width 0)
				(type default)
			)
			(fill yes)
			(layer "F.SilkS")
		)
		(fp_poly
			(pts
				(arc
					(start 5.842 -17.272)
					(mid 5.588 -17.526)
					(end 5.842 -17.78)
				)
				(arc
					(start 6.858 -17.78)
					(mid 7.112 -17.526)
					(end 6.858 -17.272)
				)
			)
			(stroke
				(width 0)
				(type default)
			)
			(fill yes)
			(layer "F.SilkS")
		)
		(fp_poly
			(pts
				(arc
					(start 6.504178 11.1252)
					(mid 6.250178 11.3792)
					(end 5.996178 11.1252)
				)
				(arc
					(start 5.996178 10.6172)
					(mid 6.250178 10.3632)
					(end 6.504178 10.6172)
				)
			)
			(stroke
				(width 0)
				(type default)
			)
			(fill yes)
			(layer "F.SilkS")
		)
		(fp_poly
			(pts
				(arc
					(start 7.25424 11.1252)
					(mid 7.00024 11.3792)
					(end 6.74624 11.1252)
				)
				(arc
					(start 6.74624 10.6172)
					(mid 7.00024 10.3632)
					(end 7.25424 10.6172)
				)
			)
			(stroke
				(width 0)
				(type default)
			)
			(fill yes)
			(layer "F.SilkS")
		)
		(fp_poly
			(pts
				(arc
					(start 8.004302 11.1252)
					(mid 7.750302 11.3792)
					(end 7.496302 11.1252)
				)
				(arc
					(start 7.496302 10.6172)
					(mid 7.750302 10.3632)
					(end 8.004302 10.6172)
				)
			)
			(stroke
				(width 0)
				(type default)
			)
			(fill yes)
			(layer "F.SilkS")
		)
		(fp_poly
			(pts
				(arc
					(start 8.754364 11.1252)
					(mid 8.500364 11.3792)
					(end 8.246364 11.1252)
				)
				(arc
					(start 8.246364 10.6172)
					(mid 8.500364 10.3632)
					(end 8.754364 10.6172)
				)
			)
			(stroke
				(width 0)
				(type default)
			)
			(fill yes)
			(layer "F.SilkS")
		)
		(fp_poly
			(pts
				(arc
					(start 11.253978 11.1252)
					(mid 10.999978 11.3792)
					(end 10.745978 11.1252)
				)
				(arc
					(start 10.745978 10.6172)
					(mid 10.999978 10.3632)
					(end 11.253978 10.6172)
				)
			)
			(stroke
				(width 0)
				(type default)
			)
			(fill yes)
			(layer "F.SilkS")
		)
		(fp_poly
			(pts
				(arc
					(start 13.753846 11.1252)
					(mid 13.499846 11.3792)
					(end 13.245846 11.1252)
				)
				(arc
					(start 13.245846 10.6172)
					(mid 13.499846 10.3632)
					(end 13.753846 10.6172)
				)
			)
			(stroke
				(width 0)
				(type default)
			)
			(fill yes)
			(layer "F.SilkS")
		)
		(fp_poly
			(pts
				(arc
					(start 14.503908 11.1252)
					(mid 14.249908 11.3792)
					(end 13.995908 11.1252)
				)
				(arc
					(start 13.995908 10.6172)
					(mid 14.249908 10.3632)
					(end 14.503908 10.6172)
				)
			)
			(stroke
				(width 0)
				(type default)
			)
			(fill yes)
			(layer "F.SilkS")
		)
		(fp_poly
			(pts
				(arc
					(start 15.25397 11.1252)
					(mid 14.99997 11.3792)
					(end 14.74597 11.1252)
				)
				(arc
					(start 14.74597 10.6172)
					(mid 14.99997 10.3632)
					(end 15.25397 10.6172)
				)
			)
			(stroke
				(width 0)
				(type default)
			)
			(fill yes)
			(layer "F.SilkS")
		)
		(fp_poly
			(pts
				(arc
					(start 16.004032 11.1252)
					(mid 15.750032 11.3792)
					(end 15.496032 11.1252)
				)
				(arc
					(start 15.496032 10.6172)
					(mid 15.750032 10.3632)
					(end 16.004032 10.6172)
				)
			)
			(stroke
				(width 0)
				(type default)
			)
			(fill yes)
			(layer "F.SilkS")
		)
		(fp_poly
			(pts
				(arc
					(start 16.754094 11.1252)
					(mid 16.500094 11.3792)
					(end 16.246094 11.1252)
				)
				(arc
					(start 16.246094 10.6172)
					(mid 16.500094 10.3632)
					(end 16.754094 10.6172)
				)
			)
			(stroke
				(width 0)
				(type default)
			)
			(fill yes)
			(layer "F.SilkS")
		)
		(fp_poly
			(pts
				(arc
					(start 16.764 -17.272)
					(mid 16.51 -17.526)
					(end 16.764 -17.78)
				)
				(arc
					(start 17.78 -17.78)
					(mid 18.034 -17.526)
					(end 17.78 -17.272)
				)
			)
			(stroke
				(width 0)
				(type default)
			)
			(fill yes)
			(layer "F.SilkS")
		)
		(fp_poly
			(pts
				(arc
					(start 17.504156 11.1252)
					(mid 17.250156 11.3792)
					(end 16.996156 11.1252)
				)
				(arc
					(start 16.996156 10.6172)
					(mid 17.250156 10.3632)
					(end 17.504156 10.6172)
				)
			)
			(stroke
				(width 0)
				(type default)
			)
			(fill yes)
			(layer "F.SilkS")
		)
		(fp_poly
			(pts
				(arc
					(start 18.254218 11.1252)
					(mid 18.000218 11.3792)
					(end 17.746218 11.1252)
				)
				(arc
					(start 17.746218 10.6172)
					(mid 18.000218 10.3632)
					(end 18.254218 10.6172)
				)
			)
			(stroke
				(width 0)
				(type default)
			)
			(fill yes)
			(layer "F.SilkS")
		)
		(fp_poly
			(pts
				(arc
					(start 19.00428 11.1252)
					(mid 18.75028 11.3792)
					(end 18.49628 11.1252)
				)
				(arc
					(start 18.49628 10.6172)
					(mid 18.75028 10.3632)
					(end 19.00428 10.6172)
				)
			)
			(stroke
				(width 0)
				(type default)
			)
			(fill yes)
			(layer "F.SilkS")
		)
		(fp_poly
			(pts
				(arc
					(start 19.754342 11.1252)
					(mid 19.500342 11.3792)
					(end 19.246342 11.1252)
				)
				(arc
					(start 19.246342 10.6172)
					(mid 19.500342 10.3632)
					(end 19.754342 10.6172)
				)
			)
			(stroke
				(width 0)
				(type default)
			)
			(fill yes)
			(layer "F.SilkS")
		)
		(fp_poly
			(pts
				(arc
					(start 22.253956 11.1252)
					(mid 21.999956 11.3792)
					(end 21.745956 11.1252)
				)
				(arc
					(start 21.745956 10.6172)
					(mid 21.999956 10.3632)
					(end 22.253956 10.6172)
				)
			)
			(stroke
				(width 0)
				(type default)
			)
			(fill yes)
			(layer "F.SilkS")
		)
		(fp_rect
			(start -27.4574 15.0622)
			(end 27.4574 -22.9616)
			(stroke
				(width 0)
				(type default)
			)
			(fill no)
			(layer "B.CrtYd")
		)
		(fp_rect
			(start -22.9235 20.3708)
			(end 22.9235 -17.8816)
			(stroke
				(width 0)
				(type default)
			)
			(fill no)
			(layer "F.CrtYd")
		)
		(fp_poly
			(pts
				(xy -27.9273 25.3746) (xy -27.9273 -22.8854) (xy 27.9273 -22.8854) (xy 27.9273 -0.00635) (xy 25.006554 -0.00635)
				(xy 25.006554 -6.197854) (xy 23.431754 -6.197854) (xy 23.431754 -18.389854) (xy 22.504654 -18.389854)
				(xy 22.504654 -21.209254) (xy -22.504654 -21.209254) (xy -22.504654 -18.389854) (xy -23.431754 -18.389854)
				(xy -23.431754 -6.197854) (xy -25.006554 -6.197854) (xy -25.006554 11.811254) (xy -23.431754 11.811254)
				(xy -23.431754 20.879054) (xy 23.431754 20.879054) (xy 23.431754 11.811254) (xy 25.006554 11.811254)
				(xy 25.006554 0.00635) (xy 27.9273 0.00635) (xy 27.9273 25.3746)
			)
			(stroke
				(width 0)
				(type default)
			)
			(fill no)
			(layer "F.CrtYd")
		)
		(fp_poly
			(pts
				(xy -23.4315 20.8788) (xy -23.4315 11.811) (xy -25.0063 11.811) (xy -25.0063 -6.1976) (xy -23.4315 -6.1976)
				(xy -23.4315 -18.3896) (xy -22.5044 -18.3896) (xy -22.5044 -21.209) (xy 22.5044 -21.209) (xy 22.5044 -18.3896)
				(xy 23.4315 -18.3896) (xy 23.4315 -6.1976) (xy 25.0063 -6.1976) (xy 25.0063 -0.00635) (xy 22.9235 -0.00635)
				(xy 22.9235 -17.8816) (xy -22.9235 -17.8816) (xy -22.9235 20.3708) (xy 22.9235 20.3708) (xy 22.9235 0.00635)
				(xy 25.0063 0.00635) (xy 25.0063 11.811) (xy 23.4315 11.811) (xy 23.4315 20.8788)
			)
			(stroke
				(width 0)
				(type default)
			)
			(fill no)
			(layer "F.CrtYd")
		)
		(fp_rect
			(start -32.4612 20.066)
			(end 32.4612 -27.9654)
			(stroke
				(width 0)
				(type default)
			)
			(fill no)
			(layer "B.Fab")
		)
		(fp_rect
			(start -27.4574 15.0622)
			(end 27.4574 -22.9616)
			(stroke
				(width 0)
				(type default)
			)
			(fill no)
			(layer "B.Fab")
		)
		(fp_rect
			(start -32.9311 30.3784)
			(end 32.9311 -27.8892)
			(stroke
				(width 0)
				(type default)
			)
			(fill no)
			(layer "F.Fab")
		)
		(fp_rect
			(start -27.9273 25.3746)
			(end 27.9273 -22.8854)
			(stroke
				(width 0)
				(type default)
			)
			(fill no)
			(layer "F.Fab")
		)
		(fp_poly
			(pts
				(xy -23.4315 20.8788) (xy -23.4315 11.811) (xy -25.0063 11.811) (xy -25.0063 -6.1976) (xy -23.4315 -6.1976)
				(xy -23.4315 -18.3896) (xy -22.5044 -18.3896) (xy -22.5044 -21.209) (xy 22.5044 -21.209) (xy 22.5044 -18.4658)
				(xy 23.4315 -18.4658) (xy 23.4315 -6.1976) (xy 25.0063 -6.1976) (xy 25.0063 11.811) (xy 23.4315 11.811)
				(xy 23.4315 20.8788)
			)
			(stroke
				(width 0)
				(type default)
			)
			(fill no)
			(layer "F.Fab")
		)
		(fp_text user "Press Fit"
			(at -5.1308 12.403836 0)
			(unlocked yes)
			(layer "F.SilkS")
			(effects
				(font
					(size 1.016 1.016)
					(thickness 0.1524)
				)
				(justify left)
			)
		)
		(fp_text user "Can not place BGA,CSP,Wave Solder Component"
			(at -25.0444 18.677636 0)
			(unlocked yes)
			(layer "B.Fab")
			(effects
				(font
					(size 1.016 1.016)
					(thickness 0.1524)
				)
				(justify left)
			)
		)
		(fp_text user "Can not place BGA,CSP,Wave Solder Component"
			(at -24.0284 28.837636 0)
			(unlocked yes)
			(layer "F.Fab")
			(effects
				(font
					(size 1.016 1.016)
					(thickness 0.1524)
				)
				(justify left)
			)
		)
		(fp_text user "High Limit 2mm"
			(at -8.1026 24.265636 0)
			(unlocked yes)
			(layer "F.Fab")
			(effects
				(font
					(size 1.016 1.016)
					(thickness 0.1524)
				)
				(justify left)
			)
		)
		(pad "AA1" thru_hole circle
			(at -19.500088 -4.400042)
			(size 0.7366 0.7366)
			(drill 0.369824)
			(layers "*.Cu" "*.Mask")
			(remove_unused_layers no)
			(net "PCIE_REFCLK_H2_P_R")
			(clearance 0.1778)
			(thermal_gap 0.1778)
		)
		(pad "AA2" thru_hole circle
			(at -18.750026 -2.999994)
			(size 0.7366 0.7366)
			(drill 0.369824)
			(layers "*.Cu" "*.Mask")
			(remove_unused_layers no)
			(net "PCIE_REFCLK_H2_N_R")
			(clearance 0.1778)
			(thermal_gap 0.1778)
		)
		(pad "AA3" thru_hole circle
			(at -17.999964 -3.700018)
			(size 0.7366 0.7366)
			(drill 0.369824)
			(layers "*.Cu" "*.Mask")
			(remove_unused_layers no)
			(net "GND")
			(clearance 0.1778)
			(thermal_gap 0.1778)
		)
		(pad "AA4" thru_hole circle
			(at -17.249902 -4.400042)
			(size 0.7366 0.7366)
			(drill 0.369824)
			(layers "*.Cu" "*.Mask")
			(remove_unused_layers no)
			(net "PCIE_RX_P80")
			(clearance 0.1778)
			(thermal_gap 0.1778)
		)
		(pad "AA5" thru_hole circle
			(at -16.500094 -2.999994)
			(size 0.7366 0.7366)
			(drill 0.369824)
			(layers "*.Cu" "*.Mask")
			(remove_unused_layers no)
			(net "PCIE_RX_N80")
			(clearance 0.1778)
			(thermal_gap 0.1778)
		)
		(pad "AA6" thru_hole circle
			(at -15.750032 -3.700018)
			(size 0.7366 0.7366)
			(drill 0.369824)
			(layers "*.Cu" "*.Mask")
			(remove_unused_layers no)
			(net "GND")
			(clearance 0.1778)
			(thermal_gap 0.1778)
		)
		(pad "AA7" thru_hole circle
			(at -14.99997 -4.400042)
			(size 0.7366 0.7366)
			(drill 0.369824)
			(layers "*.Cu" "*.Mask")
			(remove_unused_layers no)
			(net "PCIE_RX_P83")
			(clearance 0.1778)
			(thermal_gap 0.1778)
		)
		(pad "AA8" thru_hole circle
			(at -14.249908 -2.999994)
			(size 0.7366 0.7366)
			(drill 0.369824)
			(layers "*.Cu" "*.Mask")
			(remove_unused_layers no)
			(net "PCIE_RX_N83")
			(clearance 0.1778)
			(thermal_gap 0.1778)
		)
		(pad "AA9" thru_hole circle
			(at -13.5001 -3.700018)
			(size 0.7366 0.7366)
			(drill 0.369824)
			(layers "*.Cu" "*.Mask")
			(remove_unused_layers no)
			(net "GND")
			(clearance 0.1778)
			(thermal_gap 0.1778)
		)
		(pad "AB1" thru_hole circle
			(at -19.500088 -8.199882)
			(size 0.7366 0.7366)
			(drill 0.369824)
			(layers "*.Cu" "*.Mask")
			(remove_unused_layers no)
			(net "HOST1_RST_N_C")
			(clearance 0.1778)
			(thermal_gap 0.1778)
		)
		(pad "AB2" thru_hole circle
			(at -18.750026 -6.800088)
			(size 0.7366 0.7366)
			(drill 0.369824)
			(layers "*.Cu" "*.Mask")
			(remove_unused_layers no)
			(net "8644_SDA_R_1")
			(clearance 0.1778)
			(thermal_gap 0.1778)
		)
		(pad "AB3" thru_hole circle
			(at -17.999964 -7.500112)
			(size 0.7366 0.7366)
			(drill 0.369824)
			(layers "*.Cu" "*.Mask")
			(remove_unused_layers no)
			(net "GND")
			(clearance 0.1778)
			(thermal_gap 0.1778)
		)
		(pad "AB4" thru_hole circle
			(at -17.249902 -8.199882)
			(size 0.7366 0.7366)
			(drill 0.369824)
			(layers "*.Cu" "*.Mask")
			(remove_unused_layers no)
			(net "PCIE_RX_P81")
			(clearance 0.1778)
			(thermal_gap 0.1778)
		)
		(pad "AB5" thru_hole circle
			(at -16.500094 -6.800088)
			(size 0.7366 0.7366)
			(drill 0.369824)
			(layers "*.Cu" "*.Mask")
			(remove_unused_layers no)
			(net "PCIE_RX_N81")
			(clearance 0.1778)
			(thermal_gap 0.1778)
		)
		(pad "AB6" thru_hole circle
			(at -15.750032 -7.500112)
			(size 0.7366 0.7366)
			(drill 0.369824)
			(layers "*.Cu" "*.Mask")
			(remove_unused_layers no)
			(net "GND")
			(clearance 0.1778)
			(thermal_gap 0.1778)
		)
		(pad "AB7" thru_hole circle
			(at -14.99997 -8.199882)
			(size 0.7366 0.7366)
			(drill 0.369824)
			(layers "*.Cu" "*.Mask")
			(remove_unused_layers no)
			(net "PCIE_RX_P82")
			(clearance 0.1778)
			(thermal_gap 0.1778)
		)
		(pad "AB8" thru_hole circle
			(at -14.249908 -6.800088)
			(size 0.7366 0.7366)
			(drill 0.369824)
			(layers "*.Cu" "*.Mask")
			(remove_unused_layers no)
			(net "PCIE_RX_N82")
			(clearance 0.1778)
			(thermal_gap 0.1778)
		)
		(pad "AB9" thru_hole circle
			(at -13.5001 -7.500112)
			(size 0.7366 0.7366)
			(drill 0.369824)
			(layers "*.Cu" "*.Mask")
			(remove_unused_layers no)
			(net "GND")
			(clearance 0.1778)
			(thermal_gap 0.1778)
		)
		(pad "AC1" thru_hole circle
			(at -19.500088 -11.999976)
			(size 0.7366 0.7366)
			(drill 0.369824)
			(layers "*.Cu" "*.Mask")
			(remove_unused_layers no)
			(net "BMC_I2C1_MINI1_SCL")
			(clearance 0.1778)
			(thermal_gap 0.1778)
		)
		(pad "AC2" thru_hole circle
			(at -18.750026 -10.599928)
			(size 0.7366 0.7366)
			(drill 0.369824)
			(layers "*.Cu" "*.Mask")
			(remove_unused_layers no)
			(net "8644_CBL_PRSNT_R_1")
			(clearance 0.1778)
			(thermal_gap 0.1778)
		)
		(pad "AC3" thru_hole circle
			(at -17.999964 -11.299952)
			(size 0.7366 0.7366)
			(drill 0.369824)
			(layers "*.Cu" "*.Mask")
			(remove_unused_layers no)
			(net "GND")
			(clearance 0.1778)
			(thermal_gap 0.1778)
		)
		(pad "AC4" thru_hole circle
			(at -17.249902 -11.999976)
			(size 0.7366 0.7366)
			(drill 0.369824)
			(layers "*.Cu" "*.Mask")
			(remove_unused_layers no)
			(net "PCIE_TX_P80")
			(clearance 0.1778)
			(thermal_gap 0.1778)
		)
		(pad "AC5" thru_hole circle
			(at -16.500094 -10.599928)
			(size 0.7366 0.7366)
			(drill 0.369824)
			(layers "*.Cu" "*.Mask")
			(remove_unused_layers no)
			(net "PCIE_TX_N80")
			(clearance 0.1778)
			(thermal_gap 0.1778)
		)
		(pad "AC6" thru_hole circle
			(at -15.750032 -11.299952)
			(size 0.7366 0.7366)
			(drill 0.369824)
			(layers "*.Cu" "*.Mask")
			(remove_unused_layers no)
			(net "GND")
			(clearance 0.1778)
			(thermal_gap 0.1778)
		)
		(pad "AC7" thru_hole circle
			(at -14.99997 -11.999976)
			(size 0.7366 0.7366)
			(drill 0.369824)
			(layers "*.Cu" "*.Mask")
			(remove_unused_layers no)
			(net "PCIE_TX_P83")
			(clearance 0.1778)
			(thermal_gap 0.1778)
		)
		(pad "AC8" thru_hole circle
			(at -14.249908 -10.599928)
			(size 0.7366 0.7366)
			(drill 0.369824)
			(layers "*.Cu" "*.Mask")
			(remove_unused_layers no)
			(net "PCIE_TX_N83")
			(clearance 0.1778)
			(thermal_gap 0.1778)
		)
		(pad "AC9" thru_hole circle
			(at -13.5001 -11.299952)
			(size 0.7366 0.7366)
			(drill 0.369824)
			(layers "*.Cu" "*.Mask")
			(remove_unused_layers no)
			(net "GND")
			(clearance 0.1778)
			(thermal_gap 0.1778)
		)
		(pad "AD1" thru_hole circle
			(at -19.500088 -15.80007)
			(size 0.7366 0.7366)
			(drill 0.369824)
			(layers "*.Cu" "*.Mask")
			(remove_unused_layers no)
			(net "8644_USB_DN1")
			(clearance 0.1778)
			(thermal_gap 0.1778)
		)
		(pad "AD2" thru_hole circle
			(at -18.750026 -14.400022)
			(size 0.7366 0.7366)
			(drill 0.369824)
			(layers "*.Cu" "*.Mask")
			(remove_unused_layers no)
			(net "8644_USB_DP1")
			(clearance 0.1778)
			(thermal_gap 0.1778)
		)
		(pad "AD3" thru_hole circle
			(at -17.999964 -15.100046)
			(size 0.7366 0.7366)
			(drill 0.369824)
			(layers "*.Cu" "*.Mask")
			(remove_unused_layers no)
			(net "GND")
			(clearance 0.1778)
			(thermal_gap 0.1778)
		)
		(pad "AD4" thru_hole circle
			(at -17.249902 -15.80007)
			(size 0.7366 0.7366)
			(drill 0.369824)
			(layers "*.Cu" "*.Mask")
			(remove_unused_layers no)
			(net "PCIE_TX_P81")
			(clearance 0.1778)
			(thermal_gap 0.1778)
		)
		(pad "AD5" thru_hole circle
			(at -16.500094 -14.400022)
			(size 0.7366 0.7366)
			(drill 0.369824)
			(layers "*.Cu" "*.Mask")
			(remove_unused_layers no)
			(net "PCIE_TX_N81")
			(clearance 0.1778)
			(thermal_gap 0.1778)
		)
		(pad "AD6" thru_hole circle
			(at -15.750032 -15.100046)
			(size 0.7366 0.7366)
			(drill 0.369824)
			(layers "*.Cu" "*.Mask")
			(remove_unused_layers no)
			(net "GND")
			(clearance 0.1778)
			(thermal_gap 0.1778)
		)
		(pad "AD7" thru_hole circle
			(at -14.99997 -15.80007)
			(size 0.7366 0.7366)
			(drill 0.369824)
			(layers "*.Cu" "*.Mask")
			(remove_unused_layers no)
			(net "PCIE_TX_P82")
			(clearance 0.1778)
			(thermal_gap 0.1778)
		)
		(pad "AD8" thru_hole circle
			(at -14.249908 -14.400022)
			(size 0.7366 0.7366)
			(drill 0.369824)
			(layers "*.Cu" "*.Mask")
			(remove_unused_layers no)
			(net "PCIE_TX_N82")
			(clearance 0.1778)
			(thermal_gap 0.1778)
		)
		(pad "AD9" thru_hole circle
			(at -13.5001 -15.100046)
			(size 0.7366 0.7366)
			(drill 0.369824)
			(layers "*.Cu" "*.Mask")
			(remove_unused_layers no)
			(net "GND")
			(clearance 0.1778)
			(thermal_gap 0.1778)
		)
		(pad "BA1" thru_hole circle
			(at -8.50011 -4.400042)
			(size 0.7366 0.7366)
			(drill 0.369824)
			(layers "*.Cu" "*.Mask")
			(remove_unused_layers no)
			(net "CLK_P_2")
			(clearance 0.1778)
			(thermal_gap 0.1778)
		)
		(pad "BA2" thru_hole circle
			(at -7.750048 -2.999994)
			(size 0.7366 0.7366)
			(drill 0.369824)
			(layers "*.Cu" "*.Mask")
			(remove_unused_layers no)
			(net "CLK_N_2")
			(clearance 0.1778)
			(thermal_gap 0.1778)
		)
		(pad "BA3" thru_hole circle
			(at -6.999986 -3.700018)
			(size 0.7366 0.7366)
			(drill 0.369824)
			(layers "*.Cu" "*.Mask")
			(remove_unused_layers no)
			(net "GND")
			(clearance 0.1778)
			(thermal_gap 0.1778)
		)
		(pad "BA4" thru_hole circle
			(at -6.249924 -4.400042)
			(size 0.7366 0.7366)
			(drill 0.369824)
			(layers "*.Cu" "*.Mask")
			(remove_unused_layers no)
			(net "PCIE_RX_P84")
			(clearance 0.1778)
			(thermal_gap 0.1778)
		)
		(pad "BA5" thru_hole circle
			(at -5.500116 -2.999994)
			(size 0.7366 0.7366)
			(drill 0.369824)
			(layers "*.Cu" "*.Mask")
			(remove_unused_layers no)
			(net "PCIE_RX_N84")
			(clearance 0.1778)
			(thermal_gap 0.1778)
		)
		(pad "BA6" thru_hole circle
			(at -4.750054 -3.700018)
			(size 0.7366 0.7366)
			(drill 0.369824)
			(layers "*.Cu" "*.Mask")
			(remove_unused_layers no)
			(net "GND")
			(clearance 0.1778)
			(thermal_gap 0.1778)
		)
		(pad "BA7" thru_hole circle
			(at -3.999992 -4.400042)
			(size 0.7366 0.7366)
			(drill 0.369824)
			(layers "*.Cu" "*.Mask")
			(remove_unused_layers no)
			(net "PCIE_RX_P87")
			(clearance 0.1778)
			(thermal_gap 0.1778)
		)
		(pad "BA8" thru_hole circle
			(at -3.24993 -2.999994)
			(size 0.7366 0.7366)
			(drill 0.369824)
			(layers "*.Cu" "*.Mask")
			(remove_unused_layers no)
			(net "PCIE_RX_N87")
			(clearance 0.1778)
			(thermal_gap 0.1778)
		)
		(pad "BA9" thru_hole circle
			(at -2.500122 -3.700018)
			(size 0.7366 0.7366)
			(drill 0.369824)
			(layers "*.Cu" "*.Mask")
			(remove_unused_layers no)
			(net "GND")
			(clearance 0.1778)
			(thermal_gap 0.1778)
		)
		(pad "BB1" thru_hole circle
			(at -8.50011 -8.199882)
			(size 0.7366 0.7366)
			(drill 0.369824)
			(layers "*.Cu" "*.Mask")
			(remove_unused_layers no)
			(net "HOST2_RST_N_C")
			(clearance 0.1778)
			(thermal_gap 0.1778)
		)
		(pad "BB2" thru_hole circle
			(at -7.750048 -6.800088)
			(size 0.7366 0.7366)
			(drill 0.369824)
			(layers "*.Cu" "*.Mask")
			(remove_unused_layers no)
			(net "8644_SDA_R_2")
			(clearance 0.1778)
			(thermal_gap 0.1778)
		)
		(pad "BB3" thru_hole circle
			(at -6.999986 -7.500112)
			(size 0.7366 0.7366)
			(drill 0.369824)
			(layers "*.Cu" "*.Mask")
			(remove_unused_layers no)
			(net "GND")
			(clearance 0.1778)
			(thermal_gap 0.1778)
		)
		(pad "BB4" thru_hole circle
			(at -6.249924 -8.199882)
			(size 0.7366 0.7366)
			(drill 0.369824)
			(layers "*.Cu" "*.Mask")
			(remove_unused_layers no)
			(net "PCIE_RX_P85")
			(clearance 0.1778)
			(thermal_gap 0.1778)
		)
		(pad "BB5" thru_hole circle
			(at -5.500116 -6.800088)
			(size 0.7366 0.7366)
			(drill 0.369824)
			(layers "*.Cu" "*.Mask")
			(remove_unused_layers no)
			(net "PCIE_RX_N85")
			(clearance 0.1778)
			(thermal_gap 0.1778)
		)
		(pad "BB6" thru_hole circle
			(at -4.750054 -7.500112)
			(size 0.7366 0.7366)
			(drill 0.369824)
			(layers "*.Cu" "*.Mask")
			(remove_unused_layers no)
			(net "GND")
			(clearance 0.1778)
			(thermal_gap 0.1778)
		)
		(pad "BB7" thru_hole circle
			(at -3.999992 -8.199882)
			(size 0.7366 0.7366)
			(drill 0.369824)
			(layers "*.Cu" "*.Mask")
			(remove_unused_layers no)
			(net "PCIE_RX_P86")
			(clearance 0.1778)
			(thermal_gap 0.1778)
		)
		(pad "BB8" thru_hole circle
			(at -3.24993 -6.800088)
			(size 0.7366 0.7366)
			(drill 0.369824)
			(layers "*.Cu" "*.Mask")
			(remove_unused_layers no)
			(net "PCIE_RX_N86")
			(clearance 0.1778)
			(thermal_gap 0.1778)
		)
		(pad "BB9" thru_hole circle
			(at -2.500122 -7.500112)
			(size 0.7366 0.7366)
			(drill 0.369824)
			(layers "*.Cu" "*.Mask")
			(remove_unused_layers no)
			(net "GND")
			(clearance 0.1778)
			(thermal_gap 0.1778)
		)
		(pad "BC1" thru_hole circle
			(at -8.50011 -11.999976)
			(size 0.7366 0.7366)
			(drill 0.369824)
			(layers "*.Cu" "*.Mask")
			(remove_unused_layers no)
			(net "BMC_I2C2_MINI2_SCL")
			(clearance 0.1778)
			(thermal_gap 0.1778)
		)
		(pad "BC2" thru_hole circle
			(at -7.750048 -10.599928)
			(size 0.7366 0.7366)
			(drill 0.369824)
			(layers "*.Cu" "*.Mask")
			(remove_unused_layers no)
			(net "8644_CBL_PRSNT_R_2")
			(clearance 0.1778)
			(thermal_gap 0.1778)
		)
		(pad "BC3" thru_hole circle
			(at -6.999986 -11.299952)
			(size 0.7366 0.7366)
			(drill 0.369824)
			(layers "*.Cu" "*.Mask")
			(remove_unused_layers no)
			(net "GND")
			(clearance 0.1778)
			(thermal_gap 0.1778)
		)
		(pad "BC4" thru_hole circle
			(at -6.249924 -11.999976)
			(size 0.7366 0.7366)
			(drill 0.369824)
			(layers "*.Cu" "*.Mask")
			(remove_unused_layers no)
			(net "PCIE_TX_P84")
			(clearance 0.1778)
			(thermal_gap 0.1778)
		)
		(pad "BC5" thru_hole circle
			(at -5.500116 -10.599928)
			(size 0.7366 0.7366)
			(drill 0.369824)
			(layers "*.Cu" "*.Mask")
			(remove_unused_layers no)
			(net "PCIE_TX_N84")
			(clearance 0.1778)
			(thermal_gap 0.1778)
		)
		(pad "BC6" thru_hole circle
			(at -4.750054 -11.299952)
			(size 0.7366 0.7366)
			(drill 0.369824)
			(layers "*.Cu" "*.Mask")
			(remove_unused_layers no)
			(net "GND")
			(clearance 0.1778)
			(thermal_gap 0.1778)
		)
		(pad "BC7" thru_hole circle
			(at -3.999992 -11.999976)
			(size 0.7366 0.7366)
			(drill 0.369824)
			(layers "*.Cu" "*.Mask")
			(remove_unused_layers no)
			(net "PCIE_TX_P87")
			(clearance 0.1778)
			(thermal_gap 0.1778)
		)
		(pad "BC8" thru_hole circle
			(at -3.24993 -10.599928)
			(size 0.7366 0.7366)
			(drill 0.369824)
			(layers "*.Cu" "*.Mask")
			(remove_unused_layers no)
			(net "PCIE_TX_N87")
			(clearance 0.1778)
			(thermal_gap 0.1778)
		)
		(pad "BC9" thru_hole circle
			(at -2.500122 -11.299952)
			(size 0.7366 0.7366)
			(drill 0.369824)
			(layers "*.Cu" "*.Mask")
			(remove_unused_layers no)
			(net "GND")
			(clearance 0.1778)
			(thermal_gap 0.1778)
		)
		(pad "BD1" thru_hole circle
			(at -8.50011 -15.80007)
			(size 0.7366 0.7366)
			(drill 0.369824)
			(layers "*.Cu" "*.Mask")
			(remove_unused_layers no)
			(net "8644_USB_DN2")
			(clearance 0.1778)
			(thermal_gap 0.1778)
		)
		(pad "BD2" thru_hole circle
			(at -7.750048 -14.400022)
			(size 0.7366 0.7366)
			(drill 0.369824)
			(layers "*.Cu" "*.Mask")
			(remove_unused_layers no)
			(net "8644_USB_DP2")
			(clearance 0.1778)
			(thermal_gap 0.1778)
		)
		(pad "BD3" thru_hole circle
			(at -6.999986 -15.100046)
			(size 0.7366 0.7366)
			(drill 0.369824)
			(layers "*.Cu" "*.Mask")
			(remove_unused_layers no)
			(net "GND")
			(clearance 0.1778)
			(thermal_gap 0.1778)
		)
		(pad "BD4" thru_hole circle
			(at -6.249924 -15.80007)
			(size 0.7366 0.7366)
			(drill 0.369824)
			(layers "*.Cu" "*.Mask")
			(remove_unused_layers no)
			(net "PCIE_TX_P85")
			(clearance 0.1778)
			(thermal_gap 0.1778)
		)
		(pad "BD5" thru_hole circle
			(at -5.500116 -14.400022)
			(size 0.7366 0.7366)
			(drill 0.369824)
			(layers "*.Cu" "*.Mask")
			(remove_unused_layers no)
			(net "PCIE_TX_N85")
			(clearance 0.1778)
			(thermal_gap 0.1778)
		)
		(pad "BD6" thru_hole circle
			(at -4.750054 -15.100046)
			(size 0.7366 0.7366)
			(drill 0.369824)
			(layers "*.Cu" "*.Mask")
			(remove_unused_layers no)
			(net "GND")
			(clearance 0.1778)
			(thermal_gap 0.1778)
		)
		(pad "BD7" thru_hole circle
			(at -3.999992 -15.80007)
			(size 0.7366 0.7366)
			(drill 0.369824)
			(layers "*.Cu" "*.Mask")
			(remove_unused_layers no)
			(net "PCIE_TX_P86")
			(clearance 0.1778)
			(thermal_gap 0.1778)
		)
		(pad "BD8" thru_hole circle
			(at -3.24993 -14.400022)
			(size 0.7366 0.7366)
			(drill 0.369824)
			(layers "*.Cu" "*.Mask")
			(remove_unused_layers no)
			(net "PCIE_TX_N86")
			(clearance 0.1778)
			(thermal_gap 0.1778)
		)
		(pad "BD9" thru_hole circle
			(at -2.500122 -15.100046)
			(size 0.7366 0.7366)
			(drill 0.369824)
			(layers "*.Cu" "*.Mask")
			(remove_unused_layers no)
			(net "GND")
			(clearance 0.1778)
			(thermal_gap 0.1778)
		)
		(pad "CA1" thru_hole circle
			(at 2.500122 -4.400042)
			(size 0.7366 0.7366)
			(drill 0.369824)
			(layers "*.Cu" "*.Mask")
			(remove_unused_layers no)
			(net "PCIE_REFCLK_H3_P_R")
			(clearance 0.1778)
			(thermal_gap 0.1778)
		)
		(pad "CA2" thru_hole circle
			(at 3.24993 -2.999994)
			(size 0.7366 0.7366)
			(drill 0.369824)
			(layers "*.Cu" "*.Mask")
			(remove_unused_layers no)
			(net "PCIE_REFCLK_H3_N_R")
			(clearance 0.1778)
			(thermal_gap 0.1778)
		)
		(pad "CA3" thru_hole circle
			(at 3.999992 -3.700018)
			(size 0.7366 0.7366)
			(drill 0.369824)
			(layers "*.Cu" "*.Mask")
			(remove_unused_layers no)
			(net "GND")
			(clearance 0.1778)
			(thermal_gap 0.1778)
		)
		(pad "CA4" thru_hole circle
			(at 4.750054 -4.400042)
			(size 0.7366 0.7366)
			(drill 0.369824)
			(layers "*.Cu" "*.Mask")
			(remove_unused_layers no)
			(net "PCIE_RX_P88")
			(clearance 0.1778)
			(thermal_gap 0.1778)
		)
		(pad "CA5" thru_hole circle
			(at 5.500116 -2.999994)
			(size 0.7366 0.7366)
			(drill 0.369824)
			(layers "*.Cu" "*.Mask")
			(remove_unused_layers no)
			(net "PCIE_RX_N88")
			(clearance 0.1778)
			(thermal_gap 0.1778)
		)
		(pad "CA6" thru_hole circle
			(at 6.249924 -3.700018)
			(size 0.7366 0.7366)
			(drill 0.369824)
			(layers "*.Cu" "*.Mask")
			(remove_unused_layers no)
			(net "GND")
			(clearance 0.1778)
			(thermal_gap 0.1778)
		)
		(pad "CA7" thru_hole circle
			(at 6.999986 -4.400042)
			(size 0.7366 0.7366)
			(drill 0.369824)
			(layers "*.Cu" "*.Mask")
			(remove_unused_layers no)
			(net "PCIE_RX_P91")
			(clearance 0.1778)
			(thermal_gap 0.1778)
		)
		(pad "CA8" thru_hole circle
			(at 7.750048 -2.999994)
			(size 0.7366 0.7366)
			(drill 0.369824)
			(layers "*.Cu" "*.Mask")
			(remove_unused_layers no)
			(net "PCIE_RX_N91")
			(clearance 0.1778)
			(thermal_gap 0.1778)
		)
		(pad "CA9" thru_hole circle
			(at 8.50011 -3.700018)
			(size 0.7366 0.7366)
			(drill 0.369824)
			(layers "*.Cu" "*.Mask")
			(remove_unused_layers no)
			(net "GND")
			(clearance 0.1778)
			(thermal_gap 0.1778)
		)
		(pad "CB1" thru_hole circle
			(at 2.500122 -8.199882)
			(size 0.7366 0.7366)
			(drill 0.369824)
			(layers "*.Cu" "*.Mask")
			(remove_unused_layers no)
			(net "HOST3_RST_N_C")
			(clearance 0.1778)
			(thermal_gap 0.1778)
		)
		(pad "CB2" thru_hole circle
			(at 3.24993 -6.800088)
			(size 0.7366 0.7366)
			(drill 0.369824)
			(layers "*.Cu" "*.Mask")
			(remove_unused_layers no)
			(net "8644_SDA_R_3")
			(clearance 0.1778)
			(thermal_gap 0.1778)
		)
		(pad "CB3" thru_hole circle
			(at 3.999992 -7.500112)
			(size 0.7366 0.7366)
			(drill 0.369824)
			(layers "*.Cu" "*.Mask")
			(remove_unused_layers no)
			(net "GND")
			(clearance 0.1778)
			(thermal_gap 0.1778)
		)
		(pad "CB4" thru_hole circle
			(at 4.750054 -8.199882)
			(size 0.7366 0.7366)
			(drill 0.369824)
			(layers "*.Cu" "*.Mask")
			(remove_unused_layers no)
			(net "PCIE_RX_P89")
			(clearance 0.1778)
			(thermal_gap 0.1778)
		)
		(pad "CB5" thru_hole circle
			(at 5.500116 -6.800088)
			(size 0.7366 0.7366)
			(drill 0.369824)
			(layers "*.Cu" "*.Mask")
			(remove_unused_layers no)
			(net "PCIE_RX_N89")
			(clearance 0.1778)
			(thermal_gap 0.1778)
		)
		(pad "CB6" thru_hole circle
			(at 6.249924 -7.500112)
			(size 0.7366 0.7366)
			(drill 0.369824)
			(layers "*.Cu" "*.Mask")
			(remove_unused_layers no)
			(net "GND")
			(clearance 0.1778)
			(thermal_gap 0.1778)
		)
		(pad "CB7" thru_hole circle
			(at 6.999986 -8.199882)
			(size 0.7366 0.7366)
			(drill 0.369824)
			(layers "*.Cu" "*.Mask")
			(remove_unused_layers no)
			(net "PCIE_RX_P90")
			(clearance 0.1778)
			(thermal_gap 0.1778)
		)
		(pad "CB8" thru_hole circle
			(at 7.750048 -6.800088)
			(size 0.7366 0.7366)
			(drill 0.369824)
			(layers "*.Cu" "*.Mask")
			(remove_unused_layers no)
			(net "PCIE_RX_N90")
			(clearance 0.1778)
			(thermal_gap 0.1778)
		)
		(pad "CB9" thru_hole circle
			(at 8.50011 -7.500112)
			(size 0.7366 0.7366)
			(drill 0.369824)
			(layers "*.Cu" "*.Mask")
			(remove_unused_layers no)
			(net "GND")
			(clearance 0.1778)
			(thermal_gap 0.1778)
		)
		(pad "CC1" thru_hole circle
			(at 2.500122 -11.999976)
			(size 0.7366 0.7366)
			(drill 0.369824)
			(layers "*.Cu" "*.Mask")
			(remove_unused_layers no)
			(net "BMC_I2C3_MINI3_SCL")
			(clearance 0.1778)
			(thermal_gap 0.1778)
		)
		(pad "CC2" thru_hole circle
			(at 3.24993 -10.599928)
			(size 0.7366 0.7366)
			(drill 0.369824)
			(layers "*.Cu" "*.Mask")
			(remove_unused_layers no)
			(net "8644_CBL_PRSNT_R_3")
			(clearance 0.1778)
			(thermal_gap 0.1778)
		)
		(pad "CC3" thru_hole circle
			(at 3.999992 -11.299952)
			(size 0.7366 0.7366)
			(drill 0.369824)
			(layers "*.Cu" "*.Mask")
			(remove_unused_layers no)
			(net "GND")
			(clearance 0.1778)
			(thermal_gap 0.1778)
		)
		(pad "CC4" thru_hole circle
			(at 4.750054 -11.999976)
			(size 0.7366 0.7366)
			(drill 0.369824)
			(layers "*.Cu" "*.Mask")
			(remove_unused_layers no)
			(net "PCIE_TX_P88")
			(clearance 0.1778)
			(thermal_gap 0.1778)
		)
		(pad "CC5" thru_hole circle
			(at 5.500116 -10.599928)
			(size 0.7366 0.7366)
			(drill 0.369824)
			(layers "*.Cu" "*.Mask")
			(remove_unused_layers no)
			(net "PCIE_TX_N88")
			(clearance 0.1778)
			(thermal_gap 0.1778)
		)
		(pad "CC6" thru_hole circle
			(at 6.249924 -11.299952)
			(size 0.7366 0.7366)
			(drill 0.369824)
			(layers "*.Cu" "*.Mask")
			(remove_unused_layers no)
			(net "GND")
			(clearance 0.1778)
			(thermal_gap 0.1778)
		)
		(pad "CC7" thru_hole circle
			(at 6.999986 -11.999976)
			(size 0.7366 0.7366)
			(drill 0.369824)
			(layers "*.Cu" "*.Mask")
			(remove_unused_layers no)
			(net "PCIE_TX_P91")
			(clearance 0.1778)
			(thermal_gap 0.1778)
		)
		(pad "CC8" thru_hole circle
			(at 7.750048 -10.599928)
			(size 0.7366 0.7366)
			(drill 0.369824)
			(layers "*.Cu" "*.Mask")
			(remove_unused_layers no)
			(net "PCIE_TX_N91")
			(clearance 0.1778)
			(thermal_gap 0.1778)
		)
		(pad "CC9" thru_hole circle
			(at 8.50011 -11.299952)
			(size 0.7366 0.7366)
			(drill 0.369824)
			(layers "*.Cu" "*.Mask")
			(remove_unused_layers no)
			(net "GND")
			(clearance 0.1778)
			(thermal_gap 0.1778)
		)
		(pad "CD1" thru_hole circle
			(at 2.500122 -15.80007)
			(size 0.7366 0.7366)
			(drill 0.369824)
			(layers "*.Cu" "*.Mask")
			(remove_unused_layers no)
			(net "8644_USB_DN3")
			(clearance 0.1778)
			(thermal_gap 0.1778)
		)
		(pad "CD2" thru_hole circle
			(at 3.24993 -14.400022)
			(size 0.7366 0.7366)
			(drill 0.369824)
			(layers "*.Cu" "*.Mask")
			(remove_unused_layers no)
			(net "8644_USB_DP3")
			(clearance 0.1778)
			(thermal_gap 0.1778)
		)
		(pad "CD3" thru_hole circle
			(at 3.999992 -15.100046)
			(size 0.7366 0.7366)
			(drill 0.369824)
			(layers "*.Cu" "*.Mask")
			(remove_unused_layers no)
			(net "GND")
			(clearance 0.1778)
			(thermal_gap 0.1778)
		)
		(pad "CD4" thru_hole circle
			(at 4.750054 -15.80007)
			(size 0.7366 0.7366)
			(drill 0.369824)
			(layers "*.Cu" "*.Mask")
			(remove_unused_layers no)
			(net "PCIE_TX_P89")
			(clearance 0.1778)
			(thermal_gap 0.1778)
		)
		(pad "CD5" thru_hole circle
			(at 5.500116 -14.400022)
			(size 0.7366 0.7366)
			(drill 0.369824)
			(layers "*.Cu" "*.Mask")
			(remove_unused_layers no)
			(net "PCIE_TX_N89")
			(clearance 0.1778)
			(thermal_gap 0.1778)
		)
		(pad "CD6" thru_hole circle
			(at 6.249924 -15.100046)
			(size 0.7366 0.7366)
			(drill 0.369824)
			(layers "*.Cu" "*.Mask")
			(remove_unused_layers no)
			(net "GND")
			(clearance 0.1778)
			(thermal_gap 0.1778)
		)
		(pad "CD7" thru_hole circle
			(at 6.999986 -15.80007)
			(size 0.7366 0.7366)
			(drill 0.369824)
			(layers "*.Cu" "*.Mask")
			(remove_unused_layers no)
			(net "PCIE_TX_P90")
			(clearance 0.1778)
			(thermal_gap 0.1778)
		)
		(pad "CD8" thru_hole circle
			(at 7.750048 -14.400022)
			(size 0.7366 0.7366)
			(drill 0.369824)
			(layers "*.Cu" "*.Mask")
			(remove_unused_layers no)
			(net "PCIE_TX_N90")
			(clearance 0.1778)
			(thermal_gap 0.1778)
		)
		(pad "CD9" thru_hole circle
			(at 8.50011 -15.100046)
			(size 0.7366 0.7366)
			(drill 0.369824)
			(layers "*.Cu" "*.Mask")
			(remove_unused_layers no)
			(net "GND")
			(clearance 0.1778)
			(thermal_gap 0.1778)
		)
		(pad "DA1" thru_hole circle
			(at 13.5001 -4.400042)
			(size 0.7366 0.7366)
			(drill 0.369824)
			(layers "*.Cu" "*.Mask")
			(remove_unused_layers no)
			(net "CLK_P_4")
			(clearance 0.1778)
			(thermal_gap 0.1778)
		)
		(pad "DA2" thru_hole circle
			(at 14.249908 -2.999994)
			(size 0.7366 0.7366)
			(drill 0.369824)
			(layers "*.Cu" "*.Mask")
			(remove_unused_layers no)
			(net "CLK_N_4")
			(clearance 0.1778)
			(thermal_gap 0.1778)
		)
		(pad "DA3" thru_hole circle
			(at 14.99997 -3.700018)
			(size 0.7366 0.7366)
			(drill 0.369824)
			(layers "*.Cu" "*.Mask")
			(remove_unused_layers no)
			(net "GND")
			(clearance 0.1778)
			(thermal_gap 0.1778)
		)
		(pad "DA4" thru_hole circle
			(at 15.750032 -4.400042)
			(size 0.7366 0.7366)
			(drill 0.369824)
			(layers "*.Cu" "*.Mask")
			(remove_unused_layers no)
			(net "PCIE_RX_P92")
			(clearance 0.1778)
			(thermal_gap 0.1778)
		)
		(pad "DA5" thru_hole circle
			(at 16.500094 -2.999994)
			(size 0.7366 0.7366)
			(drill 0.369824)
			(layers "*.Cu" "*.Mask")
			(remove_unused_layers no)
			(net "PCIE_RX_N92")
			(clearance 0.1778)
			(thermal_gap 0.1778)
		)
		(pad "DA6" thru_hole circle
			(at 17.249902 -3.700018)
			(size 0.7366 0.7366)
			(drill 0.369824)
			(layers "*.Cu" "*.Mask")
			(remove_unused_layers no)
			(net "GND")
			(clearance 0.1778)
			(thermal_gap 0.1778)
		)
		(pad "DA7" thru_hole circle
			(at 17.999964 -4.400042)
			(size 0.7366 0.7366)
			(drill 0.369824)
			(layers "*.Cu" "*.Mask")
			(remove_unused_layers no)
			(net "PCIE_RX_P95")
			(clearance 0.1778)
			(thermal_gap 0.1778)
		)
		(pad "DA8" thru_hole circle
			(at 18.750026 -2.999994)
			(size 0.7366 0.7366)
			(drill 0.369824)
			(layers "*.Cu" "*.Mask")
			(remove_unused_layers no)
			(net "PCIE_RX_N95")
			(clearance 0.1778)
			(thermal_gap 0.1778)
		)
		(pad "DA9" thru_hole circle
			(at 19.500088 -3.700018)
			(size 0.7366 0.7366)
			(drill 0.369824)
			(layers "*.Cu" "*.Mask")
			(remove_unused_layers no)
			(net "GND")
			(clearance 0.1778)
			(thermal_gap 0.1778)
		)
		(pad "DB1" thru_hole circle
			(at 13.5001 -8.199882)
			(size 0.7366 0.7366)
			(drill 0.369824)
			(layers "*.Cu" "*.Mask")
			(remove_unused_layers no)
			(net "HOST4_RST_N_C")
			(clearance 0.1778)
			(thermal_gap 0.1778)
		)
		(pad "DB2" thru_hole circle
			(at 14.249908 -6.800088)
			(size 0.7366 0.7366)
			(drill 0.369824)
			(layers "*.Cu" "*.Mask")
			(remove_unused_layers no)
			(net "8644_SDA_R_4")
			(clearance 0.1778)
			(thermal_gap 0.1778)
		)
		(pad "DB3" thru_hole circle
			(at 14.99997 -7.500112)
			(size 0.7366 0.7366)
			(drill 0.369824)
			(layers "*.Cu" "*.Mask")
			(remove_unused_layers no)
			(net "GND")
			(clearance 0.1778)
			(thermal_gap 0.1778)
		)
		(pad "DB4" thru_hole circle
			(at 15.750032 -8.199882)
			(size 0.7366 0.7366)
			(drill 0.369824)
			(layers "*.Cu" "*.Mask")
			(remove_unused_layers no)
			(net "PCIE_RX_P93")
			(clearance 0.1778)
			(thermal_gap 0.1778)
		)
		(pad "DB5" thru_hole circle
			(at 16.500094 -6.800088)
			(size 0.7366 0.7366)
			(drill 0.369824)
			(layers "*.Cu" "*.Mask")
			(remove_unused_layers no)
			(net "PCIE_RX_N93")
			(clearance 0.1778)
			(thermal_gap 0.1778)
		)
		(pad "DB6" thru_hole circle
			(at 17.249902 -7.500112)
			(size 0.7366 0.7366)
			(drill 0.369824)
			(layers "*.Cu" "*.Mask")
			(remove_unused_layers no)
			(net "GND")
			(clearance 0.1778)
			(thermal_gap 0.1778)
		)
		(pad "DB7" thru_hole circle
			(at 17.999964 -8.199882)
			(size 0.7366 0.7366)
			(drill 0.369824)
			(layers "*.Cu" "*.Mask")
			(remove_unused_layers no)
			(net "PCIE_RX_P94")
			(clearance 0.1778)
			(thermal_gap 0.1778)
		)
		(pad "DB8" thru_hole circle
			(at 18.750026 -6.800088)
			(size 0.7366 0.7366)
			(drill 0.369824)
			(layers "*.Cu" "*.Mask")
			(remove_unused_layers no)
			(net "PCIE_RX_N94")
			(clearance 0.1778)
			(thermal_gap 0.1778)
		)
		(pad "DB9" thru_hole circle
			(at 19.500088 -7.500112)
			(size 0.7366 0.7366)
			(drill 0.369824)
			(layers "*.Cu" "*.Mask")
			(remove_unused_layers no)
			(net "GND")
			(clearance 0.1778)
			(thermal_gap 0.1778)
		)
		(pad "DC1" thru_hole circle
			(at 13.5001 -11.999976)
			(size 0.7366 0.7366)
			(drill 0.369824)
			(layers "*.Cu" "*.Mask")
			(remove_unused_layers no)
			(net "BMC_I2C4_MINI4_SCL")
			(clearance 0.1778)
			(thermal_gap 0.1778)
		)
		(pad "DC2" thru_hole circle
			(at 14.249908 -10.599928)
			(size 0.7366 0.7366)
			(drill 0.369824)
			(layers "*.Cu" "*.Mask")
			(remove_unused_layers no)
			(net "8644_CBL_PRSNT_R_4")
			(clearance 0.1778)
			(thermal_gap 0.1778)
		)
		(pad "DC3" thru_hole circle
			(at 14.99997 -11.299952)
			(size 0.7366 0.7366)
			(drill 0.369824)
			(layers "*.Cu" "*.Mask")
			(remove_unused_layers no)
			(net "GND")
			(clearance 0.1778)
			(thermal_gap 0.1778)
		)
		(pad "DC4" thru_hole circle
			(at 15.750032 -11.999976)
			(size 0.7366 0.7366)
			(drill 0.369824)
			(layers "*.Cu" "*.Mask")
			(remove_unused_layers no)
			(net "PCIE_TX_P92")
			(clearance 0.1778)
			(thermal_gap 0.1778)
		)
		(pad "DC5" thru_hole circle
			(at 16.500094 -10.599928)
			(size 0.7366 0.7366)
			(drill 0.369824)
			(layers "*.Cu" "*.Mask")
			(remove_unused_layers no)
			(net "PCIE_TX_N92")
			(clearance 0.1778)
			(thermal_gap 0.1778)
		)
		(pad "DC6" thru_hole circle
			(at 17.249902 -11.299952)
			(size 0.7366 0.7366)
			(drill 0.369824)
			(layers "*.Cu" "*.Mask")
			(remove_unused_layers no)
			(net "GND")
			(clearance 0.1778)
			(thermal_gap 0.1778)
		)
		(pad "DC7" thru_hole circle
			(at 17.999964 -11.999976)
			(size 0.7366 0.7366)
			(drill 0.369824)
			(layers "*.Cu" "*.Mask")
			(remove_unused_layers no)
			(net "PCIE_TX_P95")
			(clearance 0.1778)
			(thermal_gap 0.1778)
		)
		(pad "DC8" thru_hole circle
			(at 18.750026 -10.599928)
			(size 0.7366 0.7366)
			(drill 0.369824)
			(layers "*.Cu" "*.Mask")
			(remove_unused_layers no)
			(net "PCIE_TX_N95")
			(clearance 0.1778)
			(thermal_gap 0.1778)
		)
		(pad "DC9" thru_hole circle
			(at 19.500088 -11.299952)
			(size 0.7366 0.7366)
			(drill 0.369824)
			(layers "*.Cu" "*.Mask")
			(remove_unused_layers no)
			(net "GND")
			(clearance 0.1778)
			(thermal_gap 0.1778)
		)
		(pad "DD1" thru_hole circle
			(at 13.5001 -15.80007)
			(size 0.7366 0.7366)
			(drill 0.369824)
			(layers "*.Cu" "*.Mask")
			(remove_unused_layers no)
			(net "8644_USB_DN4")
			(clearance 0.1778)
			(thermal_gap 0.1778)
		)
		(pad "DD2" thru_hole circle
			(at 14.249908 -14.400022)
			(size 0.7366 0.7366)
			(drill 0.369824)
			(layers "*.Cu" "*.Mask")
			(remove_unused_layers no)
			(net "8644_USB_DP4")
			(clearance 0.1778)
			(thermal_gap 0.1778)
		)
		(pad "DD3" thru_hole circle
			(at 14.99997 -15.100046)
			(size 0.7366 0.7366)
			(drill 0.369824)
			(layers "*.Cu" "*.Mask")
			(remove_unused_layers no)
			(net "GND")
			(clearance 0.1778)
			(thermal_gap 0.1778)
		)
		(pad "DD4" thru_hole circle
			(at 15.750032 -15.80007)
			(size 0.7366 0.7366)
			(drill 0.369824)
			(layers "*.Cu" "*.Mask")
			(remove_unused_layers no)
			(net "PCIE_TX_P93")
			(clearance 0.1778)
			(thermal_gap 0.1778)
		)
		(pad "DD5" thru_hole circle
			(at 16.500094 -14.400022)
			(size 0.7366 0.7366)
			(drill 0.369824)
			(layers "*.Cu" "*.Mask")
			(remove_unused_layers no)
			(net "PCIE_TX_N93")
			(clearance 0.1778)
			(thermal_gap 0.1778)
		)
		(pad "DD6" thru_hole circle
			(at 17.249902 -15.100046)
			(size 0.7366 0.7366)
			(drill 0.369824)
			(layers "*.Cu" "*.Mask")
			(remove_unused_layers no)
			(net "GND")
			(clearance 0.1778)
			(thermal_gap 0.1778)
		)
		(pad "DD7" thru_hole circle
			(at 17.999964 -15.80007)
			(size 0.7366 0.7366)
			(drill 0.369824)
			(layers "*.Cu" "*.Mask")
			(remove_unused_layers no)
			(net "PCIE_TX_P94")
			(clearance 0.1778)
			(thermal_gap 0.1778)
		)
		(pad "DD8" thru_hole circle
			(at 18.750026 -14.400022)
			(size 0.7366 0.7366)
			(drill 0.369824)
			(layers "*.Cu" "*.Mask")
			(remove_unused_layers no)
			(net "PCIE_TX_N94")
			(clearance 0.1778)
			(thermal_gap 0.1778)
		)
		(pad "DD9" thru_hole circle
			(at 19.500088 -15.100046)
			(size 0.7366 0.7366)
			(drill 0.369824)
			(layers "*.Cu" "*.Mask")
			(remove_unused_layers no)
			(net "GND")
			(clearance 0.1778)
			(thermal_gap 0.1778)
		)
		(pad "PTH1" thru_hole circle
			(at -21.999956 -3.700018)
			(size 0.9144 0.9144)
			(drill 0.569976)
			(layers "*.Cu" "*.Mask")
			(remove_unused_layers no)
			(net "GND")
			(clearance 0.1905)
			(thermal_gap 0.1905)
		)
		(pad "PTH2" thru_hole circle
			(at -17.999964 -17.509998)
			(size 0.9144 0.9144)
			(drill 0.569976)
			(layers "*.Cu" "*.Mask")
			(remove_unused_layers no)
			(net "GND")
			(clearance 0.1905)
			(thermal_gap 0.1905)
		)
		(pad "PTH3" thru_hole circle
			(at -13.5001 -17.509998)
			(size 0.9144 0.9144)
			(drill 0.569976)
			(layers "*.Cu" "*.Mask")
			(remove_unused_layers no)
			(net "GND")
			(clearance 0.1905)
			(thermal_gap 0.1905)
		)
		(pad "PTH4" thru_hole circle
			(at -6.999986 -17.509998)
			(size 0.9144 0.9144)
			(drill 0.569976)
			(layers "*.Cu" "*.Mask")
			(remove_unused_layers no)
			(net "GND")
			(clearance 0.1905)
			(thermal_gap 0.1905)
		)
		(pad "PTH5" thru_hole circle
			(at -2.500122 -17.509998)
			(size 0.9144 0.9144)
			(drill 0.569976)
			(layers "*.Cu" "*.Mask")
			(remove_unused_layers no)
			(net "GND")
			(clearance 0.1905)
			(thermal_gap 0.1905)
		)
		(pad "PTH6" thru_hole circle
			(at 3.999992 -17.509998)
			(size 0.9144 0.9144)
			(drill 0.569976)
			(layers "*.Cu" "*.Mask")
			(remove_unused_layers no)
			(net "GND")
			(clearance 0.1905)
			(thermal_gap 0.1905)
		)
		(pad "PTH7" thru_hole circle
			(at 8.50011 -17.509998)
			(size 0.9144 0.9144)
			(drill 0.569976)
			(layers "*.Cu" "*.Mask")
			(remove_unused_layers no)
			(net "GND")
			(clearance 0.1905)
			(thermal_gap 0.1905)
		)
		(pad "PTH8" thru_hole circle
			(at 14.99997 -17.509998)
			(size 0.9144 0.9144)
			(drill 0.569976)
			(layers "*.Cu" "*.Mask")
			(remove_unused_layers no)
			(net "GND")
			(clearance 0.1905)
			(thermal_gap 0.1905)
		)
		(pad "PTH9" thru_hole circle
			(at 19.500088 -17.509998)
			(size 0.9144 0.9144)
			(drill 0.569976)
			(layers "*.Cu" "*.Mask")
			(remove_unused_layers no)
			(net "GND")
			(clearance 0.1905)
			(thermal_gap 0.1905)
		)
		(pad "PTH10" thru_hole circle
			(at 21.999956 -3.700018)
			(size 0.9144 0.9144)
			(drill 0.569976)
			(layers "*.Cu" "*.Mask")
			(remove_unused_layers no)
			(net "GND")
			(clearance 0.1905)
			(thermal_gap 0.1905)
		)
		(pad "PTH11" thru_hole circle
			(at 21.999956 9.61009)
			(size 0.9144 0.9144)
			(drill 0.569976)
			(layers "*.Cu" "*.Mask")
			(remove_unused_layers no)
			(net "GND")
			(clearance 0.1905)
			(thermal_gap 0.1905)
		)
		(pad "PTH12" thru_hole circle
			(at 10.999978 9.61009)
			(size 0.9144 0.9144)
			(drill 0.569976)
			(layers "*.Cu" "*.Mask")
			(remove_unused_layers no)
			(net "GND")
			(clearance 0.1905)
			(thermal_gap 0.1905)
		)
		(pad "PTH13" thru_hole circle
			(at 0 9.61009)
			(size 0.9144 0.9144)
			(drill 0.569976)
			(layers "*.Cu" "*.Mask")
			(remove_unused_layers no)
			(net "GND")
			(clearance 0.1905)
			(thermal_gap 0.1905)
		)
		(pad "PTH14" thru_hole circle
			(at -10.999978 9.61009)
			(size 0.9144 0.9144)
			(drill 0.569976)
			(layers "*.Cu" "*.Mask")
			(remove_unused_layers no)
			(net "GND")
			(clearance 0.1905)
			(thermal_gap 0.1905)
		)
		(pad "PTH15" thru_hole circle
			(at -21.999956 9.61009)
			(size 0.9144 0.9144)
			(drill 0.569976)
			(layers "*.Cu" "*.Mask")
			(remove_unused_layers no)
			(net "GND")
			(clearance 0.1905)
			(thermal_gap 0.1905)
		)
		(pad "PTH16" thru_hole circle
			(at -10.999978 -3.700018)
			(size 0.9144 0.9144)
			(drill 0.569976)
			(layers "*.Cu" "*.Mask")
			(remove_unused_layers no)
			(net "GND")
			(clearance 0.1905)
			(thermal_gap 0.1905)
		)
		(pad "PTH17" thru_hole circle
			(at 0 -3.700018)
			(size 0.9144 0.9144)
			(drill 0.569976)
			(layers "*.Cu" "*.Mask")
			(remove_unused_layers no)
			(net "GND")
			(clearance 0.1905)
			(thermal_gap 0.1905)
		)
		(pad "PTH18" thru_hole circle
			(at 10.999978 -3.700018)
			(size 0.9144 0.9144)
			(drill 0.569976)
			(layers "*.Cu" "*.Mask")
			(remove_unused_layers no)
			(net "GND")
			(clearance 0.1905)
			(thermal_gap 0.1905)
		)
		(pad "PTH19" thru_hole circle
			(at -16.500094 0)
			(size 2.6162 2.6162)
			(drill 2.2098)
			(layers "*.Cu" "*.Mask")
			(remove_unused_layers no)
			(net "GND")
			(clearance 0.3048)
			(thermal_gap 0.3048)
			(padstack
				(mode front_inner_back)
				(layer "Inner"
					(shape circle)
					(size 2.6162 2.6162)
					(clearance 0.3048)
				)
				(layer "B.Cu"
					(shape custom)
					(size 1.246578 1.246578)
					(options
						(anchor circle)
					)
					(primitives
						(gr_poly
							(pts
								(arc
									(start 0.300228 -2.49301)
									(mid 0 2.492801)
									(end -0.300228 -2.49301)
								)
								(arc
									(start -0.300228 -2.49301)
									(mid 0 -2.412041)
									(end 0.300228 -2.49301)
								)
							)
							(width 0)
							(fill yes)
						)
					)
					(clearance -0.889)
				)
			)
		)
		(pad "PTH20" thru_hole circle
			(at -5.500116 0)
			(size 2.6162 2.6162)
			(drill 2.2098)
			(layers "*.Cu" "*.Mask")
			(remove_unused_layers no)
			(net "GND")
			(clearance 0.3048)
			(thermal_gap 0.3048)
			(padstack
				(mode front_inner_back)
				(layer "Inner"
					(shape circle)
					(size 2.6162 2.6162)
					(clearance 0.3048)
				)
				(layer "B.Cu"
					(shape custom)
					(size 1.246578 1.246578)
					(options
						(anchor circle)
					)
					(primitives
						(gr_poly
							(pts
								(arc
									(start 0.300228 -2.49301)
									(mid 0 2.492801)
									(end -0.300228 -2.49301)
								)
								(arc
									(start -0.300228 -2.49301)
									(mid 0 -2.412041)
									(end 0.300228 -2.49301)
								)
							)
							(width 0)
							(fill yes)
						)
					)
					(clearance -0.889)
				)
			)
		)
		(pad "PTH21" thru_hole circle
			(at 5.500116 0)
			(size 2.6162 2.6162)
			(drill 2.2098)
			(layers "*.Cu" "*.Mask")
			(remove_unused_layers no)
			(net "GND")
			(clearance 0.3048)
			(thermal_gap 0.3048)
			(padstack
				(mode front_inner_back)
				(layer "Inner"
					(shape circle)
					(size 2.6162 2.6162)
					(clearance 0.3048)
				)
				(layer "B.Cu"
					(shape custom)
					(size 1.246578 1.246578)
					(options
						(anchor circle)
					)
					(primitives
						(gr_poly
							(pts
								(arc
									(start 0.300228 -2.49301)
									(mid 0 2.492801)
									(end -0.300228 -2.49301)
								)
								(arc
									(start -0.300228 -2.49301)
									(mid 0 -2.412041)
									(end 0.300228 -2.49301)
								)
							)
							(width 0)
							(fill yes)
						)
					)
					(clearance -0.889)
				)
			)
		)
		(pad "PTH22" thru_hole circle
			(at 16.500094 0)
			(size 2.6162 2.6162)
			(drill 2.2098)
			(layers "*.Cu" "*.Mask")
			(remove_unused_layers no)
			(net "GND")
			(clearance 0.3048)
			(thermal_gap 0.3048)
			(padstack
				(mode front_inner_back)
				(layer "Inner"
					(shape circle)
					(size 2.6162 2.6162)
					(clearance 0.3048)
				)
				(layer "B.Cu"
					(shape custom)
					(size 1.246578 1.246578)
					(options
						(anchor circle)
					)
					(primitives
						(gr_poly
							(pts
								(arc
									(start 0.300228 -2.49301)
									(mid 0 2.492801)
									(end -0.300228 -2.49301)
								)
								(arc
									(start -0.300228 -2.49301)
									(mid 0 -2.412041)
									(end 0.300228 -2.49301)
								)
							)
							(width 0)
							(fill yes)
						)
					)
					(clearance -0.889)
				)
			)
		)
		(zone
			(layer "F.Cu")
			(hatch none 0.5)
			(connect_pads
				(clearance 0)
			)
			(min_thickness 0.25)
			(keepout
				(tracks allowed)
				(vias not_allowed)
				(pads allowed)
				(copperpour not_allowed)
				(footprints allowed)
			)
			(placement
				(enabled no)
				(sheetname "")
			)
			(fill
				(thermal_gap 0.5)
				(thermal_bridge_width 0.5)
				(island_removal_mode 0)
			)
			(polygon
				(pts
					(xy 130.334512 -0.790194) (xy 130.334512 -2.090166) (xy 130.93446 -2.090166) (xy 130.93446 -0.790194)
				)
			)
		)
		(zone
			(layer "F.Cu")
			(hatch none 0.5)
			(connect_pads
				(clearance 0)
			)
			(min_thickness 0.25)
			(keepout
				(tracks not_allowed)
				(vias allowed)
				(pads allowed)
				(copperpour not_allowed)
				(footprints allowed)
			)
			(placement
				(enabled no)
				(sheetname "")
			)
			(fill
				(thermal_gap 0.5)
				(thermal_bridge_width 0.5)
				(island_removal_mode 0)
			)
			(polygon
				(pts
					(xy 130.334512 -0.790194) (xy 130.93446 -0.790194) (xy 130.93446 -2.090166) (xy 130.334512 -2.090166)
				)
			)
		)
		(zone
			(layer "F.Cu")
			(hatch none 0.5)
			(connect_pads
				(clearance 0)
			)
			(min_thickness 0.25)
			(keepout
				(tracks allowed)
				(vias not_allowed)
				(pads allowed)
				(copperpour not_allowed)
				(footprints allowed)
			)
			(placement
				(enabled no)
				(sheetname "")
			)
			(fill
				(thermal_gap 0.5)
				(thermal_bridge_width 0.5)
				(island_removal_mode 0)
			)
			(polygon
				(pts
					(xy 141.33449 -0.790194) (xy 141.33449 -2.090166) (xy 141.934438 -2.090166) (xy 141.934438 -0.790194)
				)
			)
		)
		(zone
			(layer "F.Cu")
			(hatch none 0.5)
			(connect_pads
				(clearance 0)
			)
			(min_thickness 0.25)
			(keepout
				(tracks not_allowed)
				(vias allowed)
				(pads allowed)
				(copperpour not_allowed)
				(footprints allowed)
			)
			(placement
				(enabled no)
				(sheetname "")
			)
			(fill
				(thermal_gap 0.5)
				(thermal_bridge_width 0.5)
				(island_removal_mode 0)
			)
			(polygon
				(pts
					(xy 141.33449 -0.790194) (xy 141.934438 -0.790194) (xy 141.934438 -2.090166) (xy 141.33449 -2.090166)
				)
			)
		)
		(zone
			(layer "F.Cu")
			(hatch none 0.5)
			(connect_pads
				(clearance 0)
			)
			(min_thickness 0.25)
			(keepout
				(tracks allowed)
				(vias not_allowed)
				(pads allowed)
				(copperpour not_allowed)
				(footprints allowed)
			)
			(placement
				(enabled no)
				(sheetname "")
			)
			(fill
				(thermal_gap 0.5)
				(thermal_bridge_width 0.5)
				(island_removal_mode 0)
			)
			(polygon
				(pts
					(xy 152.334468 -0.790194) (xy 152.334468 -2.090166) (xy 152.934416 -2.090166) (xy 152.934416 -0.790194)
				)
			)
		)
		(zone
			(layer "F.Cu")
			(hatch none 0.5)
			(connect_pads
				(clearance 0)
			)
			(min_thickness 0.25)
			(keepout
				(tracks not_allowed)
				(vias allowed)
				(pads allowed)
				(copperpour not_allowed)
				(footprints allowed)
			)
			(placement
				(enabled no)
				(sheetname "")
			)
			(fill
				(thermal_gap 0.5)
				(thermal_bridge_width 0.5)
				(island_removal_mode 0)
			)
			(polygon
				(pts
					(xy 152.334468 -0.790194) (xy 152.934416 -0.790194) (xy 152.934416 -2.090166) (xy 152.334468 -2.090166)
				)
			)
		)
		(zone
			(layer "F.Cu")
			(hatch none 0.5)
			(connect_pads
				(clearance 0)
			)
			(min_thickness 0.25)
			(keepout
				(tracks allowed)
				(vias not_allowed)
				(pads allowed)
				(copperpour not_allowed)
				(footprints allowed)
			)
			(placement
				(enabled no)
				(sheetname "")
			)
			(fill
				(thermal_gap 0.5)
				(thermal_bridge_width 0.5)
				(island_removal_mode 0)
			)
			(polygon
				(pts
					(xy 163.334446 -0.790194) (xy 163.334446 -2.090166) (xy 163.934394 -2.090166) (xy 163.934394 -0.790194)
				)
			)
		)
		(zone
			(layer "F.Cu")
			(hatch none 0.5)
			(connect_pads
				(clearance 0)
			)
			(min_thickness 0.25)
			(keepout
				(tracks not_allowed)
				(vias allowed)
				(pads allowed)
				(copperpour not_allowed)
				(footprints allowed)
			)
			(placement
				(enabled no)
				(sheetname "")
			)
			(fill
				(thermal_gap 0.5)
				(thermal_bridge_width 0.5)
				(island_removal_mode 0)
			)
			(polygon
				(pts
					(xy 163.334446 -0.790194) (xy 163.934394 -0.790194) (xy 163.934394 -2.090166) (xy 163.334446 -2.090166)
				)
			)
		)
		(zone
			(layer "F.Cu")
			(hatch none 0.5)
			(connect_pads
				(clearance 0)
			)
			(min_thickness 0.25)
			(keepout
				(tracks allowed)
				(vias not_allowed)
				(pads allowed)
				(copperpour not_allowed)
				(footprints allowed)
			)
			(placement
				(enabled no)
				(sheetname "")
			)
			(fill
				(thermal_gap 0.5)
				(thermal_bridge_width 0.5)
				(island_removal_mode 0)
			)
			(polygon
				(pts
					(xy 174.334424 -0.790194) (xy 174.334424 -2.090166) (xy 174.934372 -2.090166) (xy 174.934372 -0.790194)
				)
			)
		)
		(zone
			(layer "F.Cu")
			(hatch none 0.5)
			(connect_pads
				(clearance 0)
			)
			(min_thickness 0.25)
			(keepout
				(tracks not_allowed)
				(vias allowed)
				(pads allowed)
				(copperpour not_allowed)
				(footprints allowed)
			)
			(placement
				(enabled no)
				(sheetname "")
			)
			(fill
				(thermal_gap 0.5)
				(thermal_bridge_width 0.5)
				(island_removal_mode 0)
			)
			(polygon
				(pts
					(xy 174.334424 -0.790194) (xy 174.934372 -0.790194) (xy 174.934372 -2.090166) (xy 174.334424 -2.090166)
				)
			)
		)
		(zone
			(layer "F.Cu")
			(hatch none 0.5)
			(connect_pads
				(clearance 0)
			)
			(min_thickness 0.25)
			(keepout
				(tracks not_allowed)
				(vias allowed)
				(pads allowed)
				(copperpour not_allowed)
				(footprints allowed)
			)
			(placement
				(enabled no)
				(sheetname "")
			)
			(fill
				(thermal_gap 0.5)
				(thermal_bridge_width 0.5)
				(island_removal_mode 0)
			)
			(polygon
				(pts
					(arc
						(start 137.696448 -9.53008)
						(mid 134.572248 -9.53008)
						(end 137.696448 -9.53008)
					)
				)
			)
		)
		(zone
			(layer "F.Cu")
			(hatch none 0.5)
			(connect_pads
				(clearance 0)
			)
			(min_thickness 0.25)
			(keepout
				(tracks allowed)
				(vias not_allowed)
				(pads allowed)
				(copperpour not_allowed)
				(footprints allowed)
			)
			(placement
				(enabled no)
				(sheetname "")
			)
			(fill
				(thermal_gap 0.5)
				(thermal_bridge_width 0.5)
				(island_removal_mode 0)
			)
			(polygon
				(pts
					(arc
						(start 137.696448 -9.53008)
						(mid 134.572248 -9.53008)
						(end 137.696448 -9.53008)
					)
				)
			)
		)
		(zone
			(layer "F.Cu")
			(hatch none 0.5)
			(connect_pads
				(clearance 0)
			)
			(min_thickness 0.25)
			(keepout
				(tracks not_allowed)
				(vias allowed)
				(pads allowed)
				(copperpour not_allowed)
				(footprints allowed)
			)
			(placement
				(enabled no)
				(sheetname "")
			)
			(fill
				(thermal_gap 0.5)
				(thermal_bridge_width 0.5)
				(island_removal_mode 0)
			)
			(polygon
				(pts
					(arc
						(start 148.696426 -9.53008)
						(mid 145.572226 -9.53008)
						(end 148.696426 -9.53008)
					)
				)
			)
		)
		(zone
			(layer "F.Cu")
			(hatch none 0.5)
			(connect_pads
				(clearance 0)
			)
			(min_thickness 0.25)
			(keepout
				(tracks allowed)
				(vias not_allowed)
				(pads allowed)
				(copperpour not_allowed)
				(footprints allowed)
			)
			(placement
				(enabled no)
				(sheetname "")
			)
			(fill
				(thermal_gap 0.5)
				(thermal_bridge_width 0.5)
				(island_removal_mode 0)
			)
			(polygon
				(pts
					(arc
						(start 148.696426 -9.53008)
						(mid 145.572226 -9.53008)
						(end 148.696426 -9.53008)
					)
				)
			)
		)
		(zone
			(layer "F.Cu")
			(hatch none 0.5)
			(connect_pads
				(clearance 0)
			)
			(min_thickness 0.25)
			(keepout
				(tracks not_allowed)
				(vias allowed)
				(pads allowed)
				(copperpour not_allowed)
				(footprints allowed)
			)
			(placement
				(enabled no)
				(sheetname "")
			)
			(fill
				(thermal_gap 0.5)
				(thermal_bridge_width 0.5)
				(island_removal_mode 0)
			)
			(polygon
				(pts
					(arc
						(start 159.696404 -9.53008)
						(mid 156.572204 -9.53008)
						(end 159.696404 -9.53008)
					)
				)
			)
		)
		(zone
			(layer "F.Cu")
			(hatch none 0.5)
			(connect_pads
				(clearance 0)
			)
			(min_thickness 0.25)
			(keepout
				(tracks allowed)
				(vias not_allowed)
				(pads allowed)
				(copperpour not_allowed)
				(footprints allowed)
			)
			(placement
				(enabled no)
				(sheetname "")
			)
			(fill
				(thermal_gap 0.5)
				(thermal_bridge_width 0.5)
				(island_removal_mode 0)
			)
			(polygon
				(pts
					(arc
						(start 159.696404 -9.53008)
						(mid 156.572204 -9.53008)
						(end 159.696404 -9.53008)
					)
				)
			)
		)
		(zone
			(layer "F.Cu")
			(hatch none 0.5)
			(connect_pads
				(clearance 0)
			)
			(min_thickness 0.25)
			(keepout
				(tracks allowed)
				(vias not_allowed)
				(pads allowed)
				(copperpour not_allowed)
				(footprints allowed)
			)
			(placement
				(enabled no)
				(sheetname "")
			)
			(fill
				(thermal_gap 0.5)
				(thermal_bridge_width 0.5)
				(island_removal_mode 0)
			)
			(polygon
				(pts
					(arc
						(start 170.696382 -9.53008)
						(mid 167.572182 -9.53008)
						(end 170.696382 -9.53008)
					)
				)
			)
		)
		(zone
			(layer "F.Cu")
			(hatch none 0.5)
			(connect_pads
				(clearance 0)
			)
			(min_thickness 0.25)
			(keepout
				(tracks not_allowed)
				(vias allowed)
				(pads allowed)
				(copperpour not_allowed)
				(footprints allowed)
			)
			(placement
				(enabled no)
				(sheetname "")
			)
			(fill
				(thermal_gap 0.5)
				(thermal_bridge_width 0.5)
				(island_removal_mode 0)
			)
			(polygon
				(pts
					(arc
						(start 170.696382 -9.53008)
						(mid 167.572182 -9.53008)
						(end 170.696382 -9.53008)
					)
				)
			)
		)
		(zone
			(layer "B.Cu")
			(hatch none 0.5)
			(connect_pads
				(clearance 0)
			)
			(min_thickness 0.25)
			(keepout
				(tracks allowed)
				(vias not_allowed)
				(pads allowed)
				(copperpour not_allowed)
				(footprints allowed)
			)
			(placement
				(enabled no)
				(sheetname "")
			)
			(fill
				(thermal_gap 0.5)
				(thermal_bridge_width 0.5)
				(island_removal_mode 0)
			)
			(polygon
				(pts
					(arc
						(start 138.890248 -9.53008)
						(mid 133.378448 -9.53008)
						(end 138.890248 -9.53008)
					)
				)
			)
		)
		(zone
			(layer "B.Cu")
			(hatch none 0.5)
			(connect_pads
				(clearance 0)
			)
			(min_thickness 0.25)
			(keepout
				(tracks allowed)
				(vias not_allowed)
				(pads allowed)
				(copperpour not_allowed)
				(footprints allowed)
			)
			(placement
				(enabled no)
				(sheetname "")
			)
			(fill
				(thermal_gap 0.5)
				(thermal_bridge_width 0.5)
				(island_removal_mode 0)
			)
			(polygon
				(pts
					(arc
						(start 149.890226 -9.53008)
						(mid 144.378426 -9.53008)
						(end 149.890226 -9.53008)
					)
				)
			)
		)
		(zone
			(layer "B.Cu")
			(hatch none 0.5)
			(connect_pads
				(clearance 0)
			)
			(min_thickness 0.25)
			(keepout
				(tracks allowed)
				(vias not_allowed)
				(pads allowed)
				(copperpour not_allowed)
				(footprints allowed)
			)
			(placement
				(enabled no)
				(sheetname "")
			)
			(fill
				(thermal_gap 0.5)
				(thermal_bridge_width 0.5)
				(island_removal_mode 0)
			)
			(polygon
				(pts
					(arc
						(start 160.890204 -9.53008)
						(mid 155.378404 -9.53008)
						(end 160.890204 -9.53008)
					)
				)
			)
		)
		(zone
			(layer "B.Cu")
			(hatch none 0.5)
			(connect_pads
				(clearance 0)
			)
			(min_thickness 0.25)
			(keepout
				(tracks allowed)
				(vias not_allowed)
				(pads allowed)
				(copperpour not_allowed)
				(footprints allowed)
			)
			(placement
				(enabled no)
				(sheetname "")
			)
			(fill
				(thermal_gap 0.5)
				(thermal_bridge_width 0.5)
				(island_removal_mode 0)
			)
			(polygon
				(pts
					(arc
						(start 171.890182 -9.53008)
						(mid 166.378382 -9.53008)
						(end 171.890182 -9.53008)
					)
				)
			)
		)
	)
	(footprint ""
		(layer "F.Cu")
		(at 23.876 -135.763 90)
		(property "Reference" "R358"
			(at 0 0 90)
			(layer "F.SilkS")
			(hide yes)
			(effects
				(font
					(size 1.27 1.27)
				)
			)
		)
		(property "Value" "3K3R2F-2-GP"
			(at 0.064008 -3.993896 90)
			(unlocked yes)
			(layer "F.Fab")
			(hide yes)
			(effects
				(font
					(size 1.016 1.016)
					(thickness 0.1524)
				)
			)
		)
		(property "Device Type" "R402H16"
			(at 0.064008 -5.517896 90)
			(unlocked yes)
			(layer "F.Fab")
			(hide yes)
			(effects
				(font
					(size 1.016 1.016)
					(thickness 0.1524)
				)
			)
		)
		(duplicate_pad_numbers_are_jumpers no)
		(fp_line
			(start 0.508 -0.9398)
			(end -0.508 -0.9398)
			(stroke
				(width 0.1524)
				(type default)
			)
			(layer "F.SilkS")
		)
		(fp_line
			(start -0.508 -0.9398)
			(end -0.508 0.9398)
			(stroke
				(width 0.1524)
				(type default)
			)
			(layer "F.SilkS")
		)
		(fp_rect
			(start -0.508 0.9398)
			(end 0.508 -0.9398)
			(stroke
				(width 0)
				(type default)
			)
			(fill no)
			(layer "F.CrtYd")
		)
		(fp_rect
			(start -0.508 0.9398)
			(end 0.508 -0.9398)
			(stroke
				(width 0)
				(type default)
			)
			(fill no)
			(layer "F.Fab")
		)
		(pad "1" smd custom
			(at 0 -0.4445 90)
			(size 0.1397 0.1397)
			(layers "F.Cu" "F.Mask" "F.Paste")
			(net "P3V3_STBY")
			(options
				(clearance outline)
				(anchor circle)
			)
			(primitives
				(gr_poly
					(pts
						(arc
							(start -0.1778 -0.2794)
							(mid -0.249642 -0.249642)
							(end -0.2794 -0.1778)
						)
						(arc
							(start -0.2794 0.1778)
							(mid -0.249642 0.249642)
							(end -0.1778 0.2794)
						)
						(arc
							(start 0.1778 0.2794)
							(mid 0.249642 0.249642)
							(end 0.2794 0.1778)
						)
						(arc
							(start 0.2794 -0.1778)
							(mid 0.249642 -0.249642)
							(end 0.1778 -0.2794)
						)
					)
					(width 0)
					(fill yes)
				)
			)
		)
		(pad "2" smd custom
			(at 0 0.4445 90)
			(size 0.1397 0.1397)
			(layers "F.Cu" "F.Mask" "F.Paste")
			(net "ROMD4")
			(options
				(clearance outline)
				(anchor circle)
			)
			(primitives
				(gr_poly
					(pts
						(arc
							(start -0.1778 -0.2794)
							(mid -0.249642 -0.249642)
							(end -0.2794 -0.1778)
						)
						(arc
							(start -0.2794 0.1778)
							(mid -0.249642 0.249642)
							(end -0.1778 0.2794)
						)
						(arc
							(start 0.1778 0.2794)
							(mid 0.249642 0.249642)
							(end 0.2794 0.1778)
						)
						(arc
							(start 0.2794 -0.1778)
							(mid 0.249642 -0.249642)
							(end 0.1778 -0.2794)
						)
					)
					(width 0)
					(fill yes)
				)
			)
		)
	)
	(footprint ""
		(layer "F.Cu")
		(at 166.116 -91.9734 90)
		(property "Reference" "R3106"
			(at 0 0 90)
			(layer "F.SilkS")
			(hide yes)
			(effects
				(font
					(size 1.27 1.27)
				)
			)
		)
		(property "Value" "27R2F-GP"
			(at 0.064008 -3.993896 90)
			(unlocked yes)
			(layer "F.Fab")
			(hide yes)
			(effects
				(font
					(size 1.016 1.016)
					(thickness 0.1524)
				)
			)
		)
		(property "Device Type" "R402H16"
			(at 0.064008 -5.517896 90)
			(unlocked yes)
			(layer "F.Fab")
			(hide yes)
			(effects
				(font
					(size 1.016 1.016)
					(thickness 0.1524)
				)
			)
		)
		(duplicate_pad_numbers_are_jumpers no)
		(fp_line
			(start 0.508 -0.9398)
			(end -0.508 -0.9398)
			(stroke
				(width 0.1524)
				(type default)
			)
			(layer "F.SilkS")
		)
		(fp_line
			(start -0.508 -0.9398)
			(end -0.508 0.9398)
			(stroke
				(width 0.1524)
				(type default)
			)
			(layer "F.SilkS")
		)
		(fp_rect
			(start -0.508 0.9398)
			(end 0.508 -0.9398)
			(stroke
				(width 0)
				(type default)
			)
			(fill no)
			(layer "F.CrtYd")
		)
		(fp_rect
			(start -0.508 0.9398)
			(end 0.508 -0.9398)
			(stroke
				(width 0)
				(type default)
			)
			(fill no)
			(layer "F.Fab")
		)
		(pad "1" smd custom
			(at 0 -0.4445 90)
			(size 0.1397 0.1397)
			(layers "F.Cu" "F.Mask" "F.Paste")
			(net "CLKGEN_P2_R")
			(options
				(clearance outline)
				(anchor circle)
			)
			(primitives
				(gr_poly
					(pts
						(arc
							(start -0.1778 -0.2794)
							(mid -0.249642 -0.249642)
							(end -0.2794 -0.1778)
						)
						(arc
							(start -0.2794 0.1778)
							(mid -0.249642 0.249642)
							(end -0.1778 0.2794)
						)
						(arc
							(start 0.1778 0.2794)
							(mid 0.249642 0.249642)
							(end 0.2794 0.1778)
						)
						(arc
							(start 0.2794 -0.1778)
							(mid 0.249642 -0.249642)
							(end 0.1778 -0.2794)
						)
					)
					(width 0)
					(fill yes)
				)
			)
		)
		(pad "2" smd custom
			(at 0 0.4445 90)
			(size 0.1397 0.1397)
			(layers "F.Cu" "F.Mask" "F.Paste")
			(net "CLKGEN_P2")
			(options
				(clearance outline)
				(anchor circle)
			)
			(primitives
				(gr_poly
					(pts
						(arc
							(start -0.1778 -0.2794)
							(mid -0.249642 -0.249642)
							(end -0.2794 -0.1778)
						)
						(arc
							(start -0.2794 0.1778)
							(mid -0.249642 0.249642)
							(end -0.1778 0.2794)
						)
						(arc
							(start 0.1778 0.2794)
							(mid 0.249642 0.249642)
							(end 0.2794 0.1778)
						)
						(arc
							(start 0.2794 -0.1778)
							(mid 0.249642 -0.249642)
							(end 0.1778 -0.2794)
						)
					)
					(width 0)
					(fill yes)
				)
			)
		)
	)
	(footprint ""
		(layer "F.Cu")
		(at 338.792058 -212.420454 180)
		(property "Reference" "C56"
			(at 0 0 180)
			(layer "F.SilkS")
			(hide yes)
			(effects
				(font
					(size 1.27 1.27)
				)
			)
		)
		(property "Value" "SCD22U10V2KX-1GP"
			(at 1.1811 -2.7051 180)
			(unlocked yes)
			(layer "F.Fab")
			(hide yes)
			(effects
				(font
					(size 1.016 1.016)
					(thickness 0.1524)
				)
			)
		)
		(property "Device Type" "C402H22"
			(at 1.1811 -4.2291 180)
			(unlocked yes)
			(layer "F.Fab")
			(hide yes)
			(effects
				(font
					(size 1.016 1.016)
					(thickness 0.1524)
				)
			)
		)
		(duplicate_pad_numbers_are_jumpers no)
		(fp_rect
			(start -0.4318 0.9525)
			(end 0.4318 -0.9525)
			(stroke
				(width 0)
				(type default)
			)
			(fill no)
			(layer "F.CrtYd")
		)
		(fp_rect
			(start -0.4318 0.9525)
			(end 0.4318 -0.9525)
			(stroke
				(width 0)
				(type default)
			)
			(fill no)
			(layer "F.Fab")
		)
		(pad "1" smd custom
			(at 0 -0.4445 180)
			(size 0.1524 0.1524)
			(layers "F.Cu" "F.Mask" "F.Paste")
			(net "PCIE_TX_CAP_P17")
			(options
				(clearance outline)
				(anchor circle)
			)
			(primitives
				(gr_poly
					(pts
						(arc
							(start 0.3048 -0.2032)
							(mid 0.275042 -0.275042)
							(end 0.2032 -0.3048)
						)
						(arc
							(start -0.2032 -0.3048)
							(mid -0.275042 -0.275042)
							(end -0.3048 -0.2032)
						)
						(arc
							(start -0.3048 0.2032)
							(mid -0.275042 0.275042)
							(end -0.2032 0.3048)
						)
						(arc
							(start 0.2032 0.3048)
							(mid 0.275042 0.275042)
							(end 0.3048 0.2032)
						)
					)
					(width 0)
					(fill yes)
				)
			)
		)
		(pad "2" smd custom
			(at 0 0.4445 180)
			(size 0.1524 0.1524)
			(layers "F.Cu" "F.Mask" "F.Paste")
			(net "PCIE_TX_P17")
			(options
				(clearance outline)
				(anchor circle)
			)
			(primitives
				(gr_poly
					(pts
						(arc
							(start 0.3048 -0.2032)
							(mid 0.275042 -0.275042)
							(end 0.2032 -0.3048)
						)
						(arc
							(start -0.2032 -0.3048)
							(mid -0.275042 -0.275042)
							(end -0.3048 -0.2032)
						)
						(arc
							(start -0.3048 0.2032)
							(mid -0.275042 0.275042)
							(end -0.2032 0.3048)
						)
						(arc
							(start 0.2032 0.3048)
							(mid 0.275042 0.275042)
							(end 0.3048 0.2032)
						)
					)
					(width 0)
					(fill yes)
				)
			)
		)
	)
	(footprint ""
		(layer "F.Cu")
		(at 277.191978 -212.420454 180)
		(property "Reference" "C99"
			(at 0 0 180)
			(layer "F.SilkS")
			(hide yes)
			(effects
				(font
					(size 1.27 1.27)
				)
			)
		)
		(property "Value" "SCD22U10V2KX-1GP"
			(at 1.1811 -2.7051 180)
			(unlocked yes)
			(layer "F.Fab")
			(hide yes)
			(effects
				(font
					(size 1.016 1.016)
					(thickness 0.1524)
				)
			)
		)
		(property "Device Type" "C402H22"
			(at 1.1811 -4.2291 180)
			(unlocked yes)
			(layer "F.Fab")
			(hide yes)
			(effects
				(font
					(size 1.016 1.016)
					(thickness 0.1524)
				)
			)
		)
		(duplicate_pad_numbers_are_jumpers no)
		(fp_rect
			(start -0.4318 0.9525)
			(end 0.4318 -0.9525)
			(stroke
				(width 0)
				(type default)
			)
			(fill no)
			(layer "F.CrtYd")
		)
		(fp_rect
			(start -0.4318 0.9525)
			(end 0.4318 -0.9525)
			(stroke
				(width 0)
				(type default)
			)
			(fill no)
			(layer "F.Fab")
		)
		(pad "1" smd custom
			(at 0 -0.4445 180)
			(size 0.1524 0.1524)
			(layers "F.Cu" "F.Mask" "F.Paste")
			(net "PCIE_TX_CAP_P33")
			(options
				(clearance outline)
				(anchor circle)
			)
			(primitives
				(gr_poly
					(pts
						(arc
							(start 0.3048 -0.2032)
							(mid 0.275042 -0.275042)
							(end 0.2032 -0.3048)
						)
						(arc
							(start -0.2032 -0.3048)
							(mid -0.275042 -0.275042)
							(end -0.3048 -0.2032)
						)
						(arc
							(start -0.3048 0.2032)
							(mid -0.275042 0.275042)
							(end -0.2032 0.3048)
						)
						(arc
							(start 0.2032 0.3048)
							(mid 0.275042 0.275042)
							(end 0.3048 0.2032)
						)
					)
					(width 0)
					(fill yes)
				)
			)
		)
		(pad "2" smd custom
			(at 0 0.4445 180)
			(size 0.1524 0.1524)
			(layers "F.Cu" "F.Mask" "F.Paste")
			(net "PCIE_TX_P33")
			(options
				(clearance outline)
				(anchor circle)
			)
			(primitives
				(gr_poly
					(pts
						(arc
							(start 0.3048 -0.2032)
							(mid 0.275042 -0.275042)
							(end 0.2032 -0.3048)
						)
						(arc
							(start -0.2032 -0.3048)
							(mid -0.275042 -0.275042)
							(end -0.3048 -0.2032)
						)
						(arc
							(start -0.3048 0.2032)
							(mid -0.275042 0.275042)
							(end -0.2032 0.3048)
						)
						(arc
							(start 0.2032 0.3048)
							(mid 0.275042 0.275042)
							(end 0.3048 0.2032)
						)
					)
					(width 0)
					(fill yes)
				)
			)
		)
	)
	(footprint ""
		(layer "F.Cu")
		(at 27.051 -70.8406 180)
		(property "Reference" "R404"
			(at 0 0 180)
			(layer "F.SilkS")
			(hide yes)
			(effects
				(font
					(size 1.27 1.27)
				)
			)
		)
		(property "Value" "3K3R2F-2-GP"
			(at 0.064008 -3.993896 180)
			(unlocked yes)
			(layer "F.Fab")
			(hide yes)
			(effects
				(font
					(size 1.016 1.016)
					(thickness 0.1524)
				)
			)
		)
		(property "Device Type" "R402H16"
			(at 0.064008 -5.517896 180)
			(unlocked yes)
			(layer "F.Fab")
			(hide yes)
			(effects
				(font
					(size 1.016 1.016)
					(thickness 0.1524)
				)
			)
		)
		(duplicate_pad_numbers_are_jumpers no)
		(fp_line
			(start 0.508 -0.9398)
			(end -0.508 -0.9398)
			(stroke
				(width 0.1524)
				(type default)
			)
			(layer "F.SilkS")
		)
		(fp_line
			(start -0.508 -0.9398)
			(end -0.508 0.9398)
			(stroke
				(width 0.1524)
				(type default)
			)
			(layer "F.SilkS")
		)
		(fp_rect
			(start -0.508 0.9398)
			(end 0.508 -0.9398)
			(stroke
				(width 0)
				(type default)
			)
			(fill no)
			(layer "F.CrtYd")
		)
		(fp_rect
			(start -0.508 0.9398)
			(end 0.508 -0.9398)
			(stroke
				(width 0)
				(type default)
			)
			(fill no)
			(layer "F.Fab")
		)
		(pad "1" smd custom
			(at 0 -0.4445 180)
			(size 0.1397 0.1397)
			(layers "F.Cu" "F.Mask" "F.Paste")
			(net "P3V3_STBY")
			(options
				(clearance outline)
				(anchor circle)
			)
			(primitives
				(gr_poly
					(pts
						(arc
							(start -0.1778 -0.2794)
							(mid -0.249642 -0.249642)
							(end -0.2794 -0.1778)
						)
						(arc
							(start -0.2794 0.1778)
							(mid -0.249642 0.249642)
							(end -0.1778 0.2794)
						)
						(arc
							(start 0.1778 0.2794)
							(mid 0.249642 0.249642)
							(end 0.2794 0.1778)
						)
						(arc
							(start 0.2794 -0.1778)
							(mid 0.249642 -0.249642)
							(end 0.1778 -0.2794)
						)
					)
					(width 0)
					(fill yes)
				)
			)
		)
		(pad "2" smd custom
			(at 0 0.4445 180)
			(size 0.1397 0.1397)
			(layers "F.Cu" "F.Mask" "F.Paste")
			(net "NIC_JTDO")
			(options
				(clearance outline)
				(anchor circle)
			)
			(primitives
				(gr_poly
					(pts
						(arc
							(start -0.1778 -0.2794)
							(mid -0.249642 -0.249642)
							(end -0.2794 -0.1778)
						)
						(arc
							(start -0.2794 0.1778)
							(mid -0.249642 0.249642)
							(end -0.1778 0.2794)
						)
						(arc
							(start 0.1778 0.2794)
							(mid 0.249642 0.249642)
							(end 0.2794 0.1778)
						)
						(arc
							(start 0.2794 -0.1778)
							(mid 0.249642 -0.249642)
							(end 0.1778 -0.2794)
						)
					)
					(width 0)
					(fill yes)
				)
			)
		)
	)
	(footprint ""
		(layer "F.Cu")
		(at 292.227 -59.563 -90)
		(property "Reference" "R643"
			(at 0 0 270)
			(layer "F.SilkS")
			(hide yes)
			(effects
				(font
					(size 1.27 1.27)
				)
			)
		)
		(property "Value" "0R2J-2-GP"
			(at 0.064008 -3.993896 270)
			(unlocked yes)
			(layer "F.Fab")
			(hide yes)
			(effects
				(font
					(size 1.016 1.016)
					(thickness 0.1524)
				)
			)
		)
		(property "Device Type" "R402H16"
			(at 0.064008 -5.517896 270)
			(unlocked yes)
			(layer "F.Fab")
			(hide yes)
			(effects
				(font
					(size 1.016 1.016)
					(thickness 0.1524)
				)
			)
		)
		(duplicate_pad_numbers_are_jumpers no)
		(fp_line
			(start -0.508 -0.9398)
			(end -0.508 0.9398)
			(stroke
				(width 0.1524)
				(type default)
			)
			(layer "F.SilkS")
		)
		(fp_line
			(start 0.508 -0.9398)
			(end -0.508 -0.9398)
			(stroke
				(width 0.1524)
				(type default)
			)
			(layer "F.SilkS")
		)
		(fp_rect
			(start -0.508 0.9398)
			(end 0.508 -0.9398)
			(stroke
				(width 0)
				(type default)
			)
			(fill no)
			(layer "F.CrtYd")
		)
		(fp_rect
			(start -0.508 0.9398)
			(end 0.508 -0.9398)
			(stroke
				(width 0)
				(type default)
			)
			(fill no)
			(layer "F.Fab")
		)
		(pad "1" smd custom
			(at 0 -0.4445 270)
			(size 0.1397 0.1397)
			(layers "F.Cu" "F.Mask" "F.Paste")
			(net "VS6_LED_R")
			(options
				(clearance outline)
				(anchor circle)
			)
			(primitives
				(gr_poly
					(pts
						(arc
							(start -0.1778 -0.2794)
							(mid -0.249642 -0.249642)
							(end -0.2794 -0.1778)
						)
						(arc
							(start -0.2794 0.1778)
							(mid -0.249642 0.249642)
							(end -0.1778 0.2794)
						)
						(arc
							(start 0.1778 0.2794)
							(mid 0.249642 0.249642)
							(end 0.2794 0.1778)
						)
						(arc
							(start 0.2794 -0.1778)
							(mid 0.249642 -0.249642)
							(end 0.1778 -0.2794)
						)
					)
					(width 0)
					(fill yes)
				)
			)
		)
		(pad "2" smd custom
			(at 0 0.4445 270)
			(size 0.1397 0.1397)
			(layers "F.Cu" "F.Mask" "F.Paste")
			(net "VS6_LED")
			(options
				(clearance outline)
				(anchor circle)
			)
			(primitives
				(gr_poly
					(pts
						(arc
							(start -0.1778 -0.2794)
							(mid -0.249642 -0.249642)
							(end -0.2794 -0.1778)
						)
						(arc
							(start -0.2794 0.1778)
							(mid -0.249642 0.249642)
							(end -0.1778 0.2794)
						)
						(arc
							(start 0.1778 0.2794)
							(mid 0.249642 0.249642)
							(end 0.2794 0.1778)
						)
						(arc
							(start 0.2794 -0.1778)
							(mid 0.249642 -0.249642)
							(end 0.1778 -0.2794)
						)
					)
					(width 0)
					(fill yes)
				)
			)
		)
	)
	(footprint ""
		(layer "F.Cu")
		(at 227.179124 -203.047092 180)
		(property "Reference" "R7947"
			(at 0 0 180)
			(layer "F.SilkS")
			(hide yes)
			(effects
				(font
					(size 1.27 1.27)
				)
			)
		)
		(property "Value" "0R2J-2-GP"
			(at 0.064008 -3.993896 180)
			(unlocked yes)
			(layer "F.Fab")
			(hide yes)
			(effects
				(font
					(size 1.016 1.016)
					(thickness 0.1524)
				)
			)
		)
		(property "Device Type" "R402H16"
			(at 0.064008 -5.517896 180)
			(unlocked yes)
			(layer "F.Fab")
			(hide yes)
			(effects
				(font
					(size 1.016 1.016)
					(thickness 0.1524)
				)
			)
		)
		(duplicate_pad_numbers_are_jumpers no)
		(fp_line
			(start 0.508 -0.9398)
			(end -0.508 -0.9398)
			(stroke
				(width 0.1524)
				(type default)
			)
			(layer "F.SilkS")
		)
		(fp_line
			(start -0.508 -0.9398)
			(end -0.508 0.9398)
			(stroke
				(width 0.1524)
				(type default)
			)
			(layer "F.SilkS")
		)
		(fp_rect
			(start -0.508 0.9398)
			(end 0.508 -0.9398)
			(stroke
				(width 0)
				(type default)
			)
			(fill no)
			(layer "F.CrtYd")
		)
		(fp_rect
			(start -0.508 0.9398)
			(end 0.508 -0.9398)
			(stroke
				(width 0)
				(type default)
			)
			(fill no)
			(layer "F.Fab")
		)
		(pad "1" smd custom
			(at 0 -0.4445 180)
			(size 0.1397 0.1397)
			(layers "F.Cu" "F.Mask" "F.Paste")
			(net "SSD_ATNLED#12")
			(options
				(clearance outline)
				(anchor circle)
			)
			(primitives
				(gr_poly
					(pts
						(arc
							(start -0.1778 -0.2794)
							(mid -0.249642 -0.249642)
							(end -0.2794 -0.1778)
						)
						(arc
							(start -0.2794 0.1778)
							(mid -0.249642 0.249642)
							(end -0.1778 0.2794)
						)
						(arc
							(start 0.1778 0.2794)
							(mid 0.249642 0.249642)
							(end 0.2794 0.1778)
						)
						(arc
							(start 0.2794 -0.1778)
							(mid 0.249642 -0.249642)
							(end 0.1778 -0.2794)
						)
					)
					(width 0)
					(fill yes)
				)
			)
		)
		(pad "2" smd custom
			(at 0 0.4445 180)
			(size 0.1397 0.1397)
			(layers "F.Cu" "F.Mask" "F.Paste")
			(net "SSD_ATNLED#12_R")
			(options
				(clearance outline)
				(anchor circle)
			)
			(primitives
				(gr_poly
					(pts
						(arc
							(start -0.1778 -0.2794)
							(mid -0.249642 -0.249642)
							(end -0.2794 -0.1778)
						)
						(arc
							(start -0.2794 0.1778)
							(mid -0.249642 0.249642)
							(end -0.1778 0.2794)
						)
						(arc
							(start 0.1778 0.2794)
							(mid 0.249642 0.249642)
							(end 0.2794 0.1778)
						)
						(arc
							(start 0.2794 -0.1778)
							(mid 0.249642 -0.249642)
							(end 0.1778 -0.2794)
						)
					)
					(width 0)
					(fill yes)
				)
			)
		)
	)
	(footprint ""
		(layer "F.Cu")
		(at 17.43456 -133.92658 -90)
		(property "Reference" "R685"
			(at 0 0 270)
			(layer "F.SilkS")
			(hide yes)
			(effects
				(font
					(size 1.27 1.27)
				)
			)
		)
		(property "Value" "0R2J-2-GP"
			(at 0.064008 -3.993896 270)
			(unlocked yes)
			(layer "F.Fab")
			(hide yes)
			(effects
				(font
					(size 1.016 1.016)
					(thickness 0.1524)
				)
			)
		)
		(property "Device Type" "R402H16"
			(at 0.064008 -5.517896 270)
			(unlocked yes)
			(layer "F.Fab")
			(hide yes)
			(effects
				(font
					(size 1.016 1.016)
					(thickness 0.1524)
				)
			)
		)
		(duplicate_pad_numbers_are_jumpers no)
		(fp_line
			(start -0.508 -0.9398)
			(end -0.508 0.9398)
			(stroke
				(width 0.1524)
				(type default)
			)
			(layer "F.SilkS")
		)
		(fp_line
			(start 0.508 -0.9398)
			(end -0.508 -0.9398)
			(stroke
				(width 0.1524)
				(type default)
			)
			(layer "F.SilkS")
		)
		(fp_rect
			(start -0.508 0.9398)
			(end 0.508 -0.9398)
			(stroke
				(width 0)
				(type default)
			)
			(fill no)
			(layer "F.CrtYd")
		)
		(fp_rect
			(start -0.508 0.9398)
			(end 0.508 -0.9398)
			(stroke
				(width 0)
				(type default)
			)
			(fill no)
			(layer "F.Fab")
		)
		(pad "1" smd custom
			(at 0 -0.4445 270)
			(size 0.1397 0.1397)
			(layers "F.Cu" "F.Mask" "F.Paste")
			(net "GPIOS5_R")
			(options
				(clearance outline)
				(anchor circle)
			)
			(primitives
				(gr_poly
					(pts
						(arc
							(start -0.1778 -0.2794)
							(mid -0.249642 -0.249642)
							(end -0.2794 -0.1778)
						)
						(arc
							(start -0.2794 0.1778)
							(mid -0.249642 0.249642)
							(end -0.1778 0.2794)
						)
						(arc
							(start 0.1778 0.2794)
							(mid 0.249642 0.249642)
							(end 0.2794 0.1778)
						)
						(arc
							(start 0.2794 -0.1778)
							(mid 0.249642 -0.249642)
							(end 0.1778 -0.2794)
						)
					)
					(width 0)
					(fill yes)
				)
			)
		)
		(pad "2" smd custom
			(at 0 0.4445 270)
			(size 0.1397 0.1397)
			(layers "F.Cu" "F.Mask" "F.Paste")
			(net "TRAY_ID0")
			(options
				(clearance outline)
				(anchor circle)
			)
			(primitives
				(gr_poly
					(pts
						(arc
							(start -0.1778 -0.2794)
							(mid -0.249642 -0.249642)
							(end -0.2794 -0.1778)
						)
						(arc
							(start -0.2794 0.1778)
							(mid -0.249642 0.249642)
							(end -0.1778 0.2794)
						)
						(arc
							(start 0.1778 0.2794)
							(mid 0.249642 0.249642)
							(end 0.2794 0.1778)
						)
						(arc
							(start 0.2794 -0.1778)
							(mid 0.249642 -0.249642)
							(end 0.1778 -0.2794)
						)
					)
					(width 0)
					(fill yes)
				)
			)
		)
	)
	(footprint ""
		(layer "F.Cu")
		(at 154.1018 -88.4428 90)
		(property "Reference" "R3110"
			(at 0 0 90)
			(layer "F.SilkS")
			(hide yes)
			(effects
				(font
					(size 1.27 1.27)
				)
			)
		)
		(property "Value" "33R2F-3-GP"
			(at 0.064008 -3.993896 90)
			(unlocked yes)
			(layer "F.Fab")
			(hide yes)
			(effects
				(font
					(size 1.016 1.016)
					(thickness 0.1524)
				)
			)
		)
		(property "Device Type" "R402H16"
			(at 0.064008 -5.517896 90)
			(unlocked yes)
			(layer "F.Fab")
			(hide yes)
			(effects
				(font
					(size 1.016 1.016)
					(thickness 0.1524)
				)
			)
		)
		(duplicate_pad_numbers_are_jumpers no)
		(fp_line
			(start 0.508 -0.9398)
			(end -0.508 -0.9398)
			(stroke
				(width 0.1524)
				(type default)
			)
			(layer "F.SilkS")
		)
		(fp_line
			(start -0.508 -0.9398)
			(end -0.508 0.9398)
			(stroke
				(width 0.1524)
				(type default)
			)
			(layer "F.SilkS")
		)
		(fp_rect
			(start -0.508 0.9398)
			(end 0.508 -0.9398)
			(stroke
				(width 0)
				(type default)
			)
			(fill no)
			(layer "F.CrtYd")
		)
		(fp_rect
			(start -0.508 0.9398)
			(end 0.508 -0.9398)
			(stroke
				(width 0)
				(type default)
			)
			(fill no)
			(layer "F.Fab")
		)
		(pad "1" smd custom
			(at 0 -0.4445 90)
			(size 0.1397 0.1397)
			(layers "F.Cu" "F.Mask" "F.Paste")
			(net "CLKGNE_SADR_R")
			(options
				(clearance outline)
				(anchor circle)
			)
			(primitives
				(gr_poly
					(pts
						(arc
							(start -0.1778 -0.2794)
							(mid -0.249642 -0.249642)
							(end -0.2794 -0.1778)
						)
						(arc
							(start -0.2794 0.1778)
							(mid -0.249642 0.249642)
							(end -0.1778 0.2794)
						)
						(arc
							(start 0.1778 0.2794)
							(mid 0.249642 0.249642)
							(end 0.2794 0.1778)
						)
						(arc
							(start 0.2794 -0.1778)
							(mid 0.249642 -0.249642)
							(end 0.1778 -0.2794)
						)
					)
					(width 0)
					(fill yes)
				)
			)
		)
		(pad "2" smd custom
			(at 0 0.4445 90)
			(size 0.1397 0.1397)
			(layers "F.Cu" "F.Mask" "F.Paste")
			(net "CLKGNE_SADR")
			(options
				(clearance outline)
				(anchor circle)
			)
			(primitives
				(gr_poly
					(pts
						(arc
							(start -0.1778 -0.2794)
							(mid -0.249642 -0.249642)
							(end -0.2794 -0.1778)
						)
						(arc
							(start -0.2794 0.1778)
							(mid -0.249642 0.249642)
							(end -0.1778 0.2794)
						)
						(arc
							(start 0.1778 0.2794)
							(mid 0.249642 0.249642)
							(end 0.2794 0.1778)
						)
						(arc
							(start 0.2794 -0.1778)
							(mid 0.249642 -0.249642)
							(end 0.1778 -0.2794)
						)
					)
					(width 0)
					(fill yes)
				)
			)
		)
	)
	(footprint ""
		(layer "F.Cu")
		(at 132.310124 -208.889092 180)
		(property "Reference" "R7971"
			(at 0 0 180)
			(layer "F.SilkS")
			(hide yes)
			(effects
				(font
					(size 1.27 1.27)
				)
			)
		)
		(property "Value" "0R2J-2-GP"
			(at 0.064008 -3.993896 180)
			(unlocked yes)
			(layer "F.Fab")
			(hide yes)
			(effects
				(font
					(size 1.016 1.016)
					(thickness 0.1524)
				)
			)
		)
		(property "Device Type" "R402H16"
			(at 0.064008 -5.517896 180)
			(unlocked yes)
			(layer "F.Fab")
			(hide yes)
			(effects
				(font
					(size 1.016 1.016)
					(thickness 0.1524)
				)
			)
		)
		(duplicate_pad_numbers_are_jumpers no)
		(fp_line
			(start 0.508 -0.9398)
			(end -0.508 -0.9398)
			(stroke
				(width 0.1524)
				(type default)
			)
			(layer "F.SilkS")
		)
		(fp_line
			(start -0.508 -0.9398)
			(end -0.508 0.9398)
			(stroke
				(width 0.1524)
				(type default)
			)
			(layer "F.SilkS")
		)
		(fp_rect
			(start -0.508 0.9398)
			(end 0.508 -0.9398)
			(stroke
				(width 0)
				(type default)
			)
			(fill no)
			(layer "F.CrtYd")
		)
		(fp_rect
			(start -0.508 0.9398)
			(end 0.508 -0.9398)
			(stroke
				(width 0)
				(type default)
			)
			(fill no)
			(layer "F.Fab")
		)
		(pad "1" smd custom
			(at 0 -0.4445 180)
			(size 0.1397 0.1397)
			(layers "F.Cu" "F.Mask" "F.Paste")
			(net "SSD_PERST#6")
			(options
				(clearance outline)
				(anchor circle)
			)
			(primitives
				(gr_poly
					(pts
						(arc
							(start -0.1778 -0.2794)
							(mid -0.249642 -0.249642)
							(end -0.2794 -0.1778)
						)
						(arc
							(start -0.2794 0.1778)
							(mid -0.249642 0.249642)
							(end -0.1778 0.2794)
						)
						(arc
							(start 0.1778 0.2794)
							(mid 0.249642 0.249642)
							(end 0.2794 0.1778)
						)
						(arc
							(start 0.2794 -0.1778)
							(mid 0.249642 -0.249642)
							(end 0.1778 -0.2794)
						)
					)
					(width 0)
					(fill yes)
				)
			)
		)
		(pad "2" smd custom
			(at 0 0.4445 180)
			(size 0.1397 0.1397)
			(layers "F.Cu" "F.Mask" "F.Paste")
			(net "SSD_PERST#6_R")
			(options
				(clearance outline)
				(anchor circle)
			)
			(primitives
				(gr_poly
					(pts
						(arc
							(start -0.1778 -0.2794)
							(mid -0.249642 -0.249642)
							(end -0.2794 -0.1778)
						)
						(arc
							(start -0.2794 0.1778)
							(mid -0.249642 0.249642)
							(end -0.1778 0.2794)
						)
						(arc
							(start 0.1778 0.2794)
							(mid 0.249642 0.249642)
							(end 0.2794 0.1778)
						)
						(arc
							(start 0.2794 -0.1778)
							(mid 0.249642 -0.249642)
							(end 0.1778 -0.2794)
						)
					)
					(width 0)
					(fill yes)
				)
			)
		)
	)
	(footprint ""
		(layer "F.Cu")
		(at 268.351 -12.3698 -90)
		(property "Reference" "R7904"
			(at 0 0 270)
			(layer "F.SilkS")
			(hide yes)
			(effects
				(font
					(size 1.27 1.27)
				)
			)
		)
		(property "Value" "0R2J-2-GP"
			(at 0.064008 -3.993896 270)
			(unlocked yes)
			(layer "F.Fab")
			(hide yes)
			(effects
				(font
					(size 1.016 1.016)
					(thickness 0.1524)
				)
			)
		)
		(property "Device Type" "R402H16"
			(at 0.064008 -5.517896 270)
			(unlocked yes)
			(layer "F.Fab")
			(hide yes)
			(effects
				(font
					(size 1.016 1.016)
					(thickness 0.1524)
				)
			)
		)
		(duplicate_pad_numbers_are_jumpers no)
		(fp_line
			(start -0.508 -0.9398)
			(end -0.508 0.9398)
			(stroke
				(width 0.1524)
				(type default)
			)
			(layer "F.SilkS")
		)
		(fp_line
			(start 0.508 -0.9398)
			(end -0.508 -0.9398)
			(stroke
				(width 0.1524)
				(type default)
			)
			(layer "F.SilkS")
		)
		(fp_rect
			(start -0.508 0.9398)
			(end 0.508 -0.9398)
			(stroke
				(width 0)
				(type default)
			)
			(fill no)
			(layer "F.CrtYd")
		)
		(fp_rect
			(start -0.508 0.9398)
			(end 0.508 -0.9398)
			(stroke
				(width 0)
				(type default)
			)
			(fill no)
			(layer "F.Fab")
		)
		(pad "1" smd custom
			(at 0 -0.4445 270)
			(size 0.1397 0.1397)
			(layers "F.Cu" "F.Mask" "F.Paste")
			(net "PM8536_RST#_LS")
			(options
				(clearance outline)
				(anchor circle)
			)
			(primitives
				(gr_poly
					(pts
						(arc
							(start -0.1778 -0.2794)
							(mid -0.249642 -0.249642)
							(end -0.2794 -0.1778)
						)
						(arc
							(start -0.2794 0.1778)
							(mid -0.249642 0.249642)
							(end -0.1778 0.2794)
						)
						(arc
							(start 0.1778 0.2794)
							(mid 0.249642 0.249642)
							(end 0.2794 0.1778)
						)
						(arc
							(start 0.2794 -0.1778)
							(mid 0.249642 -0.249642)
							(end 0.1778 -0.2794)
						)
					)
					(width 0)
					(fill yes)
				)
			)
		)
		(pad "2" smd custom
			(at 0 0.4445 270)
			(size 0.1397 0.1397)
			(layers "F.Cu" "F.Mask" "F.Paste")
			(net "PM8536_RST#_LS_R")
			(options
				(clearance outline)
				(anchor circle)
			)
			(primitives
				(gr_poly
					(pts
						(arc
							(start -0.1778 -0.2794)
							(mid -0.249642 -0.249642)
							(end -0.2794 -0.1778)
						)
						(arc
							(start -0.2794 0.1778)
							(mid -0.249642 0.249642)
							(end -0.1778 0.2794)
						)
						(arc
							(start 0.1778 0.2794)
							(mid 0.249642 0.249642)
							(end 0.2794 0.1778)
						)
						(arc
							(start 0.2794 -0.1778)
							(mid 0.249642 -0.249642)
							(end 0.1778 -0.2794)
						)
					)
					(width 0)
					(fill yes)
				)
			)
		)
	)
	(footprint ""
		(layer "F.Cu")
		(at 71.3994 -52.5272 180)
		(property "Reference" "R960"
			(at 0 0 180)
			(layer "F.SilkS")
			(hide yes)
			(effects
				(font
					(size 1.27 1.27)
				)
			)
		)
		(property "Value" "4K7R2F-GP"
			(at 0.064008 -3.993896 180)
			(unlocked yes)
			(layer "F.Fab")
			(hide yes)
			(effects
				(font
					(size 1.016 1.016)
					(thickness 0.1524)
				)
			)
		)
		(property "Device Type" "R402H16"
			(at 0.064008 -5.517896 180)
			(unlocked yes)
			(layer "F.Fab")
			(hide yes)
			(effects
				(font
					(size 1.016 1.016)
					(thickness 0.1524)
				)
			)
		)
		(duplicate_pad_numbers_are_jumpers no)
		(fp_line
			(start 0.508 -0.9398)
			(end -0.508 -0.9398)
			(stroke
				(width 0.1524)
				(type default)
			)
			(layer "F.SilkS")
		)
		(fp_line
			(start -0.508 -0.9398)
			(end -0.508 0.9398)
			(stroke
				(width 0.1524)
				(type default)
			)
			(layer "F.SilkS")
		)
		(fp_rect
			(start -0.508 0.9398)
			(end 0.508 -0.9398)
			(stroke
				(width 0)
				(type default)
			)
			(fill no)
			(layer "F.CrtYd")
		)
		(fp_rect
			(start -0.508 0.9398)
			(end 0.508 -0.9398)
			(stroke
				(width 0)
				(type default)
			)
			(fill no)
			(layer "F.Fab")
		)
		(pad "1" smd custom
			(at 0 -0.4445 180)
			(size 0.1397 0.1397)
			(layers "F.Cu" "F.Mask" "F.Paste")
			(net "BMC_CPU_EN")
			(options
				(clearance outline)
				(anchor circle)
			)
			(primitives
				(gr_poly
					(pts
						(arc
							(start -0.1778 -0.2794)
							(mid -0.249642 -0.249642)
							(end -0.2794 -0.1778)
						)
						(arc
							(start -0.2794 0.1778)
							(mid -0.249642 0.249642)
							(end -0.1778 0.2794)
						)
						(arc
							(start 0.1778 0.2794)
							(mid 0.249642 0.249642)
							(end 0.2794 0.1778)
						)
						(arc
							(start 0.2794 -0.1778)
							(mid 0.249642 -0.249642)
							(end 0.1778 -0.2794)
						)
					)
					(width 0)
					(fill yes)
				)
			)
		)
		(pad "2" smd custom
			(at 0 0.4445 180)
			(size 0.1397 0.1397)
			(layers "F.Cu" "F.Mask" "F.Paste")
			(net "P3V3_STBY")
			(options
				(clearance outline)
				(anchor circle)
			)
			(primitives
				(gr_poly
					(pts
						(arc
							(start -0.1778 -0.2794)
							(mid -0.249642 -0.249642)
							(end -0.2794 -0.1778)
						)
						(arc
							(start -0.2794 0.1778)
							(mid -0.249642 0.249642)
							(end -0.1778 0.2794)
						)
						(arc
							(start 0.1778 0.2794)
							(mid 0.249642 0.249642)
							(end 0.2794 0.1778)
						)
						(arc
							(start 0.2794 -0.1778)
							(mid 0.249642 -0.249642)
							(end 0.1778 -0.2794)
						)
					)
					(width 0)
					(fill yes)
				)
			)
		)
	)
	(footprint ""
		(layer "F.Cu")
		(at 26.0096 -82.3214 90)
		(property "Reference" "R384"
			(at 0 0 90)
			(layer "F.SilkS")
			(hide yes)
			(effects
				(font
					(size 1.27 1.27)
				)
			)
		)
		(property "Value" "0R2J-2-GP"
			(at 0.064008 -3.993896 90)
			(unlocked yes)
			(layer "F.Fab")
			(hide yes)
			(effects
				(font
					(size 1.016 1.016)
					(thickness 0.1524)
				)
			)
		)
		(property "Device Type" "R402H16"
			(at 0.064008 -5.517896 90)
			(unlocked yes)
			(layer "F.Fab")
			(hide yes)
			(effects
				(font
					(size 1.016 1.016)
					(thickness 0.1524)
				)
			)
		)
		(duplicate_pad_numbers_are_jumpers no)
		(fp_line
			(start 0.508 -0.9398)
			(end -0.508 -0.9398)
			(stroke
				(width 0.1524)
				(type default)
			)
			(layer "F.SilkS")
		)
		(fp_line
			(start -0.508 -0.9398)
			(end -0.508 0.9398)
			(stroke
				(width 0.1524)
				(type default)
			)
			(layer "F.SilkS")
		)
		(fp_rect
			(start -0.508 0.9398)
			(end 0.508 -0.9398)
			(stroke
				(width 0)
				(type default)
			)
			(fill no)
			(layer "F.CrtYd")
		)
		(fp_rect
			(start -0.508 0.9398)
			(end 0.508 -0.9398)
			(stroke
				(width 0)
				(type default)
			)
			(fill no)
			(layer "F.Fab")
		)
		(pad "1" smd custom
			(at 0 -0.4445 90)
			(size 0.1397 0.1397)
			(layers "F.Cu" "F.Mask" "F.Paste")
			(net "NVM_SO")
			(options
				(clearance outline)
				(anchor circle)
			)
			(primitives
				(gr_poly
					(pts
						(arc
							(start -0.1778 -0.2794)
							(mid -0.249642 -0.249642)
							(end -0.2794 -0.1778)
						)
						(arc
							(start -0.2794 0.1778)
							(mid -0.249642 0.249642)
							(end -0.1778 0.2794)
						)
						(arc
							(start 0.1778 0.2794)
							(mid 0.249642 0.249642)
							(end 0.2794 0.1778)
						)
						(arc
							(start 0.2794 -0.1778)
							(mid 0.249642 -0.249642)
							(end 0.1778 -0.2794)
						)
					)
					(width 0)
					(fill yes)
				)
			)
		)
		(pad "2" smd custom
			(at 0 0.4445 90)
			(size 0.1397 0.1397)
			(layers "F.Cu" "F.Mask" "F.Paste")
			(net "I210_SO_R")
			(options
				(clearance outline)
				(anchor circle)
			)
			(primitives
				(gr_poly
					(pts
						(arc
							(start -0.1778 -0.2794)
							(mid -0.249642 -0.249642)
							(end -0.2794 -0.1778)
						)
						(arc
							(start -0.2794 0.1778)
							(mid -0.249642 0.249642)
							(end -0.1778 0.2794)
						)
						(arc
							(start 0.1778 0.2794)
							(mid 0.249642 0.249642)
							(end 0.2794 0.1778)
						)
						(arc
							(start 0.2794 -0.1778)
							(mid 0.249642 -0.249642)
							(end 0.1778 -0.2794)
						)
					)
					(width 0)
					(fill yes)
				)
			)
		)
	)
	(footprint ""
		(layer "F.Cu")
		(at 205.844902 -30.200092 -90)
		(property "Reference" "R823"
			(at 0 0 270)
			(layer "F.SilkS")
			(hide yes)
			(effects
				(font
					(size 1.27 1.27)
				)
			)
		)
		(property "Value" "4K7R2F-GP"
			(at 0.064008 -3.993896 270)
			(unlocked yes)
			(layer "F.Fab")
			(hide yes)
			(effects
				(font
					(size 1.016 1.016)
					(thickness 0.1524)
				)
			)
		)
		(property "Device Type" "R402H16"
			(at 0.064008 -5.517896 270)
			(unlocked yes)
			(layer "F.Fab")
			(hide yes)
			(effects
				(font
					(size 1.016 1.016)
					(thickness 0.1524)
				)
			)
		)
		(duplicate_pad_numbers_are_jumpers no)
		(fp_line
			(start -0.508 -0.9398)
			(end -0.508 0.9398)
			(stroke
				(width 0.1524)
				(type default)
			)
			(layer "F.SilkS")
		)
		(fp_line
			(start 0.508 -0.9398)
			(end -0.508 -0.9398)
			(stroke
				(width 0.1524)
				(type default)
			)
			(layer "F.SilkS")
		)
		(fp_rect
			(start -0.508 0.9398)
			(end 0.508 -0.9398)
			(stroke
				(width 0)
				(type default)
			)
			(fill no)
			(layer "F.CrtYd")
		)
		(fp_rect
			(start -0.508 0.9398)
			(end 0.508 -0.9398)
			(stroke
				(width 0)
				(type default)
			)
			(fill no)
			(layer "F.Fab")
		)
		(pad "1" smd custom
			(at 0 -0.4445 270)
			(size 0.1397 0.1397)
			(layers "F.Cu" "F.Mask" "F.Paste")
			(net "P3V3_STBY")
			(options
				(clearance outline)
				(anchor circle)
			)
			(primitives
				(gr_poly
					(pts
						(arc
							(start -0.1778 -0.2794)
							(mid -0.249642 -0.249642)
							(end -0.2794 -0.1778)
						)
						(arc
							(start -0.2794 0.1778)
							(mid -0.249642 0.249642)
							(end -0.1778 0.2794)
						)
						(arc
							(start 0.1778 0.2794)
							(mid 0.249642 0.249642)
							(end 0.2794 0.1778)
						)
						(arc
							(start 0.2794 -0.1778)
							(mid 0.249642 -0.249642)
							(end 0.1778 -0.2794)
						)
					)
					(width 0)
					(fill yes)
				)
			)
		)
		(pad "2" smd custom
			(at 0 0.4445 270)
			(size 0.1397 0.1397)
			(layers "F.Cu" "F.Mask" "F.Paste")
			(net "U55_INT_N")
			(options
				(clearance outline)
				(anchor circle)
			)
			(primitives
				(gr_poly
					(pts
						(arc
							(start -0.1778 -0.2794)
							(mid -0.249642 -0.249642)
							(end -0.2794 -0.1778)
						)
						(arc
							(start -0.2794 0.1778)
							(mid -0.249642 0.249642)
							(end -0.1778 0.2794)
						)
						(arc
							(start 0.1778 0.2794)
							(mid 0.249642 0.249642)
							(end 0.2794 0.1778)
						)
						(arc
							(start 0.2794 -0.1778)
							(mid 0.249642 -0.249642)
							(end 0.1778 -0.2794)
						)
					)
					(width 0)
					(fill yes)
				)
			)
		)
	)
	(footprint ""
		(layer "F.Cu")
		(at 66.7766 -109.7534)
		(property "Reference" "R312"
			(at 0 0 0)
			(layer "F.SilkS")
			(hide yes)
			(effects
				(font
					(size 1.27 1.27)
				)
			)
		)
		(property "Value" "4K7R2F-GP"
			(at 0.064008 -3.993896 0)
			(unlocked yes)
			(layer "F.Fab")
			(hide yes)
			(effects
				(font
					(size 1.016 1.016)
					(thickness 0.1524)
				)
			)
		)
		(property "Device Type" "R402H16"
			(at 0.064008 -5.517896 0)
			(unlocked yes)
			(layer "F.Fab")
			(hide yes)
			(effects
				(font
					(size 1.016 1.016)
					(thickness 0.1524)
				)
			)
		)
		(duplicate_pad_numbers_are_jumpers no)
		(fp_line
			(start -0.508 -0.9398)
			(end -0.508 0.9398)
			(stroke
				(width 0.1524)
				(type default)
			)
			(layer "F.SilkS")
		)
		(fp_line
			(start 0.508 -0.9398)
			(end -0.508 -0.9398)
			(stroke
				(width 0.1524)
				(type default)
			)
			(layer "F.SilkS")
		)
		(fp_rect
			(start -0.508 0.9398)
			(end 0.508 -0.9398)
			(stroke
				(width 0)
				(type default)
			)
			(fill no)
			(layer "F.CrtYd")
		)
		(fp_rect
			(start -0.508 0.9398)
			(end 0.508 -0.9398)
			(stroke
				(width 0)
				(type default)
			)
			(fill no)
			(layer "F.Fab")
		)
		(pad "1" smd custom
			(at 0 -0.4445)
			(size 0.1397 0.1397)
			(layers "F.Cu" "F.Mask" "F.Paste")
			(net "P3V3_STBY")
			(options
				(clearance outline)
				(anchor circle)
			)
			(primitives
				(gr_poly
					(pts
						(arc
							(start -0.1778 -0.2794)
							(mid -0.249642 -0.249642)
							(end -0.2794 -0.1778)
						)
						(arc
							(start -0.2794 0.1778)
							(mid -0.249642 0.249642)
							(end -0.1778 0.2794)
						)
						(arc
							(start 0.1778 0.2794)
							(mid 0.249642 0.249642)
							(end 0.2794 0.1778)
						)
						(arc
							(start 0.2794 -0.1778)
							(mid 0.249642 -0.249642)
							(end 0.1778 -0.2794)
						)
					)
					(width 0)
					(fill yes)
				)
			)
		)
		(pad "2" smd custom
			(at 0 0.4445)
			(size 0.1397 0.1397)
			(layers "F.Cu" "F.Mask" "F.Paste")
			(net "I2C5_LS_G2")
			(options
				(clearance outline)
				(anchor circle)
			)
			(primitives
				(gr_poly
					(pts
						(arc
							(start -0.1778 -0.2794)
							(mid -0.249642 -0.249642)
							(end -0.2794 -0.1778)
						)
						(arc
							(start -0.2794 0.1778)
							(mid -0.249642 0.249642)
							(end -0.1778 0.2794)
						)
						(arc
							(start 0.1778 0.2794)
							(mid 0.249642 0.249642)
							(end 0.2794 0.1778)
						)
						(arc
							(start 0.2794 -0.1778)
							(mid 0.249642 -0.249642)
							(end 0.1778 -0.2794)
						)
					)
					(width 0)
					(fill yes)
				)
			)
		)
	)
	(footprint ""
		(layer "F.Cu")
		(at 19.809714 -92.72905 90)
		(property "Reference" "R2938"
			(at 0 0 90)
			(layer "F.SilkS")
			(hide yes)
			(effects
				(font
					(size 1.27 1.27)
				)
			)
		)
		(property "Value" "0R2J-2-GP"
			(at 0.064008 -3.993896 90)
			(unlocked yes)
			(layer "F.Fab")
			(hide yes)
			(effects
				(font
					(size 1.016 1.016)
					(thickness 0.1524)
				)
			)
		)
		(property "Device Type" "R402H16"
			(at 0.064008 -5.517896 90)
			(unlocked yes)
			(layer "F.Fab")
			(hide yes)
			(effects
				(font
					(size 1.016 1.016)
					(thickness 0.1524)
				)
			)
		)
		(duplicate_pad_numbers_are_jumpers no)
		(fp_line
			(start 0.508 -0.9398)
			(end -0.508 -0.9398)
			(stroke
				(width 0.1524)
				(type default)
			)
			(layer "F.SilkS")
		)
		(fp_line
			(start -0.508 -0.9398)
			(end -0.508 0.9398)
			(stroke
				(width 0.1524)
				(type default)
			)
			(layer "F.SilkS")
		)
		(fp_rect
			(start -0.508 0.9398)
			(end 0.508 -0.9398)
			(stroke
				(width 0)
				(type default)
			)
			(fill no)
			(layer "F.CrtYd")
		)
		(fp_rect
			(start -0.508 0.9398)
			(end 0.508 -0.9398)
			(stroke
				(width 0)
				(type default)
			)
			(fill no)
			(layer "F.Fab")
		)
		(pad "1" smd custom
			(at 0 -0.4445 90)
			(size 0.1397 0.1397)
			(layers "F.Cu" "F.Mask" "F.Paste")
			(net "BMC_TPM_RST")
			(options
				(clearance outline)
				(anchor circle)
			)
			(primitives
				(gr_poly
					(pts
						(arc
							(start -0.1778 -0.2794)
							(mid -0.249642 -0.249642)
							(end -0.2794 -0.1778)
						)
						(arc
							(start -0.2794 0.1778)
							(mid -0.249642 0.249642)
							(end -0.1778 0.2794)
						)
						(arc
							(start 0.1778 0.2794)
							(mid 0.249642 0.249642)
							(end 0.2794 0.1778)
						)
						(arc
							(start 0.2794 -0.1778)
							(mid 0.249642 -0.249642)
							(end 0.1778 -0.2794)
						)
					)
					(width 0)
					(fill yes)
				)
			)
		)
		(pad "2" smd custom
			(at 0 0.4445 90)
			(size 0.1397 0.1397)
			(layers "F.Cu" "F.Mask" "F.Paste")
			(net "FM_TPM_PRES_RST_N")
			(options
				(clearance outline)
				(anchor circle)
			)
			(primitives
				(gr_poly
					(pts
						(arc
							(start -0.1778 -0.2794)
							(mid -0.249642 -0.249642)
							(end -0.2794 -0.1778)
						)
						(arc
							(start -0.2794 0.1778)
							(mid -0.249642 0.249642)
							(end -0.1778 0.2794)
						)
						(arc
							(start 0.1778 0.2794)
							(mid 0.249642 0.249642)
							(end 0.2794 0.1778)
						)
						(arc
							(start 0.2794 -0.1778)
							(mid 0.249642 -0.249642)
							(end 0.1778 -0.2794)
						)
					)
					(width 0)
					(fill yes)
				)
			)
		)
	)
	(footprint ""
		(layer "F.Cu")
		(at 192.8368 -28.6512 -90)
		(property "Reference" "C142"
			(at 0 0 270)
			(layer "F.SilkS")
			(hide yes)
			(effects
				(font
					(size 1.27 1.27)
				)
			)
		)
		(property "Value" "SCD047U25V2KX-GP"
			(at 1.1811 -2.7051 270)
			(unlocked yes)
			(layer "F.Fab")
			(hide yes)
			(effects
				(font
					(size 1.016 1.016)
					(thickness 0.1524)
				)
			)
		)
		(property "Device Type" "C402H22"
			(at 1.1811 -4.2291 270)
			(unlocked yes)
			(layer "F.Fab")
			(hide yes)
			(effects
				(font
					(size 1.016 1.016)
					(thickness 0.1524)
				)
			)
		)
		(duplicate_pad_numbers_are_jumpers no)
		(fp_rect
			(start -0.4318 0.9525)
			(end 0.4318 -0.9525)
			(stroke
				(width 0)
				(type default)
			)
			(fill no)
			(layer "F.CrtYd")
		)
		(fp_rect
			(start -0.4318 0.9525)
			(end 0.4318 -0.9525)
			(stroke
				(width 0)
				(type default)
			)
			(fill no)
			(layer "F.Fab")
		)
		(pad "1" smd custom
			(at 0 -0.4445 270)
			(size 0.1524 0.1524)
			(layers "F.Cu" "F.Mask" "F.Paste")
			(net "P3V3_STBY")
			(options
				(clearance outline)
				(anchor circle)
			)
			(primitives
				(gr_poly
					(pts
						(arc
							(start 0.3048 -0.2032)
							(mid 0.275042 -0.275042)
							(end 0.2032 -0.3048)
						)
						(arc
							(start -0.2032 -0.3048)
							(mid -0.275042 -0.275042)
							(end -0.3048 -0.2032)
						)
						(arc
							(start -0.3048 0.2032)
							(mid -0.275042 0.275042)
							(end -0.2032 0.3048)
						)
						(arc
							(start 0.2032 0.3048)
							(mid 0.275042 0.275042)
							(end 0.3048 0.2032)
						)
					)
					(width 0)
					(fill yes)
				)
			)
		)
		(pad "2" smd custom
			(at 0 0.4445 270)
			(size 0.1524 0.1524)
			(layers "F.Cu" "F.Mask" "F.Paste")
			(net "GND")
			(options
				(clearance outline)
				(anchor circle)
			)
			(primitives
				(gr_poly
					(pts
						(arc
							(start 0.3048 -0.2032)
							(mid 0.275042 -0.275042)
							(end 0.2032 -0.3048)
						)
						(arc
							(start -0.2032 -0.3048)
							(mid -0.275042 -0.275042)
							(end -0.3048 -0.2032)
						)
						(arc
							(start -0.3048 0.2032)
							(mid -0.275042 0.275042)
							(end -0.2032 0.3048)
						)
						(arc
							(start 0.2032 0.3048)
							(mid 0.275042 0.275042)
							(end 0.3048 0.2032)
						)
					)
					(width 0)
					(fill yes)
				)
			)
		)
	)
	(footprint ""
		(layer "F.Cu")
		(at 45.623734 -152.002744 90)
		(property "Reference" "C200"
			(at 0 0 90)
			(layer "F.SilkS")
			(hide yes)
			(effects
				(font
					(size 1.27 1.27)
				)
			)
		)
		(property "Value" "SC1U10V2KX-4-GP"
			(at 1.1811 -2.7051 90)
			(unlocked yes)
			(layer "F.Fab")
			(hide yes)
			(effects
				(font
					(size 1.016 1.016)
					(thickness 0.1524)
				)
			)
		)
		(property "Device Type" "C402H22"
			(at 1.1811 -4.2291 90)
			(unlocked yes)
			(layer "F.Fab")
			(hide yes)
			(effects
				(font
					(size 1.016 1.016)
					(thickness 0.1524)
				)
			)
		)
		(duplicate_pad_numbers_are_jumpers no)
		(fp_rect
			(start -0.4318 0.9525)
			(end 0.4318 -0.9525)
			(stroke
				(width 0)
				(type default)
			)
			(fill no)
			(layer "F.CrtYd")
		)
		(fp_rect
			(start -0.4318 0.9525)
			(end 0.4318 -0.9525)
			(stroke
				(width 0)
				(type default)
			)
			(fill no)
			(layer "F.Fab")
		)
		(pad "1" smd custom
			(at 0 -0.4445 90)
			(size 0.1524 0.1524)
			(layers "F.Cu" "F.Mask" "F.Paste")
			(net "P1V53_STBY")
			(options
				(clearance outline)
				(anchor circle)
			)
			(primitives
				(gr_poly
					(pts
						(arc
							(start 0.3048 -0.2032)
							(mid 0.275042 -0.275042)
							(end 0.2032 -0.3048)
						)
						(arc
							(start -0.2032 -0.3048)
							(mid -0.275042 -0.275042)
							(end -0.3048 -0.2032)
						)
						(arc
							(start -0.3048 0.2032)
							(mid -0.275042 0.275042)
							(end -0.2032 0.3048)
						)
						(arc
							(start 0.2032 0.3048)
							(mid 0.275042 0.275042)
							(end 0.3048 0.2032)
						)
					)
					(width 0)
					(fill yes)
				)
			)
		)
		(pad "2" smd custom
			(at 0 0.4445 90)
			(size 0.1524 0.1524)
			(layers "F.Cu" "F.Mask" "F.Paste")
			(net "GND")
			(options
				(clearance outline)
				(anchor circle)
			)
			(primitives
				(gr_poly
					(pts
						(arc
							(start 0.3048 -0.2032)
							(mid 0.275042 -0.275042)
							(end 0.2032 -0.3048)
						)
						(arc
							(start -0.2032 -0.3048)
							(mid -0.275042 -0.275042)
							(end -0.3048 -0.2032)
						)
						(arc
							(start -0.3048 0.2032)
							(mid -0.275042 0.275042)
							(end -0.2032 0.3048)
						)
						(arc
							(start 0.2032 0.3048)
							(mid 0.275042 0.275042)
							(end 0.3048 0.2032)
						)
					)
					(width 0)
					(fill yes)
				)
			)
		)
	)
	(footprint ""
		(layer "F.Cu")
		(at 74.168 -42.291 90)
		(property "Reference" "PL3"
			(at 0 0 90)
			(layer "F.SilkS")
			(hide yes)
			(effects
				(font
					(size 1.27 1.27)
				)
			)
		)
		(property "Value" "COIL-1D5UH-32-GP"
			(at -4.699 -4.0132 90)
			(unlocked yes)
			(layer "F.Fab")
			(hide yes)
			(effects
				(font
					(size 1.016 1.016)
					(thickness 0.1524)
				)
			)
		)
		(property "Device Type" "L7066-1830-UH119"
			(at -4.699 -5.5372 90)
			(unlocked yes)
			(layer "F.Fab")
			(hide yes)
			(effects
				(font
					(size 1.016 1.016)
					(thickness 0.1524)
				)
			)
		)
		(duplicate_pad_numbers_are_jumpers no)
		(fp_line
			(start 3.556 -4.4958)
			(end 3.556 4.4958)
			(stroke
				(width 0.1524)
				(type default)
			)
			(layer "F.SilkS")
		)
		(fp_line
			(start -3.556 -4.4958)
			(end 3.556 -4.4958)
			(stroke
				(width 0.1524)
				(type default)
			)
			(layer "F.SilkS")
		)
		(fp_line
			(start 3.556 4.4958)
			(end -3.556 4.4958)
			(stroke
				(width 0.1524)
				(type default)
			)
			(layer "F.SilkS")
		)
		(fp_line
			(start -3.556 4.4958)
			(end -3.556 -4.4958)
			(stroke
				(width 0.1524)
				(type default)
			)
			(layer "F.SilkS")
		)
		(fp_rect
			(start -3.302 3.4798)
			(end 3.302 -3.4798)
			(stroke
				(width 0)
				(type default)
			)
			(fill no)
			(layer "F.CrtYd")
		)
		(fp_poly
			(pts
				(xy -3.81 4.572) (xy -3.81 -4.572) (xy 3.81 -4.572) (xy 3.81 -0.5588) (xy 3.302 -0.5588) (xy 3.302 -3.4798)
				(xy -3.302 -3.4798) (xy -3.302 3.4798) (xy 3.302 3.4798) (xy 3.302 -0.5461) (xy 3.81 -0.5461) (xy 3.81 4.572)
			)
			(stroke
				(width 0)
				(type default)
			)
			(fill no)
			(layer "F.CrtYd")
		)
		(fp_rect
			(start -3.81 4.572)
			(end 3.81 -4.572)
			(stroke
				(width 0)
				(type default)
			)
			(fill no)
			(layer "F.Fab")
		)
		(pad "1" smd rect
			(at 0 -2.779522 90)
			(size 3.5052 2.921)
			(layers "F.Cu" "F.Mask" "F.Paste")
			(net "P3V3_STBY_LL")
		)
		(pad "2" smd rect
			(at 0 2.779522 90)
			(size 3.5052 2.921)
			(layers "F.Cu" "F.Mask" "F.Paste")
			(net "P3V3_PWR")
		)
	)
	(footprint ""
		(layer "F.Cu")
		(at 11.1506 -76.6318 180)
		(property "Reference" "C377"
			(at 0 0 180)
			(layer "F.SilkS")
			(hide yes)
			(effects
				(font
					(size 1.27 1.27)
				)
			)
		)
		(property "Value" "SCD039U16V2KX-GP"
			(at 1.1811 -2.7051 180)
			(unlocked yes)
			(layer "F.Fab")
			(hide yes)
			(effects
				(font
					(size 1.016 1.016)
					(thickness 0.1524)
				)
			)
		)
		(property "Device Type" "C402H22"
			(at 1.1811 -4.2291 180)
			(unlocked yes)
			(layer "F.Fab")
			(hide yes)
			(effects
				(font
					(size 1.016 1.016)
					(thickness 0.1524)
				)
			)
		)
		(duplicate_pad_numbers_are_jumpers no)
		(fp_rect
			(start -0.4318 0.9525)
			(end 0.4318 -0.9525)
			(stroke
				(width 0)
				(type default)
			)
			(fill no)
			(layer "F.CrtYd")
		)
		(fp_rect
			(start -0.4318 0.9525)
			(end 0.4318 -0.9525)
			(stroke
				(width 0)
				(type default)
			)
			(fill no)
			(layer "F.Fab")
		)
		(pad "1" smd custom
			(at 0 -0.4445 180)
			(size 0.1524 0.1524)
			(layers "F.Cu" "F.Mask" "F.Paste")
			(net "I210_CTOP")
			(options
				(clearance outline)
				(anchor circle)
			)
			(primitives
				(gr_poly
					(pts
						(arc
							(start 0.3048 -0.2032)
							(mid 0.275042 -0.275042)
							(end 0.2032 -0.3048)
						)
						(arc
							(start -0.2032 -0.3048)
							(mid -0.275042 -0.275042)
							(end -0.3048 -0.2032)
						)
						(arc
							(start -0.3048 0.2032)
							(mid -0.275042 0.275042)
							(end -0.2032 0.3048)
						)
						(arc
							(start 0.2032 0.3048)
							(mid 0.275042 0.275042)
							(end 0.3048 0.2032)
						)
					)
					(width 0)
					(fill yes)
				)
			)
		)
		(pad "2" smd custom
			(at 0 0.4445 180)
			(size 0.1524 0.1524)
			(layers "F.Cu" "F.Mask" "F.Paste")
			(net "I210_CBOT")
			(options
				(clearance outline)
				(anchor circle)
			)
			(primitives
				(gr_poly
					(pts
						(arc
							(start 0.3048 -0.2032)
							(mid 0.275042 -0.275042)
							(end 0.2032 -0.3048)
						)
						(arc
							(start -0.2032 -0.3048)
							(mid -0.275042 -0.275042)
							(end -0.3048 -0.2032)
						)
						(arc
							(start -0.3048 0.2032)
							(mid -0.275042 0.275042)
							(end -0.2032 0.3048)
						)
						(arc
							(start 0.2032 0.3048)
							(mid 0.275042 0.275042)
							(end 0.3048 0.2032)
						)
					)
					(width 0)
					(fill yes)
				)
			)
		)
	)
	(footprint ""
		(layer "F.Cu")
		(at 194.3862 -26.8986 180)
		(property "Reference" "R833"
			(at 0 0 180)
			(layer "F.SilkS")
			(hide yes)
			(effects
				(font
					(size 1.27 1.27)
				)
			)
		)
		(property "Value" "4K7R2F-GP"
			(at 0.064008 -3.993896 180)
			(unlocked yes)
			(layer "F.Fab")
			(hide yes)
			(effects
				(font
					(size 1.016 1.016)
					(thickness 0.1524)
				)
			)
		)
		(property "Device Type" "R402H16"
			(at 0.064008 -5.517896 180)
			(unlocked yes)
			(layer "F.Fab")
			(hide yes)
			(effects
				(font
					(size 1.016 1.016)
					(thickness 0.1524)
				)
			)
		)
		(duplicate_pad_numbers_are_jumpers no)
		(fp_line
			(start 0.508 -0.9398)
			(end -0.508 -0.9398)
			(stroke
				(width 0.1524)
				(type default)
			)
			(layer "F.SilkS")
		)
		(fp_line
			(start -0.508 -0.9398)
			(end -0.508 0.9398)
			(stroke
				(width 0.1524)
				(type default)
			)
			(layer "F.SilkS")
		)
		(fp_rect
			(start -0.508 0.9398)
			(end 0.508 -0.9398)
			(stroke
				(width 0)
				(type default)
			)
			(fill no)
			(layer "F.CrtYd")
		)
		(fp_rect
			(start -0.508 0.9398)
			(end 0.508 -0.9398)
			(stroke
				(width 0)
				(type default)
			)
			(fill no)
			(layer "F.Fab")
		)
		(pad "1" smd custom
			(at 0 -0.4445 180)
			(size 0.1397 0.1397)
			(layers "F.Cu" "F.Mask" "F.Paste")
			(net "U56_A0")
			(options
				(clearance outline)
				(anchor circle)
			)
			(primitives
				(gr_poly
					(pts
						(arc
							(start -0.1778 -0.2794)
							(mid -0.249642 -0.249642)
							(end -0.2794 -0.1778)
						)
						(arc
							(start -0.2794 0.1778)
							(mid -0.249642 0.249642)
							(end -0.1778 0.2794)
						)
						(arc
							(start 0.1778 0.2794)
							(mid 0.249642 0.249642)
							(end 0.2794 0.1778)
						)
						(arc
							(start 0.2794 -0.1778)
							(mid 0.249642 -0.249642)
							(end 0.1778 -0.2794)
						)
					)
					(width 0)
					(fill yes)
				)
			)
		)
		(pad "2" smd custom
			(at 0 0.4445 180)
			(size 0.1397 0.1397)
			(layers "F.Cu" "F.Mask" "F.Paste")
			(net "P3V3_STBY")
			(options
				(clearance outline)
				(anchor circle)
			)
			(primitives
				(gr_poly
					(pts
						(arc
							(start -0.1778 -0.2794)
							(mid -0.249642 -0.249642)
							(end -0.2794 -0.1778)
						)
						(arc
							(start -0.2794 0.1778)
							(mid -0.249642 0.249642)
							(end -0.1778 0.2794)
						)
						(arc
							(start 0.1778 0.2794)
							(mid 0.249642 0.249642)
							(end 0.2794 0.1778)
						)
						(arc
							(start 0.2794 -0.1778)
							(mid 0.249642 -0.249642)
							(end 0.1778 -0.2794)
						)
					)
					(width 0)
					(fill yes)
				)
			)
		)
	)
	(footprint ""
		(layer "F.Cu")
		(at 78.081124 -195.681092 180)
		(property "Reference" "R7963"
			(at 0 0 180)
			(layer "F.SilkS")
			(hide yes)
			(effects
				(font
					(size 1.27 1.27)
				)
			)
		)
		(property "Value" "0R2J-2-GP"
			(at 0.064008 -3.993896 180)
			(unlocked yes)
			(layer "F.Fab")
			(hide yes)
			(effects
				(font
					(size 1.016 1.016)
					(thickness 0.1524)
				)
			)
		)
		(property "Device Type" "R402H16"
			(at 0.064008 -5.517896 180)
			(unlocked yes)
			(layer "F.Fab")
			(hide yes)
			(effects
				(font
					(size 1.016 1.016)
					(thickness 0.1524)
				)
			)
		)
		(duplicate_pad_numbers_are_jumpers no)
		(fp_line
			(start 0.508 -0.9398)
			(end -0.508 -0.9398)
			(stroke
				(width 0.1524)
				(type default)
			)
			(layer "F.SilkS")
		)
		(fp_line
			(start -0.508 -0.9398)
			(end -0.508 0.9398)
			(stroke
				(width 0.1524)
				(type default)
			)
			(layer "F.SilkS")
		)
		(fp_rect
			(start -0.508 0.9398)
			(end 0.508 -0.9398)
			(stroke
				(width 0)
				(type default)
			)
			(fill no)
			(layer "F.CrtYd")
		)
		(fp_rect
			(start -0.508 0.9398)
			(end 0.508 -0.9398)
			(stroke
				(width 0)
				(type default)
			)
			(fill no)
			(layer "F.Fab")
		)
		(pad "1" smd custom
			(at 0 -0.4445 180)
			(size 0.1397 0.1397)
			(layers "F.Cu" "F.Mask" "F.Paste")
			(net "SSD_PWREN10")
			(options
				(clearance outline)
				(anchor circle)
			)
			(primitives
				(gr_poly
					(pts
						(arc
							(start -0.1778 -0.2794)
							(mid -0.249642 -0.249642)
							(end -0.2794 -0.1778)
						)
						(arc
							(start -0.2794 0.1778)
							(mid -0.249642 0.249642)
							(end -0.1778 0.2794)
						)
						(arc
							(start 0.1778 0.2794)
							(mid 0.249642 0.249642)
							(end 0.2794 0.1778)
						)
						(arc
							(start 0.2794 -0.1778)
							(mid 0.249642 -0.249642)
							(end 0.1778 -0.2794)
						)
					)
					(width 0)
					(fill yes)
				)
			)
		)
		(pad "2" smd custom
			(at 0 0.4445 180)
			(size 0.1397 0.1397)
			(layers "F.Cu" "F.Mask" "F.Paste")
			(net "SSD_PWREN10_R")
			(options
				(clearance outline)
				(anchor circle)
			)
			(primitives
				(gr_poly
					(pts
						(arc
							(start -0.1778 -0.2794)
							(mid -0.249642 -0.249642)
							(end -0.2794 -0.1778)
						)
						(arc
							(start -0.2794 0.1778)
							(mid -0.249642 0.249642)
							(end -0.1778 0.2794)
						)
						(arc
							(start 0.1778 0.2794)
							(mid 0.249642 0.249642)
							(end 0.2794 0.1778)
						)
						(arc
							(start 0.2794 -0.1778)
							(mid 0.249642 -0.249642)
							(end 0.1778 -0.2794)
						)
					)
					(width 0)
					(fill yes)
				)
			)
		)
	)
	(footprint ""
		(layer "F.Cu")
		(at 120.1928 -93.4212 -90)
		(property "Reference" "C247"
			(at 0 0 270)
			(layer "F.SilkS")
			(hide yes)
			(effects
				(font
					(size 1.27 1.27)
				)
			)
		)
		(property "Value" "SC220P50V3JN-GP"
			(at 0 -2.8194 270)
			(unlocked yes)
			(layer "F.Fab")
			(hide yes)
			(effects
				(font
					(size 1.016 1.016)
					(thickness 0.1524)
				)
			)
		)
		(property "Device Type" "C603H36"
			(at 0 -4.3434 270)
			(unlocked yes)
			(layer "F.Fab")
			(hide yes)
			(effects
				(font
					(size 1.016 1.016)
					(thickness 0.1524)
				)
			)
		)
		(duplicate_pad_numbers_are_jumpers no)
		(fp_line
			(start 0.508 0)
			(end -0.508 0)
			(stroke
				(width 0.2032)
				(type default)
			)
			(layer "F.SilkS")
		)
		(fp_rect
			(start -0.5842 1.3335)
			(end 0.5842 -1.3335)
			(stroke
				(width 0)
				(type default)
			)
			(fill no)
			(layer "F.CrtYd")
		)
		(fp_rect
			(start -0.5842 1.3335)
			(end 0.5842 -1.3335)
			(stroke
				(width 0)
				(type default)
			)
			(fill no)
			(layer "F.Fab")
		)
		(pad "1" smd custom
			(at 0 -0.762 270)
			(size 0.2159 0.2159)
			(layers "F.Cu" "F.Mask" "F.Paste")
			(net "BMC_I2C10_8536_SDA_R")
			(options
				(clearance outline)
				(anchor circle)
			)
			(primitives
				(gr_poly
					(pts
						(arc
							(start -0.3302 -0.4318)
							(mid -0.402042 -0.402042)
							(end -0.4318 -0.3302)
						)
						(arc
							(start -0.4318 0.3302)
							(mid -0.402042 0.402042)
							(end -0.3302 0.4318)
						)
						(arc
							(start 0.3302 0.4318)
							(mid 0.402042 0.402042)
							(end 0.4318 0.3302)
						)
						(arc
							(start 0.4318 -0.3302)
							(mid 0.402042 -0.402042)
							(end 0.3302 -0.4318)
						)
					)
					(width 0)
					(fill yes)
				)
			)
		)
		(pad "2" smd custom
			(at 0 0.762 270)
			(size 0.2159 0.2159)
			(layers "F.Cu" "F.Mask" "F.Paste")
			(net "GND")
			(options
				(clearance outline)
				(anchor circle)
			)
			(primitives
				(gr_poly
					(pts
						(arc
							(start -0.3302 -0.4318)
							(mid -0.402042 -0.402042)
							(end -0.4318 -0.3302)
						)
						(arc
							(start -0.4318 0.3302)
							(mid -0.402042 0.402042)
							(end -0.3302 0.4318)
						)
						(arc
							(start 0.3302 0.4318)
							(mid 0.402042 0.402042)
							(end 0.4318 0.3302)
						)
						(arc
							(start 0.4318 -0.3302)
							(mid 0.402042 -0.402042)
							(end 0.3302 -0.4318)
						)
					)
					(width 0)
					(fill yes)
				)
			)
		)
	)
	(footprint ""
		(layer "F.Cu")
		(at 137.5283 -33.54324)
		(property "Reference" "C387"
			(at 0 0 0)
			(layer "F.SilkS")
			(hide yes)
			(effects
				(font
					(size 1.27 1.27)
				)
			)
		)
		(property "Value" "SCD22U10V2KX-1GP"
			(at 1.1811 -2.7051 0)
			(unlocked yes)
			(layer "F.Fab")
			(hide yes)
			(effects
				(font
					(size 1.016 1.016)
					(thickness 0.1524)
				)
			)
		)
		(property "Device Type" "C402H22"
			(at 1.1811 -4.2291 0)
			(unlocked yes)
			(layer "F.Fab")
			(hide yes)
			(effects
				(font
					(size 1.016 1.016)
					(thickness 0.1524)
				)
			)
		)
		(duplicate_pad_numbers_are_jumpers no)
		(fp_rect
			(start -0.4318 0.9525)
			(end 0.4318 -0.9525)
			(stroke
				(width 0)
				(type default)
			)
			(fill no)
			(layer "F.CrtYd")
		)
		(fp_rect
			(start -0.4318 0.9525)
			(end 0.4318 -0.9525)
			(stroke
				(width 0)
				(type default)
			)
			(fill no)
			(layer "F.Fab")
		)
		(pad "1" smd custom
			(at 0 -0.4445)
			(size 0.1524 0.1524)
			(layers "F.Cu" "F.Mask" "F.Paste")
			(net "PCIE_TX_CAP_P83")
			(options
				(clearance outline)
				(anchor circle)
			)
			(primitives
				(gr_poly
					(pts
						(arc
							(start 0.3048 -0.2032)
							(mid 0.275042 -0.275042)
							(end 0.2032 -0.3048)
						)
						(arc
							(start -0.2032 -0.3048)
							(mid -0.275042 -0.275042)
							(end -0.3048 -0.2032)
						)
						(arc
							(start -0.3048 0.2032)
							(mid -0.275042 0.275042)
							(end -0.2032 0.3048)
						)
						(arc
							(start 0.2032 0.3048)
							(mid 0.275042 0.275042)
							(end 0.3048 0.2032)
						)
					)
					(width 0)
					(fill yes)
				)
			)
		)
		(pad "2" smd custom
			(at 0 0.4445)
			(size 0.1524 0.1524)
			(layers "F.Cu" "F.Mask" "F.Paste")
			(net "PCIE_TX_P83")
			(options
				(clearance outline)
				(anchor circle)
			)
			(primitives
				(gr_poly
					(pts
						(arc
							(start 0.3048 -0.2032)
							(mid 0.275042 -0.275042)
							(end 0.2032 -0.3048)
						)
						(arc
							(start -0.2032 -0.3048)
							(mid -0.275042 -0.275042)
							(end -0.3048 -0.2032)
						)
						(arc
							(start -0.3048 0.2032)
							(mid -0.275042 0.275042)
							(end -0.2032 0.3048)
						)
						(arc
							(start 0.2032 0.3048)
							(mid 0.275042 0.275042)
							(end 0.3048 0.2032)
						)
					)
					(width 0)
					(fill yes)
				)
			)
		)
	)
	(footprint ""
		(layer "F.Cu")
		(at 273.699986 -0.127 -90)
		(property "Reference" "R2906"
			(at 0 0 270)
			(layer "F.SilkS")
			(hide yes)
			(effects
				(font
					(size 1.27 1.27)
				)
			)
		)
		(property "Value" "0R2J-2-GP"
			(at 0.064008 -3.993896 270)
			(unlocked yes)
			(layer "F.Fab")
			(hide yes)
			(effects
				(font
					(size 1.016 1.016)
					(thickness 0.1524)
				)
			)
		)
		(property "Device Type" "R402H16"
			(at 0.064008 -5.517896 270)
			(unlocked yes)
			(layer "F.Fab")
			(hide yes)
			(effects
				(font
					(size 1.016 1.016)
					(thickness 0.1524)
				)
			)
		)
		(duplicate_pad_numbers_are_jumpers no)
		(fp_line
			(start -0.508 -0.9398)
			(end -0.508 0.9398)
			(stroke
				(width 0.1524)
				(type default)
			)
			(layer "F.SilkS")
		)
		(fp_line
			(start 0.508 -0.9398)
			(end -0.508 -0.9398)
			(stroke
				(width 0.1524)
				(type default)
			)
			(layer "F.SilkS")
		)
		(fp_rect
			(start -0.508 0.9398)
			(end 0.508 -0.9398)
			(stroke
				(width 0)
				(type default)
			)
			(fill no)
			(layer "F.CrtYd")
		)
		(fp_rect
			(start -0.508 0.9398)
			(end 0.508 -0.9398)
			(stroke
				(width 0)
				(type default)
			)
			(fill no)
			(layer "F.Fab")
		)
		(pad "1" smd custom
			(at 0 -0.4445 270)
			(size 0.1397 0.1397)
			(layers "F.Cu" "F.Mask" "F.Paste")
			(net "CBL_PRSNT_N_7")
			(options
				(clearance outline)
				(anchor circle)
			)
			(primitives
				(gr_poly
					(pts
						(arc
							(start -0.1778 -0.2794)
							(mid -0.249642 -0.249642)
							(end -0.2794 -0.1778)
						)
						(arc
							(start -0.2794 0.1778)
							(mid -0.249642 0.249642)
							(end -0.1778 0.2794)
						)
						(arc
							(start 0.1778 0.2794)
							(mid 0.249642 0.249642)
							(end 0.2794 0.1778)
						)
						(arc
							(start 0.2794 -0.1778)
							(mid 0.249642 -0.249642)
							(end 0.1778 -0.2794)
						)
					)
					(width 0)
					(fill yes)
				)
			)
		)
		(pad "2" smd custom
			(at 0 0.4445 270)
			(size 0.1397 0.1397)
			(layers "F.Cu" "F.Mask" "F.Paste")
			(net "8644_CBL_PRSNT_R_7")
			(options
				(clearance outline)
				(anchor circle)
			)
			(primitives
				(gr_poly
					(pts
						(arc
							(start -0.1778 -0.2794)
							(mid -0.249642 -0.249642)
							(end -0.2794 -0.1778)
						)
						(arc
							(start -0.2794 0.1778)
							(mid -0.249642 0.249642)
							(end -0.1778 0.2794)
						)
						(arc
							(start 0.1778 0.2794)
							(mid 0.249642 0.249642)
							(end 0.2794 0.1778)
						)
						(arc
							(start 0.2794 -0.1778)
							(mid 0.249642 -0.249642)
							(end 0.1778 -0.2794)
						)
					)
					(width 0)
					(fill yes)
				)
			)
		)
	)
	(footprint ""
		(layer "F.Cu")
		(at 163.068 -97.5614 90)
		(property "Reference" "TP80"
			(at 0 0 90)
			(layer "F.SilkS")
			(hide yes)
			(effects
				(font
					(size 1.27 1.27)
				)
			)
		)
		(property "Value" "TPAD28-2-GP"
			(at -0.0127 -1.6637 90)
			(unlocked yes)
			(layer "F.Fab")
			(hide yes)
			(effects
				(font
					(size 1.016 1.016)
					(thickness 0.1524)
				)
			)
		)
		(property "Device Type" "TPAD28"
			(at -0.0127 -3.1877 90)
			(unlocked yes)
			(layer "F.Fab")
			(hide yes)
			(effects
				(font
					(size 1.016 1.016)
					(thickness 0.1524)
				)
			)
		)
		(duplicate_pad_numbers_are_jumpers no)
		(fp_poly
			(pts
				(arc
					(start 0 0.3556)
					(mid 0 -0.3556)
					(end 0 0.3556)
				)
			)
			(stroke
				(width 0)
				(type default)
			)
			(fill no)
			(layer "F.CrtYd")
		)
		(fp_poly
			(pts
				(arc
					(start 0 0.6096)
					(mid 0 -0.6096)
					(end 0 0.6096)
				)
			)
			(stroke
				(width 0)
				(type default)
			)
			(fill no)
			(layer "F.Fab")
		)
		(pad "1" smd circle
			(at 0 0 90)
			(size 0.7112 0.7112)
			(layers "F.Cu" "F.Mask" "F.Paste")
			(net "CLKGEN_P3")
		)
	)
	(footprint ""
		(layer "F.Cu")
		(at 150.231602 -54.688232 -90)
		(property "Reference" "R68"
			(at 0 0 270)
			(layer "F.SilkS")
			(hide yes)
			(effects
				(font
					(size 1.27 1.27)
				)
			)
		)
		(property "Value" "20KR2F-L-GP"
			(at 0.064008 -3.993896 270)
			(unlocked yes)
			(layer "F.Fab")
			(hide yes)
			(effects
				(font
					(size 1.016 1.016)
					(thickness 0.1524)
				)
			)
		)
		(property "Device Type" "R402H16"
			(at 0.064008 -5.517896 270)
			(unlocked yes)
			(layer "F.Fab")
			(hide yes)
			(effects
				(font
					(size 1.016 1.016)
					(thickness 0.1524)
				)
			)
		)
		(duplicate_pad_numbers_are_jumpers no)
		(fp_line
			(start -0.508 -0.9398)
			(end -0.508 0.9398)
			(stroke
				(width 0.1524)
				(type default)
			)
			(layer "F.SilkS")
		)
		(fp_line
			(start 0.508 -0.9398)
			(end -0.508 -0.9398)
			(stroke
				(width 0.1524)
				(type default)
			)
			(layer "F.SilkS")
		)
		(fp_rect
			(start -0.508 0.9398)
			(end 0.508 -0.9398)
			(stroke
				(width 0)
				(type default)
			)
			(fill no)
			(layer "F.CrtYd")
		)
		(fp_rect
			(start -0.508 0.9398)
			(end 0.508 -0.9398)
			(stroke
				(width 0)
				(type default)
			)
			(fill no)
			(layer "F.Fab")
		)
		(pad "1" smd custom
			(at 0 -0.4445 270)
			(size 0.1397 0.1397)
			(layers "F.Cu" "F.Mask" "F.Paste")
			(net "DUT_VDDO")
			(options
				(clearance outline)
				(anchor circle)
			)
			(primitives
				(gr_poly
					(pts
						(arc
							(start -0.1778 -0.2794)
							(mid -0.249642 -0.249642)
							(end -0.2794 -0.1778)
						)
						(arc
							(start -0.2794 0.1778)
							(mid -0.249642 0.249642)
							(end -0.1778 0.2794)
						)
						(arc
							(start 0.1778 0.2794)
							(mid 0.249642 0.249642)
							(end 0.2794 0.1778)
						)
						(arc
							(start 0.2794 -0.1778)
							(mid 0.249642 -0.249642)
							(end 0.1778 -0.2794)
						)
					)
					(width 0)
					(fill yes)
				)
			)
		)
		(pad "2" smd custom
			(at 0 0.4445 270)
			(size 0.1397 0.1397)
			(layers "F.Cu" "F.Mask" "F.Paste")
			(net "AVS_ENB1_R")
			(options
				(clearance outline)
				(anchor circle)
			)
			(primitives
				(gr_poly
					(pts
						(arc
							(start -0.1778 -0.2794)
							(mid -0.249642 -0.249642)
							(end -0.2794 -0.1778)
						)
						(arc
							(start -0.2794 0.1778)
							(mid -0.249642 0.249642)
							(end -0.1778 0.2794)
						)
						(arc
							(start 0.1778 0.2794)
							(mid 0.249642 0.249642)
							(end 0.2794 0.1778)
						)
						(arc
							(start 0.2794 -0.1778)
							(mid 0.249642 -0.249642)
							(end 0.1778 -0.2794)
						)
					)
					(width 0)
					(fill yes)
				)
			)
		)
	)
	(footprint ""
		(layer "F.Cu")
		(at 252.627638 -14.190726)
		(property "Reference" "PC224"
			(at 0 0 0)
			(layer "F.SilkS")
			(hide yes)
			(effects
				(font
					(size 1.27 1.27)
				)
			)
		)
		(property "Value" "SC1U16V3KX-5GP"
			(at 0 -2.8194 0)
			(unlocked yes)
			(layer "F.Fab")
			(hide yes)
			(effects
				(font
					(size 1.016 1.016)
					(thickness 0.1524)
				)
			)
		)
		(property "Device Type" "C603H36"
			(at 0 -4.3434 0)
			(unlocked yes)
			(layer "F.Fab")
			(hide yes)
			(effects
				(font
					(size 1.016 1.016)
					(thickness 0.1524)
				)
			)
		)
		(duplicate_pad_numbers_are_jumpers no)
		(fp_line
			(start 0.508 0)
			(end -0.508 0)
			(stroke
				(width 0.2032)
				(type default)
			)
			(layer "F.SilkS")
		)
		(fp_rect
			(start -0.5842 1.3335)
			(end 0.5842 -1.3335)
			(stroke
				(width 0)
				(type default)
			)
			(fill no)
			(layer "F.CrtYd")
		)
		(fp_rect
			(start -0.5842 1.3335)
			(end 0.5842 -1.3335)
			(stroke
				(width 0)
				(type default)
			)
			(fill no)
			(layer "F.Fab")
		)
		(pad "1" smd custom
			(at 0 -0.762)
			(size 0.2159 0.2159)
			(layers "F.Cu" "F.Mask" "F.Paste")
			(net "P3V3_GPIO")
			(options
				(clearance outline)
				(anchor circle)
			)
			(primitives
				(gr_poly
					(pts
						(arc
							(start -0.3302 -0.4318)
							(mid -0.402042 -0.402042)
							(end -0.4318 -0.3302)
						)
						(arc
							(start -0.4318 0.3302)
							(mid -0.402042 0.402042)
							(end -0.3302 0.4318)
						)
						(arc
							(start 0.3302 0.4318)
							(mid 0.402042 0.402042)
							(end 0.4318 0.3302)
						)
						(arc
							(start 0.4318 -0.3302)
							(mid 0.402042 -0.402042)
							(end 0.3302 -0.4318)
						)
					)
					(width 0)
					(fill yes)
				)
			)
		)
		(pad "2" smd custom
			(at 0 0.762)
			(size 0.2159 0.2159)
			(layers "F.Cu" "F.Mask" "F.Paste")
			(net "GND")
			(options
				(clearance outline)
				(anchor circle)
			)
			(primitives
				(gr_poly
					(pts
						(arc
							(start -0.3302 -0.4318)
							(mid -0.402042 -0.402042)
							(end -0.4318 -0.3302)
						)
						(arc
							(start -0.4318 0.3302)
							(mid -0.402042 0.402042)
							(end -0.3302 0.4318)
						)
						(arc
							(start 0.3302 0.4318)
							(mid 0.402042 0.402042)
							(end 0.4318 0.3302)
						)
						(arc
							(start 0.4318 -0.3302)
							(mid 0.402042 -0.402042)
							(end 0.3302 -0.4318)
						)
					)
					(width 0)
					(fill yes)
				)
			)
		)
	)
	(footprint ""
		(layer "F.Cu")
		(at 5.8674 -55.5498 180)
		(property "Reference" "C422"
			(at 0 0 180)
			(layer "F.SilkS")
			(hide yes)
			(effects
				(font
					(size 1.27 1.27)
				)
			)
		)
		(property "Value" "SCD1U16V2KX-3GP"
			(at 1.1811 -2.7051 180)
			(unlocked yes)
			(layer "F.Fab")
			(hide yes)
			(effects
				(font
					(size 1.016 1.016)
					(thickness 0.1524)
				)
			)
		)
		(property "Device Type" "C402H22"
			(at 1.1811 -4.2291 180)
			(unlocked yes)
			(layer "F.Fab")
			(hide yes)
			(effects
				(font
					(size 1.016 1.016)
					(thickness 0.1524)
				)
			)
		)
		(duplicate_pad_numbers_are_jumpers no)
		(fp_rect
			(start -0.4318 0.9525)
			(end 0.4318 -0.9525)
			(stroke
				(width 0)
				(type default)
			)
			(fill no)
			(layer "F.CrtYd")
		)
		(fp_rect
			(start -0.4318 0.9525)
			(end 0.4318 -0.9525)
			(stroke
				(width 0)
				(type default)
			)
			(fill no)
			(layer "F.Fab")
		)
		(pad "1" smd custom
			(at 0 -0.4445 180)
			(size 0.1524 0.1524)
			(layers "F.Cu" "F.Mask" "F.Paste")
			(net "LED_MDI0_ACT")
			(options
				(clearance outline)
				(anchor circle)
			)
			(primitives
				(gr_poly
					(pts
						(arc
							(start 0.3048 -0.2032)
							(mid 0.275042 -0.275042)
							(end 0.2032 -0.3048)
						)
						(arc
							(start -0.2032 -0.3048)
							(mid -0.275042 -0.275042)
							(end -0.3048 -0.2032)
						)
						(arc
							(start -0.3048 0.2032)
							(mid -0.275042 0.275042)
							(end -0.2032 0.3048)
						)
						(arc
							(start 0.2032 0.3048)
							(mid 0.275042 0.275042)
							(end 0.3048 0.2032)
						)
					)
					(width 0)
					(fill yes)
				)
			)
		)
		(pad "2" smd custom
			(at 0 0.4445 180)
			(size 0.1524 0.1524)
			(layers "F.Cu" "F.Mask" "F.Paste")
			(net "GND")
			(options
				(clearance outline)
				(anchor circle)
			)
			(primitives
				(gr_poly
					(pts
						(arc
							(start 0.3048 -0.2032)
							(mid 0.275042 -0.275042)
							(end 0.2032 -0.3048)
						)
						(arc
							(start -0.2032 -0.3048)
							(mid -0.275042 -0.275042)
							(end -0.3048 -0.2032)
						)
						(arc
							(start -0.3048 0.2032)
							(mid -0.275042 0.275042)
							(end -0.2032 0.3048)
						)
						(arc
							(start 0.2032 0.3048)
							(mid 0.275042 0.275042)
							(end 0.3048 0.2032)
						)
					)
					(width 0)
					(fill yes)
				)
			)
		)
	)
	(footprint ""
		(layer "F.Cu")
		(at 336.836512 -184.878218 180)
		(property "Reference" "R7975"
			(at 0 0 180)
			(layer "F.SilkS")
			(hide yes)
			(effects
				(font
					(size 1.27 1.27)
				)
			)
		)
		(property "Value" "0R2J-2-GP"
			(at 0.064008 -3.993896 180)
			(unlocked yes)
			(layer "F.Fab")
			(hide yes)
			(effects
				(font
					(size 1.016 1.016)
					(thickness 0.1524)
				)
			)
		)
		(property "Device Type" "R402H16"
			(at 0.064008 -5.517896 180)
			(unlocked yes)
			(layer "F.Fab")
			(hide yes)
			(effects
				(font
					(size 1.016 1.016)
					(thickness 0.1524)
				)
			)
		)
		(duplicate_pad_numbers_are_jumpers no)
		(fp_line
			(start 0.508 -0.9398)
			(end -0.508 -0.9398)
			(stroke
				(width 0.1524)
				(type default)
			)
			(layer "F.SilkS")
		)
		(fp_line
			(start -0.508 -0.9398)
			(end -0.508 0.9398)
			(stroke
				(width 0.1524)
				(type default)
			)
			(layer "F.SilkS")
		)
		(fp_rect
			(start -0.508 0.9398)
			(end 0.508 -0.9398)
			(stroke
				(width 0)
				(type default)
			)
			(fill no)
			(layer "F.CrtYd")
		)
		(fp_rect
			(start -0.508 0.9398)
			(end 0.508 -0.9398)
			(stroke
				(width 0)
				(type default)
			)
			(fill no)
			(layer "F.Fab")
		)
		(pad "1" smd custom
			(at 0 -0.4445 180)
			(size 0.1397 0.1397)
			(layers "F.Cu" "F.Mask" "F.Paste")
			(net "SSD_PERST#14")
			(options
				(clearance outline)
				(anchor circle)
			)
			(primitives
				(gr_poly
					(pts
						(arc
							(start -0.1778 -0.2794)
							(mid -0.249642 -0.249642)
							(end -0.2794 -0.1778)
						)
						(arc
							(start -0.2794 0.1778)
							(mid -0.249642 0.249642)
							(end -0.1778 0.2794)
						)
						(arc
							(start 0.1778 0.2794)
							(mid 0.249642 0.249642)
							(end 0.2794 0.1778)
						)
						(arc
							(start 0.2794 -0.1778)
							(mid 0.249642 -0.249642)
							(end 0.1778 -0.2794)
						)
					)
					(width 0)
					(fill yes)
				)
			)
		)
		(pad "2" smd custom
			(at 0 0.4445 180)
			(size 0.1397 0.1397)
			(layers "F.Cu" "F.Mask" "F.Paste")
			(net "SSD_PERST#14_R")
			(options
				(clearance outline)
				(anchor circle)
			)
			(primitives
				(gr_poly
					(pts
						(arc
							(start -0.1778 -0.2794)
							(mid -0.249642 -0.249642)
							(end -0.2794 -0.1778)
						)
						(arc
							(start -0.2794 0.1778)
							(mid -0.249642 0.249642)
							(end -0.1778 0.2794)
						)
						(arc
							(start 0.1778 0.2794)
							(mid 0.249642 0.249642)
							(end 0.2794 0.1778)
						)
						(arc
							(start 0.2794 -0.1778)
							(mid 0.249642 -0.249642)
							(end 0.1778 -0.2794)
						)
					)
					(width 0)
					(fill yes)
				)
			)
		)
	)
	(footprint ""
		(layer "F.Cu")
		(at 12.192 -108.204 90)
		(property "Reference" "PU5"
			(at 0 0 90)
			(layer "F.SilkS")
			(hide yes)
			(effects
				(font
					(size 1.27 1.27)
				)
			)
		)
		(property "Value" "TPS74801DRCR-1-GP-U"
			(at -3.5306 1.3208 90)
			(unlocked yes)
			(layer "F.Fab")
			(hide yes)
			(effects
				(font
					(size 1.016 1.016)
					(thickness 0.1524)
				)
			)
		)
		(property "Device Type" "DFN10G3-G315175H40"
			(at -3.5306 -0.2032 90)
			(unlocked yes)
			(layer "F.Fab")
			(hide yes)
			(effects
				(font
					(size 1.016 1.016)
					(thickness 0.1524)
				)
			)
		)
		(duplicate_pad_numbers_are_jumpers no)
		(fp_line
			(start -0.9906 -2.794)
			(end -0.9906 -2.286)
			(stroke
				(width 0.1524)
				(type default)
			)
			(layer "F.SilkS")
		)
		(fp_line
			(start -1.6256 -2.5146)
			(end -2.3876 -2.5146)
			(stroke
				(width 0.1524)
				(type default)
			)
			(layer "F.SilkS")
		)
		(fp_line
			(start -2.3876 -2.5146)
			(end -2.3876 -1.7526)
			(stroke
				(width 0.1524)
				(type default)
			)
			(layer "F.SilkS")
		)
		(fp_line
			(start -2.3876 1.7526)
			(end -2.3876 2.5146)
			(stroke
				(width 0.1524)
				(type default)
			)
			(layer "F.SilkS")
		)
		(fp_line
			(start 0.9906 2.286)
			(end 0.9906 3.048)
			(stroke
				(width 0.1524)
				(type default)
			)
			(layer "F.SilkS")
		)
		(fp_line
			(start 2.3876 2.5146)
			(end 2.3876 1.7526)
			(stroke
				(width 0.1524)
				(type default)
			)
			(layer "F.SilkS")
		)
		(fp_line
			(start 1.6256 2.5146)
			(end 2.3876 2.5146)
			(stroke
				(width 0.1524)
				(type default)
			)
			(layer "F.SilkS")
		)
		(fp_line
			(start -2.3876 2.5146)
			(end -1.6256 2.5146)
			(stroke
				(width 0.1524)
				(type default)
			)
			(layer "F.SilkS")
		)
		(fp_poly
			(pts
				(xy 1.6256 -2.5146) (xy 2.3876 -2.5146) (xy 2.3876 -1.7526)
			)
			(stroke
				(width 0)
				(type default)
			)
			(fill yes)
			(layer "F.SilkS")
		)
		(fp_rect
			(start -1.4986 1.4986)
			(end 1.4986 -1.4986)
			(stroke
				(width 0)
				(type default)
			)
			(fill no)
			(layer "F.CrtYd")
		)
		(fp_poly
			(pts
				(xy -2.3876 2.5146) (xy -2.3876 0.00254) (xy -1.4986 0.00254) (xy -1.4986 1.4986) (xy 1.4986 1.4986)
				(xy 1.4986 -1.4986) (xy -1.4986 -1.4986) (xy -1.4986 -0.00254) (xy -2.3876 -0.00254) (xy -2.3876 -2.5146)
				(xy 2.3876 -2.5146) (xy 2.3876 2.5146)
			)
			(stroke
				(width 0)
				(type default)
			)
			(fill no)
			(layer "F.CrtYd")
		)
		(fp_rect
			(start -2.3876 2.5146)
			(end 2.3876 -2.5146)
			(stroke
				(width 0)
				(type default)
			)
			(fill no)
			(layer "F.Fab")
		)
		(pad "1" smd rect
			(at 0.99949 -1.5494 90)
			(size 0.3048 0.9144)
			(layers "F.Cu" "F.Mask" "F.Paste")
			(net "VR_P1V26_STBY_IN")
		)
		(pad "2" smd rect
			(at 0.50038 -1.5494 90)
			(size 0.3048 0.9144)
			(layers "F.Cu" "F.Mask" "F.Paste")
			(net "VR_P1V26_STBY_IN")
		)
		(pad "3" smd rect
			(at 0 -1.5494 90)
			(size 0.3048 0.9144)
			(layers "F.Cu" "F.Mask" "F.Paste")
			(net "PWRGD_P1V26_STBY")
		)
		(pad "4" smd rect
			(at -0.50038 -1.5494 90)
			(size 0.3048 0.9144)
			(layers "F.Cu" "F.Mask" "F.Paste")
			(net "VR_P1V26_STBY_BIAS")
		)
		(pad "5" smd rect
			(at -0.99949 -1.5494 90)
			(size 0.3048 0.9144)
			(layers "F.Cu" "F.Mask" "F.Paste")
			(net "VR_P1V26_STBY_EN_R")
		)
		(pad "6" smd rect
			(at -0.99949 1.5494 90)
			(size 0.3048 0.9144)
			(layers "F.Cu" "F.Mask" "F.Paste")
			(net "GND")
		)
		(pad "7" smd rect
			(at -0.50038 1.5494 90)
			(size 0.3048 0.9144)
			(layers "F.Cu" "F.Mask" "F.Paste")
			(net "VR_P1V26_STBY_SS_C")
		)
		(pad "8" smd rect
			(at 0 1.5494 90)
			(size 0.3048 0.9144)
			(layers "F.Cu" "F.Mask" "F.Paste")
			(net "VR_P1V26_STBY_FB")
		)
		(pad "9" smd rect
			(at 0.50038 1.5494 90)
			(size 0.3048 0.9144)
			(layers "F.Cu" "F.Mask" "F.Paste")
			(net "P1V26_PWR")
		)
		(pad "10" smd rect
			(at 0.99949 1.5494 90)
			(size 0.3048 0.9144)
			(layers "F.Cu" "F.Mask" "F.Paste")
			(net "P1V26_PWR")
		)
		(pad "11" smd custom
			(at 0 0 90)
			(size 0.4318 0.4318)
			(layers "F.Cu" "F.Mask" "F.Paste")
			(net "GND")
			(options
				(clearance outline)
				(anchor circle)
			)
			(primitives
				(gr_poly
					(pts
						(xy -1.2446 0.8636) (xy -1.2446 0.3937) (xy -1.8796 0.3937) (xy -1.8796 0.1143) (xy -1.2446 0.1143)
						(xy -1.2446 -0.1143) (xy -1.8796 -0.1143) (xy -1.8796 -0.3937) (xy -1.2446 -0.3937) (xy -1.2446 -0.8636)
						(xy 1.2446 -0.8636) (xy 1.2446 -0.3937) (xy 1.8796 -0.3937) (xy 1.8796 -0.1143) (xy 1.2446 -0.1143)
						(xy 1.2446 0.1143) (xy 1.8796 0.1143) (xy 1.8796 0.3937) (xy 1.2446 0.3937) (xy 1.2446 0.8636)
					)
					(width 0)
					(fill yes)
				)
			)
		)
	)
	(footprint ""
		(layer "F.Cu")
		(at 127.992886 -84.211414 90)
		(property "Reference" "U43"
			(at 0 0 90)
			(layer "F.SilkS")
			(hide yes)
			(effects
				(font
					(size 1.27 1.27)
				)
			)
		)
		(property "Value" "PCF8563T-1-GP"
			(at -3.707384 -1.5367 90)
			(unlocked yes)
			(layer "F.Fab")
			(hide yes)
			(effects
				(font
					(size 1.016 1.016)
					(thickness 0.1524)
				)
			)
		)
		(property "Device Type" "SOIC8H69"
			(at -3.707384 -3.0607 90)
			(unlocked yes)
			(layer "F.Fab")
			(hide yes)
			(effects
				(font
					(size 1.016 1.016)
					(thickness 0.1524)
				)
			)
		)
		(duplicate_pad_numbers_are_jumpers no)
		(fp_line
			(start 2.1336 -1.4224)
			(end -2.7432 -1.4224)
			(stroke
				(width 0.1524)
				(type default)
			)
			(layer "F.SilkS")
		)
		(fp_line
			(start -2.7432 -1.4224)
			(end -2.7432 1.4224)
			(stroke
				(width 0.1524)
				(type default)
			)
			(layer "F.SilkS")
		)
		(fp_line
			(start -2.7178 -0.508)
			(end -2.1844 -0.0508)
			(stroke
				(width 0.1524)
				(type default)
			)
			(layer "F.SilkS")
		)
		(fp_line
			(start -2.1844 -0.0508)
			(end -2.7178 0.508)
			(stroke
				(width 0.1524)
				(type default)
			)
			(layer "F.SilkS")
		)
		(fp_line
			(start 2.1336 1.4224)
			(end 2.1336 -1.4224)
			(stroke
				(width 0.1524)
				(type default)
			)
			(layer "F.SilkS")
		)
		(fp_line
			(start -2.7432 1.4224)
			(end 2.1336 1.4224)
			(stroke
				(width 0.1524)
				(type default)
			)
			(layer "F.SilkS")
		)
		(fp_line
			(start -2.7432 1.4224)
			(end -2.6416 1.4224)
			(stroke
				(width 0.1524)
				(type default)
			)
			(layer "F.SilkS")
		)
		(fp_line
			(start -2.6289 3.4417)
			(end -2.6289 1.4732)
			(stroke
				(width 0.381)
				(type default)
			)
			(layer "F.SilkS")
		)
		(fp_poly
			(pts
				(xy -2.2098 -1.4224) (xy -2.2098 1.4224) (xy 2.2098 1.4224) (xy 2.2098 -1.4224)
			)
			(stroke
				(width 0)
				(type default)
			)
			(fill yes)
			(layer "F.SilkS")
		)
		(fp_rect
			(start -2.450084 2.999994)
			(end 2.450084 -2.999994)
			(stroke
				(width 0)
				(type default)
			)
			(fill no)
			(layer "F.CrtYd")
		)
		(fp_poly
			(pts
				(xy -2.8194 3.6322) (xy -2.8194 -3.6322) (xy 2.8194 -3.6322) (xy 2.8194 1.18364) (xy 2.450084 1.18364)
				(xy 2.450084 -2.999994) (xy -2.450084 -2.999994) (xy -2.450084 2.999994) (xy 2.450084 2.999994)
				(xy 2.450084 1.18618) (xy 2.8194 1.18618) (xy 2.8194 3.6322)
			)
			(stroke
				(width 0)
				(type default)
			)
			(fill no)
			(layer "F.CrtYd")
		)
		(fp_rect
			(start -2.8194 3.6322)
			(end 2.8194 -3.6322)
			(stroke
				(width 0)
				(type default)
			)
			(fill no)
			(layer "F.Fab")
		)
		(pad "1" smd rect
			(at -1.905 2.54 90)
			(size 0.635 1.651)
			(layers "F.Cu" "F.Mask" "F.Paste")
			(net "RTC_OSCI")
		)
		(pad "2" smd rect
			(at -0.635 2.54 90)
			(size 0.635 1.651)
			(layers "F.Cu" "F.Mask" "F.Paste")
			(net "RTC_OSCO")
		)
		(pad "3" smd rect
			(at 0.635 2.54 90)
			(size 0.635 1.651)
			(layers "F.Cu" "F.Mask" "F.Paste")
			(net "RTC_INT_N")
		)
		(pad "4" smd rect
			(at 1.905 2.54 90)
			(size 0.635 1.651)
			(layers "F.Cu" "F.Mask" "F.Paste")
			(net "GND")
		)
		(pad "5" smd rect
			(at 1.905 -2.54 90)
			(size 0.635 1.651)
			(layers "F.Cu" "F.Mask" "F.Paste")
			(net "RTC_I2C_SDA")
		)
		(pad "6" smd rect
			(at 0.635 -2.54 90)
			(size 0.635 1.651)
			(layers "F.Cu" "F.Mask" "F.Paste")
			(net "RTC_I2C_SCL")
		)
		(pad "7" smd rect
			(at -0.635 -2.54 90)
			(size 0.635 1.651)
			(layers "F.Cu" "F.Mask" "F.Paste")
			(net "RTC_CLK_OUT")
		)
		(pad "8" smd rect
			(at -1.905 -2.54 90)
			(size 0.635 1.651)
			(layers "F.Cu" "F.Mask" "F.Paste")
			(net "P3V3_RTC")
		)
	)
	(footprint ""
		(layer "F.Cu")
		(at 299.808138 -212.420454 180)
		(property "Reference" "C77"
			(at 0 0 180)
			(layer "F.SilkS")
			(hide yes)
			(effects
				(font
					(size 1.27 1.27)
				)
			)
		)
		(property "Value" "SCD22U10V2KX-1GP"
			(at 1.1811 -2.7051 180)
			(unlocked yes)
			(layer "F.Fab")
			(hide yes)
			(effects
				(font
					(size 1.016 1.016)
					(thickness 0.1524)
				)
			)
		)
		(property "Device Type" "C402H22"
			(at 1.1811 -4.2291 180)
			(unlocked yes)
			(layer "F.Fab")
			(hide yes)
			(effects
				(font
					(size 1.016 1.016)
					(thickness 0.1524)
				)
			)
		)
		(duplicate_pad_numbers_are_jumpers no)
		(fp_rect
			(start -0.4318 0.9525)
			(end 0.4318 -0.9525)
			(stroke
				(width 0)
				(type default)
			)
			(fill no)
			(layer "F.CrtYd")
		)
		(fp_rect
			(start -0.4318 0.9525)
			(end 0.4318 -0.9525)
			(stroke
				(width 0)
				(type default)
			)
			(fill no)
			(layer "F.Fab")
		)
		(pad "1" smd custom
			(at 0 -0.4445 180)
			(size 0.1524 0.1524)
			(layers "F.Cu" "F.Mask" "F.Paste")
			(net "PCIE_TX_CAP_N27")
			(options
				(clearance outline)
				(anchor circle)
			)
			(primitives
				(gr_poly
					(pts
						(arc
							(start 0.3048 -0.2032)
							(mid 0.275042 -0.275042)
							(end 0.2032 -0.3048)
						)
						(arc
							(start -0.2032 -0.3048)
							(mid -0.275042 -0.275042)
							(end -0.3048 -0.2032)
						)
						(arc
							(start -0.3048 0.2032)
							(mid -0.275042 0.275042)
							(end -0.2032 0.3048)
						)
						(arc
							(start 0.2032 0.3048)
							(mid 0.275042 0.275042)
							(end 0.3048 0.2032)
						)
					)
					(width 0)
					(fill yes)
				)
			)
		)
		(pad "2" smd custom
			(at 0 0.4445 180)
			(size 0.1524 0.1524)
			(layers "F.Cu" "F.Mask" "F.Paste")
			(net "PCIE_TX_N27")
			(options
				(clearance outline)
				(anchor circle)
			)
			(primitives
				(gr_poly
					(pts
						(arc
							(start 0.3048 -0.2032)
							(mid 0.275042 -0.275042)
							(end 0.2032 -0.3048)
						)
						(arc
							(start -0.2032 -0.3048)
							(mid -0.275042 -0.275042)
							(end -0.3048 -0.2032)
						)
						(arc
							(start -0.3048 0.2032)
							(mid -0.275042 0.275042)
							(end -0.2032 0.3048)
						)
						(arc
							(start 0.2032 0.3048)
							(mid 0.275042 0.275042)
							(end 0.3048 0.2032)
						)
					)
					(width 0)
					(fill yes)
				)
			)
		)
	)
	(footprint ""
		(layer "F.Cu")
		(at 339.1154 -36.49218)
		(property "Reference" "R626"
			(at 0 0 0)
			(layer "F.SilkS")
			(hide yes)
			(effects
				(font
					(size 1.27 1.27)
				)
			)
		)
		(property "Value" "0R2J-2-GP"
			(at 0.064008 -3.993896 0)
			(unlocked yes)
			(layer "F.Fab")
			(hide yes)
			(effects
				(font
					(size 1.016 1.016)
					(thickness 0.1524)
				)
			)
		)
		(property "Device Type" "R402H16"
			(at 0.064008 -5.517896 0)
			(unlocked yes)
			(layer "F.Fab")
			(hide yes)
			(effects
				(font
					(size 1.016 1.016)
					(thickness 0.1524)
				)
			)
		)
		(duplicate_pad_numbers_are_jumpers no)
		(fp_line
			(start -0.508 -0.9398)
			(end -0.508 0.9398)
			(stroke
				(width 0.1524)
				(type default)
			)
			(layer "F.SilkS")
		)
		(fp_line
			(start 0.508 -0.9398)
			(end -0.508 -0.9398)
			(stroke
				(width 0.1524)
				(type default)
			)
			(layer "F.SilkS")
		)
		(fp_rect
			(start -0.508 0.9398)
			(end 0.508 -0.9398)
			(stroke
				(width 0)
				(type default)
			)
			(fill no)
			(layer "F.CrtYd")
		)
		(fp_rect
			(start -0.508 0.9398)
			(end 0.508 -0.9398)
			(stroke
				(width 0)
				(type default)
			)
			(fill no)
			(layer "F.Fab")
		)
		(pad "1" smd custom
			(at 0 -0.4445)
			(size 0.1397 0.1397)
			(layers "F.Cu" "F.Mask" "F.Paste")
			(net "UPLINK7_R")
			(options
				(clearance outline)
				(anchor circle)
			)
			(primitives
				(gr_poly
					(pts
						(arc
							(start -0.1778 -0.2794)
							(mid -0.249642 -0.249642)
							(end -0.2794 -0.1778)
						)
						(arc
							(start -0.2794 0.1778)
							(mid -0.249642 0.249642)
							(end -0.1778 0.2794)
						)
						(arc
							(start 0.1778 0.2794)
							(mid 0.249642 0.249642)
							(end 0.2794 0.1778)
						)
						(arc
							(start 0.2794 -0.1778)
							(mid 0.249642 -0.249642)
							(end 0.1778 -0.2794)
						)
					)
					(width 0)
					(fill yes)
				)
			)
		)
		(pad "2" smd custom
			(at 0 0.4445)
			(size 0.1397 0.1397)
			(layers "F.Cu" "F.Mask" "F.Paste")
			(net "UPLINK7")
			(options
				(clearance outline)
				(anchor circle)
			)
			(primitives
				(gr_poly
					(pts
						(arc
							(start -0.1778 -0.2794)
							(mid -0.249642 -0.249642)
							(end -0.2794 -0.1778)
						)
						(arc
							(start -0.2794 0.1778)
							(mid -0.249642 0.249642)
							(end -0.1778 0.2794)
						)
						(arc
							(start 0.1778 0.2794)
							(mid 0.249642 0.249642)
							(end 0.2794 0.1778)
						)
						(arc
							(start 0.2794 -0.1778)
							(mid 0.249642 -0.249642)
							(end 0.1778 -0.2794)
						)
					)
					(width 0)
					(fill yes)
				)
			)
		)
	)
	(footprint ""
		(layer "F.Cu")
		(at 188.208158 -212.420454 180)
		(property "Reference" "C124"
			(at 0 0 180)
			(layer "F.SilkS")
			(hide yes)
			(effects
				(font
					(size 1.27 1.27)
				)
			)
		)
		(property "Value" "SCD22U10V2KX-1GP"
			(at 1.1811 -2.7051 180)
			(unlocked yes)
			(layer "F.Fab")
			(hide yes)
			(effects
				(font
					(size 1.016 1.016)
					(thickness 0.1524)
				)
			)
		)
		(property "Device Type" "C402H22"
			(at 1.1811 -4.2291 180)
			(unlocked yes)
			(layer "F.Fab")
			(hide yes)
			(effects
				(font
					(size 1.016 1.016)
					(thickness 0.1524)
				)
			)
		)
		(duplicate_pad_numbers_are_jumpers no)
		(fp_rect
			(start -0.4318 0.9525)
			(end 0.4318 -0.9525)
			(stroke
				(width 0)
				(type default)
			)
			(fill no)
			(layer "F.CrtYd")
		)
		(fp_rect
			(start -0.4318 0.9525)
			(end 0.4318 -0.9525)
			(stroke
				(width 0)
				(type default)
			)
			(fill no)
			(layer "F.Fab")
		)
		(pad "1" smd custom
			(at 0 -0.4445 180)
			(size 0.1524 0.1524)
			(layers "F.Cu" "F.Mask" "F.Paste")
			(net "PCIE_TX_CAP_N46")
			(options
				(clearance outline)
				(anchor circle)
			)
			(primitives
				(gr_poly
					(pts
						(arc
							(start 0.3048 -0.2032)
							(mid 0.275042 -0.275042)
							(end 0.2032 -0.3048)
						)
						(arc
							(start -0.2032 -0.3048)
							(mid -0.275042 -0.275042)
							(end -0.3048 -0.2032)
						)
						(arc
							(start -0.3048 0.2032)
							(mid -0.275042 0.275042)
							(end -0.2032 0.3048)
						)
						(arc
							(start 0.2032 0.3048)
							(mid 0.275042 0.275042)
							(end 0.3048 0.2032)
						)
					)
					(width 0)
					(fill yes)
				)
			)
		)
		(pad "2" smd custom
			(at 0 0.4445 180)
			(size 0.1524 0.1524)
			(layers "F.Cu" "F.Mask" "F.Paste")
			(net "PCIE_TX_N46")
			(options
				(clearance outline)
				(anchor circle)
			)
			(primitives
				(gr_poly
					(pts
						(arc
							(start 0.3048 -0.2032)
							(mid 0.275042 -0.275042)
							(end 0.2032 -0.3048)
						)
						(arc
							(start -0.2032 -0.3048)
							(mid -0.275042 -0.275042)
							(end -0.3048 -0.2032)
						)
						(arc
							(start -0.3048 0.2032)
							(mid -0.275042 0.275042)
							(end -0.2032 0.3048)
						)
						(arc
							(start 0.2032 0.3048)
							(mid 0.275042 0.275042)
							(end 0.3048 0.2032)
						)
					)
					(width 0)
					(fill yes)
				)
			)
		)
	)
	(footprint ""
		(layer "F.Cu")
		(at 119.351806 -82.34934 -90)
		(property "Reference" "C1698"
			(at 0 0 270)
			(layer "F.SilkS")
			(hide yes)
			(effects
				(font
					(size 1.27 1.27)
				)
			)
		)
		(property "Value" "SC22UF16V6KX-GP"
			(at 0 -6.8072 270)
			(unlocked yes)
			(layer "F.Fab")
			(hide yes)
			(effects
				(font
					(size 1.016 1.016)
					(thickness 0.1524)
				)
			)
		)
		(property "Device Type" "C1206H75"
			(at 0 -8.7122 270)
			(unlocked yes)
			(layer "F.Fab")
			(hide yes)
			(effects
				(font
					(size 1.016 1.016)
					(thickness 0.1524)
				)
			)
		)
		(duplicate_pad_numbers_are_jumpers no)
		(fp_line
			(start -1.016 2.2352)
			(end -1.016 0.8128)
			(stroke
				(width 0.1524)
				(type default)
			)
			(layer "F.SilkS")
		)
		(fp_line
			(start 1.016 2.2352)
			(end -1.016 2.2352)
			(stroke
				(width 0.1524)
				(type default)
			)
			(layer "F.SilkS")
		)
		(fp_line
			(start 1.016 0.8382)
			(end 1.016 2.2352)
			(stroke
				(width 0.1524)
				(type default)
			)
			(layer "F.SilkS")
		)
		(fp_line
			(start -1.016 -2.2352)
			(end -1.016 -0.8382)
			(stroke
				(width 0.1524)
				(type default)
			)
			(layer "F.SilkS")
		)
		(fp_line
			(start 1.016 -2.2352)
			(end 1.016 -0.8382)
			(stroke
				(width 0.1524)
				(type default)
			)
			(layer "F.SilkS")
		)
		(fp_line
			(start 1.016 -2.2352)
			(end -1.016 -2.2352)
			(stroke
				(width 0.1524)
				(type default)
			)
			(layer "F.SilkS")
		)
		(fp_rect
			(start -1.0922 2.3114)
			(end 1.0922 -2.3114)
			(stroke
				(width 0)
				(type default)
			)
			(fill no)
			(layer "F.CrtYd")
		)
		(fp_poly
			(pts
				(xy -1.0922 -2.3114) (xy 1.0922 -2.3114) (xy 1.0922 2.3114) (xy -1.0922 2.3114)
			)
			(stroke
				(width 0)
				(type default)
			)
			(fill no)
			(layer "F.Fab")
		)
		(pad "1" smd rect
			(at 0 -1.397 270)
			(size 1.651 1.27)
			(layers "F.Cu" "F.Mask" "F.Paste")
			(net "P3V3_RTC")
		)
		(pad "2" smd rect
			(at 0 1.397 270)
			(size 1.651 1.27)
			(layers "F.Cu" "F.Mask" "F.Paste")
			(net "GND")
		)
	)
	(footprint ""
		(layer "F.Cu")
		(at 20.6502 -189.2046 -90)
		(property "Reference" "R2107"
			(at 0 0 270)
			(layer "F.SilkS")
			(hide yes)
			(effects
				(font
					(size 1.27 1.27)
				)
			)
		)
		(property "Value" "49K9R2F-L-GP"
			(at 0.064008 -3.993896 270)
			(unlocked yes)
			(layer "F.Fab")
			(hide yes)
			(effects
				(font
					(size 1.016 1.016)
					(thickness 0.1524)
				)
			)
		)
		(property "Device Type" "R402H16"
			(at 0.064008 -5.517896 270)
			(unlocked yes)
			(layer "F.Fab")
			(hide yes)
			(effects
				(font
					(size 1.016 1.016)
					(thickness 0.1524)
				)
			)
		)
		(duplicate_pad_numbers_are_jumpers no)
		(fp_line
			(start -0.508 -0.9398)
			(end -0.508 0.9398)
			(stroke
				(width 0.1524)
				(type default)
			)
			(layer "F.SilkS")
		)
		(fp_line
			(start 0.508 -0.9398)
			(end -0.508 -0.9398)
			(stroke
				(width 0.1524)
				(type default)
			)
			(layer "F.SilkS")
		)
		(fp_rect
			(start -0.508 0.9398)
			(end 0.508 -0.9398)
			(stroke
				(width 0)
				(type default)
			)
			(fill no)
			(layer "F.CrtYd")
		)
		(fp_rect
			(start -0.508 0.9398)
			(end 0.508 -0.9398)
			(stroke
				(width 0)
				(type default)
			)
			(fill no)
			(layer "F.Fab")
		)
		(pad "1" smd custom
			(at 0 -0.4445 270)
			(size 0.1397 0.1397)
			(layers "F.Cu" "F.Mask" "F.Paste")
			(net "P12V_PCIE")
			(options
				(clearance outline)
				(anchor circle)
			)
			(primitives
				(gr_poly
					(pts
						(arc
							(start -0.1778 -0.2794)
							(mid -0.249642 -0.249642)
							(end -0.2794 -0.1778)
						)
						(arc
							(start -0.2794 0.1778)
							(mid -0.249642 0.249642)
							(end -0.1778 0.2794)
						)
						(arc
							(start 0.1778 0.2794)
							(mid 0.249642 0.249642)
							(end 0.2794 0.1778)
						)
						(arc
							(start 0.2794 -0.1778)
							(mid 0.249642 -0.249642)
							(end 0.1778 -0.2794)
						)
					)
					(width 0)
					(fill yes)
				)
			)
		)
		(pad "2" smd custom
			(at 0 0.4445 270)
			(size 0.1397 0.1397)
			(layers "F.Cu" "F.Mask" "F.Paste")
			(net "MB0_CM_UV_R")
			(options
				(clearance outline)
				(anchor circle)
			)
			(primitives
				(gr_poly
					(pts
						(arc
							(start -0.1778 -0.2794)
							(mid -0.249642 -0.249642)
							(end -0.2794 -0.1778)
						)
						(arc
							(start -0.2794 0.1778)
							(mid -0.249642 0.249642)
							(end -0.1778 0.2794)
						)
						(arc
							(start 0.1778 0.2794)
							(mid 0.249642 0.249642)
							(end 0.2794 0.1778)
						)
						(arc
							(start 0.2794 -0.1778)
							(mid 0.249642 -0.249642)
							(end 0.1778 -0.2794)
						)
					)
					(width 0)
					(fill yes)
				)
			)
		)
	)
	(footprint ""
		(layer "F.Cu")
		(at 72.771 -195.707 180)
		(property "Reference" "R9040"
			(at 0 0 180)
			(layer "F.SilkS")
			(hide yes)
			(effects
				(font
					(size 1.27 1.27)
				)
			)
		)
		(property "Value" "4K7R2F-GP"
			(at 0.064008 -3.993896 180)
			(unlocked yes)
			(layer "F.Fab")
			(hide yes)
			(effects
				(font
					(size 1.016 1.016)
					(thickness 0.1524)
				)
			)
		)
		(property "Device Type" "R402H16"
			(at 0.064008 -5.517896 180)
			(unlocked yes)
			(layer "F.Fab")
			(hide yes)
			(effects
				(font
					(size 1.016 1.016)
					(thickness 0.1524)
				)
			)
		)
		(duplicate_pad_numbers_are_jumpers no)
		(fp_line
			(start 0.508 -0.9398)
			(end -0.508 -0.9398)
			(stroke
				(width 0.1524)
				(type default)
			)
			(layer "F.SilkS")
		)
		(fp_line
			(start -0.508 -0.9398)
			(end -0.508 0.9398)
			(stroke
				(width 0.1524)
				(type default)
			)
			(layer "F.SilkS")
		)
		(fp_rect
			(start -0.508 0.9398)
			(end 0.508 -0.9398)
			(stroke
				(width 0)
				(type default)
			)
			(fill no)
			(layer "F.CrtYd")
		)
		(fp_rect
			(start -0.508 0.9398)
			(end 0.508 -0.9398)
			(stroke
				(width 0)
				(type default)
			)
			(fill no)
			(layer "F.Fab")
		)
		(pad "1" smd custom
			(at 0 -0.4445 180)
			(size 0.1397 0.1397)
			(layers "F.Cu" "F.Mask" "F.Paste")
			(net "SSD_PERST#11")
			(options
				(clearance outline)
				(anchor circle)
			)
			(primitives
				(gr_poly
					(pts
						(arc
							(start -0.1778 -0.2794)
							(mid -0.249642 -0.249642)
							(end -0.2794 -0.1778)
						)
						(arc
							(start -0.2794 0.1778)
							(mid -0.249642 0.249642)
							(end -0.1778 0.2794)
						)
						(arc
							(start 0.1778 0.2794)
							(mid 0.249642 0.249642)
							(end 0.2794 0.1778)
						)
						(arc
							(start 0.2794 -0.1778)
							(mid 0.249642 -0.249642)
							(end 0.1778 -0.2794)
						)
					)
					(width 0)
					(fill yes)
				)
			)
		)
		(pad "2" smd custom
			(at 0 0.4445 180)
			(size 0.1397 0.1397)
			(layers "F.Cu" "F.Mask" "F.Paste")
			(net "GND")
			(options
				(clearance outline)
				(anchor circle)
			)
			(primitives
				(gr_poly
					(pts
						(arc
							(start -0.1778 -0.2794)
							(mid -0.249642 -0.249642)
							(end -0.2794 -0.1778)
						)
						(arc
							(start -0.2794 0.1778)
							(mid -0.249642 0.249642)
							(end -0.1778 0.2794)
						)
						(arc
							(start 0.1778 0.2794)
							(mid 0.249642 0.249642)
							(end 0.2794 0.1778)
						)
						(arc
							(start 0.2794 -0.1778)
							(mid 0.249642 -0.249642)
							(end 0.1778 -0.2794)
						)
					)
					(width 0)
					(fill yes)
				)
			)
		)
	)
	(footprint ""
		(layer "F.Cu")
		(at 88.9 -44.0944)
		(property "Reference" "PG6"
			(at 0 0 0)
			(layer "F.SilkS")
			(hide yes)
			(effects
				(font
					(size 1.27 1.27)
				)
			)
		)
		(property "Value" "GAP-CLOSE-PWR-3-GP"
			(at 0.0254 -6.5786 0)
			(unlocked yes)
			(layer "F.Fab")
			(hide yes)
			(effects
				(font
					(size 1.016 1.016)
					(thickness 0.1524)
				)
			)
		)
		(property "Device Type" "GAP-CLOSE-PWR-3"
			(at 0.0254 -8.255 0)
			(unlocked yes)
			(layer "F.Fab")
			(hide yes)
			(effects
				(font
					(size 1.016 1.016)
					(thickness 0.1524)
				)
			)
		)
		(duplicate_pad_numbers_are_jumpers no)
		(fp_rect
			(start -0.7112 0.4572)
			(end 0.7112 -0.4572)
			(stroke
				(width 0)
				(type default)
			)
			(fill no)
			(layer "F.CrtYd")
		)
		(fp_poly
			(pts
				(xy -0.7112 -0.4572) (xy 0.7112 -0.4572) (xy 0.7112 0.4572) (xy -0.7112 0.4572)
			)
			(stroke
				(width 0)
				(type default)
			)
			(fill no)
			(layer "F.Fab")
		)
		(pad "1" smd rect
			(at -0.3048 0)
			(size 0.6604 0.762)
			(layers "F.Cu" "F.Mask" "F.Paste")
			(net "P3V3_PWR")
		)
		(pad "2" smd rect
			(at 0.3048 0)
			(size 0.6604 0.762)
			(layers "F.Cu" "F.Mask" "F.Paste")
			(net "P3V3_STBY")
		)
	)
	(footprint ""
		(layer "F.Cu")
		(at 20.955 -140.843 -90)
		(property "Reference" "R607"
			(at 0 0 270)
			(layer "F.SilkS")
			(hide yes)
			(effects
				(font
					(size 1.27 1.27)
				)
			)
		)
		(property "Value" "0R2J-2-GP"
			(at 0.064008 -3.993896 270)
			(unlocked yes)
			(layer "F.Fab")
			(hide yes)
			(effects
				(font
					(size 1.016 1.016)
					(thickness 0.1524)
				)
			)
		)
		(property "Device Type" "R402H16"
			(at 0.064008 -5.517896 270)
			(unlocked yes)
			(layer "F.Fab")
			(hide yes)
			(effects
				(font
					(size 1.016 1.016)
					(thickness 0.1524)
				)
			)
		)
		(duplicate_pad_numbers_are_jumpers no)
		(fp_line
			(start -0.508 -0.9398)
			(end -0.508 0.9398)
			(stroke
				(width 0.1524)
				(type default)
			)
			(layer "F.SilkS")
		)
		(fp_line
			(start 0.508 -0.9398)
			(end -0.508 -0.9398)
			(stroke
				(width 0.1524)
				(type default)
			)
			(layer "F.SilkS")
		)
		(fp_rect
			(start -0.508 0.9398)
			(end 0.508 -0.9398)
			(stroke
				(width 0)
				(type default)
			)
			(fill no)
			(layer "F.CrtYd")
		)
		(fp_rect
			(start -0.508 0.9398)
			(end 0.508 -0.9398)
			(stroke
				(width 0)
				(type default)
			)
			(fill no)
			(layer "F.Fab")
		)
		(pad "1" smd custom
			(at 0 -0.4445 270)
			(size 0.1397 0.1397)
			(layers "F.Cu" "F.Mask" "F.Paste")
			(net "DP_RST_N_R")
			(options
				(clearance outline)
				(anchor circle)
			)
			(primitives
				(gr_poly
					(pts
						(arc
							(start -0.1778 -0.2794)
							(mid -0.249642 -0.249642)
							(end -0.2794 -0.1778)
						)
						(arc
							(start -0.2794 0.1778)
							(mid -0.249642 0.249642)
							(end -0.1778 0.2794)
						)
						(arc
							(start 0.1778 0.2794)
							(mid 0.249642 0.249642)
							(end 0.2794 0.1778)
						)
						(arc
							(start 0.2794 -0.1778)
							(mid 0.249642 -0.249642)
							(end 0.1778 -0.2794)
						)
					)
					(width 0)
					(fill yes)
				)
			)
		)
		(pad "2" smd custom
			(at 0 0.4445 270)
			(size 0.1397 0.1397)
			(layers "F.Cu" "F.Mask" "F.Paste")
			(net "DP_RST_N")
			(options
				(clearance outline)
				(anchor circle)
			)
			(primitives
				(gr_poly
					(pts
						(arc
							(start -0.1778 -0.2794)
							(mid -0.249642 -0.249642)
							(end -0.2794 -0.1778)
						)
						(arc
							(start -0.2794 0.1778)
							(mid -0.249642 0.249642)
							(end -0.1778 0.2794)
						)
						(arc
							(start 0.1778 0.2794)
							(mid 0.249642 0.249642)
							(end 0.2794 0.1778)
						)
						(arc
							(start 0.2794 -0.1778)
							(mid 0.249642 -0.249642)
							(end 0.1778 -0.2794)
						)
					)
					(width 0)
					(fill yes)
				)
			)
		)
	)
	(footprint ""
		(layer "F.Cu")
		(at 196.792088 -212.420454 180)
		(property "Reference" "C119"
			(at 0 0 180)
			(layer "F.SilkS")
			(hide yes)
			(effects
				(font
					(size 1.27 1.27)
				)
			)
		)
		(property "Value" "SCD22U10V2KX-1GP"
			(at 1.1811 -2.7051 180)
			(unlocked yes)
			(layer "F.Fab")
			(hide yes)
			(effects
				(font
					(size 1.016 1.016)
					(thickness 0.1524)
				)
			)
		)
		(property "Device Type" "C402H22"
			(at 1.1811 -4.2291 180)
			(unlocked yes)
			(layer "F.Fab")
			(hide yes)
			(effects
				(font
					(size 1.016 1.016)
					(thickness 0.1524)
				)
			)
		)
		(duplicate_pad_numbers_are_jumpers no)
		(fp_rect
			(start -0.4318 0.9525)
			(end 0.4318 -0.9525)
			(stroke
				(width 0)
				(type default)
			)
			(fill no)
			(layer "F.CrtYd")
		)
		(fp_rect
			(start -0.4318 0.9525)
			(end 0.4318 -0.9525)
			(stroke
				(width 0)
				(type default)
			)
			(fill no)
			(layer "F.Fab")
		)
		(pad "1" smd custom
			(at 0 -0.4445 180)
			(size 0.1524 0.1524)
			(layers "F.Cu" "F.Mask" "F.Paste")
			(net "PCIE_TX_CAP_P43")
			(options
				(clearance outline)
				(anchor circle)
			)
			(primitives
				(gr_poly
					(pts
						(arc
							(start 0.3048 -0.2032)
							(mid 0.275042 -0.275042)
							(end 0.2032 -0.3048)
						)
						(arc
							(start -0.2032 -0.3048)
							(mid -0.275042 -0.275042)
							(end -0.3048 -0.2032)
						)
						(arc
							(start -0.3048 0.2032)
							(mid -0.275042 0.275042)
							(end -0.2032 0.3048)
						)
						(arc
							(start 0.2032 0.3048)
							(mid 0.275042 0.275042)
							(end 0.3048 0.2032)
						)
					)
					(width 0)
					(fill yes)
				)
			)
		)
		(pad "2" smd custom
			(at 0 0.4445 180)
			(size 0.1524 0.1524)
			(layers "F.Cu" "F.Mask" "F.Paste")
			(net "PCIE_TX_P43")
			(options
				(clearance outline)
				(anchor circle)
			)
			(primitives
				(gr_poly
					(pts
						(arc
							(start 0.3048 -0.2032)
							(mid 0.275042 -0.275042)
							(end 0.2032 -0.3048)
						)
						(arc
							(start -0.2032 -0.3048)
							(mid -0.275042 -0.275042)
							(end -0.3048 -0.2032)
						)
						(arc
							(start -0.3048 0.2032)
							(mid -0.275042 0.275042)
							(end -0.2032 0.3048)
						)
						(arc
							(start 0.2032 0.3048)
							(mid 0.275042 0.275042)
							(end 0.3048 0.2032)
						)
					)
					(width 0)
					(fill yes)
				)
			)
		)
	)
	(footprint ""
		(layer "F.Cu")
		(at 22.352 -154.5844)
		(property "Reference" "R493"
			(at 0 0 0)
			(layer "F.SilkS")
			(hide yes)
			(effects
				(font
					(size 1.27 1.27)
				)
			)
		)
		(property "Value" "4K7R2F-GP"
			(at 0.064008 -3.993896 0)
			(unlocked yes)
			(layer "F.Fab")
			(hide yes)
			(effects
				(font
					(size 1.016 1.016)
					(thickness 0.1524)
				)
			)
		)
		(property "Device Type" "R402H16"
			(at 0.064008 -5.517896 0)
			(unlocked yes)
			(layer "F.Fab")
			(hide yes)
			(effects
				(font
					(size 1.016 1.016)
					(thickness 0.1524)
				)
			)
		)
		(duplicate_pad_numbers_are_jumpers no)
		(fp_line
			(start -0.508 -0.9398)
			(end -0.508 0.9398)
			(stroke
				(width 0.1524)
				(type default)
			)
			(layer "F.SilkS")
		)
		(fp_line
			(start 0.508 -0.9398)
			(end -0.508 -0.9398)
			(stroke
				(width 0.1524)
				(type default)
			)
			(layer "F.SilkS")
		)
		(fp_rect
			(start -0.508 0.9398)
			(end 0.508 -0.9398)
			(stroke
				(width 0)
				(type default)
			)
			(fill no)
			(layer "F.CrtYd")
		)
		(fp_rect
			(start -0.508 0.9398)
			(end 0.508 -0.9398)
			(stroke
				(width 0)
				(type default)
			)
			(fill no)
			(layer "F.Fab")
		)
		(pad "1" smd custom
			(at 0 -0.4445)
			(size 0.1397 0.1397)
			(layers "F.Cu" "F.Mask" "F.Paste")
			(net "P3V3_STBY")
			(options
				(clearance outline)
				(anchor circle)
			)
			(primitives
				(gr_poly
					(pts
						(arc
							(start -0.1778 -0.2794)
							(mid -0.249642 -0.249642)
							(end -0.2794 -0.1778)
						)
						(arc
							(start -0.2794 0.1778)
							(mid -0.249642 0.249642)
							(end -0.1778 0.2794)
						)
						(arc
							(start 0.1778 0.2794)
							(mid 0.249642 0.249642)
							(end 0.2794 0.1778)
						)
						(arc
							(start 0.2794 -0.1778)
							(mid 0.249642 -0.249642)
							(end 0.1778 -0.2794)
						)
					)
					(width 0)
					(fill yes)
				)
			)
		)
		(pad "2" smd custom
			(at 0 0.4445)
			(size 0.1397 0.1397)
			(layers "F.Cu" "F.Mask" "F.Paste")
			(net "FM_BMC_RESET_Q36_R")
			(options
				(clearance outline)
				(anchor circle)
			)
			(primitives
				(gr_poly
					(pts
						(arc
							(start -0.1778 -0.2794)
							(mid -0.249642 -0.249642)
							(end -0.2794 -0.1778)
						)
						(arc
							(start -0.2794 0.1778)
							(mid -0.249642 0.249642)
							(end -0.1778 0.2794)
						)
						(arc
							(start 0.1778 0.2794)
							(mid 0.249642 0.249642)
							(end 0.2794 0.1778)
						)
						(arc
							(start 0.2794 -0.1778)
							(mid 0.249642 -0.249642)
							(end 0.1778 -0.2794)
						)
					)
					(width 0)
					(fill yes)
				)
			)
		)
	)
	(footprint ""
		(layer "F.Cu")
		(at 219.831412 -203.055474)
		(property "Reference" "R557"
			(at 0 0 0)
			(layer "F.SilkS")
			(hide yes)
			(effects
				(font
					(size 1.27 1.27)
				)
			)
		)
		(property "Value" "10KR2F-2-GP"
			(at 0.064008 -3.993896 0)
			(unlocked yes)
			(layer "F.Fab")
			(hide yes)
			(effects
				(font
					(size 1.016 1.016)
					(thickness 0.1524)
				)
			)
		)
		(property "Device Type" "R402H16"
			(at 0.064008 -5.517896 0)
			(unlocked yes)
			(layer "F.Fab")
			(hide yes)
			(effects
				(font
					(size 1.016 1.016)
					(thickness 0.1524)
				)
			)
		)
		(duplicate_pad_numbers_are_jumpers no)
		(fp_line
			(start -0.508 -0.9398)
			(end -0.508 0.9398)
			(stroke
				(width 0.1524)
				(type default)
			)
			(layer "F.SilkS")
		)
		(fp_line
			(start 0.508 -0.9398)
			(end -0.508 -0.9398)
			(stroke
				(width 0.1524)
				(type default)
			)
			(layer "F.SilkS")
		)
		(fp_rect
			(start -0.508 0.9398)
			(end 0.508 -0.9398)
			(stroke
				(width 0)
				(type default)
			)
			(fill no)
			(layer "F.CrtYd")
		)
		(fp_rect
			(start -0.508 0.9398)
			(end 0.508 -0.9398)
			(stroke
				(width 0)
				(type default)
			)
			(fill no)
			(layer "F.Fab")
		)
		(pad "1" smd custom
			(at 0 -0.4445)
			(size 0.1397 0.1397)
			(layers "F.Cu" "F.Mask" "F.Paste")
			(net "GND")
			(options
				(clearance outline)
				(anchor circle)
			)
			(primitives
				(gr_poly
					(pts
						(arc
							(start -0.1778 -0.2794)
							(mid -0.249642 -0.249642)
							(end -0.2794 -0.1778)
						)
						(arc
							(start -0.2794 0.1778)
							(mid -0.249642 0.249642)
							(end -0.1778 0.2794)
						)
						(arc
							(start 0.1778 0.2794)
							(mid 0.249642 0.249642)
							(end 0.2794 0.1778)
						)
						(arc
							(start 0.2794 -0.1778)
							(mid 0.249642 -0.249642)
							(end 0.1778 -0.2794)
						)
					)
					(width 0)
					(fill yes)
				)
			)
		)
		(pad "2" smd custom
			(at 0 0.4445)
			(size 0.1397 0.1397)
			(layers "F.Cu" "F.Mask" "F.Paste")
			(net "IOEXP3_AD0")
			(options
				(clearance outline)
				(anchor circle)
			)
			(primitives
				(gr_poly
					(pts
						(arc
							(start -0.1778 -0.2794)
							(mid -0.249642 -0.249642)
							(end -0.2794 -0.1778)
						)
						(arc
							(start -0.2794 0.1778)
							(mid -0.249642 0.249642)
							(end -0.1778 0.2794)
						)
						(arc
							(start 0.1778 0.2794)
							(mid 0.249642 0.249642)
							(end 0.2794 0.1778)
						)
						(arc
							(start 0.2794 -0.1778)
							(mid 0.249642 -0.249642)
							(end 0.1778 -0.2794)
						)
					)
					(width 0)
					(fill yes)
				)
			)
		)
	)
	(footprint ""
		(layer "F.Cu")
		(at 251.640594 -3.59664 -90)
		(property "Reference" "R3601"
			(at 0 0 270)
			(layer "F.SilkS")
			(hide yes)
			(effects
				(font
					(size 1.27 1.27)
				)
			)
		)
		(property "Value" "1KR2F-3-GP"
			(at 0.064008 -3.993896 270)
			(unlocked yes)
			(layer "F.Fab")
			(hide yes)
			(effects
				(font
					(size 1.016 1.016)
					(thickness 0.1524)
				)
			)
		)
		(property "Device Type" "R402H16"
			(at 0.064008 -5.517896 270)
			(unlocked yes)
			(layer "F.Fab")
			(hide yes)
			(effects
				(font
					(size 1.016 1.016)
					(thickness 0.1524)
				)
			)
		)
		(duplicate_pad_numbers_are_jumpers no)
		(fp_line
			(start -0.508 -0.9398)
			(end -0.508 0.9398)
			(stroke
				(width 0.1524)
				(type default)
			)
			(layer "F.SilkS")
		)
		(fp_line
			(start 0.508 -0.9398)
			(end -0.508 -0.9398)
			(stroke
				(width 0.1524)
				(type default)
			)
			(layer "F.SilkS")
		)
		(fp_rect
			(start -0.508 0.9398)
			(end 0.508 -0.9398)
			(stroke
				(width 0)
				(type default)
			)
			(fill no)
			(layer "F.CrtYd")
		)
		(fp_rect
			(start -0.508 0.9398)
			(end 0.508 -0.9398)
			(stroke
				(width 0)
				(type default)
			)
			(fill no)
			(layer "F.Fab")
		)
		(pad "1" smd custom
			(at 0 -0.4445 270)
			(size 0.1397 0.1397)
			(layers "F.Cu" "F.Mask" "F.Paste")
			(net "MAX6654_ADD0")
			(options
				(clearance outline)
				(anchor circle)
			)
			(primitives
				(gr_poly
					(pts
						(arc
							(start -0.1778 -0.2794)
							(mid -0.249642 -0.249642)
							(end -0.2794 -0.1778)
						)
						(arc
							(start -0.2794 0.1778)
							(mid -0.249642 0.249642)
							(end -0.1778 0.2794)
						)
						(arc
							(start 0.1778 0.2794)
							(mid 0.249642 0.249642)
							(end 0.2794 0.1778)
						)
						(arc
							(start 0.2794 -0.1778)
							(mid 0.249642 -0.249642)
							(end 0.1778 -0.2794)
						)
					)
					(width 0)
					(fill yes)
				)
			)
		)
		(pad "2" smd custom
			(at 0 0.4445 270)
			(size 0.1397 0.1397)
			(layers "F.Cu" "F.Mask" "F.Paste")
			(net "GND")
			(options
				(clearance outline)
				(anchor circle)
			)
			(primitives
				(gr_poly
					(pts
						(arc
							(start -0.1778 -0.2794)
							(mid -0.249642 -0.249642)
							(end -0.2794 -0.1778)
						)
						(arc
							(start -0.2794 0.1778)
							(mid -0.249642 0.249642)
							(end -0.1778 0.2794)
						)
						(arc
							(start 0.1778 0.2794)
							(mid 0.249642 0.249642)
							(end 0.2794 0.1778)
						)
						(arc
							(start 0.2794 -0.1778)
							(mid 0.249642 -0.249642)
							(end 0.1778 -0.2794)
						)
					)
					(width 0)
					(fill yes)
				)
			)
		)
	)
	(footprint ""
		(layer "F.Cu")
		(at 44.3738 -190.2206 90)
		(property "Reference" "C690"
			(at 0 0 90)
			(layer "F.SilkS")
			(hide yes)
			(effects
				(font
					(size 1.27 1.27)
				)
			)
		)
		(property "Value" "SC220P50V3JN-GP"
			(at 0 -2.8194 90)
			(unlocked yes)
			(layer "F.Fab")
			(hide yes)
			(effects
				(font
					(size 1.016 1.016)
					(thickness 0.1524)
				)
			)
		)
		(property "Device Type" "C603H36"
			(at 0 -4.3434 90)
			(unlocked yes)
			(layer "F.Fab")
			(hide yes)
			(effects
				(font
					(size 1.016 1.016)
					(thickness 0.1524)
				)
			)
		)
		(duplicate_pad_numbers_are_jumpers no)
		(fp_line
			(start 0.508 0)
			(end -0.508 0)
			(stroke
				(width 0.2032)
				(type default)
			)
			(layer "F.SilkS")
		)
		(fp_rect
			(start -0.5842 1.3335)
			(end 0.5842 -1.3335)
			(stroke
				(width 0)
				(type default)
			)
			(fill no)
			(layer "F.CrtYd")
		)
		(fp_rect
			(start -0.5842 1.3335)
			(end 0.5842 -1.3335)
			(stroke
				(width 0)
				(type default)
			)
			(fill no)
			(layer "F.Fab")
		)
		(pad "1" smd custom
			(at 0 -0.762 90)
			(size 0.2159 0.2159)
			(layers "F.Cu" "F.Mask" "F.Paste")
			(net "BUF_I2C9_CLKBUF2_SCL_R")
			(options
				(clearance outline)
				(anchor circle)
			)
			(primitives
				(gr_poly
					(pts
						(arc
							(start -0.3302 -0.4318)
							(mid -0.402042 -0.402042)
							(end -0.4318 -0.3302)
						)
						(arc
							(start -0.4318 0.3302)
							(mid -0.402042 0.402042)
							(end -0.3302 0.4318)
						)
						(arc
							(start 0.3302 0.4318)
							(mid 0.402042 0.402042)
							(end 0.4318 0.3302)
						)
						(arc
							(start 0.4318 -0.3302)
							(mid 0.402042 -0.402042)
							(end 0.3302 -0.4318)
						)
					)
					(width 0)
					(fill yes)
				)
			)
		)
		(pad "2" smd custom
			(at 0 0.762 90)
			(size 0.2159 0.2159)
			(layers "F.Cu" "F.Mask" "F.Paste")
			(net "GND")
			(options
				(clearance outline)
				(anchor circle)
			)
			(primitives
				(gr_poly
					(pts
						(arc
							(start -0.3302 -0.4318)
							(mid -0.402042 -0.402042)
							(end -0.4318 -0.3302)
						)
						(arc
							(start -0.4318 0.3302)
							(mid -0.402042 0.402042)
							(end -0.3302 0.4318)
						)
						(arc
							(start 0.3302 0.4318)
							(mid 0.402042 0.402042)
							(end 0.4318 0.3302)
						)
						(arc
							(start 0.4318 -0.3302)
							(mid 0.402042 -0.402042)
							(end 0.3302 -0.4318)
						)
					)
					(width 0)
					(fill yes)
				)
			)
		)
	)
	(footprint ""
		(layer "F.Cu")
		(at 17.9324 -52.0192 -90)
		(property "Reference" "D16"
			(at 0 0 270)
			(layer "F.SilkS")
			(hide yes)
			(effects
				(font
					(size 1.27 1.27)
				)
			)
		)
		(property "Value" "PGB1010603MR-GP"
			(at -0.0254 -2.8956 270)
			(unlocked yes)
			(layer "F.Fab")
			(hide yes)
			(effects
				(font
					(size 1.016 1.016)
					(thickness 0.1524)
				)
			)
		)
		(property "Device Type" "L1608-UH15"
			(at -0.0254 -4.4196 270)
			(unlocked yes)
			(layer "F.Fab")
			(hide yes)
			(effects
				(font
					(size 1.016 1.016)
					(thickness 0.1524)
				)
			)
		)
		(duplicate_pad_numbers_are_jumpers no)
		(fp_line
			(start 0.254 0)
			(end -0.254 0)
			(stroke
				(width 0.2032)
				(type default)
			)
			(layer "F.SilkS")
		)
		(fp_rect
			(start -0.5842 1.3335)
			(end 0.5842 -1.3335)
			(stroke
				(width 0)
				(type default)
			)
			(fill no)
			(layer "F.CrtYd")
		)
		(fp_rect
			(start -0.5842 1.3335)
			(end 0.5842 -1.3335)
			(stroke
				(width 0)
				(type default)
			)
			(fill no)
			(layer "F.Fab")
		)
		(pad "1" smd custom
			(at 0 -0.762 270)
			(size 0.2159 0.2159)
			(layers "F.Cu" "F.Mask" "F.Paste")
			(net "NIC0_MDI0_P2_R")
			(options
				(clearance outline)
				(anchor circle)
			)
			(primitives
				(gr_poly
					(pts
						(arc
							(start -0.3302 -0.4318)
							(mid -0.402042 -0.402042)
							(end -0.4318 -0.3302)
						)
						(arc
							(start -0.4318 0.3302)
							(mid -0.402042 0.402042)
							(end -0.3302 0.4318)
						)
						(arc
							(start 0.3302 0.4318)
							(mid 0.402042 0.402042)
							(end 0.4318 0.3302)
						)
						(arc
							(start 0.4318 -0.3302)
							(mid 0.402042 -0.402042)
							(end 0.3302 -0.4318)
						)
					)
					(width 0)
					(fill yes)
				)
			)
		)
		(pad "2" smd custom
			(at 0 0.762 270)
			(size 0.2159 0.2159)
			(layers "F.Cu" "F.Mask" "F.Paste")
			(net "GND")
			(options
				(clearance outline)
				(anchor circle)
			)
			(primitives
				(gr_poly
					(pts
						(arc
							(start -0.3302 -0.4318)
							(mid -0.402042 -0.402042)
							(end -0.4318 -0.3302)
						)
						(arc
							(start -0.4318 0.3302)
							(mid -0.402042 0.402042)
							(end -0.3302 0.4318)
						)
						(arc
							(start 0.3302 0.4318)
							(mid 0.402042 0.402042)
							(end 0.4318 0.3302)
						)
						(arc
							(start 0.4318 -0.3302)
							(mid 0.402042 -0.402042)
							(end 0.3302 -0.4318)
						)
					)
					(width 0)
					(fill yes)
				)
			)
		)
	)
	(footprint ""
		(layer "F.Cu")
		(at 347.527372 -45.110908)
		(property "Reference" "Q37"
			(at 0 0 0)
			(layer "F.SilkS")
			(hide yes)
			(effects
				(font
					(size 1.27 1.27)
				)
			)
		)
		(property "Value" "2N7002K-1-GP"
			(at 0.127 -8.9662 0)
			(unlocked yes)
			(layer "F.Fab")
			(hide yes)
			(effects
				(font
					(size 1.016 1.016)
					(thickness 0.1524)
				)
			)
		)
		(property "Device Type" "SOT23DGS2D4H44"
			(at 0.127 -10.4902 0)
			(unlocked yes)
			(layer "F.Fab")
			(hide yes)
			(effects
				(font
					(size 1.016 1.016)
					(thickness 0.1524)
				)
			)
		)
		(duplicate_pad_numbers_are_jumpers no)
		(fp_line
			(start -1.651 -1.778)
			(end -1.651 1.778)
			(stroke
				(width 0.1524)
				(type default)
			)
			(layer "F.SilkS")
		)
		(fp_line
			(start -1.651 1.778)
			(end 1.651 1.778)
			(stroke
				(width 0.1524)
				(type default)
			)
			(layer "F.SilkS")
		)
		(fp_line
			(start 1.651 -1.778)
			(end -1.651 -1.778)
			(stroke
				(width 0.1524)
				(type default)
			)
			(layer "F.SilkS")
		)
		(fp_line
			(start 1.651 1.778)
			(end 1.651 -1.778)
			(stroke
				(width 0.1524)
				(type default)
			)
			(layer "F.SilkS")
		)
		(fp_poly
			(pts
				(xy -1.778 1.8796) (xy -1.778 -1.8796) (xy 1.778 -1.8796) (xy 1.778 1.8796)
			)
			(stroke
				(width 0)
				(type default)
			)
			(fill no)
			(layer "F.CrtYd")
		)
		(fp_poly
			(pts
				(xy -1.778 1.8796) (xy -1.778 -1.8796) (xy 1.778 -1.8796) (xy 1.778 1.8796)
			)
			(stroke
				(width 0)
				(type default)
			)
			(fill no)
			(layer "F.Fab")
		)
		(pad "D" smd custom
			(at 0 -0.9525)
			(size 0.1905 0.1905)
			(layers "F.Cu" "F.Mask" "F.Paste")
			(net "PE1_PERST#_R")
			(options
				(clearance outline)
				(anchor circle)
			)
			(primitives
				(gr_poly
					(pts
						(arc
							(start -0.1778 0.5715)
							(mid -0.321484 0.511984)
							(end -0.381 0.3683)
						)
						(arc
							(start -0.381 -0.3683)
							(mid -0.321484 -0.511984)
							(end -0.1778 -0.5715)
						)
						(arc
							(start 0.1778 -0.5715)
							(mid 0.321484 -0.511984)
							(end 0.381 -0.3683)
						)
						(arc
							(start 0.381 0.3683)
							(mid 0.321484 0.511984)
							(end 0.1778 0.5715)
						)
					)
					(width 0)
					(fill yes)
				)
			)
		)
		(pad "G" smd custom
			(at -0.98425 0.9525)
			(size 0.1905 0.1905)
			(layers "F.Cu" "F.Mask" "F.Paste")
			(net "Q37_G")
			(options
				(clearance outline)
				(anchor circle)
			)
			(primitives
				(gr_poly
					(pts
						(arc
							(start -0.1778 0.5715)
							(mid -0.321484 0.511984)
							(end -0.381 0.3683)
						)
						(arc
							(start -0.381 -0.3683)
							(mid -0.321484 -0.511984)
							(end -0.1778 -0.5715)
						)
						(arc
							(start 0.1778 -0.5715)
							(mid 0.321484 -0.511984)
							(end 0.381 -0.3683)
						)
						(arc
							(start 0.381 0.3683)
							(mid 0.321484 0.511984)
							(end 0.1778 0.5715)
						)
					)
					(width 0)
					(fill yes)
				)
			)
		)
		(pad "S" smd custom
			(at 0.98425 0.9525)
			(size 0.1905 0.1905)
			(layers "F.Cu" "F.Mask" "F.Paste")
			(net "PE1_PERST#")
			(options
				(clearance outline)
				(anchor circle)
			)
			(primitives
				(gr_poly
					(pts
						(arc
							(start -0.1778 0.5715)
							(mid -0.321484 0.511984)
							(end -0.381 0.3683)
						)
						(arc
							(start -0.381 -0.3683)
							(mid -0.321484 -0.511984)
							(end -0.1778 -0.5715)
						)
						(arc
							(start 0.1778 -0.5715)
							(mid 0.321484 -0.511984)
							(end 0.381 -0.3683)
						)
						(arc
							(start 0.381 0.3683)
							(mid 0.321484 0.511984)
							(end 0.1778 0.5715)
						)
					)
					(width 0)
					(fill yes)
				)
			)
		)
	)
	(footprint ""
		(layer "F.Cu")
		(at 25.6286 -48.8696 180)
		(property "Reference" "C335"
			(at 0 0 180)
			(layer "F.SilkS")
			(hide yes)
			(effects
				(font
					(size 1.27 1.27)
				)
			)
		)
		(property "Value" "SCD1U16V2KX-3GP"
			(at 1.1811 -2.7051 180)
			(unlocked yes)
			(layer "F.Fab")
			(hide yes)
			(effects
				(font
					(size 1.016 1.016)
					(thickness 0.1524)
				)
			)
		)
		(property "Device Type" "C402H22"
			(at 1.1811 -4.2291 180)
			(unlocked yes)
			(layer "F.Fab")
			(hide yes)
			(effects
				(font
					(size 1.016 1.016)
					(thickness 0.1524)
				)
			)
		)
		(duplicate_pad_numbers_are_jumpers no)
		(fp_rect
			(start -0.4318 0.9525)
			(end 0.4318 -0.9525)
			(stroke
				(width 0)
				(type default)
			)
			(fill no)
			(layer "F.CrtYd")
		)
		(fp_rect
			(start -0.4318 0.9525)
			(end 0.4318 -0.9525)
			(stroke
				(width 0)
				(type default)
			)
			(fill no)
			(layer "F.Fab")
		)
		(pad "1" smd custom
			(at 0 -0.4445 180)
			(size 0.1524 0.1524)
			(layers "F.Cu" "F.Mask" "F.Paste")
			(net "NIC0_CT_POWER")
			(options
				(clearance outline)
				(anchor circle)
			)
			(primitives
				(gr_poly
					(pts
						(arc
							(start 0.3048 -0.2032)
							(mid 0.275042 -0.275042)
							(end 0.2032 -0.3048)
						)
						(arc
							(start -0.2032 -0.3048)
							(mid -0.275042 -0.275042)
							(end -0.3048 -0.2032)
						)
						(arc
							(start -0.3048 0.2032)
							(mid -0.275042 0.275042)
							(end -0.2032 0.3048)
						)
						(arc
							(start 0.2032 0.3048)
							(mid 0.275042 0.275042)
							(end 0.3048 0.2032)
						)
					)
					(width 0)
					(fill yes)
				)
			)
		)
		(pad "2" smd custom
			(at 0 0.4445 180)
			(size 0.1524 0.1524)
			(layers "F.Cu" "F.Mask" "F.Paste")
			(net "GND")
			(options
				(clearance outline)
				(anchor circle)
			)
			(primitives
				(gr_poly
					(pts
						(arc
							(start 0.3048 -0.2032)
							(mid 0.275042 -0.275042)
							(end 0.2032 -0.3048)
						)
						(arc
							(start -0.2032 -0.3048)
							(mid -0.275042 -0.275042)
							(end -0.3048 -0.2032)
						)
						(arc
							(start -0.3048 0.2032)
							(mid -0.275042 0.275042)
							(end -0.2032 0.3048)
						)
						(arc
							(start 0.2032 0.3048)
							(mid 0.275042 0.275042)
							(end 0.3048 0.2032)
						)
					)
					(width 0)
					(fill yes)
				)
			)
		)
	)
	(footprint ""
		(layer "F.Cu")
		(at 12.0142 -180.6956)
		(property "Reference" "C7272"
			(at 0 0 0)
			(layer "F.SilkS")
			(hide yes)
			(effects
				(font
					(size 1.27 1.27)
				)
			)
		)
		(property "Value" "SCD1U16V2KX-3GP"
			(at 1.1811 -2.7051 0)
			(unlocked yes)
			(layer "F.Fab")
			(hide yes)
			(effects
				(font
					(size 1.016 1.016)
					(thickness 0.1524)
				)
			)
		)
		(property "Device Type" "C402H22"
			(at 1.1811 -4.2291 0)
			(unlocked yes)
			(layer "F.Fab")
			(hide yes)
			(effects
				(font
					(size 1.016 1.016)
					(thickness 0.1524)
				)
			)
		)
		(duplicate_pad_numbers_are_jumpers no)
		(fp_rect
			(start -0.4318 0.9525)
			(end 0.4318 -0.9525)
			(stroke
				(width 0)
				(type default)
			)
			(fill no)
			(layer "F.CrtYd")
		)
		(fp_rect
			(start -0.4318 0.9525)
			(end 0.4318 -0.9525)
			(stroke
				(width 0)
				(type default)
			)
			(fill no)
			(layer "F.Fab")
		)
		(pad "1" smd custom
			(at 0 -0.4445)
			(size 0.1524 0.1524)
			(layers "F.Cu" "F.Mask" "F.Paste")
			(net "MB0_CM_VOUT_R")
			(options
				(clearance outline)
				(anchor circle)
			)
			(primitives
				(gr_poly
					(pts
						(arc
							(start 0.3048 -0.2032)
							(mid 0.275042 -0.275042)
							(end 0.2032 -0.3048)
						)
						(arc
							(start -0.2032 -0.3048)
							(mid -0.275042 -0.275042)
							(end -0.3048 -0.2032)
						)
						(arc
							(start -0.3048 0.2032)
							(mid -0.275042 0.275042)
							(end -0.2032 0.3048)
						)
						(arc
							(start 0.2032 0.3048)
							(mid 0.275042 0.275042)
							(end 0.3048 0.2032)
						)
					)
					(width 0)
					(fill yes)
				)
			)
		)
		(pad "2" smd custom
			(at 0 0.4445)
			(size 0.1524 0.1524)
			(layers "F.Cu" "F.Mask" "F.Paste")
			(net "AGND_CURRENT_MON")
			(options
				(clearance outline)
				(anchor circle)
			)
			(primitives
				(gr_poly
					(pts
						(arc
							(start 0.3048 -0.2032)
							(mid 0.275042 -0.275042)
							(end 0.2032 -0.3048)
						)
						(arc
							(start -0.2032 -0.3048)
							(mid -0.275042 -0.275042)
							(end -0.3048 -0.2032)
						)
						(arc
							(start -0.3048 0.2032)
							(mid -0.275042 0.275042)
							(end -0.2032 0.3048)
						)
						(arc
							(start 0.2032 0.3048)
							(mid 0.275042 0.275042)
							(end 0.3048 0.2032)
						)
					)
					(width 0)
					(fill yes)
				)
			)
		)
	)
	(footprint ""
		(layer "F.Cu")
		(at 38.104826 -130.48488 180)
		(property "Reference" "U40"
			(at 0 0 180)
			(layer "F.SilkS")
			(hide yes)
			(effects
				(font
					(size 1.27 1.27)
				)
			)
		)
		(property "Value" "AST2400A1-GP"
			(at -17.7292 -6.184392 180)
			(unlocked yes)
			(layer "F.Fab")
			(hide yes)
			(effects
				(font
					(size 1.016 1.016)
					(thickness 0.1524)
				)
			)
		)
		(property "Device Type" "BGA408D19H52"
			(at -17.7292 -7.708392 180)
			(unlocked yes)
			(layer "F.Fab")
			(hide yes)
			(effects
				(font
					(size 1.016 1.016)
					(thickness 0.1524)
				)
			)
		)
		(duplicate_pad_numbers_are_jumpers no)
		(fp_line
			(start 9.500108 9.500108)
			(end 9.500108 -9.500108)
			(stroke
				(width 0.1524)
				(type default)
			)
			(layer "F.SilkS")
		)
		(fp_line
			(start 9.500108 -9.500108)
			(end -9.500108 -9.500108)
			(stroke
				(width 0.1524)
				(type default)
			)
			(layer "F.SilkS")
		)
		(fp_line
			(start -9.500108 9.500108)
			(end 9.500108 9.500108)
			(stroke
				(width 0.1524)
				(type default)
			)
			(layer "F.SilkS")
		)
		(fp_line
			(start -9.500108 -9.500108)
			(end -9.500108 9.500108)
			(stroke
				(width 0.1524)
				(type default)
			)
			(layer "F.SilkS")
		)
		(fp_line
			(start -9.830308 -8.230108)
			(end -9.830308 -9.830308)
			(stroke
				(width 0.508)
				(type default)
			)
			(layer "F.SilkS")
		)
		(fp_line
			(start -9.830308 -9.830308)
			(end -8.230108 -9.830308)
			(stroke
				(width 0.508)
				(type default)
			)
			(layer "F.SilkS")
		)
		(fp_rect
			(start -9.500108 9.500108)
			(end 9.500108 -9.500108)
			(stroke
				(width 0)
				(type default)
			)
			(fill no)
			(layer "F.CrtYd")
		)
		(fp_poly
			(pts
				(xy 10.500106 -9.500108) (xy -9.500108 -9.500108) (xy -9.500108 9.500108) (xy 9.500108 9.500108)
				(xy 9.500108 -9.487408) (xy 10.500106 -9.487408) (xy 10.500106 10.500106) (xy -10.500106 10.500106)
				(xy -10.500106 -10.500106) (xy 10.500106 -10.500106)
			)
			(stroke
				(width 0)
				(type default)
			)
			(fill no)
			(layer "F.CrtYd")
		)
		(fp_rect
			(start -11.500104 11.500104)
			(end 11.500104 -11.500104)
			(stroke
				(width 0)
				(type default)
			)
			(fill no)
			(layer "F.Fab")
		)
		(pad "A1" smd circle
			(at -8.400034 -8.400034 180)
			(size 0.4064 0.4064)
			(layers "F.Cu" "F.Mask" "F.Paste")
			(net "BMC0_SDA13_R")
		)
		(pad "A2" smd circle
			(at -7.599934 -8.400034 180)
			(size 0.4064 0.4064)
			(layers "F.Cu" "F.Mask" "F.Paste")
			(net "BMC0_SCL11_R")
		)
		(pad "A3" smd circle
			(at -6.800088 -8.400034 180)
			(size 0.4064 0.4064)
			(layers "F.Cu" "F.Mask" "F.Paste")
			(net "TP_GPIOA6")
		)
		(pad "A4" smd circle
			(at -5.999988 -8.400034 180)
			(size 0.3556 0.3556)
			(layers "F.Cu" "F.Mask" "F.Paste")
			(net "DP_BMC_CPU_RST_N_R")
		)
		(pad "A5" smd circle
			(at -5.199888 -8.400034 180)
			(size 0.3556 0.3556)
			(layers "F.Cu" "F.Mask" "F.Paste")
			(net "Net_192")
		)
		(pad "A6" smd circle
			(at -4.400042 -8.400034 180)
			(size 0.3556 0.3556)
			(layers "F.Cu" "F.Mask" "F.Paste")
			(net "TP_GPIOH6")
		)
		(pad "A7" smd circle
			(at -3.599942 -8.400034 180)
			(size 0.3556 0.3556)
			(layers "F.Cu" "F.Mask" "F.Paste")
			(net "TP_GPIOH3")
		)
		(pad "A8" smd circle
			(at -2.800096 -8.400034 180)
			(size 0.3556 0.3556)
			(layers "F.Cu" "F.Mask" "F.Paste")
			(net "GPIOH0")
		)
		(pad "A9" smd circle
			(at -1.999996 -8.400034 180)
			(size 0.3556 0.3556)
			(layers "F.Cu" "F.Mask" "F.Paste")
			(net "TP_GPIOV4")
		)
		(pad "A10" smd circle
			(at -1.199896 -8.400034 180)
			(size 0.3556 0.3556)
			(layers "F.Cu" "F.Mask" "F.Paste")
			(net "TP_GPIOU0")
		)
		(pad "A11" smd circle
			(at -0.40005 -8.400034 180)
			(size 0.3556 0.3556)
			(layers "F.Cu" "F.Mask" "F.Paste")
			(net "RMII0_BMC_C_CRS_DV")
		)
		(pad "A12" smd circle
			(at 0.40005 -8.400034 180)
			(size 0.3556 0.3556)
			(layers "F.Cu" "F.Mask" "F.Paste")
			(net "RMII0_BMC_C_TX_EN")
		)
		(pad "A13" smd circle
			(at 1.199896 -8.400034 180)
			(size 0.3556 0.3556)
			(layers "F.Cu" "F.Mask" "F.Paste")
			(net "GND")
		)
		(pad "A14" smd circle
			(at 1.999996 -8.400034 180)
			(size 0.3556 0.3556)
			(layers "F.Cu" "F.Mask" "F.Paste")
			(net "HIGH_HEX_0")
		)
		(pad "A15" smd circle
			(at 2.800096 -8.400034 180)
			(size 0.3556 0.3556)
			(layers "F.Cu" "F.Mask" "F.Paste")
			(net "TP_GPIOE3")
		)
		(pad "A16" smd circle
			(at 3.599942 -8.400034 180)
			(size 0.3556 0.3556)
			(layers "F.Cu" "F.Mask" "F.Paste")
			(net "PMC_PLX_BOARD")
		)
		(pad "A17" smd circle
			(at 4.400042 -8.400034 180)
			(size 0.3556 0.3556)
			(layers "F.Cu" "F.Mask" "F.Paste")
			(net "TP_GPIOD3")
		)
		(pad "A18" smd circle
			(at 5.199888 -8.400034 180)
			(size 0.3556 0.3556)
			(layers "F.Cu" "F.Mask" "F.Paste")
			(net "TP_GPIOD0")
		)
		(pad "A19" smd circle
			(at 5.999988 -8.400034 180)
			(size 0.3556 0.3556)
			(layers "F.Cu" "F.Mask" "F.Paste")
			(net "BMC_SSD_RST#12")
		)
		(pad "A20" smd circle
			(at 6.800088 -8.400034 180)
			(size 0.4064 0.4064)
			(layers "F.Cu" "F.Mask" "F.Paste")
			(net "BMC_SSD_RST#9")
		)
		(pad "A21" smd circle
			(at 7.599934 -8.400034 180)
			(size 0.4064 0.4064)
			(layers "F.Cu" "F.Mask" "F.Paste")
			(net "TP_LPC_CPU_FRAME_N")
		)
		(pad "A22" smd circle
			(at 8.400034 -8.400034 180)
			(size 0.4064 0.4064)
			(layers "F.Cu" "F.Mask" "F.Paste")
			(net "TP_BMC0_LPC_LAD1")
		)
		(pad "AA1" smd circle
			(at -8.400034 7.599934 180)
			(size 0.4064 0.4064)
			(layers "F.Cu" "F.Mask" "F.Paste")
			(net "BMC_SSD_RST#5")
		)
		(pad "AA2" smd circle
			(at -7.599934 7.599934 180)
			(size 0.4064 0.4064)
			(layers "F.Cu" "F.Mask" "F.Paste")
			(net "LED_DR_LED1")
		)
		(pad "AA3" smd circle
			(at -6.800088 7.599934 180)
			(size 0.4064 0.4064)
			(layers "F.Cu" "F.Mask" "F.Paste")
			(net "BMC_FW_DET_BOARD_VER_1")
		)
		(pad "AA4" smd circle
			(at -5.999988 7.599934 180)
			(size 0.3556 0.3556)
			(layers "F.Cu" "F.Mask" "F.Paste")
			(net "TP_GPIOO2")
		)
		(pad "AA5" smd circle
			(at -5.199888 7.599934 180)
			(size 0.3556 0.3556)
			(layers "F.Cu" "F.Mask" "F.Paste")
			(net "PEER_BMC_HB")
		)
		(pad "AA6" smd circle
			(at -4.400042 7.599934 180)
			(size 0.3556 0.3556)
			(layers "F.Cu" "F.Mask" "F.Paste")
			(net "BMC_UART_SWITCH_1")
		)
		(pad "AA7" smd circle
			(at -3.599942 7.599934 180)
			(size 0.3556 0.3556)
			(layers "F.Cu" "F.Mask" "F.Paste")
			(net "TP_GPIOP6")
		)
		(pad "AA8" smd circle
			(at -2.800096 7.599934 180)
			(size 0.3556 0.3556)
			(layers "F.Cu" "F.Mask" "F.Paste")
			(net "MEMDQS_P1")
		)
		(pad "AA9" smd circle
			(at -1.999996 7.599934 180)
			(size 0.3556 0.3556)
			(layers "F.Cu" "F.Mask" "F.Paste")
			(net "MEMDQ_10")
		)
		(pad "AA10" smd circle
			(at -1.199896 7.599934 180)
			(size 0.3556 0.3556)
			(layers "F.Cu" "F.Mask" "F.Paste")
			(net "MEMDQS_N0")
		)
		(pad "AA11" smd circle
			(at -0.40005 7.599934 180)
			(size 0.3556 0.3556)
			(layers "F.Cu" "F.Mask" "F.Paste")
			(net "MEMDQ_3")
		)
		(pad "AA12" smd circle
			(at 0.40005 7.599934 180)
			(size 0.3556 0.3556)
			(layers "F.Cu" "F.Mask" "F.Paste")
			(net "MEMCK_N")
		)
		(pad "AA13" smd circle
			(at 1.199896 7.599934 180)
			(size 0.3556 0.3556)
			(layers "F.Cu" "F.Mask" "F.Paste")
			(net "MEMCSN")
		)
		(pad "AA14" smd circle
			(at 1.999996 7.599934 180)
			(size 0.3556 0.3556)
			(layers "F.Cu" "F.Mask" "F.Paste")
			(net "MEMBA_1")
		)
		(pad "AA15" smd circle
			(at 2.800096 7.599934 180)
			(size 0.3556 0.3556)
			(layers "F.Cu" "F.Mask" "F.Paste")
			(net "MEMA_6")
		)
		(pad "AA16" smd circle
			(at 3.599942 7.599934 180)
			(size 0.3556 0.3556)
			(layers "F.Cu" "F.Mask" "F.Paste")
			(net "MEMA_11")
		)
		(pad "AA17" smd circle
			(at 4.400042 7.599934 180)
			(size 0.3556 0.3556)
			(layers "F.Cu" "F.Mask" "F.Paste")
			(net "MEMA_9")
		)
		(pad "AA18" smd circle
			(at 5.199888 7.599934 180)
			(size 0.3556 0.3556)
			(layers "F.Cu" "F.Mask" "F.Paste")
			(net "GND")
		)
		(pad "AA19" smd circle
			(at 5.999988 7.599934 180)
			(size 0.3556 0.3556)
			(layers "F.Cu" "F.Mask" "F.Paste")
			(net "GND")
		)
		(pad "AA20" smd circle
			(at 6.800088 7.599934 180)
			(size 0.4064 0.4064)
			(layers "F.Cu" "F.Mask" "F.Paste")
			(net "PD_USB2VRES")
		)
		(pad "AA21" smd circle
			(at 7.599934 7.599934 180)
			(size 0.4064 0.4064)
			(layers "F.Cu" "F.Mask" "F.Paste")
			(net "PECI0_R")
		)
		(pad "AA22" smd circle
			(at 8.400034 7.599934 180)
			(size 0.4064 0.4064)
			(layers "F.Cu" "F.Mask" "F.Paste")
			(net "DP_RST_N_R")
		)
		(pad "AB1" smd circle
			(at -8.400034 8.400034 180)
			(size 0.4064 0.4064)
			(layers "F.Cu" "F.Mask" "F.Paste")
			(net "BMC0_LED_DR_R_LED0")
		)
		(pad "AB2" smd circle
			(at -7.599934 8.400034 180)
			(size 0.4064 0.4064)
			(layers "F.Cu" "F.Mask" "F.Paste")
			(net "BMC_FW_DET_BOARD_VER_2")
		)
		(pad "AB3" smd circle
			(at -6.800088 8.400034 180)
			(size 0.4064 0.4064)
			(layers "F.Cu" "F.Mask" "F.Paste")
			(net "HB_OUT_BMC")
		)
		(pad "AB4" smd circle
			(at -5.999988 8.400034 180)
			(size 0.3556 0.3556)
			(layers "F.Cu" "F.Mask" "F.Paste")
			(net "TP_GPIOO6")
		)
		(pad "AB5" smd circle
			(at -5.199888 8.400034 180)
			(size 0.3556 0.3556)
			(layers "F.Cu" "F.Mask" "F.Paste")
			(net "TP_GPIOP1")
		)
		(pad "AB6" smd circle
			(at -4.400042 8.400034 180)
			(size 0.3556 0.3556)
			(layers "F.Cu" "F.Mask" "F.Paste")
			(net "TP_GPIOP4")
		)
		(pad "AB7" smd circle
			(at -3.599942 8.400034 180)
			(size 0.3556 0.3556)
			(layers "F.Cu" "F.Mask" "F.Paste")
			(net "BMC_ENCLOSURE_LED")
		)
		(pad "AB8" smd circle
			(at -2.800096 8.400034 180)
			(size 0.3556 0.3556)
			(layers "F.Cu" "F.Mask" "F.Paste")
			(net "MEMDQS_N1")
		)
		(pad "AB9" smd circle
			(at -1.999996 8.400034 180)
			(size 0.3556 0.3556)
			(layers "F.Cu" "F.Mask" "F.Paste")
			(net "MEMDQ_9")
		)
		(pad "AB10" smd circle
			(at -1.199896 8.400034 180)
			(size 0.3556 0.3556)
			(layers "F.Cu" "F.Mask" "F.Paste")
			(net "MEMDQS_P0")
		)
		(pad "AB11" smd circle
			(at -0.40005 8.400034 180)
			(size 0.3556 0.3556)
			(layers "F.Cu" "F.Mask" "F.Paste")
			(net "MEMDQ_2")
		)
		(pad "AB12" smd circle
			(at 0.40005 8.400034 180)
			(size 0.3556 0.3556)
			(layers "F.Cu" "F.Mask" "F.Paste")
			(net "MEMCK_P")
		)
		(pad "AB13" smd circle
			(at 1.199896 8.400034 180)
			(size 0.3556 0.3556)
			(layers "F.Cu" "F.Mask" "F.Paste")
			(net "MEMCASN")
		)
		(pad "AB14" smd circle
			(at 1.999996 8.400034 180)
			(size 0.3556 0.3556)
			(layers "F.Cu" "F.Mask" "F.Paste")
			(net "MEMA_0")
		)
		(pad "AB15" smd circle
			(at 2.800096 8.400034 180)
			(size 0.3556 0.3556)
			(layers "F.Cu" "F.Mask" "F.Paste")
			(net "MEMA_4")
		)
		(pad "AB16" smd circle
			(at 3.599942 8.400034 180)
			(size 0.3556 0.3556)
			(layers "F.Cu" "F.Mask" "F.Paste")
			(net "MEMA_8")
		)
		(pad "AB17" smd circle
			(at 4.400042 8.400034 180)
			(size 0.3556 0.3556)
			(layers "F.Cu" "F.Mask" "F.Paste")
			(net "MEMA_14")
		)
		(pad "AB18" smd circle
			(at 5.199888 8.400034 180)
			(size 0.3556 0.3556)
			(layers "F.Cu" "F.Mask" "F.Paste")
			(net "MEMA_7")
		)
		(pad "AB19" smd circle
			(at 5.999988 8.400034 180)
			(size 0.3556 0.3556)
			(layers "F.Cu" "F.Mask" "F.Paste")
			(net "MPLLAV33")
		)
		(pad "AB20" smd circle
			(at 6.800088 8.400034 180)
			(size 0.4064 0.4064)
			(layers "F.Cu" "F.Mask" "F.Paste")
			(net "BMC_USB2_HDN")
		)
		(pad "AB21" smd circle
			(at 7.599934 8.400034 180)
			(size 0.4064 0.4064)
			(layers "F.Cu" "F.Mask" "F.Paste")
			(net "BMC_USB2_HDP")
		)
		(pad "AB22" smd circle
			(at 8.400034 8.400034 180)
			(size 0.4064 0.4064)
			(layers "F.Cu" "F.Mask" "F.Paste")
			(net "OSC0_AS_CLKIN")
		)
		(pad "B1" smd circle
			(at -8.400034 -7.599934 180)
			(size 0.4064 0.4064)
			(layers "F.Cu" "F.Mask" "F.Paste")
			(net "BMC0_SMB4_CLK")
		)
		(pad "B2" smd circle
			(at -7.599934 -7.599934 180)
			(size 0.4064 0.4064)
			(layers "F.Cu" "F.Mask" "F.Paste")
			(net "BMC0_SCL13_R")
		)
		(pad "B3" smd circle
			(at -6.800088 -7.599934 180)
			(size 0.4064 0.4064)
			(layers "F.Cu" "F.Mask" "F.Paste")
			(net "BMC0_SMB10_DAT")
		)
		(pad "B4" smd circle
			(at -5.999988 -7.599934 180)
			(size 0.3556 0.3556)
			(layers "F.Cu" "F.Mask" "F.Paste")
			(net "BMC0_SMB9_DAT")
		)
		(pad "B5" smd circle
			(at -5.199888 -7.599934 180)
			(size 0.3556 0.3556)
			(layers "F.Cu" "F.Mask" "F.Paste")
			(net "BMC_JTAG_L_EN_R")
		)
		(pad "B6" smd circle
			(at -4.400042 -7.599934 180)
			(size 0.3556 0.3556)
			(layers "F.Cu" "F.Mask" "F.Paste")
			(net "TP_GPIOH5")
		)
		(pad "B7" smd circle
			(at -3.599942 -7.599934 180)
			(size 0.3556 0.3556)
			(layers "F.Cu" "F.Mask" "F.Paste")
			(net "GPIOH2_R")
		)
		(pad "B8" smd circle
			(at -2.800096 -7.599934 180)
			(size 0.3556 0.3556)
			(layers "F.Cu" "F.Mask" "F.Paste")
			(net "TP_RGMIICK")
		)
		(pad "B9" smd circle
			(at -1.999996 -7.599934 180)
			(size 0.3556 0.3556)
			(layers "F.Cu" "F.Mask" "F.Paste")
			(net "TP_GPIOV3")
		)
		(pad "B10" smd circle
			(at -1.199896 -7.599934 180)
			(size 0.3556 0.3556)
			(layers "F.Cu" "F.Mask" "F.Paste")
			(net "TP_GPIOU1")
		)
		(pad "B11" smd circle
			(at -0.40005 -7.599934 180)
			(size 0.3556 0.3556)
			(layers "F.Cu" "F.Mask" "F.Paste")
			(net "RMII_PHY_BMC_RXD1")
		)
		(pad "B12" smd circle
			(at 0.40005 -7.599934 180)
			(size 0.3556 0.3556)
			(layers "F.Cu" "F.Mask" "F.Paste")
			(net "GND")
		)
		(pad "B13" smd circle
			(at 1.199896 -7.599934 180)
			(size 0.3556 0.3556)
			(layers "F.Cu" "F.Mask" "F.Paste")
			(net "FM_TPM_PRES_N_R")
		)
		(pad "B14" smd circle
			(at 1.999996 -7.599934 180)
			(size 0.3556 0.3556)
			(layers "F.Cu" "F.Mask" "F.Paste")
			(net "TP_GPIOE7")
		)
		(pad "B15" smd circle
			(at 2.800096 -7.599934 180)
			(size 0.3556 0.3556)
			(layers "F.Cu" "F.Mask" "F.Paste")
			(net "TP_GPIOE2")
		)
		(pad "B16" smd circle
			(at 3.599942 -7.599934 180)
			(size 0.3556 0.3556)
			(layers "F.Cu" "F.Mask" "F.Paste")
			(net "TP_GPIOD5")
		)
		(pad "B17" smd circle
			(at 4.400042 -7.599934 180)
			(size 0.3556 0.3556)
			(layers "F.Cu" "F.Mask" "F.Paste")
			(net "TP_GPIOD2")
		)
		(pad "B18" smd circle
			(at 5.199888 -7.599934 180)
			(size 0.3556 0.3556)
			(layers "F.Cu" "F.Mask" "F.Paste")
			(net "BMC_SSD_RST#11")
		)
		(pad "B19" smd circle
			(at 5.999988 -7.599934 180)
			(size 0.3556 0.3556)
			(layers "F.Cu" "F.Mask" "F.Paste")
			(net "BMC_SSD_RST#8")
		)
		(pad "B20" smd circle
			(at 6.800088 -7.599934 180)
			(size 0.4064 0.4064)
			(layers "F.Cu" "F.Mask" "F.Paste")
			(net "TP_LPC_CPU_CLKOUT0")
		)
		(pad "B21" smd circle
			(at 7.599934 -7.599934 180)
			(size 0.4064 0.4064)
			(layers "F.Cu" "F.Mask" "F.Paste")
			(net "TP_BMC0_LPC_LAD0")
		)
		(pad "B22" smd circle
			(at 8.400034 -7.599934 180)
			(size 0.4064 0.4064)
			(layers "F.Cu" "F.Mask" "F.Paste")
			(net "SPICS0_N_R")
		)
		(pad "C1" smd circle
			(at -8.400034 -6.800088 180)
			(size 0.4064 0.4064)
			(layers "F.Cu" "F.Mask" "F.Paste")
			(net "BMC0_SMB6_CLK")
		)
		(pad "C2" smd circle
			(at -7.599934 -6.800088 180)
			(size 0.4064 0.4064)
			(layers "F.Cu" "F.Mask" "F.Paste")
			(net "BMC0_SMB3_DAT")
		)
		(pad "C3" smd circle
			(at -6.800088 -6.800088 180)
			(size 0.4064 0.4064)
			(layers "F.Cu" "F.Mask" "F.Paste")
			(net "BMC0_SDA12_R")
		)
		(pad "C4" smd circle
			(at -5.999988 -6.800088 180)
			(size 0.3556 0.3556)
			(layers "F.Cu" "F.Mask" "F.Paste")
			(net "BMC0_SMB10_CLK")
		)
		(pad "C5" smd circle
			(at -5.199888 -6.800088 180)
			(size 0.3556 0.3556)
			(layers "F.Cu" "F.Mask" "F.Paste")
			(net "BMC0_SMB9_CLK")
		)
		(pad "C6" smd circle
			(at -4.400042 -6.800088 180)
			(size 0.3556 0.3556)
			(layers "F.Cu" "F.Mask" "F.Paste")
			(net "Net_191")
		)
		(pad "C7" smd circle
			(at -3.599942 -6.800088 180)
			(size 0.3556 0.3556)
			(layers "F.Cu" "F.Mask" "F.Paste")
			(net "BMC_ID_LED")
		)
		(pad "C8" smd circle
			(at -2.800096 -6.800088 180)
			(size 0.3556 0.3556)
			(layers "F.Cu" "F.Mask" "F.Paste")
			(net "TP_GPIOV7")
		)
		(pad "C9" smd circle
			(at -1.999996 -6.800088 180)
			(size 0.3556 0.3556)
			(layers "F.Cu" "F.Mask" "F.Paste")
			(net "CLK_50M_BMC_NCSI_R")
		)
		(pad "C10" smd circle
			(at -1.199896 -6.800088 180)
			(size 0.3556 0.3556)
			(layers "F.Cu" "F.Mask" "F.Paste")
			(net "TP_GPIOU2")
		)
		(pad "C11" smd circle
			(at -0.40005 -6.800088 180)
			(size 0.3556 0.3556)
			(layers "F.Cu" "F.Mask" "F.Paste")
			(net "RMII_PHY_BMC_RXD0")
		)
		(pad "C12" smd circle
			(at 0.40005 -6.800088 180)
			(size 0.3556 0.3556)
			(layers "F.Cu" "F.Mask" "F.Paste")
			(net "RMII0_BMC_C_PHY_TXD0")
		)
		(pad "C13" smd circle
			(at 1.199896 -6.800088 180)
			(size 0.3556 0.3556)
			(layers "F.Cu" "F.Mask" "F.Paste")
			(net "HIGH_HEX_3")
		)
		(pad "C14" smd circle
			(at 1.999996 -6.800088 180)
			(size 0.3556 0.3556)
			(layers "F.Cu" "F.Mask" "F.Paste")
			(net "TP_GPIOE6")
		)
		(pad "C15" smd circle
			(at 2.800096 -6.800088 180)
			(size 0.3556 0.3556)
			(layers "F.Cu" "F.Mask" "F.Paste")
			(net "TP_GPIOE1")
		)
		(pad "C16" smd circle
			(at 3.599942 -6.800088 180)
			(size 0.3556 0.3556)
			(layers "F.Cu" "F.Mask" "F.Paste")
			(net "TP_GPIOD4")
		)
		(pad "C17" smd circle
			(at 4.400042 -6.800088 180)
			(size 0.3556 0.3556)
			(layers "F.Cu" "F.Mask" "F.Paste")
			(net "BMC_SSD_RST#14")
		)
		(pad "C18" smd circle
			(at 5.199888 -6.800088 180)
			(size 0.3556 0.3556)
			(layers "F.Cu" "F.Mask" "F.Paste")
			(net "SPIDO_R")
		)
		(pad "C19" smd circle
			(at 5.999988 -6.800088 180)
			(size 0.3556 0.3556)
			(layers "F.Cu" "F.Mask" "F.Paste")
			(net "TP_BMC0_LPC_LAD3")
		)
		(pad "C20" smd circle
			(at 6.800088 -6.800088 180)
			(size 0.4064 0.4064)
			(layers "F.Cu" "F.Mask" "F.Paste")
			(net "PWGD_P0V9_E_PG_R")
		)
		(pad "C21" smd circle
			(at 7.599934 -6.800088 180)
			(size 0.4064 0.4064)
			(layers "F.Cu" "F.Mask" "F.Paste")
			(net "SPI_FLASH_SELECT")
		)
		(pad "C22" smd circle
			(at 8.400034 -6.800088 180)
			(size 0.4064 0.4064)
			(layers "F.Cu" "F.Mask" "F.Paste")
			(net "TP_GPIOI0")
		)
		(pad "D1" smd circle
			(at -8.400034 -5.999988 180)
			(size 0.3556 0.3556)
			(layers "F.Cu" "F.Mask" "F.Paste")
			(net "BMC0_SMB7_DAT")
		)
		(pad "D2" smd circle
			(at -7.599934 -5.999988 180)
			(size 0.3556 0.3556)
			(layers "F.Cu" "F.Mask" "F.Paste")
			(net "BMC0_SMB5_DAT")
		)
		(pad "D3" smd circle
			(at -6.800088 -5.999988 180)
			(size 0.3556 0.3556)
			(layers "F.Cu" "F.Mask" "F.Paste")
			(net "BMC0_SMB3_CLK")
		)
		(pad "D4" smd circle
			(at -5.999988 -5.999988 180)
			(size 0.3556 0.3556)
			(layers "F.Cu" "F.Mask" "F.Paste")
			(net "BMC0_SCL12_R")
		)
		(pad "D5" smd circle
			(at -5.199888 -5.999988 180)
			(size 0.3556 0.3556)
			(layers "F.Cu" "F.Mask" "F.Paste")
			(net "TP_GPIOA7")
		)
		(pad "D6" smd circle
			(at -4.400042 -5.999988 180)
			(size 0.3556 0.3556)
			(layers "F.Cu" "F.Mask" "F.Paste")
			(net "PEER_TRAY_BMC")
		)
		(pad "D7" smd circle
			(at -3.599942 -5.999988 180)
			(size 0.3556 0.3556)
			(layers "F.Cu" "F.Mask" "F.Paste")
			(net "TP_GPIOH4")
		)
		(pad "D8" smd circle
			(at -2.800096 -5.999988 180)
			(size 0.3556 0.3556)
			(layers "F.Cu" "F.Mask" "F.Paste")
			(net "TP_GPIOV6")
		)
		(pad "D9" smd circle
			(at -1.999996 -5.999988 180)
			(size 0.3556 0.3556)
			(layers "F.Cu" "F.Mask" "F.Paste")
			(net "TP_GPIOT6")
		)
		(pad "D10" smd circle
			(at -1.199896 -5.999988 180)
			(size 0.3556 0.3556)
			(layers "F.Cu" "F.Mask" "F.Paste")
			(net "TP_GPIOU3")
		)
		(pad "D11" smd circle
			(at -0.40005 -5.999988 180)
			(size 0.3556 0.3556)
			(layers "F.Cu" "F.Mask" "F.Paste")
			(net "RMII0_PHY_BMC_RXCTL0")
		)
		(pad "D12" smd circle
			(at 0.40005 -5.999988 180)
			(size 0.3556 0.3556)
			(layers "F.Cu" "F.Mask" "F.Paste")
			(net "RMII0_BMC_C_PHY_TXD1")
		)
		(pad "D13" smd circle
			(at 1.199896 -5.999988 180)
			(size 0.3556 0.3556)
			(layers "F.Cu" "F.Mask" "F.Paste")
			(net "HIGH_HEX_2")
		)
		(pad "D14" smd circle
			(at 1.999996 -5.999988 180)
			(size 0.3556 0.3556)
			(layers "F.Cu" "F.Mask" "F.Paste")
			(net "BMC_ADD2_R")
		)
		(pad "D15" smd circle
			(at 2.800096 -5.999988 180)
			(size 0.3556 0.3556)
			(layers "F.Cu" "F.Mask" "F.Paste")
			(net "FLA1_WPN_R")
		)
		(pad "D16" smd circle
			(at 3.599942 -5.999988 180)
			(size 0.3556 0.3556)
			(layers "F.Cu" "F.Mask" "F.Paste")
			(net "TP_GPIOD1")
		)
		(pad "D17" smd circle
			(at 4.400042 -5.999988 180)
			(size 0.3556 0.3556)
			(layers "F.Cu" "F.Mask" "F.Paste")
			(net "BMC_SSD_RST#10")
		)
		(pad "D18" smd circle
			(at 5.199888 -5.999988 180)
			(size 0.3556 0.3556)
			(layers "F.Cu" "F.Mask" "F.Paste")
			(net "BMC_SSD_RST#7")
		)
		(pad "D19" smd circle
			(at 5.999988 -5.999988 180)
			(size 0.3556 0.3556)
			(layers "F.Cu" "F.Mask" "F.Paste")
			(net "TP_GPIOI2")
		)
		(pad "D20" smd circle
			(at 6.800088 -5.999988 180)
			(size 0.3556 0.3556)
			(layers "F.Cu" "F.Mask" "F.Paste")
			(net "BMC_PEREXT")
		)
		(pad "D21" smd circle
			(at 7.599934 -5.999988 180)
			(size 0.3556 0.3556)
			(layers "F.Cu" "F.Mask" "F.Paste")
			(net "GND")
		)
		(pad "D22" smd circle
			(at 8.400034 -5.999988 180)
			(size 0.3556 0.3556)
			(layers "F.Cu" "F.Mask" "F.Paste")
			(net "GND")
		)
		(pad "E1" smd circle
			(at -8.400034 -5.199888 180)
			(size 0.3556 0.3556)
			(layers "F.Cu" "F.Mask" "F.Paste")
			(net "JTAG_BMC_TRST_N")
		)
		(pad "E2" smd circle
			(at -7.599934 -5.199888 180)
			(size 0.3556 0.3556)
			(layers "F.Cu" "F.Mask" "F.Paste")
			(net "BMC0_SMB7_CLK")
		)
		(pad "E3" smd circle
			(at -6.800088 -5.199888 180)
			(size 0.3556 0.3556)
			(layers "F.Cu" "F.Mask" "F.Paste")
			(net "BMC0_SMB5_CLK")
		)
		(pad "E4" smd circle
			(at -5.999988 -5.199888 180)
			(size 0.3556 0.3556)
			(layers "F.Cu" "F.Mask" "F.Paste")
			(net "BMC0_ENTEST1")
		)
		(pad "E5" smd circle
			(at -5.199888 -5.199888 180)
			(size 0.3556 0.3556)
			(layers "F.Cu" "F.Mask" "F.Paste")
			(net "BMC0_SDA11_R")
		)
		(pad "E6" smd circle
			(at -4.400042 -5.199888 180)
			(size 0.3556 0.3556)
			(layers "F.Cu" "F.Mask" "F.Paste")
			(net "TP_GPIOA3")
		)
		(pad "E7" smd circle
			(at -3.599942 -5.199888 180)
			(size 0.3556 0.3556)
			(layers "F.Cu" "F.Mask" "F.Paste")
			(net "TP_GPIOH7")
		)
		(pad "E8" smd circle
			(at -2.800096 -5.199888 180)
			(size 0.3556 0.3556)
			(layers "F.Cu" "F.Mask" "F.Paste")
			(net "TP_GPIOV5")
		)
		(pad "E9" smd circle
			(at -1.999996 -5.199888 180)
			(size 0.3556 0.3556)
			(layers "F.Cu" "F.Mask" "F.Paste")
			(net "TP_GPIOT7")
		)
		(pad "E10" smd circle
			(at -1.199896 -5.199888 180)
			(size 0.3556 0.3556)
			(layers "F.Cu" "F.Mask" "F.Paste")
			(net "RMII_BMC_RX_ER")
		)
		(pad "E11" smd circle
			(at -0.40005 -5.199888 180)
			(size 0.3556 0.3556)
			(layers "F.Cu" "F.Mask" "F.Paste")
			(net "BMC_RXCK_R")
		)
		(pad "E12" smd circle
			(at 0.40005 -5.199888 180)
			(size 0.3556 0.3556)
			(layers "F.Cu" "F.Mask" "F.Paste")
			(net "GND")
		)
		(pad "E13" smd circle
			(at 1.199896 -5.199888 180)
			(size 0.3556 0.3556)
			(layers "F.Cu" "F.Mask" "F.Paste")
			(net "HIGH_HEX_1")
		)
		(pad "E14" smd circle
			(at 1.999996 -5.199888 180)
			(size 0.3556 0.3556)
			(layers "F.Cu" "F.Mask" "F.Paste")
			(net "BMC_ADD1_R")
		)
		(pad "E15" smd circle
			(at 2.800096 -5.199888 180)
			(size 0.3556 0.3556)
			(layers "F.Cu" "F.Mask" "F.Paste")
			(net "TP_GPIOD7")
		)
		(pad "E16" smd circle
			(at 3.599942 -5.199888 180)
			(size 0.3556 0.3556)
			(layers "F.Cu" "F.Mask" "F.Paste")
			(net "BMC_SSD_RST#13")
		)
		(pad "E17" smd circle
			(at 4.400042 -5.199888 180)
			(size 0.3556 0.3556)
			(layers "F.Cu" "F.Mask" "F.Paste")
			(net "TP_IRQ_CPU_SERIAL")
		)
		(pad "E18" smd circle
			(at 5.199888 -5.199888 180)
			(size 0.3556 0.3556)
			(layers "F.Cu" "F.Mask" "F.Paste")
			(net "RST_BMC_EXTRST_N_R")
		)
		(pad "E19" smd circle
			(at 5.999988 -5.199888 180)
			(size 0.3556 0.3556)
			(layers "F.Cu" "F.Mask" "F.Paste")
			(net "FM_PCH_LAN1_DISABLE_N_R")
		)
		(pad "E20" smd circle
			(at 6.800088 -5.199888 180)
			(size 0.3556 0.3556)
			(layers "F.Cu" "F.Mask" "F.Paste")
			(net "SPIDI_R")
		)
		(pad "E21" smd circle
			(at 7.599934 -5.199888 180)
			(size 0.3556 0.3556)
			(layers "F.Cu" "F.Mask" "F.Paste")
			(net "BMC_PETXN")
		)
		(pad "E22" smd circle
			(at 8.400034 -5.199888 180)
			(size 0.3556 0.3556)
			(layers "F.Cu" "F.Mask" "F.Paste")
			(net "BMC_PETXP")
		)
		(pad "F1" smd circle
			(at -8.400034 -4.400042 180)
			(size 0.3556 0.3556)
			(layers "F.Cu" "F.Mask" "F.Paste")
			(net "JTAG_BMC_TDI")
		)
		(pad "F2" smd circle
			(at -7.599934 -4.400042 180)
			(size 0.3556 0.3556)
			(layers "F.Cu" "F.Mask" "F.Paste")
			(net "JTAG_BMC_TCK")
		)
		(pad "F3" smd circle
			(at -6.800088 -4.400042 180)
			(size 0.3556 0.3556)
			(layers "F.Cu" "F.Mask" "F.Paste")
			(net "BMC0_SMB8_DAT")
		)
		(pad "F4" smd circle
			(at -5.999988 -4.400042 180)
			(size 0.3556 0.3556)
			(layers "F.Cu" "F.Mask" "F.Paste")
			(net "BMC0_SMB6_DAT")
		)
		(pad "F5" smd circle
			(at -5.199888 -4.400042 180)
			(size 0.3556 0.3556)
			(layers "F.Cu" "F.Mask" "F.Paste")
			(net "BMC0_SMB4_DAT")
		)
		(pad "F8" smd circle
			(at -2.800096 -4.400042 180)
			(size 0.3556 0.3556)
			(layers "F.Cu" "F.Mask" "F.Paste")
			(net "P3V3_STBY")
		)
		(pad "F9" smd circle
			(at -1.999996 -4.400042 180)
			(size 0.3556 0.3556)
			(layers "F.Cu" "F.Mask" "F.Paste")
			(net "P3V3_STBY")
		)
		(pad "F10" smd circle
			(at -1.199896 -4.400042 180)
			(size 0.3556 0.3556)
			(layers "F.Cu" "F.Mask" "F.Paste")
			(net "P3V3_STBY")
		)
		(pad "F11" smd circle
			(at -0.40005 -4.400042 180)
			(size 0.3556 0.3556)
			(layers "F.Cu" "F.Mask" "F.Paste")
			(net "P3V3_STBY")
		)
		(pad "F12" smd circle
			(at 0.40005 -4.400042 180)
			(size 0.3556 0.3556)
			(layers "F.Cu" "F.Mask" "F.Paste")
			(net "P3V3_STBY")
		)
		(pad "F13" smd circle
			(at 1.199896 -4.400042 180)
			(size 0.3556 0.3556)
			(layers "F.Cu" "F.Mask" "F.Paste")
			(net "P3V3_STBY")
		)
		(pad "F14" smd circle
			(at 1.999996 -4.400042 180)
			(size 0.3556 0.3556)
			(layers "F.Cu" "F.Mask" "F.Paste")
			(net "P1V26_STBY")
		)
		(pad "F15" smd circle
			(at 2.800096 -4.400042 180)
			(size 0.3556 0.3556)
			(layers "F.Cu" "F.Mask" "F.Paste")
			(net "P1V26_STBY")
		)
		(pad "F18" smd circle
			(at 5.199888 -4.400042 180)
			(size 0.3556 0.3556)
			(layers "F.Cu" "F.Mask" "F.Paste")
			(net "LAN_SMB_ALERT_N_R")
		)
		(pad "F19" smd circle
			(at 5.999988 -4.400042 180)
			(size 0.3556 0.3556)
			(layers "F.Cu" "F.Mask" "F.Paste")
			(net "TP_BMC0_LPC_LAD2")
		)
		(pad "F20" smd circle
			(at 6.800088 -4.400042 180)
			(size 0.3556 0.3556)
			(layers "F.Cu" "F.Mask" "F.Paste")
			(net "FCB_HW_REVISION")
		)
		(pad "F21" smd circle
			(at 7.599934 -4.400042 180)
			(size 0.3556 0.3556)
			(layers "F.Cu" "F.Mask" "F.Paste")
			(net "PCIE_TX_P76")
		)
		(pad "F22" smd circle
			(at 8.400034 -4.400042 180)
			(size 0.3556 0.3556)
			(layers "F.Cu" "F.Mask" "F.Paste")
			(net "PCIE_TX_N76")
		)
		(pad "G1" smd circle
			(at -8.400034 -3.599942 180)
			(size 0.3556 0.3556)
			(layers "F.Cu" "F.Mask" "F.Paste")
			(net "BMC_RXD5_R")
		)
		(pad "G2" smd circle
			(at -7.599934 -3.599942 180)
			(size 0.3556 0.3556)
			(layers "F.Cu" "F.Mask" "F.Paste")
			(net "JTAG_BMC_TMS")
		)
		(pad "G3" smd circle
			(at -6.800088 -3.599942 180)
			(size 0.3556 0.3556)
			(layers "F.Cu" "F.Mask" "F.Paste")
			(net "JTAG_BMC_TDO")
		)
		(pad "G4" smd circle
			(at -5.999988 -3.599942 180)
			(size 0.3556 0.3556)
			(layers "F.Cu" "F.Mask" "F.Paste")
			(net "BMC0_JTAG_RTCK")
		)
		(pad "G5" smd circle
			(at -5.199888 -3.599942 180)
			(size 0.3556 0.3556)
			(layers "F.Cu" "F.Mask" "F.Paste")
			(net "BMC0_SMB8_CLK")
		)
		(pad "G18" smd circle
			(at 5.199888 -3.599942 180)
			(size 0.3556 0.3556)
			(layers "F.Cu" "F.Mask" "F.Paste")
			(net "TP_GPIOI1")
		)
		(pad "G19" smd circle
			(at 5.999988 -3.599942 180)
			(size 0.3556 0.3556)
			(layers "F.Cu" "F.Mask" "F.Paste")
			(net "SPICK_R")
		)
		(pad "G20" smd circle
			(at 6.800088 -3.599942 180)
			(size 0.3556 0.3556)
			(layers "F.Cu" "F.Mask" "F.Paste")
			(net "DPB_HW_REVISION")
		)
		(pad "G21" smd circle
			(at 7.599934 -3.599942 180)
			(size 0.3556 0.3556)
			(layers "F.Cu" "F.Mask" "F.Paste")
			(net "BMC_REFCLK_N")
		)
		(pad "G22" smd circle
			(at 8.400034 -3.599942 180)
			(size 0.3556 0.3556)
			(layers "F.Cu" "F.Mask" "F.Paste")
			(net "BMC_REFCLK_P")
		)
		(pad "H1" smd circle
			(at -8.400034 -2.800096 180)
			(size 0.3556 0.3556)
			(layers "F.Cu" "F.Mask" "F.Paste")
			(net "TCA9554_INT_N_R")
		)
		(pad "H2" smd circle
			(at -7.599934 -2.800096 180)
			(size 0.3556 0.3556)
			(layers "F.Cu" "F.Mask" "F.Paste")
			(net "I2C_MUX_RESET_PEB_R")
		)
		(pad "H3" smd circle
			(at -6.800088 -2.800096 180)
			(size 0.3556 0.3556)
			(layers "F.Cu" "F.Mask" "F.Paste")
			(net "BMC0_SMB14_SDA")
		)
		(pad "H4" smd circle
			(at -5.999988 -2.800096 180)
			(size 0.3556 0.3556)
			(layers "F.Cu" "F.Mask" "F.Paste")
			(net "BMC0_SMB14_CLK")
		)
		(pad "H5" smd circle
			(at -5.199888 -2.800096 180)
			(size 0.3556 0.3556)
			(layers "F.Cu" "F.Mask" "F.Paste")
			(net "BMC_TXD5_R")
		)
		(pad "H6" smd circle
			(at -4.400042 -2.800096 180)
			(size 0.3556 0.3556)
			(layers "F.Cu" "F.Mask" "F.Paste")
			(net "P3V3_STBY")
		)
		(pad "H17" smd circle
			(at 4.400042 -2.800096 180)
			(size 0.3556 0.3556)
			(layers "F.Cu" "F.Mask" "F.Paste")
			(net "P3V3_STBY")
		)
		(pad "H18" smd circle
			(at 5.199888 -2.800096 180)
			(size 0.3556 0.3556)
			(layers "F.Cu" "F.Mask" "F.Paste")
			(net "TP_GPIOB2")
		)
		(pad "H19" smd circle
			(at 5.999988 -2.800096 180)
			(size 0.3556 0.3556)
			(layers "F.Cu" "F.Mask" "F.Paste")
			(net "TP_GPIOB5")
		)
		(pad "H20" smd circle
			(at 6.800088 -2.800096 180)
			(size 0.3556 0.3556)
			(layers "F.Cu" "F.Mask" "F.Paste")
			(net "TP_GPIOB6")
		)
		(pad "H21" smd circle
			(at 7.599934 -2.800096 180)
			(size 0.3556 0.3556)
			(layers "F.Cu" "F.Mask" "F.Paste")
			(net "Net_2083")
		)
		(pad "H22" smd circle
			(at 8.400034 -2.800096 180)
			(size 0.3556 0.3556)
			(layers "F.Cu" "F.Mask" "F.Paste")
			(net "Net_2082")
		)
		(pad "J1" smd circle
			(at -8.400034 -1.999996 180)
			(size 0.3556 0.3556)
			(layers "F.Cu" "F.Mask" "F.Paste")
			(net "BMC_USB1_HDP")
		)
		(pad "J2" smd circle
			(at -7.599934 -1.999996 180)
			(size 0.3556 0.3556)
			(layers "F.Cu" "F.Mask" "F.Paste")
			(net "BMC_USB1_HDN")
		)
		(pad "J3" smd circle
			(at -6.800088 -1.999996 180)
			(size 0.3556 0.3556)
			(layers "F.Cu" "F.Mask" "F.Paste")
			(net "LOW_HEX_3")
		)
		(pad "J4" smd circle
			(at -5.999988 -1.999996 180)
			(size 0.3556 0.3556)
			(layers "F.Cu" "F.Mask" "F.Paste")
			(net "LOW_HEX_1")
		)
		(pad "J5" smd circle
			(at -5.199888 -1.999996 180)
			(size 0.3556 0.3556)
			(layers "F.Cu" "F.Mask" "F.Paste")
			(net "LOW_HEX_0")
		)
		(pad "J6" smd circle
			(at -4.400042 -1.999996 180)
			(size 0.3556 0.3556)
			(layers "F.Cu" "F.Mask" "F.Paste")
			(net "P3V3_STBY")
		)
		(pad "J9" smd circle
			(at -1.999996 -1.999996 180)
			(size 0.3556 0.3556)
			(layers "F.Cu" "F.Mask" "F.Paste")
			(net "GND")
		)
		(pad "J10" smd circle
			(at -1.199896 -1.999996 180)
			(size 0.3556 0.3556)
			(layers "F.Cu" "F.Mask" "F.Paste")
			(net "GND")
		)
		(pad "J11" smd circle
			(at -0.40005 -1.999996 180)
			(size 0.3556 0.3556)
			(layers "F.Cu" "F.Mask" "F.Paste")
			(net "GND")
		)
		(pad "J12" smd circle
			(at 0.40005 -1.999996 180)
			(size 0.3556 0.3556)
			(layers "F.Cu" "F.Mask" "F.Paste")
			(net "GND")
		)
		(pad "J13" smd circle
			(at 1.199896 -1.999996 180)
			(size 0.3556 0.3556)
			(layers "F.Cu" "F.Mask" "F.Paste")
			(net "GND")
		)
		(pad "J14" smd circle
			(at 1.999996 -1.999996 180)
			(size 0.3556 0.3556)
			(layers "F.Cu" "F.Mask" "F.Paste")
			(net "GND")
		)
		(pad "J17" smd circle
			(at 4.400042 -1.999996 180)
			(size 0.3556 0.3556)
			(layers "F.Cu" "F.Mask" "F.Paste")
			(net "P3V3_STBY")
		)
		(pad "J18" smd circle
			(at 5.199888 -1.999996 180)
			(size 0.3556 0.3556)
			(layers "F.Cu" "F.Mask" "F.Paste")
			(net "BMC0_SMB2_DAT")
		)
		(pad "J19" smd circle
			(at 5.999988 -1.999996 180)
			(size 0.3556 0.3556)
			(layers "F.Cu" "F.Mask" "F.Paste")
			(net "BMC0_SMB2_CLK")
		)
		(pad "J20" smd circle
			(at 6.800088 -1.999996 180)
			(size 0.3556 0.3556)
			(layers "F.Cu" "F.Mask" "F.Paste")
			(net "GPIOB1")
		)
		(pad "J21" smd circle
			(at 7.599934 -1.999996 180)
			(size 0.3556 0.3556)
			(layers "F.Cu" "F.Mask" "F.Paste")
			(net "PE1_PERST#_BMC")
		)
		(pad "J22" smd circle
			(at 8.400034 -1.999996 180)
			(size 0.3556 0.3556)
			(layers "F.Cu" "F.Mask" "F.Paste")
			(net "PEWAKE#")
		)
		(pad "K1" smd circle
			(at -8.400034 -1.199896 180)
			(size 0.3556 0.3556)
			(layers "F.Cu" "F.Mask" "F.Paste")
			(net "ADCVREFFP")
		)
		(pad "K2" smd circle
			(at -7.599934 -1.199896 180)
			(size 0.3556 0.3556)
			(layers "F.Cu" "F.Mask" "F.Paste")
			(net "ADCVREFFN")
		)
		(pad "K3" smd circle
			(at -6.800088 -1.199896 180)
			(size 0.3556 0.3556)
			(layers "F.Cu" "F.Mask" "F.Paste")
			(net "BMC_USB1_HDN2")
		)
		(pad "K4" smd circle
			(at -5.999988 -1.199896 180)
			(size 0.3556 0.3556)
			(layers "F.Cu" "F.Mask" "F.Paste")
			(net "BMC_USB1_HDP2")
		)
		(pad "K5" smd circle
			(at -5.199888 -1.199896 180)
			(size 0.3556 0.3556)
			(layers "F.Cu" "F.Mask" "F.Paste")
			(net "LOW_HEX_2")
		)
		(pad "K6" smd circle
			(at -4.400042 -1.199896 180)
			(size 0.3556 0.3556)
			(layers "F.Cu" "F.Mask" "F.Paste")
			(net "P1V26_STBY")
		)
		(pad "K9" smd circle
			(at -1.999996 -1.199896 180)
			(size 0.3556 0.3556)
			(layers "F.Cu" "F.Mask" "F.Paste")
			(net "GND")
		)
		(pad "K10" smd circle
			(at -1.199896 -1.199896 180)
			(size 0.3556 0.3556)
			(layers "F.Cu" "F.Mask" "F.Paste")
			(net "GND")
		)
		(pad "K11" smd circle
			(at -0.40005 -1.199896 180)
			(size 0.3556 0.3556)
			(layers "F.Cu" "F.Mask" "F.Paste")
			(net "GND")
		)
		(pad "K12" smd circle
			(at 0.40005 -1.199896 180)
			(size 0.3556 0.3556)
			(layers "F.Cu" "F.Mask" "F.Paste")
			(net "GND")
		)
		(pad "K13" smd circle
			(at 1.199896 -1.199896 180)
			(size 0.3556 0.3556)
			(layers "F.Cu" "F.Mask" "F.Paste")
			(net "GND")
		)
		(pad "K14" smd circle
			(at 1.999996 -1.199896 180)
			(size 0.3556 0.3556)
			(layers "F.Cu" "F.Mask" "F.Paste")
			(net "GND")
		)
		(pad "K17" smd circle
			(at 4.400042 -1.199896 180)
			(size 0.3556 0.3556)
			(layers "F.Cu" "F.Mask" "F.Paste")
			(net "P1V26_STBY")
		)
		(pad "K18" smd circle
			(at 5.199888 -1.199896 180)
			(size 0.3556 0.3556)
			(layers "F.Cu" "F.Mask" "F.Paste")
			(net "ROMA23")
		)
		(pad "K19" smd circle
			(at 5.999988 -1.199896 180)
			(size 0.3556 0.3556)
			(layers "F.Cu" "F.Mask" "F.Paste")
			(net "BMC_PERST#_R")
		)
		(pad "K20" smd circle
			(at 6.800088 -1.199896 180)
			(size 0.3556 0.3556)
			(layers "F.Cu" "F.Mask" "F.Paste")
			(net "TP_GPIOY3")
		)
		(pad "K21" smd circle
			(at 7.599934 -1.199896 180)
			(size 0.3556 0.3556)
			(layers "F.Cu" "F.Mask" "F.Paste")
			(net "BMC0_SMB1_CLK")
		)
		(pad "K22" smd circle
			(at 8.400034 -1.199896 180)
			(size 0.3556 0.3556)
			(layers "F.Cu" "F.Mask" "F.Paste")
			(net "BMC0_SMB1_DAT")
		)
		(pad "L1" smd circle
			(at -8.400034 -0.40005 180)
			(size 0.3556 0.3556)
			(layers "F.Cu" "F.Mask" "F.Paste")
			(net "ADC_P1V53_BMC")
		)
		(pad "L2" smd circle
			(at -7.599934 -0.40005 180)
			(size 0.3556 0.3556)
			(layers "F.Cu" "F.Mask" "F.Paste")
			(net "ADC_P1V8_STBY_BMC")
		)
		(pad "L3" smd circle
			(at -6.800088 -0.40005 180)
			(size 0.3556 0.3556)
			(layers "F.Cu" "F.Mask" "F.Paste")
			(net "ADC_P3V3_STBY_BMC")
		)
		(pad "L4" smd circle
			(at -5.999988 -0.40005 180)
			(size 0.3556 0.3556)
			(layers "F.Cu" "F.Mask" "F.Paste")
			(net "ADC_P5V_STBY_BMC")
		)
		(pad "L5" smd circle
			(at -5.199888 -0.40005 180)
			(size 0.3556 0.3556)
			(layers "F.Cu" "F.Mask" "F.Paste")
			(net "ADC0_12V_BMC")
		)
		(pad "L6" smd circle
			(at -4.400042 -0.40005 180)
			(size 0.3556 0.3556)
			(layers "F.Cu" "F.Mask" "F.Paste")
			(net "P1V26_STBY")
		)
		(pad "L9" smd circle
			(at -1.999996 -0.40005 180)
			(size 0.3556 0.3556)
			(layers "F.Cu" "F.Mask" "F.Paste")
			(net "GND")
		)
		(pad "L10" smd circle
			(at -1.199896 -0.40005 180)
			(size 0.3556 0.3556)
			(layers "F.Cu" "F.Mask" "F.Paste")
			(net "GND")
		)
		(pad "L11" smd circle
			(at -0.40005 -0.40005 180)
			(size 0.3556 0.3556)
			(layers "F.Cu" "F.Mask" "F.Paste")
			(net "GND")
		)
		(pad "L12" smd circle
			(at 0.40005 -0.40005 180)
			(size 0.3556 0.3556)
			(layers "F.Cu" "F.Mask" "F.Paste")
			(net "GND")
		)
		(pad "L13" smd circle
			(at 1.199896 -0.40005 180)
			(size 0.3556 0.3556)
			(layers "F.Cu" "F.Mask" "F.Paste")
			(net "GND")
		)
		(pad "L14" smd circle
			(at 1.999996 -0.40005 180)
			(size 0.3556 0.3556)
			(layers "F.Cu" "F.Mask" "F.Paste")
			(net "GND")
		)
		(pad "L17" smd circle
			(at 4.400042 -0.40005 180)
			(size 0.3556 0.3556)
			(layers "F.Cu" "F.Mask" "F.Paste")
			(net "P1V26_STBY")
		)
		(pad "L18" smd circle
			(at 5.199888 -0.40005 180)
			(size 0.3556 0.3556)
			(layers "F.Cu" "F.Mask" "F.Paste")
			(net "ROMA12")
		)
		(pad "L19" smd circle
			(at 5.999988 -0.40005 180)
			(size 0.3556 0.3556)
			(layers "F.Cu" "F.Mask" "F.Paste")
			(net "ROMA13")
		)
		(pad "L20" smd circle
			(at 6.800088 -0.40005 180)
			(size 0.3556 0.3556)
			(layers "F.Cu" "F.Mask" "F.Paste")
			(net "ROMA14")
		)
		(pad "L21" smd circle
			(at 7.599934 -0.40005 180)
			(size 0.3556 0.3556)
			(layers "F.Cu" "F.Mask" "F.Paste")
			(net "ROMA15")
		)
		(pad "L22" smd circle
			(at 8.400034 -0.40005 180)
			(size 0.3556 0.3556)
			(layers "F.Cu" "F.Mask" "F.Paste")
			(net "ROMA22")
		)
		(pad "M1" smd circle
			(at -8.400034 0.40005 180)
			(size 0.3556 0.3556)
			(layers "F.Cu" "F.Mask" "F.Paste")
			(net "GND")
		)
		(pad "M2" smd circle
			(at -7.599934 0.40005 180)
			(size 0.3556 0.3556)
			(layers "F.Cu" "F.Mask" "F.Paste")
			(net "GND")
		)
		(pad "M3" smd circle
			(at -6.800088 0.40005 180)
			(size 0.3556 0.3556)
			(layers "F.Cu" "F.Mask" "F.Paste")
			(net "ADC_P1V26_BMC")
		)
		(pad "M4" smd circle
			(at -5.999988 0.40005 180)
			(size 0.3556 0.3556)
			(layers "F.Cu" "F.Mask" "F.Paste")
			(net "ADC_P0V9_E_BMC")
		)
		(pad "M5" smd circle
			(at -5.199888 0.40005 180)
			(size 0.3556 0.3556)
			(layers "F.Cu" "F.Mask" "F.Paste")
			(net "ADC_P0V9_BMC")
		)
		(pad "M6" smd circle
			(at -4.400042 0.40005 180)
			(size 0.3556 0.3556)
			(layers "F.Cu" "F.Mask" "F.Paste")
			(net "P3V3_STBY")
		)
		(pad "M9" smd circle
			(at -1.999996 0.40005 180)
			(size 0.3556 0.3556)
			(layers "F.Cu" "F.Mask" "F.Paste")
			(net "GND")
		)
		(pad "M10" smd circle
			(at -1.199896 0.40005 180)
			(size 0.3556 0.3556)
			(layers "F.Cu" "F.Mask" "F.Paste")
			(net "GND")
		)
		(pad "M11" smd circle
			(at -0.40005 0.40005 180)
			(size 0.3556 0.3556)
			(layers "F.Cu" "F.Mask" "F.Paste")
			(net "GND")
		)
		(pad "M12" smd circle
			(at 0.40005 0.40005 180)
			(size 0.3556 0.3556)
			(layers "F.Cu" "F.Mask" "F.Paste")
			(net "GND")
		)
		(pad "M13" smd circle
			(at 1.199896 0.40005 180)
			(size 0.3556 0.3556)
			(layers "F.Cu" "F.Mask" "F.Paste")
			(net "GND")
		)
		(pad "M14" smd circle
			(at 1.999996 0.40005 180)
			(size 0.3556 0.3556)
			(layers "F.Cu" "F.Mask" "F.Paste")
			(net "GND")
		)
		(pad "M17" smd circle
			(at 4.400042 0.40005 180)
			(size 0.3556 0.3556)
			(layers "F.Cu" "F.Mask" "F.Paste")
			(net "P3V3_STBY")
		)
		(pad "M18" smd circle
			(at 5.199888 0.40005 180)
			(size 0.3556 0.3556)
			(layers "F.Cu" "F.Mask" "F.Paste")
			(net "ROMA19")
		)
		(pad "M19" smd circle
			(at 5.999988 0.40005 180)
			(size 0.3556 0.3556)
			(layers "F.Cu" "F.Mask" "F.Paste")
			(net "ROMA8")
		)
		(pad "M20" smd circle
			(at 6.800088 0.40005 180)
			(size 0.3556 0.3556)
			(layers "F.Cu" "F.Mask" "F.Paste")
			(net "ROMA9")
		)
		(pad "M21" smd circle
			(at 7.599934 0.40005 180)
			(size 0.3556 0.3556)
			(layers "F.Cu" "F.Mask" "F.Paste")
			(net "ROMA10")
		)
		(pad "M22" smd circle
			(at 8.400034 0.40005 180)
			(size 0.3556 0.3556)
			(layers "F.Cu" "F.Mask" "F.Paste")
			(net "ROMA11")
		)
		(pad "N1" smd circle
			(at -8.400034 1.199896 180)
			(size 0.3556 0.3556)
			(layers "F.Cu" "F.Mask" "F.Paste")
			(net "GND")
		)
		(pad "N2" smd circle
			(at -7.599934 1.199896 180)
			(size 0.3556 0.3556)
			(layers "F.Cu" "F.Mask" "F.Paste")
			(net "GND")
		)
		(pad "N3" smd circle
			(at -6.800088 1.199896 180)
			(size 0.3556 0.3556)
			(layers "F.Cu" "F.Mask" "F.Paste")
			(net "GND")
		)
		(pad "N4" smd circle
			(at -5.999988 1.199896 180)
			(size 0.3556 0.3556)
			(layers "F.Cu" "F.Mask" "F.Paste")
			(net "GND")
		)
		(pad "N5" smd circle
			(at -5.199888 1.199896 180)
			(size 0.3556 0.3556)
			(layers "F.Cu" "F.Mask" "F.Paste")
			(net "GND")
		)
		(pad "N6" smd circle
			(at -4.400042 1.199896 180)
			(size 0.3556 0.3556)
			(layers "F.Cu" "F.Mask" "F.Paste")
			(net "P3V3_STBY")
		)
		(pad "N9" smd circle
			(at -1.999996 1.199896 180)
			(size 0.3556 0.3556)
			(layers "F.Cu" "F.Mask" "F.Paste")
			(net "GND")
		)
		(pad "N10" smd circle
			(at -1.199896 1.199896 180)
			(size 0.3556 0.3556)
			(layers "F.Cu" "F.Mask" "F.Paste")
			(net "GND")
		)
		(pad "N11" smd circle
			(at -0.40005 1.199896 180)
			(size 0.3556 0.3556)
			(layers "F.Cu" "F.Mask" "F.Paste")
			(net "GND")
		)
		(pad "N12" smd circle
			(at 0.40005 1.199896 180)
			(size 0.3556 0.3556)
			(layers "F.Cu" "F.Mask" "F.Paste")
			(net "GND")
		)
		(pad "N13" smd circle
			(at 1.199896 1.199896 180)
			(size 0.3556 0.3556)
			(layers "F.Cu" "F.Mask" "F.Paste")
			(net "GND")
		)
		(pad "N14" smd circle
			(at 1.999996 1.199896 180)
			(size 0.3556 0.3556)
			(layers "F.Cu" "F.Mask" "F.Paste")
			(net "GND")
		)
		(pad "N17" smd circle
			(at 4.400042 1.199896 180)
			(size 0.3556 0.3556)
			(layers "F.Cu" "F.Mask" "F.Paste")
			(net "P3V3_STBY")
		)
		(pad "N18" smd circle
			(at 5.199888 1.199896 180)
			(size 0.3556 0.3556)
			(layers "F.Cu" "F.Mask" "F.Paste")
			(net "ROMA17")
		)
		(pad "N19" smd circle
			(at 5.999988 1.199896 180)
			(size 0.3556 0.3556)
			(layers "F.Cu" "F.Mask" "F.Paste")
			(net "ROMA18")
		)
		(pad "N20" smd circle
			(at 6.800088 1.199896 180)
			(size 0.3556 0.3556)
			(layers "F.Cu" "F.Mask" "F.Paste")
			(net "ROMA21")
		)
		(pad "N21" smd circle
			(at 7.599934 1.199896 180)
			(size 0.3556 0.3556)
			(layers "F.Cu" "F.Mask" "F.Paste")
			(net "GPIOS5_R")
		)
		(pad "N22" smd circle
			(at 8.400034 1.199896 180)
			(size 0.3556 0.3556)
			(layers "F.Cu" "F.Mask" "F.Paste")
			(net "ROMA20")
		)
		(pad "P1" smd circle
			(at -8.400034 1.999996 180)
			(size 0.3556 0.3556)
			(layers "F.Cu" "F.Mask" "F.Paste")
			(net "P3V3_STBY")
		)
		(pad "P2" smd circle
			(at -7.599934 1.999996 180)
			(size 0.3556 0.3556)
			(layers "F.Cu" "F.Mask" "F.Paste")
			(net "ADCVREXT")
		)
		(pad "P3" smd circle
			(at -6.800088 1.999996 180)
			(size 0.3556 0.3556)
			(layers "F.Cu" "F.Mask" "F.Paste")
			(net "ADCAV33")
		)
		(pad "P4" smd circle
			(at -5.999988 1.999996 180)
			(size 0.3556 0.3556)
			(layers "F.Cu" "F.Mask" "F.Paste")
			(net "GND")
		)
		(pad "P5" smd circle
			(at -5.199888 1.999996 180)
			(size 0.3556 0.3556)
			(layers "F.Cu" "F.Mask" "F.Paste")
			(net "GND")
		)
		(pad "P6" smd circle
			(at -4.400042 1.999996 180)
			(size 0.3556 0.3556)
			(layers "F.Cu" "F.Mask" "F.Paste")
			(net "P1V26_STBY")
		)
		(pad "P9" smd circle
			(at -1.999996 1.999996 180)
			(size 0.3556 0.3556)
			(layers "F.Cu" "F.Mask" "F.Paste")
			(net "GND")
		)
		(pad "P10" smd circle
			(at -1.199896 1.999996 180)
			(size 0.3556 0.3556)
			(layers "F.Cu" "F.Mask" "F.Paste")
			(net "GND")
		)
		(pad "P11" smd circle
			(at -0.40005 1.999996 180)
			(size 0.3556 0.3556)
			(layers "F.Cu" "F.Mask" "F.Paste")
			(net "GND")
		)
		(pad "P12" smd circle
			(at 0.40005 1.999996 180)
			(size 0.3556 0.3556)
			(layers "F.Cu" "F.Mask" "F.Paste")
			(net "GND")
		)
		(pad "P13" smd circle
			(at 1.199896 1.999996 180)
			(size 0.3556 0.3556)
			(layers "F.Cu" "F.Mask" "F.Paste")
			(net "GND")
		)
		(pad "P14" smd circle
			(at 1.999996 1.999996 180)
			(size 0.3556 0.3556)
			(layers "F.Cu" "F.Mask" "F.Paste")
			(net "GND")
		)
		(pad "P17" smd circle
			(at 4.400042 1.999996 180)
			(size 0.3556 0.3556)
			(layers "F.Cu" "F.Mask" "F.Paste")
			(net "P1V26_STBY")
		)
		(pad "P18" smd circle
			(at 5.199888 1.999996 180)
			(size 0.3556 0.3556)
			(layers "F.Cu" "F.Mask" "F.Paste")
			(net "ROMA3")
		)
		(pad "P19" smd circle
			(at 5.999988 1.999996 180)
			(size 0.3556 0.3556)
			(layers "F.Cu" "F.Mask" "F.Paste")
			(net "ROMA4")
		)
		(pad "P20" smd circle
			(at 6.800088 1.999996 180)
			(size 0.3556 0.3556)
			(layers "F.Cu" "F.Mask" "F.Paste")
			(net "ROMA5")
		)
		(pad "P21" smd circle
			(at 7.599934 1.999996 180)
			(size 0.3556 0.3556)
			(layers "F.Cu" "F.Mask" "F.Paste")
			(net "ROMA6")
		)
		(pad "P22" smd circle
			(at 8.400034 1.999996 180)
			(size 0.3556 0.3556)
			(layers "F.Cu" "F.Mask" "F.Paste")
			(net "ROMA7")
		)
		(pad "R1" smd circle
			(at -8.400034 2.800096 180)
			(size 0.3556 0.3556)
			(layers "F.Cu" "F.Mask" "F.Paste")
			(net "DACRSET")
		)
		(pad "R2" smd circle
			(at -7.599934 2.800096 180)
			(size 0.3556 0.3556)
			(layers "F.Cu" "F.Mask" "F.Paste")
			(net "DACR")
		)
		(pad "R3" smd circle
			(at -6.800088 2.800096 180)
			(size 0.3556 0.3556)
			(layers "F.Cu" "F.Mask" "F.Paste")
			(net "DACG")
		)
		(pad "R4" smd circle
			(at -5.999988 2.800096 180)
			(size 0.3556 0.3556)
			(layers "F.Cu" "F.Mask" "F.Paste")
			(net "DACB")
		)
		(pad "R5" smd circle
			(at -5.199888 2.800096 180)
			(size 0.3556 0.3556)
			(layers "F.Cu" "F.Mask" "F.Paste")
			(net "GND")
		)
		(pad "R6" smd circle
			(at -4.400042 2.800096 180)
			(size 0.3556 0.3556)
			(layers "F.Cu" "F.Mask" "F.Paste")
			(net "P1V26_STBY")
		)
		(pad "R17" smd circle
			(at 4.400042 2.800096 180)
			(size 0.3556 0.3556)
			(layers "F.Cu" "F.Mask" "F.Paste")
			(net "P1V26_STBY")
		)
		(pad "R18" smd circle
			(at 5.199888 2.800096 180)
			(size 0.3556 0.3556)
			(layers "F.Cu" "F.Mask" "F.Paste")
			(net "TP_GPIOS4")
		)
		(pad "R19" smd circle
			(at 5.999988 2.800096 180)
			(size 0.3556 0.3556)
			(layers "F.Cu" "F.Mask" "F.Paste")
			(net "FLA_CS")
		)
		(pad "R20" smd circle
			(at 6.800088 2.800096 180)
			(size 0.3556 0.3556)
			(layers "F.Cu" "F.Mask" "F.Paste")
			(net "ROMA0")
		)
		(pad "R21" smd circle
			(at 7.599934 2.800096 180)
			(size 0.3556 0.3556)
			(layers "F.Cu" "F.Mask" "F.Paste")
			(net "ROMA1")
		)
		(pad "R22" smd circle
			(at 8.400034 2.800096 180)
			(size 0.3556 0.3556)
			(layers "F.Cu" "F.Mask" "F.Paste")
			(net "ROMA2")
		)
		(pad "T1" smd circle
			(at -8.400034 3.599942 180)
			(size 0.3556 0.3556)
			(layers "F.Cu" "F.Mask" "F.Paste")
			(net "TP_BMC_GPIOJ7")
		)
		(pad "T2" smd circle
			(at -7.599934 3.599942 180)
			(size 0.3556 0.3556)
			(layers "F.Cu" "F.Mask" "F.Paste")
			(net "TP_BMC_GPIOJ6")
		)
		(pad "T3" smd circle
			(at -6.800088 3.599942 180)
			(size 0.3556 0.3556)
			(layers "F.Cu" "F.Mask" "F.Paste")
			(net "P3V3_STBY")
		)
		(pad "T4" smd circle
			(at -5.999988 3.599942 180)
			(size 0.3556 0.3556)
			(layers "F.Cu" "F.Mask" "F.Paste")
			(net "TP_BMC_GPIOJ4")
		)
		(pad "T5" smd circle
			(at -5.199888 3.599942 180)
			(size 0.3556 0.3556)
			(layers "F.Cu" "F.Mask" "F.Paste")
			(net "CBL_PRSNT_N_2")
		)
		(pad "T18" smd circle
			(at 5.199888 3.599942 180)
			(size 0.3556 0.3556)
			(layers "F.Cu" "F.Mask" "F.Paste")
			(net "ROMA16")
		)
		(pad "T19" smd circle
			(at 5.999988 3.599942 180)
			(size 0.3556 0.3556)
			(layers "F.Cu" "F.Mask" "F.Paste")
			(net "ROMD5")
		)
		(pad "T20" smd circle
			(at 6.800088 3.599942 180)
			(size 0.3556 0.3556)
			(layers "F.Cu" "F.Mask" "F.Paste")
			(net "ROMD2")
		)
		(pad "T21" smd circle
			(at 7.599934 3.599942 180)
			(size 0.3556 0.3556)
			(layers "F.Cu" "F.Mask" "F.Paste")
			(net "ROMD1")
		)
		(pad "T22" smd circle
			(at 8.400034 3.599942 180)
			(size 0.3556 0.3556)
			(layers "F.Cu" "F.Mask" "F.Paste")
			(net "ROMD0")
		)
		(pad "U1" smd circle
			(at -8.400034 4.400042 180)
			(size 0.3556 0.3556)
			(layers "F.Cu" "F.Mask" "F.Paste")
			(net "CBL_PRSNT_N_1")
		)
		(pad "U2" smd circle
			(at -7.599934 4.400042 180)
			(size 0.3556 0.3556)
			(layers "F.Cu" "F.Mask" "F.Paste")
			(net "TP_BMC_GPIOJ5")
		)
		(pad "U3" smd circle
			(at -6.800088 4.400042 180)
			(size 0.3556 0.3556)
			(layers "F.Cu" "F.Mask" "F.Paste")
			(net "CBL_PRSNT_N_3")
		)
		(pad "U4" smd circle
			(at -5.999988 4.400042 180)
			(size 0.3556 0.3556)
			(layers "F.Cu" "F.Mask" "F.Paste")
			(net "CBL_PRSNT_N_5")
		)
		(pad "U5" smd circle
			(at -5.199888 4.400042 180)
			(size 0.3556 0.3556)
			(layers "F.Cu" "F.Mask" "F.Paste")
			(net "CBL_PRSNT_N_8")
		)
		(pad "U8" smd circle
			(at -2.800096 4.400042 180)
			(size 0.3556 0.3556)
			(layers "F.Cu" "F.Mask" "F.Paste")
			(net "P3V3_STBY")
		)
		(pad "U9" smd circle
			(at -1.999996 4.400042 180)
			(size 0.3556 0.3556)
			(layers "F.Cu" "F.Mask" "F.Paste")
			(net "P3V3_STBY")
		)
		(pad "U10" smd circle
			(at -1.199896 4.400042 180)
			(size 0.3556 0.3556)
			(layers "F.Cu" "F.Mask" "F.Paste")
			(net "P1V53_STBY")
		)
		(pad "U11" smd circle
			(at -0.40005 4.400042 180)
			(size 0.3556 0.3556)
			(layers "F.Cu" "F.Mask" "F.Paste")
			(net "P1V53_STBY")
		)
		(pad "U12" smd circle
			(at 0.40005 4.400042 180)
			(size 0.3556 0.3556)
			(layers "F.Cu" "F.Mask" "F.Paste")
			(net "P1V26_STBY")
		)
		(pad "U13" smd circle
			(at 1.199896 4.400042 180)
			(size 0.3556 0.3556)
			(layers "F.Cu" "F.Mask" "F.Paste")
			(net "P1V26_STBY")
		)
		(pad "U14" smd circle
			(at 1.999996 4.400042 180)
			(size 0.3556 0.3556)
			(layers "F.Cu" "F.Mask" "F.Paste")
			(net "P1V53_STBY")
		)
		(pad "U15" smd circle
			(at 2.800096 4.400042 180)
			(size 0.3556 0.3556)
			(layers "F.Cu" "F.Mask" "F.Paste")
			(net "P1V53_STBY")
		)
		(pad "U18" smd circle
			(at 5.199888 4.400042 180)
			(size 0.3556 0.3556)
			(layers "F.Cu" "F.Mask" "F.Paste")
			(net "EXP_TRAY_ID_BMC")
		)
		(pad "U19" smd circle
			(at 5.999988 4.400042 180)
			(size 0.3556 0.3556)
			(layers "F.Cu" "F.Mask" "F.Paste")
			(net "GPIOR3_R")
		)
		(pad "U20" smd circle
			(at 6.800088 4.400042 180)
			(size 0.3556 0.3556)
			(layers "F.Cu" "F.Mask" "F.Paste")
			(net "ROMD7")
		)
		(pad "U21" smd circle
			(at 7.599934 4.400042 180)
			(size 0.3556 0.3556)
			(layers "F.Cu" "F.Mask" "F.Paste")
			(net "ROMD4")
		)
		(pad "U22" smd circle
			(at 8.400034 4.400042 180)
			(size 0.3556 0.3556)
			(layers "F.Cu" "F.Mask" "F.Paste")
			(net "ROMD3")
		)
		(pad "V1" smd circle
			(at -8.400034 5.199888 180)
			(size 0.3556 0.3556)
			(layers "F.Cu" "F.Mask" "F.Paste")
			(net "CBL_PRSNT_N_4")
		)
		(pad "V2" smd circle
			(at -7.599934 5.199888 180)
			(size 0.3556 0.3556)
			(layers "F.Cu" "F.Mask" "F.Paste")
			(net "CBL_PRSNT_N_6")
		)
		(pad "V3" smd circle
			(at -6.800088 5.199888 180)
			(size 0.3556 0.3556)
			(layers "F.Cu" "F.Mask" "F.Paste")
			(net "GPIOM0_I210_PERST_N")
		)
		(pad "V4" smd circle
			(at -5.999988 5.199888 180)
			(size 0.3556 0.3556)
			(layers "F.Cu" "F.Mask" "F.Paste")
			(net "BMC_SSD_RST#2")
		)
		(pad "V5" smd circle
			(at -5.199888 5.199888 180)
			(size 0.3556 0.3556)
			(layers "F.Cu" "F.Mask" "F.Paste")
			(net "BMC_SSD_RST#6")
		)
		(pad "V6" smd circle
			(at -4.400042 5.199888 180)
			(size 0.3556 0.3556)
			(layers "F.Cu" "F.Mask" "F.Paste")
			(net "TP_GPIOO0")
		)
		(pad "V7" smd circle
			(at -3.599942 5.199888 180)
			(size 0.3556 0.3556)
			(layers "F.Cu" "F.Mask" "F.Paste")
			(net "TP_GPIOO7")
		)
		(pad "V8" smd circle
			(at -2.800096 5.199888 180)
			(size 0.3556 0.3556)
			(layers "F.Cu" "F.Mask" "F.Paste")
			(net "MEMDM_1")
		)
		(pad "V9" smd circle
			(at -1.999996 5.199888 180)
			(size 0.3556 0.3556)
			(layers "F.Cu" "F.Mask" "F.Paste")
			(net "MEMDQ_13")
		)
		(pad "V10" smd circle
			(at -1.199896 5.199888 180)
			(size 0.3556 0.3556)
			(layers "F.Cu" "F.Mask" "F.Paste")
			(net "MEMDQ_8")
		)
		(pad "V11" smd circle
			(at -0.40005 5.199888 180)
			(size 0.3556 0.3556)
			(layers "F.Cu" "F.Mask" "F.Paste")
			(net "MEMDQ_6")
		)
		(pad "V12" smd circle
			(at 0.40005 5.199888 180)
			(size 0.3556 0.3556)
			(layers "F.Cu" "F.Mask" "F.Paste")
			(net "MEMDQ_1")
		)
		(pad "V13" smd circle
			(at 1.199896 5.199888 180)
			(size 0.3556 0.3556)
			(layers "F.Cu" "F.Mask" "F.Paste")
			(net "DDR_VREF")
		)
		(pad "V14" smd circle
			(at 1.999996 5.199888 180)
			(size 0.3556 0.3556)
			(layers "F.Cu" "F.Mask" "F.Paste")
			(net "MEMODT")
		)
		(pad "V15" smd circle
			(at 2.800096 5.199888 180)
			(size 0.3556 0.3556)
			(layers "F.Cu" "F.Mask" "F.Paste")
			(net "MEMA_2")
		)
		(pad "V16" smd circle
			(at 3.599942 5.199888 180)
			(size 0.3556 0.3556)
			(layers "F.Cu" "F.Mask" "F.Paste")
			(net "BMC_MIOZ")
		)
		(pad "V17" smd circle
			(at 4.400042 5.199888 180)
			(size 0.3556 0.3556)
			(layers "F.Cu" "F.Mask" "F.Paste")
			(net "MPLLAV33")
		)
		(pad "V18" smd circle
			(at 5.199888 5.199888 180)
			(size 0.3556 0.3556)
			(layers "F.Cu" "F.Mask" "F.Paste")
			(net "GND")
		)
		(pad "V19" smd circle
			(at 5.999988 5.199888 180)
			(size 0.3556 0.3556)
			(layers "F.Cu" "F.Mask" "F.Paste")
			(net "P1V26_STBY")
		)
		(pad "V20" smd circle
			(at 6.800088 5.199888 180)
			(size 0.3556 0.3556)
			(layers "F.Cu" "F.Mask" "F.Paste")
			(net "FLA_CS1")
		)
		(pad "V21" smd circle
			(at 7.599934 5.199888 180)
			(size 0.3556 0.3556)
			(layers "F.Cu" "F.Mask" "F.Paste")
			(net "GPIOR4_BMC_INT_N_R")
		)
		(pad "V22" smd circle
			(at 8.400034 5.199888 180)
			(size 0.3556 0.3556)
			(layers "F.Cu" "F.Mask" "F.Paste")
			(net "ROMD6")
		)
		(pad "W1" smd circle
			(at -8.400034 5.999988 180)
			(size 0.3556 0.3556)
			(layers "F.Cu" "F.Mask" "F.Paste")
			(net "CBL_PRSNT_N_7")
		)
		(pad "W2" smd circle
			(at -7.599934 5.999988 180)
			(size 0.3556 0.3556)
			(layers "F.Cu" "F.Mask" "F.Paste")
			(net "BMC_SSD_RST#0")
		)
		(pad "W3" smd circle
			(at -6.800088 5.999988 180)
			(size 0.3556 0.3556)
			(layers "F.Cu" "F.Mask" "F.Paste")
			(net "BMC_SSD_RST#3")
		)
		(pad "W4" smd circle
			(at -5.999988 5.999988 180)
			(size 0.3556 0.3556)
			(layers "F.Cu" "F.Mask" "F.Paste")
			(net "FAN_PWM_PCIE_BMC")
		)
		(pad "W5" smd circle
			(at -5.199888 5.999988 180)
			(size 0.3556 0.3556)
			(layers "F.Cu" "F.Mask" "F.Paste")
			(net "BMC_SELF_TRAY_R")
		)
		(pad "W6" smd circle
			(at -4.400042 5.999988 180)
			(size 0.3556 0.3556)
			(layers "F.Cu" "F.Mask" "F.Paste")
			(net "TP_GPIOO4")
		)
		(pad "W7" smd circle
			(at -3.599942 5.999988 180)
			(size 0.3556 0.3556)
			(layers "F.Cu" "F.Mask" "F.Paste")
			(net "TP_GPIOP2")
		)
		(pad "W8" smd circle
			(at -2.800096 5.999988 180)
			(size 0.3556 0.3556)
			(layers "F.Cu" "F.Mask" "F.Paste")
			(net "MEMDQ_15")
		)
		(pad "W9" smd circle
			(at -1.999996 5.999988 180)
			(size 0.3556 0.3556)
			(layers "F.Cu" "F.Mask" "F.Paste")
			(net "MEMDQ_12")
		)
		(pad "W10" smd circle
			(at -1.199896 5.999988 180)
			(size 0.3556 0.3556)
			(layers "F.Cu" "F.Mask" "F.Paste")
			(net "MEMDM_0")
		)
		(pad "W11" smd circle
			(at -0.40005 5.999988 180)
			(size 0.3556 0.3556)
			(layers "F.Cu" "F.Mask" "F.Paste")
			(net "MEMDQ_5")
		)
		(pad "W12" smd circle
			(at 0.40005 5.999988 180)
			(size 0.3556 0.3556)
			(layers "F.Cu" "F.Mask" "F.Paste")
			(net "MEMDQ_0")
		)
		(pad "W13" smd circle
			(at 1.199896 5.999988 180)
			(size 0.3556 0.3556)
			(layers "F.Cu" "F.Mask" "F.Paste")
			(net "MEMRASN")
		)
		(pad "W14" smd circle
			(at 1.999996 5.999988 180)
			(size 0.3556 0.3556)
			(layers "F.Cu" "F.Mask" "F.Paste")
			(net "MEMBA_0")
		)
		(pad "W15" smd circle
			(at 2.800096 5.999988 180)
			(size 0.3556 0.3556)
			(layers "F.Cu" "F.Mask" "F.Paste")
			(net "MEMA_1")
		)
		(pad "W16" smd circle
			(at 3.599942 5.999988 180)
			(size 0.3556 0.3556)
			(layers "F.Cu" "F.Mask" "F.Paste")
			(net "MEMA_5")
		)
		(pad "W17" smd circle
			(at 4.400042 5.999988 180)
			(size 0.3556 0.3556)
			(layers "F.Cu" "F.Mask" "F.Paste")
			(net "MEMA_12")
		)
		(pad "W18" smd circle
			(at 5.199888 5.999988 180)
			(size 0.3556 0.3556)
			(layers "F.Cu" "F.Mask" "F.Paste")
			(net "P3V3_STBY")
		)
		(pad "W19" smd circle
			(at 5.999988 5.999988 180)
			(size 0.3556 0.3556)
			(layers "F.Cu" "F.Mask" "F.Paste")
			(net "V1PLLAV12")
		)
		(pad "W20" smd circle
			(at 6.800088 5.999988 180)
			(size 0.3556 0.3556)
			(layers "F.Cu" "F.Mask" "F.Paste")
			(net "BMC0_SRST_N")
		)
		(pad "W21" smd circle
			(at 7.599934 5.999988 180)
			(size 0.3556 0.3556)
			(layers "F.Cu" "F.Mask" "F.Paste")
			(net "GPIOR1_R")
		)
		(pad "W22" smd circle
			(at 8.400034 5.999988 180)
			(size 0.3556 0.3556)
			(layers "F.Cu" "F.Mask" "F.Paste")
			(net "GPIOR5_R")
		)
		(pad "Y1" smd circle
			(at -8.400034 6.800088 180)
			(size 0.4064 0.4064)
			(layers "F.Cu" "F.Mask" "F.Paste")
			(net "BMC_SSD_RST#1")
		)
		(pad "Y2" smd circle
			(at -7.599934 6.800088 180)
			(size 0.4064 0.4064)
			(layers "F.Cu" "F.Mask" "F.Paste")
			(net "BMC_SSD_RST#4")
		)
		(pad "Y3" smd circle
			(at -6.800088 6.800088 180)
			(size 0.4064 0.4064)
			(layers "F.Cu" "F.Mask" "F.Paste")
			(net "BMC_FW_DET_BOARD_VER_0")
		)
		(pad "Y4" smd circle
			(at -5.999988 6.800088 180)
			(size 0.3556 0.3556)
			(layers "F.Cu" "F.Mask" "F.Paste")
			(net "TP_GPION5")
		)
		(pad "Y5" smd circle
			(at -5.199888 6.800088 180)
			(size 0.3556 0.3556)
			(layers "F.Cu" "F.Mask" "F.Paste")
			(net "TP_GPIOO1")
		)
		(pad "Y6" smd circle
			(at -4.400042 6.800088 180)
			(size 0.3556 0.3556)
			(layers "F.Cu" "F.Mask" "F.Paste")
			(net "TP_GPIOP0")
		)
		(pad "Y7" smd circle
			(at -3.599942 6.800088 180)
			(size 0.3556 0.3556)
			(layers "F.Cu" "F.Mask" "F.Paste")
			(net "BMC0_TACH13")
		)
		(pad "Y8" smd circle
			(at -2.800096 6.800088 180)
			(size 0.3556 0.3556)
			(layers "F.Cu" "F.Mask" "F.Paste")
			(net "MEMDQ_14")
		)
		(pad "Y9" smd circle
			(at -1.999996 6.800088 180)
			(size 0.3556 0.3556)
			(layers "F.Cu" "F.Mask" "F.Paste")
			(net "MEMDQ_11")
		)
		(pad "Y10" smd circle
			(at -1.199896 6.800088 180)
			(size 0.3556 0.3556)
			(layers "F.Cu" "F.Mask" "F.Paste")
			(net "MEMDQ_7")
		)
		(pad "Y11" smd circle
			(at -0.40005 6.800088 180)
			(size 0.3556 0.3556)
			(layers "F.Cu" "F.Mask" "F.Paste")
			(net "MEMDQ_4")
		)
		(pad "Y12" smd circle
			(at 0.40005 6.800088 180)
			(size 0.3556 0.3556)
			(layers "F.Cu" "F.Mask" "F.Paste")
			(net "MEMCKE")
		)
		(pad "Y13" smd circle
			(at 1.199896 6.800088 180)
			(size 0.3556 0.3556)
			(layers "F.Cu" "F.Mask" "F.Paste")
			(net "MEMWEN")
		)
		(pad "Y14" smd circle
			(at 1.999996 6.800088 180)
			(size 0.3556 0.3556)
			(layers "F.Cu" "F.Mask" "F.Paste")
			(net "MEMBA_2")
		)
		(pad "Y15" smd circle
			(at 2.800096 6.800088 180)
			(size 0.3556 0.3556)
			(layers "F.Cu" "F.Mask" "F.Paste")
			(net "MEMA_10")
		)
		(pad "Y16" smd circle
			(at 3.599942 6.800088 180)
			(size 0.3556 0.3556)
			(layers "F.Cu" "F.Mask" "F.Paste")
			(net "MEMA_3")
		)
		(pad "Y17" smd circle
			(at 4.400042 6.800088 180)
			(size 0.3556 0.3556)
			(layers "F.Cu" "F.Mask" "F.Paste")
			(net "MEMA_13")
		)
		(pad "Y18" smd circle
			(at 5.199888 6.800088 180)
			(size 0.3556 0.3556)
			(layers "F.Cu" "F.Mask" "F.Paste")
			(net "P1V26_STBY")
		)
		(pad "Y19" smd circle
			(at 5.999988 6.800088 180)
			(size 0.3556 0.3556)
			(layers "F.Cu" "F.Mask" "F.Paste")
			(net "GND")
		)
		(pad "Y20" smd circle
			(at 6.800088 6.800088 180)
			(size 0.4064 0.4064)
			(layers "F.Cu" "F.Mask" "F.Paste")
			(net "V1PLLAV12")
		)
		(pad "Y21" smd circle
			(at 7.599934 6.800088 180)
			(size 0.4064 0.4064)
			(layers "F.Cu" "F.Mask" "F.Paste")
			(net "BMC_SELF_HW_RST_R")
		)
		(pad "Y22" smd circle
			(at 8.400034 6.800088 180)
			(size 0.4064 0.4064)
			(layers "F.Cu" "F.Mask" "F.Paste")
			(net "GPIOR2_R")
		)
	)
	(footprint ""
		(layer "F.Cu")
		(at 293.191946 -212.420454 180)
		(property "Reference" "C79"
			(at 0 0 180)
			(layer "F.SilkS")
			(hide yes)
			(effects
				(font
					(size 1.27 1.27)
				)
			)
		)
		(property "Value" "SCD22U10V2KX-1GP"
			(at 1.1811 -2.7051 180)
			(unlocked yes)
			(layer "F.Fab")
			(hide yes)
			(effects
				(font
					(size 1.016 1.016)
					(thickness 0.1524)
				)
			)
		)
		(property "Device Type" "C402H22"
			(at 1.1811 -4.2291 180)
			(unlocked yes)
			(layer "F.Fab")
			(hide yes)
			(effects
				(font
					(size 1.016 1.016)
					(thickness 0.1524)
				)
			)
		)
		(duplicate_pad_numbers_are_jumpers no)
		(fp_rect
			(start -0.4318 0.9525)
			(end 0.4318 -0.9525)
			(stroke
				(width 0)
				(type default)
			)
			(fill no)
			(layer "F.CrtYd")
		)
		(fp_rect
			(start -0.4318 0.9525)
			(end 0.4318 -0.9525)
			(stroke
				(width 0)
				(type default)
			)
			(fill no)
			(layer "F.Fab")
		)
		(pad "1" smd custom
			(at 0 -0.4445 180)
			(size 0.1524 0.1524)
			(layers "F.Cu" "F.Mask" "F.Paste")
			(net "PCIE_TX_CAP_P28")
			(options
				(clearance outline)
				(anchor circle)
			)
			(primitives
				(gr_poly
					(pts
						(arc
							(start 0.3048 -0.2032)
							(mid 0.275042 -0.275042)
							(end 0.2032 -0.3048)
						)
						(arc
							(start -0.2032 -0.3048)
							(mid -0.275042 -0.275042)
							(end -0.3048 -0.2032)
						)
						(arc
							(start -0.3048 0.2032)
							(mid -0.275042 0.275042)
							(end -0.2032 0.3048)
						)
						(arc
							(start 0.2032 0.3048)
							(mid 0.275042 0.275042)
							(end 0.3048 0.2032)
						)
					)
					(width 0)
					(fill yes)
				)
			)
		)
		(pad "2" smd custom
			(at 0 0.4445 180)
			(size 0.1524 0.1524)
			(layers "F.Cu" "F.Mask" "F.Paste")
			(net "PCIE_TX_P28")
			(options
				(clearance outline)
				(anchor circle)
			)
			(primitives
				(gr_poly
					(pts
						(arc
							(start 0.3048 -0.2032)
							(mid 0.275042 -0.275042)
							(end 0.2032 -0.3048)
						)
						(arc
							(start -0.2032 -0.3048)
							(mid -0.275042 -0.275042)
							(end -0.3048 -0.2032)
						)
						(arc
							(start -0.3048 0.2032)
							(mid -0.275042 0.275042)
							(end -0.2032 0.3048)
						)
						(arc
							(start 0.2032 0.3048)
							(mid 0.275042 0.275042)
							(end 0.3048 0.2032)
						)
					)
					(width 0)
					(fill yes)
				)
			)
		)
	)
	(footprint ""
		(layer "F.Cu")
		(at 51.943 -124.46)
		(property "Reference" "TP178"
			(at 0 0 0)
			(layer "F.SilkS")
			(hide yes)
			(effects
				(font
					(size 1.27 1.27)
				)
			)
		)
		(property "Value" "TPAD28-2-GP"
			(at -0.0127 -1.6637 0)
			(unlocked yes)
			(layer "F.Fab")
			(hide yes)
			(effects
				(font
					(size 1.016 1.016)
					(thickness 0.1524)
				)
			)
		)
		(property "Device Type" "TPAD28"
			(at -0.0127 -3.1877 0)
			(unlocked yes)
			(layer "F.Fab")
			(hide yes)
			(effects
				(font
					(size 1.016 1.016)
					(thickness 0.1524)
				)
			)
		)
		(duplicate_pad_numbers_are_jumpers no)
		(fp_poly
			(pts
				(arc
					(start 0.3556 0)
					(mid -0.3556 0)
					(end 0.3556 0)
				)
			)
			(stroke
				(width 0)
				(type default)
			)
			(fill no)
			(layer "F.CrtYd")
		)
		(fp_poly
			(pts
				(arc
					(start 0.6096 0)
					(mid -0.6096 0)
					(end 0.6096 0)
				)
			)
			(stroke
				(width 0)
				(type default)
			)
			(fill no)
			(layer "F.Fab")
		)
		(pad "1" smd circle
			(at 0 0)
			(size 0.7112 0.7112)
			(layers "F.Cu" "F.Mask" "F.Paste")
			(net "JTAG_BMC_TCK")
		)
	)
	(footprint ""
		(layer "F.Cu")
		(at 204.3684 -27.0002 -90)
		(property "Reference" "C135"
			(at 0 0 270)
			(layer "F.SilkS")
			(hide yes)
			(effects
				(font
					(size 1.27 1.27)
				)
			)
		)
		(property "Value" "SCD047U25V2KX-GP"
			(at 1.1811 -2.7051 270)
			(unlocked yes)
			(layer "F.Fab")
			(hide yes)
			(effects
				(font
					(size 1.016 1.016)
					(thickness 0.1524)
				)
			)
		)
		(property "Device Type" "C402H22"
			(at 1.1811 -4.2291 270)
			(unlocked yes)
			(layer "F.Fab")
			(hide yes)
			(effects
				(font
					(size 1.016 1.016)
					(thickness 0.1524)
				)
			)
		)
		(duplicate_pad_numbers_are_jumpers no)
		(fp_rect
			(start -0.4318 0.9525)
			(end 0.4318 -0.9525)
			(stroke
				(width 0)
				(type default)
			)
			(fill no)
			(layer "F.CrtYd")
		)
		(fp_rect
			(start -0.4318 0.9525)
			(end 0.4318 -0.9525)
			(stroke
				(width 0)
				(type default)
			)
			(fill no)
			(layer "F.Fab")
		)
		(pad "1" smd custom
			(at 0 -0.4445 270)
			(size 0.1524 0.1524)
			(layers "F.Cu" "F.Mask" "F.Paste")
			(net "P3V3_STBY")
			(options
				(clearance outline)
				(anchor circle)
			)
			(primitives
				(gr_poly
					(pts
						(arc
							(start 0.3048 -0.2032)
							(mid 0.275042 -0.275042)
							(end 0.2032 -0.3048)
						)
						(arc
							(start -0.2032 -0.3048)
							(mid -0.275042 -0.275042)
							(end -0.3048 -0.2032)
						)
						(arc
							(start -0.3048 0.2032)
							(mid -0.275042 0.275042)
							(end -0.2032 0.3048)
						)
						(arc
							(start 0.2032 0.3048)
							(mid 0.275042 0.275042)
							(end 0.3048 0.2032)
						)
					)
					(width 0)
					(fill yes)
				)
			)
		)
		(pad "2" smd custom
			(at 0 0.4445 270)
			(size 0.1524 0.1524)
			(layers "F.Cu" "F.Mask" "F.Paste")
			(net "GND")
			(options
				(clearance outline)
				(anchor circle)
			)
			(primitives
				(gr_poly
					(pts
						(arc
							(start 0.3048 -0.2032)
							(mid 0.275042 -0.275042)
							(end 0.2032 -0.3048)
						)
						(arc
							(start -0.2032 -0.3048)
							(mid -0.275042 -0.275042)
							(end -0.3048 -0.2032)
						)
						(arc
							(start -0.3048 0.2032)
							(mid -0.275042 0.275042)
							(end -0.2032 0.3048)
						)
						(arc
							(start 0.2032 0.3048)
							(mid 0.275042 0.275042)
							(end 0.3048 0.2032)
						)
					)
					(width 0)
					(fill yes)
				)
			)
		)
	)
	(footprint ""
		(layer "F.Cu")
		(at 215.06942 -31.274512)
		(property "Reference" "TP277"
			(at 0 0 0)
			(layer "F.SilkS")
			(hide yes)
			(effects
				(font
					(size 1.27 1.27)
				)
			)
		)
		(property "Value" "TPAD28-2-GP"
			(at -0.0127 -1.6637 0)
			(unlocked yes)
			(layer "F.Fab")
			(hide yes)
			(effects
				(font
					(size 1.016 1.016)
					(thickness 0.1524)
				)
			)
		)
		(property "Device Type" "TPAD28"
			(at -0.0127 -3.1877 0)
			(unlocked yes)
			(layer "F.Fab")
			(hide yes)
			(effects
				(font
					(size 1.016 1.016)
					(thickness 0.1524)
				)
			)
		)
		(duplicate_pad_numbers_are_jumpers no)
		(fp_poly
			(pts
				(arc
					(start 0.3556 0)
					(mid -0.3556 0)
					(end 0.3556 0)
				)
			)
			(stroke
				(width 0)
				(type default)
			)
			(fill no)
			(layer "F.CrtYd")
		)
		(fp_poly
			(pts
				(arc
					(start 0.6096 0)
					(mid -0.6096 0)
					(end 0.6096 0)
				)
			)
			(stroke
				(width 0)
				(type default)
			)
			(fill no)
			(layer "F.Fab")
		)
		(pad "1" smd circle
			(at 0 0)
			(size 0.7112 0.7112)
			(layers "F.Cu" "F.Mask" "F.Paste")
			(net "LBI_DATA12_R")
		)
	)
	(footprint ""
		(layer "F.Cu")
		(at 199.323452 -22.6314 -90)
		(property "Reference" "U56"
			(at 0 0 270)
			(layer "F.SilkS")
			(hide yes)
			(effects
				(font
					(size 1.27 1.27)
				)
			)
		)
		(property "Value" "TCA9554PWR-GP"
			(at 0.127 -12.573 270)
			(unlocked yes)
			(layer "F.Fab")
			(hide yes)
			(effects
				(font
					(size 1.016 1.016)
					(thickness 0.1524)
				)
			)
		)
		(property "Device Type" "TSOIC16H48"
			(at 0.1016 -14.5796 270)
			(unlocked yes)
			(layer "F.Fab")
			(hide yes)
			(effects
				(font
					(size 1.016 1.016)
					(thickness 0.1524)
				)
			)
		)
		(duplicate_pad_numbers_are_jumpers no)
		(fp_line
			(start -2.921 3.81)
			(end -2.921 1.778)
			(stroke
				(width 0.508)
				(type default)
			)
			(layer "F.SilkS")
		)
		(fp_line
			(start 2.3622 1.778)
			(end -2.921 1.778)
			(stroke
				(width 0.1524)
				(type default)
			)
			(layer "F.SilkS")
		)
		(fp_line
			(start -2.54 0)
			(end -3.0988 0.5588)
			(stroke
				(width 0.1524)
				(type default)
			)
			(layer "F.SilkS")
		)
		(fp_line
			(start -2.54 0)
			(end -3.0988 -0.5588)
			(stroke
				(width 0.1524)
				(type default)
			)
			(layer "F.SilkS")
		)
		(fp_line
			(start -3.0988 -1.778)
			(end -3.0988 1.778)
			(stroke
				(width 0.1524)
				(type default)
			)
			(layer "F.SilkS")
		)
		(fp_line
			(start -3.0988 -1.778)
			(end 2.3622 -1.778)
			(stroke
				(width 0.1524)
				(type default)
			)
			(layer "F.SilkS")
		)
		(fp_line
			(start 2.3622 -1.778)
			(end 2.3622 1.778)
			(stroke
				(width 0.1524)
				(type default)
			)
			(layer "F.SilkS")
		)
		(fp_poly
			(pts
				(xy -2.4638 -1.778) (xy -2.4638 1.778) (xy 2.3622 1.778) (xy 2.3622 -1.778)
			)
			(stroke
				(width 0)
				(type default)
			)
			(fill yes)
			(layer "F.SilkS")
		)
		(fp_rect
			(start -3.175 4.064)
			(end 3.175 -4.064)
			(stroke
				(width 0)
				(type default)
			)
			(fill no)
			(layer "F.CrtYd")
		)
		(fp_poly
			(pts
				(xy -3.175 -4.064) (xy 3.175 -4.064) (xy 3.175 4.064) (xy -3.175 4.064)
			)
			(stroke
				(width 0)
				(type default)
			)
			(fill no)
			(layer "F.Fab")
		)
		(pad "1" smd rect
			(at -2.27584 2.8194 270)
			(size 0.3556 1.524)
			(layers "F.Cu" "F.Mask" "F.Paste")
			(net "U56_A0")
		)
		(pad "2" smd rect
			(at -1.6256 2.8194 270)
			(size 0.3556 1.524)
			(layers "F.Cu" "F.Mask" "F.Paste")
			(net "U56_A1")
		)
		(pad "3" smd rect
			(at -0.97536 2.8194 270)
			(size 0.3556 1.524)
			(layers "F.Cu" "F.Mask" "F.Paste")
			(net "U56_A2")
		)
		(pad "4" smd rect
			(at -0.32512 2.8194 270)
			(size 0.3556 1.524)
			(layers "F.Cu" "F.Mask" "F.Paste")
			(net "MINISAS_CN15_A_I2C_INT#")
		)
		(pad "5" smd rect
			(at 0.32512 2.8194 270)
			(size 0.3556 1.524)
			(layers "F.Cu" "F.Mask" "F.Paste")
			(net "MINISAS_CN15_B_I2C_INT#")
		)
		(pad "6" smd rect
			(at 0.97536 2.8194 270)
			(size 0.3556 1.524)
			(layers "F.Cu" "F.Mask" "F.Paste")
			(net "MINISAS_CN15_C_I2C_INT#")
		)
		(pad "7" smd rect
			(at 1.6256 2.8194 270)
			(size 0.3556 1.524)
			(layers "F.Cu" "F.Mask" "F.Paste")
			(net "MINISAS_CN15_D_I2C_INT#")
		)
		(pad "8" smd rect
			(at 2.27584 2.8194 270)
			(size 0.3556 1.524)
			(layers "F.Cu" "F.Mask" "F.Paste")
			(net "GND")
		)
		(pad "9" smd rect
			(at 2.27584 -2.8194 270)
			(size 0.3556 1.524)
			(layers "F.Cu" "F.Mask" "F.Paste")
			(net "MINISAS_CN16_A_I2C_INT#")
		)
		(pad "10" smd rect
			(at 1.6256 -2.8194 270)
			(size 0.3556 1.524)
			(layers "F.Cu" "F.Mask" "F.Paste")
			(net "MINISAS_CN16_B_I2C_INT#")
		)
		(pad "11" smd rect
			(at 0.97536 -2.8194 270)
			(size 0.3556 1.524)
			(layers "F.Cu" "F.Mask" "F.Paste")
			(net "MINISAS_CN16_C_I2C_INT#")
		)
		(pad "12" smd rect
			(at 0.32512 -2.8194 270)
			(size 0.3556 1.524)
			(layers "F.Cu" "F.Mask" "F.Paste")
			(net "MINISAS_CN16_D_I2C_INT#")
		)
		(pad "13" smd rect
			(at -0.32512 -2.8194 270)
			(size 0.3556 1.524)
			(layers "F.Cu" "F.Mask" "F.Paste")
			(net "U56_INT_N")
		)
		(pad "14" smd rect
			(at -0.97536 -2.8194 270)
			(size 0.3556 1.524)
			(layers "F.Cu" "F.Mask" "F.Paste")
			(net "U56_SCL")
		)
		(pad "15" smd rect
			(at -1.6256 -2.8194 270)
			(size 0.3556 1.524)
			(layers "F.Cu" "F.Mask" "F.Paste")
			(net "U56_SDA")
		)
		(pad "16" smd rect
			(at -2.27584 -2.8194 270)
			(size 0.3556 1.524)
			(layers "F.Cu" "F.Mask" "F.Paste")
			(net "P3V3_STBY")
		)
	)
	(footprint ""
		(layer "F.Cu")
		(at 123.19 -12.66952 90)
		(property "Reference" "SR709"
			(at 0 0 90)
			(layer "F.SilkS")
			(hide yes)
			(effects
				(font
					(size 1.27 1.27)
				)
			)
		)
		(property "Value" "150R2F-1-GP"
			(at 0.064008 -3.993896 90)
			(unlocked yes)
			(layer "F.Fab")
			(hide yes)
			(effects
				(font
					(size 1.016 1.016)
					(thickness 0.1524)
				)
			)
		)
		(property "Device Type" "R402H16"
			(at 0.064008 -5.517896 90)
			(unlocked yes)
			(layer "F.Fab")
			(hide yes)
			(effects
				(font
					(size 1.016 1.016)
					(thickness 0.1524)
				)
			)
		)
		(duplicate_pad_numbers_are_jumpers no)
		(fp_line
			(start 0.508 -0.9398)
			(end -0.508 -0.9398)
			(stroke
				(width 0.1524)
				(type default)
			)
			(layer "F.SilkS")
		)
		(fp_line
			(start -0.508 -0.9398)
			(end -0.508 0.9398)
			(stroke
				(width 0.1524)
				(type default)
			)
			(layer "F.SilkS")
		)
		(fp_rect
			(start -0.508 0.9398)
			(end 0.508 -0.9398)
			(stroke
				(width 0)
				(type default)
			)
			(fill no)
			(layer "F.CrtYd")
		)
		(fp_rect
			(start -0.508 0.9398)
			(end 0.508 -0.9398)
			(stroke
				(width 0)
				(type default)
			)
			(fill no)
			(layer "F.Fab")
		)
		(pad "1" smd custom
			(at 0 -0.4445 90)
			(size 0.1397 0.1397)
			(layers "F.Cu" "F.Mask" "F.Paste")
			(net "P3V3_STBY")
			(options
				(clearance outline)
				(anchor circle)
			)
			(primitives
				(gr_poly
					(pts
						(arc
							(start -0.1778 -0.2794)
							(mid -0.249642 -0.249642)
							(end -0.2794 -0.1778)
						)
						(arc
							(start -0.2794 0.1778)
							(mid -0.249642 0.249642)
							(end -0.1778 0.2794)
						)
						(arc
							(start 0.1778 0.2794)
							(mid 0.249642 0.249642)
							(end 0.2794 0.1778)
						)
						(arc
							(start 0.2794 -0.1778)
							(mid 0.249642 -0.249642)
							(end 0.1778 -0.2794)
						)
					)
					(width 0)
					(fill yes)
				)
			)
		)
		(pad "2" smd custom
			(at 0 0.4445 90)
			(size 0.1397 0.1397)
			(layers "F.Cu" "F.Mask" "F.Paste")
			(net "LED_R_2")
			(options
				(clearance outline)
				(anchor circle)
			)
			(primitives
				(gr_poly
					(pts
						(arc
							(start -0.1778 -0.2794)
							(mid -0.249642 -0.249642)
							(end -0.2794 -0.1778)
						)
						(arc
							(start -0.2794 0.1778)
							(mid -0.249642 0.249642)
							(end -0.1778 0.2794)
						)
						(arc
							(start 0.1778 0.2794)
							(mid 0.249642 0.249642)
							(end 0.2794 0.1778)
						)
						(arc
							(start 0.2794 -0.1778)
							(mid 0.249642 -0.249642)
							(end 0.1778 -0.2794)
						)
					)
					(width 0)
					(fill yes)
				)
			)
		)
	)
	(footprint ""
		(layer "F.Cu")
		(at 161.6202 -95.9104 180)
		(property "Reference" "R3109"
			(at 0 0 180)
			(layer "F.SilkS")
			(hide yes)
			(effects
				(font
					(size 1.27 1.27)
				)
			)
		)
		(property "Value" "27R2F-GP"
			(at 0.064008 -3.993896 180)
			(unlocked yes)
			(layer "F.Fab")
			(hide yes)
			(effects
				(font
					(size 1.016 1.016)
					(thickness 0.1524)
				)
			)
		)
		(property "Device Type" "R402H16"
			(at 0.064008 -5.517896 180)
			(unlocked yes)
			(layer "F.Fab")
			(hide yes)
			(effects
				(font
					(size 1.016 1.016)
					(thickness 0.1524)
				)
			)
		)
		(duplicate_pad_numbers_are_jumpers no)
		(fp_line
			(start 0.508 -0.9398)
			(end -0.508 -0.9398)
			(stroke
				(width 0.1524)
				(type default)
			)
			(layer "F.SilkS")
		)
		(fp_line
			(start -0.508 -0.9398)
			(end -0.508 0.9398)
			(stroke
				(width 0.1524)
				(type default)
			)
			(layer "F.SilkS")
		)
		(fp_rect
			(start -0.508 0.9398)
			(end 0.508 -0.9398)
			(stroke
				(width 0)
				(type default)
			)
			(fill no)
			(layer "F.CrtYd")
		)
		(fp_rect
			(start -0.508 0.9398)
			(end 0.508 -0.9398)
			(stroke
				(width 0)
				(type default)
			)
			(fill no)
			(layer "F.Fab")
		)
		(pad "1" smd custom
			(at 0 -0.4445 180)
			(size 0.1397 0.1397)
			(layers "F.Cu" "F.Mask" "F.Paste")
			(net "CLKGEN_N3_R")
			(options
				(clearance outline)
				(anchor circle)
			)
			(primitives
				(gr_poly
					(pts
						(arc
							(start -0.1778 -0.2794)
							(mid -0.249642 -0.249642)
							(end -0.2794 -0.1778)
						)
						(arc
							(start -0.2794 0.1778)
							(mid -0.249642 0.249642)
							(end -0.1778 0.2794)
						)
						(arc
							(start 0.1778 0.2794)
							(mid 0.249642 0.249642)
							(end 0.2794 0.1778)
						)
						(arc
							(start 0.2794 -0.1778)
							(mid 0.249642 -0.249642)
							(end 0.1778 -0.2794)
						)
					)
					(width 0)
					(fill yes)
				)
			)
		)
		(pad "2" smd custom
			(at 0 0.4445 180)
			(size 0.1397 0.1397)
			(layers "F.Cu" "F.Mask" "F.Paste")
			(net "CLKGEN_N3")
			(options
				(clearance outline)
				(anchor circle)
			)
			(primitives
				(gr_poly
					(pts
						(arc
							(start -0.1778 -0.2794)
							(mid -0.249642 -0.249642)
							(end -0.2794 -0.1778)
						)
						(arc
							(start -0.2794 0.1778)
							(mid -0.249642 0.249642)
							(end -0.1778 0.2794)
						)
						(arc
							(start 0.1778 0.2794)
							(mid 0.249642 0.249642)
							(end 0.2794 0.1778)
						)
						(arc
							(start 0.2794 -0.1778)
							(mid 0.249642 -0.249642)
							(end 0.1778 -0.2794)
						)
					)
					(width 0)
					(fill yes)
				)
			)
		)
	)
	(footprint ""
		(layer "F.Cu")
		(at 41.712388 -116.311426)
		(property "Reference" "TP156"
			(at 0 0 0)
			(layer "F.SilkS")
			(hide yes)
			(effects
				(font
					(size 1.27 1.27)
				)
			)
		)
		(property "Value" "TPAD28-2-GP"
			(at -0.0127 -1.6637 0)
			(unlocked yes)
			(layer "F.Fab")
			(hide yes)
			(effects
				(font
					(size 1.016 1.016)
					(thickness 0.1524)
				)
			)
		)
		(property "Device Type" "TPAD28"
			(at -0.0127 -3.1877 0)
			(unlocked yes)
			(layer "F.Fab")
			(hide yes)
			(effects
				(font
					(size 1.016 1.016)
					(thickness 0.1524)
				)
			)
		)
		(duplicate_pad_numbers_are_jumpers no)
		(fp_poly
			(pts
				(arc
					(start 0.3556 0)
					(mid -0.3556 0)
					(end 0.3556 0)
				)
			)
			(stroke
				(width 0)
				(type default)
			)
			(fill no)
			(layer "F.CrtYd")
		)
		(fp_poly
			(pts
				(arc
					(start 0.6096 0)
					(mid -0.6096 0)
					(end 0.6096 0)
				)
			)
			(stroke
				(width 0)
				(type default)
			)
			(fill no)
			(layer "F.Fab")
		)
		(pad "1" smd circle
			(at 0 0)
			(size 0.7112 0.7112)
			(layers "F.Cu" "F.Mask" "F.Paste")
			(net "TP_GPIOT7")
		)
	)
	(footprint ""
		(layer "F.Cu")
		(at 108.608114 -212.420454 180)
		(property "Reference" "C144"
			(at 0 0 180)
			(layer "F.SilkS")
			(hide yes)
			(effects
				(font
					(size 1.27 1.27)
				)
			)
		)
		(property "Value" "SCD22U10V2KX-1GP"
			(at 1.1811 -2.7051 180)
			(unlocked yes)
			(layer "F.Fab")
			(hide yes)
			(effects
				(font
					(size 1.016 1.016)
					(thickness 0.1524)
				)
			)
		)
		(property "Device Type" "C402H22"
			(at 1.1811 -4.2291 180)
			(unlocked yes)
			(layer "F.Fab")
			(hide yes)
			(effects
				(font
					(size 1.016 1.016)
					(thickness 0.1524)
				)
			)
		)
		(duplicate_pad_numbers_are_jumpers no)
		(fp_rect
			(start -0.4318 0.9525)
			(end 0.4318 -0.9525)
			(stroke
				(width 0)
				(type default)
			)
			(fill no)
			(layer "F.CrtYd")
		)
		(fp_rect
			(start -0.4318 0.9525)
			(end 0.4318 -0.9525)
			(stroke
				(width 0)
				(type default)
			)
			(fill no)
			(layer "F.Fab")
		)
		(pad "1" smd custom
			(at 0 -0.4445 180)
			(size 0.1524 0.1524)
			(layers "F.Cu" "F.Mask" "F.Paste")
			(net "PCIE_TX_CAP_N60")
			(options
				(clearance outline)
				(anchor circle)
			)
			(primitives
				(gr_poly
					(pts
						(arc
							(start 0.3048 -0.2032)
							(mid 0.275042 -0.275042)
							(end 0.2032 -0.3048)
						)
						(arc
							(start -0.2032 -0.3048)
							(mid -0.275042 -0.275042)
							(end -0.3048 -0.2032)
						)
						(arc
							(start -0.3048 0.2032)
							(mid -0.275042 0.275042)
							(end -0.2032 0.3048)
						)
						(arc
							(start 0.2032 0.3048)
							(mid 0.275042 0.275042)
							(end 0.3048 0.2032)
						)
					)
					(width 0)
					(fill yes)
				)
			)
		)
		(pad "2" smd custom
			(at 0 0.4445 180)
			(size 0.1524 0.1524)
			(layers "F.Cu" "F.Mask" "F.Paste")
			(net "PCIE_TX_N60")
			(options
				(clearance outline)
				(anchor circle)
			)
			(primitives
				(gr_poly
					(pts
						(arc
							(start 0.3048 -0.2032)
							(mid 0.275042 -0.275042)
							(end 0.2032 -0.3048)
						)
						(arc
							(start -0.2032 -0.3048)
							(mid -0.275042 -0.275042)
							(end -0.3048 -0.2032)
						)
						(arc
							(start -0.3048 0.2032)
							(mid -0.275042 0.275042)
							(end -0.2032 0.3048)
						)
						(arc
							(start 0.2032 0.3048)
							(mid 0.275042 0.275042)
							(end 0.3048 0.2032)
						)
					)
					(width 0)
					(fill yes)
				)
			)
		)
	)
	(footprint ""
		(layer "F.Cu")
		(at 30.607 -117.094)
		(property "Reference" "TP242"
			(at 0 0 0)
			(layer "F.SilkS")
			(hide yes)
			(effects
				(font
					(size 1.27 1.27)
				)
			)
		)
		(property "Value" "TPAD28-2-GP"
			(at -0.0127 -1.6637 0)
			(unlocked yes)
			(layer "F.Fab")
			(hide yes)
			(effects
				(font
					(size 1.016 1.016)
					(thickness 0.1524)
				)
			)
		)
		(property "Device Type" "TPAD28"
			(at -0.0127 -3.1877 0)
			(unlocked yes)
			(layer "F.Fab")
			(hide yes)
			(effects
				(font
					(size 1.016 1.016)
					(thickness 0.1524)
				)
			)
		)
		(duplicate_pad_numbers_are_jumpers no)
		(fp_poly
			(pts
				(arc
					(start 0.3556 0)
					(mid -0.3556 0)
					(end 0.3556 0)
				)
			)
			(stroke
				(width 0)
				(type default)
			)
			(fill no)
			(layer "F.CrtYd")
		)
		(fp_poly
			(pts
				(arc
					(start 0.6096 0)
					(mid -0.6096 0)
					(end 0.6096 0)
				)
			)
			(stroke
				(width 0)
				(type default)
			)
			(fill no)
			(layer "F.Fab")
		)
		(pad "1" smd circle
			(at 0 0)
			(size 0.7112 0.7112)
			(layers "F.Cu" "F.Mask" "F.Paste")
			(net "TP_GPIOD2")
		)
	)
	(footprint ""
		(layer "F.Cu")
		(at 131.0513 -33.54324)
		(property "Reference" "C383"
			(at 0 0 0)
			(layer "F.SilkS")
			(hide yes)
			(effects
				(font
					(size 1.27 1.27)
				)
			)
		)
		(property "Value" "SCD22U10V2KX-1GP"
			(at 1.1811 -2.7051 0)
			(unlocked yes)
			(layer "F.Fab")
			(hide yes)
			(effects
				(font
					(size 1.016 1.016)
					(thickness 0.1524)
				)
			)
		)
		(property "Device Type" "C402H22"
			(at 1.1811 -4.2291 0)
			(unlocked yes)
			(layer "F.Fab")
			(hide yes)
			(effects
				(font
					(size 1.016 1.016)
					(thickness 0.1524)
				)
			)
		)
		(duplicate_pad_numbers_are_jumpers no)
		(fp_rect
			(start -0.4318 0.9525)
			(end 0.4318 -0.9525)
			(stroke
				(width 0)
				(type default)
			)
			(fill no)
			(layer "F.CrtYd")
		)
		(fp_rect
			(start -0.4318 0.9525)
			(end 0.4318 -0.9525)
			(stroke
				(width 0)
				(type default)
			)
			(fill no)
			(layer "F.Fab")
		)
		(pad "1" smd custom
			(at 0 -0.4445)
			(size 0.1524 0.1524)
			(layers "F.Cu" "F.Mask" "F.Paste")
			(net "PCIE_TX_CAP_P81")
			(options
				(clearance outline)
				(anchor circle)
			)
			(primitives
				(gr_poly
					(pts
						(arc
							(start 0.3048 -0.2032)
							(mid 0.275042 -0.275042)
							(end 0.2032 -0.3048)
						)
						(arc
							(start -0.2032 -0.3048)
							(mid -0.275042 -0.275042)
							(end -0.3048 -0.2032)
						)
						(arc
							(start -0.3048 0.2032)
							(mid -0.275042 0.275042)
							(end -0.2032 0.3048)
						)
						(arc
							(start 0.2032 0.3048)
							(mid 0.275042 0.275042)
							(end 0.3048 0.2032)
						)
					)
					(width 0)
					(fill yes)
				)
			)
		)
		(pad "2" smd custom
			(at 0 0.4445)
			(size 0.1524 0.1524)
			(layers "F.Cu" "F.Mask" "F.Paste")
			(net "PCIE_TX_P81")
			(options
				(clearance outline)
				(anchor circle)
			)
			(primitives
				(gr_poly
					(pts
						(arc
							(start 0.3048 -0.2032)
							(mid 0.275042 -0.275042)
							(end 0.2032 -0.3048)
						)
						(arc
							(start -0.2032 -0.3048)
							(mid -0.275042 -0.275042)
							(end -0.3048 -0.2032)
						)
						(arc
							(start -0.3048 0.2032)
							(mid -0.275042 0.275042)
							(end -0.2032 0.3048)
						)
						(arc
							(start 0.2032 0.3048)
							(mid 0.275042 0.275042)
							(end 0.3048 0.2032)
						)
					)
					(width 0)
					(fill yes)
				)
			)
		)
	)
	(footprint ""
		(layer "F.Cu")
		(at 18.288 -154.432)
		(property "Reference" "R8003"
			(at 0 0 0)
			(layer "F.SilkS")
			(hide yes)
			(effects
				(font
					(size 1.27 1.27)
				)
			)
		)
		(property "Value" "0R2J-2-GP"
			(at 0.064008 -3.993896 0)
			(unlocked yes)
			(layer "F.Fab")
			(hide yes)
			(effects
				(font
					(size 1.016 1.016)
					(thickness 0.1524)
				)
			)
		)
		(property "Device Type" "R402H16"
			(at 0.064008 -5.517896 0)
			(unlocked yes)
			(layer "F.Fab")
			(hide yes)
			(effects
				(font
					(size 1.016 1.016)
					(thickness 0.1524)
				)
			)
		)
		(duplicate_pad_numbers_are_jumpers no)
		(fp_line
			(start -0.508 -0.9398)
			(end -0.508 0.9398)
			(stroke
				(width 0.1524)
				(type default)
			)
			(layer "F.SilkS")
		)
		(fp_line
			(start 0.508 -0.9398)
			(end -0.508 -0.9398)
			(stroke
				(width 0.1524)
				(type default)
			)
			(layer "F.SilkS")
		)
		(fp_rect
			(start -0.508 0.9398)
			(end 0.508 -0.9398)
			(stroke
				(width 0)
				(type default)
			)
			(fill no)
			(layer "F.CrtYd")
		)
		(fp_rect
			(start -0.508 0.9398)
			(end 0.508 -0.9398)
			(stroke
				(width 0)
				(type default)
			)
			(fill no)
			(layer "F.Fab")
		)
		(pad "1" smd custom
			(at 0 -0.4445)
			(size 0.1397 0.1397)
			(layers "F.Cu" "F.Mask" "F.Paste")
			(net "FM_BMC_RESET#_BTN_D")
			(options
				(clearance outline)
				(anchor circle)
			)
			(primitives
				(gr_poly
					(pts
						(arc
							(start -0.1778 -0.2794)
							(mid -0.249642 -0.249642)
							(end -0.2794 -0.1778)
						)
						(arc
							(start -0.2794 0.1778)
							(mid -0.249642 0.249642)
							(end -0.1778 0.2794)
						)
						(arc
							(start 0.1778 0.2794)
							(mid 0.249642 0.249642)
							(end 0.2794 0.1778)
						)
						(arc
							(start 0.2794 -0.1778)
							(mid 0.249642 -0.249642)
							(end 0.1778 -0.2794)
						)
					)
					(width 0)
					(fill yes)
				)
			)
		)
		(pad "2" smd custom
			(at 0 0.4445)
			(size 0.1397 0.1397)
			(layers "F.Cu" "F.Mask" "F.Paste")
			(net "FM_BMC_RESET_Q36")
			(options
				(clearance outline)
				(anchor circle)
			)
			(primitives
				(gr_poly
					(pts
						(arc
							(start -0.1778 -0.2794)
							(mid -0.249642 -0.249642)
							(end -0.2794 -0.1778)
						)
						(arc
							(start -0.2794 0.1778)
							(mid -0.249642 0.249642)
							(end -0.1778 0.2794)
						)
						(arc
							(start 0.1778 0.2794)
							(mid 0.249642 0.249642)
							(end 0.2794 0.1778)
						)
						(arc
							(start 0.2794 -0.1778)
							(mid 0.249642 -0.249642)
							(end 0.1778 -0.2794)
						)
					)
					(width 0)
					(fill yes)
				)
			)
		)
	)
	(footprint ""
		(layer "F.Cu")
		(at 346.456 -58.547 90)
		(property "Reference" "PC220"
			(at 0 0 90)
			(layer "F.SilkS")
			(hide yes)
			(effects
				(font
					(size 1.27 1.27)
				)
			)
		)
		(property "Value" "SC22U25V6KX-GP-U"
			(at -2.860802 -5.279644 90)
			(unlocked yes)
			(layer "F.Fab")
			(hide yes)
			(effects
				(font
					(size 1.016 1.016)
					(thickness 0.1524)
				)
			)
		)
		(property "Device Type" "C1206-TO0D3H75"
			(at -2.860802 -6.803644 90)
			(unlocked yes)
			(layer "F.Fab")
			(hide yes)
			(effects
				(font
					(size 1.016 1.016)
					(thickness 0.1524)
				)
			)
		)
		(duplicate_pad_numbers_are_jumpers no)
		(fp_line
			(start 1.3081 -2.3749)
			(end 1.3081 2.3749)
			(stroke
				(width 0.1524)
				(type default)
			)
			(layer "F.SilkS")
		)
		(fp_line
			(start -1.3081 -2.3749)
			(end 1.3081 -2.3749)
			(stroke
				(width 0.1524)
				(type default)
			)
			(layer "F.SilkS")
		)
		(fp_line
			(start 1.3081 2.3749)
			(end -1.3081 2.3749)
			(stroke
				(width 0.1524)
				(type default)
			)
			(layer "F.SilkS")
		)
		(fp_line
			(start -1.3081 2.3749)
			(end -1.3081 -2.3749)
			(stroke
				(width 0.1524)
				(type default)
			)
			(layer "F.SilkS")
		)
		(fp_rect
			(start -0.8001 1.6002)
			(end 0.8001 -1.6002)
			(stroke
				(width 0)
				(type default)
			)
			(fill no)
			(layer "F.CrtYd")
		)
		(fp_poly
			(pts
				(xy -1.5621 2.4511) (xy -1.5621 1.6002) (xy 0.8001 1.6002) (xy 0.8001 -1.6002) (xy -0.8001 -1.6002)
				(xy -0.8001 1.5875) (xy -1.5621 1.5875) (xy -1.5621 -2.4511) (xy 1.5621 -2.4511) (xy 1.5621 2.4511)
			)
			(stroke
				(width 0)
				(type default)
			)
			(fill no)
			(layer "F.CrtYd")
		)
		(fp_rect
			(start -1.5621 2.4511)
			(end 1.5621 -2.4511)
			(stroke
				(width 0)
				(type default)
			)
			(fill no)
			(layer "F.Fab")
		)
		(pad "1" smd rect
			(at 0 -1.392936 90)
			(size 2.1082 1.4478)
			(layers "F.Cu" "F.Mask" "F.Paste")
			(net "P0V9_E_VIN")
		)
		(pad "2" smd rect
			(at 0 1.392936 90)
			(size 2.1082 1.4478)
			(layers "F.Cu" "F.Mask" "F.Paste")
			(net "GND")
		)
	)
	(footprint ""
		(layer "F.Cu")
		(at 294.108378 -33.694116)
		(property "Reference" "C12"
			(at 0 0 0)
			(layer "F.SilkS")
			(hide yes)
			(effects
				(font
					(size 1.27 1.27)
				)
			)
		)
		(property "Value" "SCD22U10V2KX-1GP"
			(at 1.1811 -2.7051 0)
			(unlocked yes)
			(layer "F.Fab")
			(hide yes)
			(effects
				(font
					(size 1.016 1.016)
					(thickness 0.1524)
				)
			)
		)
		(property "Device Type" "C402H22"
			(at 1.1811 -4.2291 0)
			(unlocked yes)
			(layer "F.Fab")
			(hide yes)
			(effects
				(font
					(size 1.016 1.016)
					(thickness 0.1524)
				)
			)
		)
		(duplicate_pad_numbers_are_jumpers no)
		(fp_rect
			(start -0.4318 0.9525)
			(end 0.4318 -0.9525)
			(stroke
				(width 0)
				(type default)
			)
			(fill no)
			(layer "F.CrtYd")
		)
		(fp_rect
			(start -0.4318 0.9525)
			(end 0.4318 -0.9525)
			(stroke
				(width 0)
				(type default)
			)
			(fill no)
			(layer "F.Fab")
		)
		(pad "1" smd custom
			(at 0 -0.4445)
			(size 0.1524 0.1524)
			(layers "F.Cu" "F.Mask" "F.Paste")
			(net "PCIE_TX_CAP_P4")
			(options
				(clearance outline)
				(anchor circle)
			)
			(primitives
				(gr_poly
					(pts
						(arc
							(start 0.3048 -0.2032)
							(mid 0.275042 -0.275042)
							(end 0.2032 -0.3048)
						)
						(arc
							(start -0.2032 -0.3048)
							(mid -0.275042 -0.275042)
							(end -0.3048 -0.2032)
						)
						(arc
							(start -0.3048 0.2032)
							(mid -0.275042 0.275042)
							(end -0.2032 0.3048)
						)
						(arc
							(start 0.2032 0.3048)
							(mid 0.275042 0.275042)
							(end 0.3048 0.2032)
						)
					)
					(width 0)
					(fill yes)
				)
			)
		)
		(pad "2" smd custom
			(at 0 0.4445)
			(size 0.1524 0.1524)
			(layers "F.Cu" "F.Mask" "F.Paste")
			(net "PCIE_TX_P4")
			(options
				(clearance outline)
				(anchor circle)
			)
			(primitives
				(gr_poly
					(pts
						(arc
							(start 0.3048 -0.2032)
							(mid 0.275042 -0.275042)
							(end 0.2032 -0.3048)
						)
						(arc
							(start -0.2032 -0.3048)
							(mid -0.275042 -0.275042)
							(end -0.3048 -0.2032)
						)
						(arc
							(start -0.3048 0.2032)
							(mid -0.275042 0.275042)
							(end -0.2032 0.3048)
						)
						(arc
							(start 0.2032 0.3048)
							(mid 0.275042 0.275042)
							(end 0.3048 0.2032)
						)
					)
					(width 0)
					(fill yes)
				)
			)
		)
	)
	(footprint ""
		(layer "F.Cu")
		(at 25.916128 -120.719596 -90)
		(property "Reference" "TP266"
			(at 0 0 270)
			(layer "F.SilkS")
			(hide yes)
			(effects
				(font
					(size 1.27 1.27)
				)
			)
		)
		(property "Value" "TPAD28-2-GP"
			(at -0.0127 -1.6637 270)
			(unlocked yes)
			(layer "F.Fab")
			(hide yes)
			(effects
				(font
					(size 1.016 1.016)
					(thickness 0.1524)
				)
			)
		)
		(property "Device Type" "TPAD28"
			(at -0.0127 -3.1877 270)
			(unlocked yes)
			(layer "F.Fab")
			(hide yes)
			(effects
				(font
					(size 1.016 1.016)
					(thickness 0.1524)
				)
			)
		)
		(duplicate_pad_numbers_are_jumpers no)
		(fp_poly
			(pts
				(arc
					(start 0 -0.3556)
					(mid 0 0.3556)
					(end 0 -0.3556)
				)
			)
			(stroke
				(width 0)
				(type default)
			)
			(fill no)
			(layer "F.CrtYd")
		)
		(fp_poly
			(pts
				(arc
					(start 0 -0.6096)
					(mid 0 0.6096)
					(end 0 -0.6096)
				)
			)
			(stroke
				(width 0)
				(type default)
			)
			(fill no)
			(layer "F.Fab")
		)
		(pad "1" smd circle
			(at 0 0 270)
			(size 0.7112 0.7112)
			(layers "F.Cu" "F.Mask" "F.Paste")
			(net "TP_GPIOI0")
		)
	)
	(footprint ""
		(layer "F.Cu")
		(at 104.392222 -212.420454 180)
		(property "Reference" "C149"
			(at 0 0 180)
			(layer "F.SilkS")
			(hide yes)
			(effects
				(font
					(size 1.27 1.27)
				)
			)
		)
		(property "Value" "SCD22U10V2KX-1GP"
			(at 1.1811 -2.7051 180)
			(unlocked yes)
			(layer "F.Fab")
			(hide yes)
			(effects
				(font
					(size 1.016 1.016)
					(thickness 0.1524)
				)
			)
		)
		(property "Device Type" "C402H22"
			(at 1.1811 -4.2291 180)
			(unlocked yes)
			(layer "F.Fab")
			(hide yes)
			(effects
				(font
					(size 1.016 1.016)
					(thickness 0.1524)
				)
			)
		)
		(duplicate_pad_numbers_are_jumpers no)
		(fp_rect
			(start -0.4318 0.9525)
			(end 0.4318 -0.9525)
			(stroke
				(width 0)
				(type default)
			)
			(fill no)
			(layer "F.CrtYd")
		)
		(fp_rect
			(start -0.4318 0.9525)
			(end 0.4318 -0.9525)
			(stroke
				(width 0)
				(type default)
			)
			(fill no)
			(layer "F.Fab")
		)
		(pad "1" smd custom
			(at 0 -0.4445 180)
			(size 0.1524 0.1524)
			(layers "F.Cu" "F.Mask" "F.Paste")
			(net "PCIE_TX_CAP_P61")
			(options
				(clearance outline)
				(anchor circle)
			)
			(primitives
				(gr_poly
					(pts
						(arc
							(start 0.3048 -0.2032)
							(mid 0.275042 -0.275042)
							(end 0.2032 -0.3048)
						)
						(arc
							(start -0.2032 -0.3048)
							(mid -0.275042 -0.275042)
							(end -0.3048 -0.2032)
						)
						(arc
							(start -0.3048 0.2032)
							(mid -0.275042 0.275042)
							(end -0.2032 0.3048)
						)
						(arc
							(start 0.2032 0.3048)
							(mid 0.275042 0.275042)
							(end 0.3048 0.2032)
						)
					)
					(width 0)
					(fill yes)
				)
			)
		)
		(pad "2" smd custom
			(at 0 0.4445 180)
			(size 0.1524 0.1524)
			(layers "F.Cu" "F.Mask" "F.Paste")
			(net "PCIE_TX_P61")
			(options
				(clearance outline)
				(anchor circle)
			)
			(primitives
				(gr_poly
					(pts
						(arc
							(start 0.3048 -0.2032)
							(mid 0.275042 -0.275042)
							(end 0.2032 -0.3048)
						)
						(arc
							(start -0.2032 -0.3048)
							(mid -0.275042 -0.275042)
							(end -0.3048 -0.2032)
						)
						(arc
							(start -0.3048 0.2032)
							(mid -0.275042 0.275042)
							(end -0.2032 0.3048)
						)
						(arc
							(start 0.2032 0.3048)
							(mid 0.275042 0.275042)
							(end 0.3048 0.2032)
						)
					)
					(width 0)
					(fill yes)
				)
			)
		)
	)
	(footprint ""
		(layer "F.Cu")
		(at 298.958 -57.0992)
		(property "Reference" "C425"
			(at 0 0 0)
			(layer "F.SilkS")
			(hide yes)
			(effects
				(font
					(size 1.27 1.27)
				)
			)
		)
		(property "Value" "SC10U16V5KX-1-GP"
			(at -0.0762 -6.1214 0)
			(unlocked yes)
			(layer "F.Fab")
			(hide yes)
			(effects
				(font
					(size 1.016 1.016)
					(thickness 0.1524)
				)
			)
		)
		(property "Device Type" "C805H54"
			(at -0.0762 -8.1534 0)
			(unlocked yes)
			(layer "F.Fab")
			(hide yes)
			(effects
				(font
					(size 1.016 1.016)
					(thickness 0.1524)
				)
			)
		)
		(duplicate_pad_numbers_are_jumpers no)
		(fp_line
			(start 0.635 0)
			(end -0.635 0)
			(stroke
				(width 0.508)
				(type default)
			)
			(layer "F.SilkS")
		)
		(fp_rect
			(start -0.9652 1.778)
			(end 0.9652 -1.778)
			(stroke
				(width 0)
				(type default)
			)
			(fill no)
			(layer "F.CrtYd")
		)
		(fp_poly
			(pts
				(xy -0.9652 -1.778) (xy 0.9652 -1.778) (xy 0.9652 1.778) (xy -0.9652 1.778)
			)
			(stroke
				(width 0)
				(type default)
			)
			(fill no)
			(layer "F.Fab")
		)
		(pad "1" smd rect
			(at 0 -0.9652)
			(size 1.397 1.143)
			(layers "F.Cu" "F.Mask" "F.Paste")
			(net "DUT_VDD")
		)
		(pad "2" smd rect
			(at 0 0.9652)
			(size 1.397 1.143)
			(layers "F.Cu" "F.Mask" "F.Paste")
			(net "GND")
		)
	)
	(footprint ""
		(layer "F.Cu")
		(at 8.001 -111.252 180)
		(property "Reference" "PC82"
			(at 0 0 180)
			(layer "F.SilkS")
			(hide yes)
			(effects
				(font
					(size 1.27 1.27)
				)
			)
		)
		(property "Value" "SC22U6D3V5MX-5-GP"
			(at -0.0762 -6.1214 180)
			(unlocked yes)
			(layer "F.Fab")
			(hide yes)
			(effects
				(font
					(size 1.016 1.016)
					(thickness 0.1524)
				)
			)
		)
		(property "Device Type" "C805H56"
			(at -0.0762 -8.1534 180)
			(unlocked yes)
			(layer "F.Fab")
			(hide yes)
			(effects
				(font
					(size 1.016 1.016)
					(thickness 0.1524)
				)
			)
		)
		(duplicate_pad_numbers_are_jumpers no)
		(fp_line
			(start 0.635 0)
			(end -0.635 0)
			(stroke
				(width 0.508)
				(type default)
			)
			(layer "F.SilkS")
		)
		(fp_rect
			(start -0.9652 1.778)
			(end 0.9652 -1.778)
			(stroke
				(width 0)
				(type default)
			)
			(fill no)
			(layer "F.CrtYd")
		)
		(fp_poly
			(pts
				(xy -0.9652 -1.778) (xy 0.9652 -1.778) (xy 0.9652 1.778) (xy -0.9652 1.778)
			)
			(stroke
				(width 0)
				(type default)
			)
			(fill no)
			(layer "F.Fab")
		)
		(pad "1" smd rect
			(at 0 -0.9652 180)
			(size 1.397 1.143)
			(layers "F.Cu" "F.Mask" "F.Paste")
			(net "VR_P1V26_STBY_IN")
		)
		(pad "2" smd rect
			(at 0 0.9652 180)
			(size 1.397 1.143)
			(layers "F.Cu" "F.Mask" "F.Paste")
			(net "GND")
		)
	)
	(footprint ""
		(layer "F.Cu")
		(at 14.5288 -175.8442)
		(property "Reference" "PR39"
			(at 0 0 0)
			(layer "F.SilkS")
			(hide yes)
			(effects
				(font
					(size 1.27 1.27)
				)
			)
		)
		(property "Value" "10KR2F-2-GP"
			(at 0.064008 -3.993896 0)
			(unlocked yes)
			(layer "F.Fab")
			(hide yes)
			(effects
				(font
					(size 1.016 1.016)
					(thickness 0.1524)
				)
			)
		)
		(property "Device Type" "R402H16"
			(at 0.064008 -5.517896 0)
			(unlocked yes)
			(layer "F.Fab")
			(hide yes)
			(effects
				(font
					(size 1.016 1.016)
					(thickness 0.1524)
				)
			)
		)
		(duplicate_pad_numbers_are_jumpers no)
		(fp_line
			(start -0.508 -0.9398)
			(end -0.508 0.9398)
			(stroke
				(width 0.1524)
				(type default)
			)
			(layer "F.SilkS")
		)
		(fp_line
			(start 0.508 -0.9398)
			(end -0.508 -0.9398)
			(stroke
				(width 0.1524)
				(type default)
			)
			(layer "F.SilkS")
		)
		(fp_rect
			(start -0.508 0.9398)
			(end 0.508 -0.9398)
			(stroke
				(width 0)
				(type default)
			)
			(fill no)
			(layer "F.CrtYd")
		)
		(fp_rect
			(start -0.508 0.9398)
			(end 0.508 -0.9398)
			(stroke
				(width 0)
				(type default)
			)
			(fill no)
			(layer "F.Fab")
		)
		(pad "1" smd custom
			(at 0 -0.4445)
			(size 0.1397 0.1397)
			(layers "F.Cu" "F.Mask" "F.Paste")
			(net "GND")
			(options
				(clearance outline)
				(anchor circle)
			)
			(primitives
				(gr_poly
					(pts
						(arc
							(start -0.1778 -0.2794)
							(mid -0.249642 -0.249642)
							(end -0.2794 -0.1778)
						)
						(arc
							(start -0.2794 0.1778)
							(mid -0.249642 0.249642)
							(end -0.1778 0.2794)
						)
						(arc
							(start 0.1778 0.2794)
							(mid 0.249642 0.249642)
							(end 0.2794 0.1778)
						)
						(arc
							(start 0.2794 -0.1778)
							(mid 0.249642 -0.249642)
							(end 0.1778 -0.2794)
						)
					)
					(width 0)
					(fill yes)
				)
			)
		)
		(pad "2" smd custom
			(at 0 0.4445)
			(size 0.1397 0.1397)
			(layers "F.Cu" "F.Mask" "F.Paste")
			(net "TRAY_MBP_CTRL_EN_N")
			(options
				(clearance outline)
				(anchor circle)
			)
			(primitives
				(gr_poly
					(pts
						(arc
							(start -0.1778 -0.2794)
							(mid -0.249642 -0.249642)
							(end -0.2794 -0.1778)
						)
						(arc
							(start -0.2794 0.1778)
							(mid -0.249642 0.249642)
							(end -0.1778 0.2794)
						)
						(arc
							(start 0.1778 0.2794)
							(mid 0.249642 0.249642)
							(end 0.2794 0.1778)
						)
						(arc
							(start 0.2794 -0.1778)
							(mid 0.249642 -0.249642)
							(end 0.1778 -0.2794)
						)
					)
					(width 0)
					(fill yes)
				)
			)
		)
	)
	(footprint ""
		(layer "F.Cu")
		(at 320.675 -86.487 180)
		(property "Reference" "R568"
			(at 0 0 180)
			(layer "F.SilkS")
			(hide yes)
			(effects
				(font
					(size 1.27 1.27)
				)
			)
		)
		(property "Value" "10KR2F-2-GP"
			(at 0.064008 -3.993896 180)
			(unlocked yes)
			(layer "F.Fab")
			(hide yes)
			(effects
				(font
					(size 1.016 1.016)
					(thickness 0.1524)
				)
			)
		)
		(property "Device Type" "R402H16"
			(at 0.064008 -5.517896 180)
			(unlocked yes)
			(layer "F.Fab")
			(hide yes)
			(effects
				(font
					(size 1.016 1.016)
					(thickness 0.1524)
				)
			)
		)
		(duplicate_pad_numbers_are_jumpers no)
		(fp_line
			(start 0.508 -0.9398)
			(end -0.508 -0.9398)
			(stroke
				(width 0.1524)
				(type default)
			)
			(layer "F.SilkS")
		)
		(fp_line
			(start -0.508 -0.9398)
			(end -0.508 0.9398)
			(stroke
				(width 0.1524)
				(type default)
			)
			(layer "F.SilkS")
		)
		(fp_rect
			(start -0.508 0.9398)
			(end 0.508 -0.9398)
			(stroke
				(width 0)
				(type default)
			)
			(fill no)
			(layer "F.CrtYd")
		)
		(fp_rect
			(start -0.508 0.9398)
			(end 0.508 -0.9398)
			(stroke
				(width 0)
				(type default)
			)
			(fill no)
			(layer "F.Fab")
		)
		(pad "1" smd custom
			(at 0 -0.4445 180)
			(size 0.1397 0.1397)
			(layers "F.Cu" "F.Mask" "F.Paste")
			(net "P3V3_STBY")
			(options
				(clearance outline)
				(anchor circle)
			)
			(primitives
				(gr_poly
					(pts
						(arc
							(start -0.1778 -0.2794)
							(mid -0.249642 -0.249642)
							(end -0.2794 -0.1778)
						)
						(arc
							(start -0.2794 0.1778)
							(mid -0.249642 0.249642)
							(end -0.1778 0.2794)
						)
						(arc
							(start 0.1778 0.2794)
							(mid 0.249642 0.249642)
							(end 0.2794 0.1778)
						)
						(arc
							(start 0.2794 -0.1778)
							(mid 0.249642 -0.249642)
							(end 0.1778 -0.2794)
						)
					)
					(width 0)
					(fill yes)
				)
			)
		)
		(pad "2" smd custom
			(at 0 0.4445 180)
			(size 0.1397 0.1397)
			(layers "F.Cu" "F.Mask" "F.Paste")
			(net "IOEXP_PMC1_AD1")
			(options
				(clearance outline)
				(anchor circle)
			)
			(primitives
				(gr_poly
					(pts
						(arc
							(start -0.1778 -0.2794)
							(mid -0.249642 -0.249642)
							(end -0.2794 -0.1778)
						)
						(arc
							(start -0.2794 0.1778)
							(mid -0.249642 0.249642)
							(end -0.1778 0.2794)
						)
						(arc
							(start 0.1778 0.2794)
							(mid 0.249642 0.249642)
							(end 0.2794 0.1778)
						)
						(arc
							(start 0.2794 -0.1778)
							(mid 0.249642 -0.249642)
							(end 0.1778 -0.2794)
						)
					)
					(width 0)
					(fill yes)
				)
			)
		)
	)
	(footprint ""
		(layer "F.Cu")
		(at 41.783 -206.883)
		(property "Reference" "R883"
			(at 0 0 0)
			(layer "F.SilkS")
			(hide yes)
			(effects
				(font
					(size 1.27 1.27)
				)
			)
		)
		(property "Value" "0R2J-2-GP"
			(at 0.064008 -3.993896 0)
			(unlocked yes)
			(layer "F.Fab")
			(hide yes)
			(effects
				(font
					(size 1.016 1.016)
					(thickness 0.1524)
				)
			)
		)
		(property "Device Type" "R402H16"
			(at 0.064008 -5.517896 0)
			(unlocked yes)
			(layer "F.Fab")
			(hide yes)
			(effects
				(font
					(size 1.016 1.016)
					(thickness 0.1524)
				)
			)
		)
		(duplicate_pad_numbers_are_jumpers no)
		(fp_line
			(start -0.508 -0.9398)
			(end -0.508 0.9398)
			(stroke
				(width 0.1524)
				(type default)
			)
			(layer "F.SilkS")
		)
		(fp_line
			(start 0.508 -0.9398)
			(end -0.508 -0.9398)
			(stroke
				(width 0.1524)
				(type default)
			)
			(layer "F.SilkS")
		)
		(fp_rect
			(start -0.508 0.9398)
			(end 0.508 -0.9398)
			(stroke
				(width 0)
				(type default)
			)
			(fill no)
			(layer "F.CrtYd")
		)
		(fp_rect
			(start -0.508 0.9398)
			(end 0.508 -0.9398)
			(stroke
				(width 0)
				(type default)
			)
			(fill no)
			(layer "F.Fab")
		)
		(pad "1" smd custom
			(at 0 -0.4445)
			(size 0.1397 0.1397)
			(layers "F.Cu" "F.Mask" "F.Paste")
			(net "BUF_I2C6_C_FCB_SCL")
			(options
				(clearance outline)
				(anchor circle)
			)
			(primitives
				(gr_poly
					(pts
						(arc
							(start -0.1778 -0.2794)
							(mid -0.249642 -0.249642)
							(end -0.2794 -0.1778)
						)
						(arc
							(start -0.2794 0.1778)
							(mid -0.249642 0.249642)
							(end -0.1778 0.2794)
						)
						(arc
							(start 0.1778 0.2794)
							(mid 0.249642 0.249642)
							(end 0.2794 0.1778)
						)
						(arc
							(start 0.2794 -0.1778)
							(mid 0.249642 -0.249642)
							(end 0.1778 -0.2794)
						)
					)
					(width 0)
					(fill yes)
				)
			)
		)
		(pad "2" smd custom
			(at 0 0.4445)
			(size 0.1397 0.1397)
			(layers "F.Cu" "F.Mask" "F.Paste")
			(net "BUF_I2C6_C_FCB_SCL_R")
			(options
				(clearance outline)
				(anchor circle)
			)
			(primitives
				(gr_poly
					(pts
						(arc
							(start -0.1778 -0.2794)
							(mid -0.249642 -0.249642)
							(end -0.2794 -0.1778)
						)
						(arc
							(start -0.2794 0.1778)
							(mid -0.249642 0.249642)
							(end -0.1778 0.2794)
						)
						(arc
							(start 0.1778 0.2794)
							(mid 0.249642 0.249642)
							(end 0.2794 0.1778)
						)
						(arc
							(start 0.2794 -0.1778)
							(mid 0.249642 -0.249642)
							(end 0.1778 -0.2794)
						)
					)
					(width 0)
					(fill yes)
				)
			)
		)
	)
	(footprint ""
		(layer "F.Cu")
		(at 71.007986 -212.420454 180)
		(property "Reference" "C354"
			(at 0 0 180)
			(layer "F.SilkS")
			(hide yes)
			(effects
				(font
					(size 1.27 1.27)
				)
			)
		)
		(property "Value" "SCD22U10V2KX-1GP"
			(at 1.1811 -2.7051 180)
			(unlocked yes)
			(layer "F.Fab")
			(hide yes)
			(effects
				(font
					(size 1.016 1.016)
					(thickness 0.1524)
				)
			)
		)
		(property "Device Type" "C402H22"
			(at 1.1811 -4.2291 180)
			(unlocked yes)
			(layer "F.Fab")
			(hide yes)
			(effects
				(font
					(size 1.016 1.016)
					(thickness 0.1524)
				)
			)
		)
		(duplicate_pad_numbers_are_jumpers no)
		(fp_rect
			(start -0.4318 0.9525)
			(end 0.4318 -0.9525)
			(stroke
				(width 0)
				(type default)
			)
			(fill no)
			(layer "F.CrtYd")
		)
		(fp_rect
			(start -0.4318 0.9525)
			(end 0.4318 -0.9525)
			(stroke
				(width 0)
				(type default)
			)
			(fill no)
			(layer "F.Fab")
		)
		(pad "1" smd custom
			(at 0 -0.4445 180)
			(size 0.1524 0.1524)
			(layers "F.Cu" "F.Mask" "F.Paste")
			(net "PCIE_TX_CAP_N69")
			(options
				(clearance outline)
				(anchor circle)
			)
			(primitives
				(gr_poly
					(pts
						(arc
							(start 0.3048 -0.2032)
							(mid 0.275042 -0.275042)
							(end 0.2032 -0.3048)
						)
						(arc
							(start -0.2032 -0.3048)
							(mid -0.275042 -0.275042)
							(end -0.3048 -0.2032)
						)
						(arc
							(start -0.3048 0.2032)
							(mid -0.275042 0.275042)
							(end -0.2032 0.3048)
						)
						(arc
							(start 0.2032 0.3048)
							(mid 0.275042 0.275042)
							(end 0.3048 0.2032)
						)
					)
					(width 0)
					(fill yes)
				)
			)
		)
		(pad "2" smd custom
			(at 0 0.4445 180)
			(size 0.1524 0.1524)
			(layers "F.Cu" "F.Mask" "F.Paste")
			(net "PCIE_TX_N69")
			(options
				(clearance outline)
				(anchor circle)
			)
			(primitives
				(gr_poly
					(pts
						(arc
							(start 0.3048 -0.2032)
							(mid 0.275042 -0.275042)
							(end 0.2032 -0.3048)
						)
						(arc
							(start -0.2032 -0.3048)
							(mid -0.275042 -0.275042)
							(end -0.3048 -0.2032)
						)
						(arc
							(start -0.3048 0.2032)
							(mid -0.275042 0.275042)
							(end -0.2032 0.3048)
						)
						(arc
							(start 0.2032 0.3048)
							(mid 0.275042 0.275042)
							(end 0.3048 0.2032)
						)
					)
					(width 0)
					(fill yes)
				)
			)
		)
	)
	(footprint ""
		(layer "F.Cu")
		(at 213.932008 -4.064)
		(property "Reference" "R676"
			(at 0 0 0)
			(layer "F.SilkS")
			(hide yes)
			(effects
				(font
					(size 1.27 1.27)
				)
			)
		)
		(property "Value" "100KR2F-L1-GP"
			(at 0.064008 -3.993896 0)
			(unlocked yes)
			(layer "F.Fab")
			(hide yes)
			(effects
				(font
					(size 1.016 1.016)
					(thickness 0.1524)
				)
			)
		)
		(property "Device Type" "R402H16"
			(at 0.064008 -5.517896 0)
			(unlocked yes)
			(layer "F.Fab")
			(hide yes)
			(effects
				(font
					(size 1.016 1.016)
					(thickness 0.1524)
				)
			)
		)
		(duplicate_pad_numbers_are_jumpers no)
		(fp_line
			(start -0.508 -0.9398)
			(end -0.508 0.9398)
			(stroke
				(width 0.1524)
				(type default)
			)
			(layer "F.SilkS")
		)
		(fp_line
			(start 0.508 -0.9398)
			(end -0.508 -0.9398)
			(stroke
				(width 0.1524)
				(type default)
			)
			(layer "F.SilkS")
		)
		(fp_rect
			(start -0.508 0.9398)
			(end 0.508 -0.9398)
			(stroke
				(width 0)
				(type default)
			)
			(fill no)
			(layer "F.CrtYd")
		)
		(fp_rect
			(start -0.508 0.9398)
			(end 0.508 -0.9398)
			(stroke
				(width 0)
				(type default)
			)
			(fill no)
			(layer "F.Fab")
		)
		(pad "1" smd custom
			(at 0 -0.4445)
			(size 0.1397 0.1397)
			(layers "F.Cu" "F.Mask" "F.Paste")
			(net "HOST3_RST_N")
			(options
				(clearance outline)
				(anchor circle)
			)
			(primitives
				(gr_poly
					(pts
						(arc
							(start -0.1778 -0.2794)
							(mid -0.249642 -0.249642)
							(end -0.2794 -0.1778)
						)
						(arc
							(start -0.2794 0.1778)
							(mid -0.249642 0.249642)
							(end -0.1778 0.2794)
						)
						(arc
							(start 0.1778 0.2794)
							(mid 0.249642 0.249642)
							(end 0.2794 0.1778)
						)
						(arc
							(start 0.2794 -0.1778)
							(mid 0.249642 -0.249642)
							(end 0.1778 -0.2794)
						)
					)
					(width 0)
					(fill yes)
				)
			)
		)
		(pad "2" smd custom
			(at 0 0.4445)
			(size 0.1397 0.1397)
			(layers "F.Cu" "F.Mask" "F.Paste")
			(net "GND")
			(options
				(clearance outline)
				(anchor circle)
			)
			(primitives
				(gr_poly
					(pts
						(arc
							(start -0.1778 -0.2794)
							(mid -0.249642 -0.249642)
							(end -0.2794 -0.1778)
						)
						(arc
							(start -0.2794 0.1778)
							(mid -0.249642 0.249642)
							(end -0.1778 0.2794)
						)
						(arc
							(start 0.1778 0.2794)
							(mid 0.249642 0.249642)
							(end 0.2794 0.1778)
						)
						(arc
							(start 0.2794 -0.1778)
							(mid 0.249642 -0.249642)
							(end 0.1778 -0.2794)
						)
					)
					(width 0)
					(fill yes)
				)
			)
		)
	)
	(footprint ""
		(layer "F.Cu")
		(at 47.7901 -116.89207)
		(property "Reference" "R224"
			(at 0 0 0)
			(layer "F.SilkS")
			(hide yes)
			(effects
				(font
					(size 1.27 1.27)
				)
			)
		)
		(property "Value" "4K7R2F-GP"
			(at 0.064008 -3.993896 0)
			(unlocked yes)
			(layer "F.Fab")
			(hide yes)
			(effects
				(font
					(size 1.016 1.016)
					(thickness 0.1524)
				)
			)
		)
		(property "Device Type" "R402H16"
			(at 0.064008 -5.517896 0)
			(unlocked yes)
			(layer "F.Fab")
			(hide yes)
			(effects
				(font
					(size 1.016 1.016)
					(thickness 0.1524)
				)
			)
		)
		(duplicate_pad_numbers_are_jumpers no)
		(fp_line
			(start -0.508 -0.9398)
			(end -0.508 0.9398)
			(stroke
				(width 0.1524)
				(type default)
			)
			(layer "F.SilkS")
		)
		(fp_line
			(start 0.508 -0.9398)
			(end -0.508 -0.9398)
			(stroke
				(width 0.1524)
				(type default)
			)
			(layer "F.SilkS")
		)
		(fp_rect
			(start -0.508 0.9398)
			(end 0.508 -0.9398)
			(stroke
				(width 0)
				(type default)
			)
			(fill no)
			(layer "F.CrtYd")
		)
		(fp_rect
			(start -0.508 0.9398)
			(end 0.508 -0.9398)
			(stroke
				(width 0)
				(type default)
			)
			(fill no)
			(layer "F.Fab")
		)
		(pad "1" smd custom
			(at 0 -0.4445)
			(size 0.1397 0.1397)
			(layers "F.Cu" "F.Mask" "F.Paste")
			(net "BMC_USB_EN_1")
			(options
				(clearance outline)
				(anchor circle)
			)
			(primitives
				(gr_poly
					(pts
						(arc
							(start -0.1778 -0.2794)
							(mid -0.249642 -0.249642)
							(end -0.2794 -0.1778)
						)
						(arc
							(start -0.2794 0.1778)
							(mid -0.249642 0.249642)
							(end -0.1778 0.2794)
						)
						(arc
							(start 0.1778 0.2794)
							(mid 0.249642 0.249642)
							(end 0.2794 0.1778)
						)
						(arc
							(start 0.2794 -0.1778)
							(mid 0.249642 -0.249642)
							(end 0.1778 -0.2794)
						)
					)
					(width 0)
					(fill yes)
				)
			)
		)
		(pad "2" smd custom
			(at 0 0.4445)
			(size 0.1397 0.1397)
			(layers "F.Cu" "F.Mask" "F.Paste")
			(net "P3V3_STBY")
			(options
				(clearance outline)
				(anchor circle)
			)
			(primitives
				(gr_poly
					(pts
						(arc
							(start -0.1778 -0.2794)
							(mid -0.249642 -0.249642)
							(end -0.2794 -0.1778)
						)
						(arc
							(start -0.2794 0.1778)
							(mid -0.249642 0.249642)
							(end -0.1778 0.2794)
						)
						(arc
							(start 0.1778 0.2794)
							(mid 0.249642 0.249642)
							(end 0.2794 0.1778)
						)
						(arc
							(start 0.2794 -0.1778)
							(mid 0.249642 -0.249642)
							(end 0.1778 -0.2794)
						)
					)
					(width 0)
					(fill yes)
				)
			)
		)
	)
	(footprint ""
		(layer "F.Cu")
		(at 318.77 -54.483)
		(property "Reference" "PTC7"
			(at 0 0 0)
			(layer "F.SilkS")
			(hide yes)
			(effects
				(font
					(size 1.27 1.27)
				)
			)
		)
		(property "Value" "SE470UF2VDM-GP"
			(at 0 -9.6012 0)
			(unlocked yes)
			(layer "F.Fab")
			(hide yes)
			(effects
				(font
					(size 1.016 1.016)
					(thickness 0.1524)
				)
			)
		)
		(property "Device Type" "CT7343H83"
			(at 0 -11.1252 0)
			(unlocked yes)
			(layer "F.Fab")
			(hide yes)
			(effects
				(font
					(size 1.016 1.016)
					(thickness 0.1524)
				)
			)
		)
		(duplicate_pad_numbers_are_jumpers no)
		(fp_line
			(start -2.286 -4.8768)
			(end -2.286 -2.032)
			(stroke
				(width 0.1524)
				(type default)
			)
			(layer "F.SilkS")
		)
		(fp_line
			(start -2.286 4.8768)
			(end -2.286 2.032)
			(stroke
				(width 0.1524)
				(type default)
			)
			(layer "F.SilkS")
		)
		(fp_line
			(start 2.1082 -4.699)
			(end -2.1082 -4.699)
			(stroke
				(width 0.508)
				(type default)
			)
			(layer "F.SilkS")
		)
		(fp_line
			(start 2.286 -4.8768)
			(end -2.286 -4.8768)
			(stroke
				(width 0.1524)
				(type default)
			)
			(layer "F.SilkS")
		)
		(fp_line
			(start 2.286 -2.032)
			(end 2.286 -4.8768)
			(stroke
				(width 0.1524)
				(type default)
			)
			(layer "F.SilkS")
		)
		(fp_line
			(start 2.286 2.032)
			(end 2.286 4.8768)
			(stroke
				(width 0.1524)
				(type default)
			)
			(layer "F.SilkS")
		)
		(fp_line
			(start 2.286 4.8768)
			(end -2.286 4.8768)
			(stroke
				(width 0.1524)
				(type default)
			)
			(layer "F.SilkS")
		)
		(fp_rect
			(start -2.1463 3.6449)
			(end 2.1463 -3.6449)
			(stroke
				(width 0)
				(type default)
			)
			(fill no)
			(layer "F.CrtYd")
		)
		(fp_poly
			(pts
				(xy -2.54 4.953) (xy -2.54 4.2926) (xy -3.81 4.2926) (xy -3.81 -4.2926) (xy -2.54 -4.2926) (xy -2.54 -4.953)
				(xy 2.54 -4.953) (xy 2.54 -4.2926) (xy 3.81 -4.2926) (xy 3.81 -1.6256) (xy 2.1463 -1.6256) (xy 2.1463 -3.6449)
				(xy -2.1463 -3.6449) (xy -2.1463 3.6449) (xy 2.1463 3.6449) (xy 2.1463 -1.6129) (xy 3.81 -1.6129)
				(xy 3.81 4.2926) (xy 2.54 4.2926) (xy 2.54 4.953)
			)
			(stroke
				(width 0)
				(type default)
			)
			(fill no)
			(layer "F.CrtYd")
		)
		(fp_rect
			(start -3.81 4.2926)
			(end -2.54 -4.2926)
			(stroke
				(width 0)
				(type default)
			)
			(fill no)
			(layer "F.Fab")
		)
		(fp_rect
			(start -2.54 4.953)
			(end 2.54 -4.953)
			(stroke
				(width 0)
				(type default)
			)
			(fill no)
			(layer "F.Fab")
		)
		(fp_rect
			(start 2.54 4.2926)
			(end 3.81 -4.2926)
			(stroke
				(width 0)
				(type default)
			)
			(fill no)
			(layer "F.Fab")
		)
		(pad "1" smd rect
			(at 0 -3.1496)
			(size 2.413 2.286)
			(layers "F.Cu" "F.Mask" "F.Paste")
			(net "P0V9_E")
		)
		(pad "2" smd rect
			(at 0 3.1496)
			(size 2.413 2.286)
			(layers "F.Cu" "F.Mask" "F.Paste")
			(net "GND")
		)
		(zone
			(layer "F.Cu")
			(hatch none 0.5)
			(connect_pads
				(clearance 0)
			)
			(min_thickness 0.25)
			(keepout
				(tracks allowed)
				(vias not_allowed)
				(pads allowed)
				(copperpour not_allowed)
				(footprints allowed)
			)
			(placement
				(enabled no)
				(sheetname "")
			)
			(fill
				(thermal_gap 0.5)
				(thermal_bridge_width 0.5)
				(island_removal_mode 0)
			)
			(polygon
				(pts
					(xy 317.2587 -49.8856) (xy 320.2813 -49.8856) (xy 320.2813 -52.7812) (xy 320.2813 -53.1114) (xy 317.2587 -53.1114)
					(xy 317.2587 -52.7812)
				)
			)
		)
		(zone
			(layer "F.Cu")
			(hatch none 0.5)
			(connect_pads
				(clearance 0)
			)
			(min_thickness 0.25)
			(keepout
				(tracks allowed)
				(vias not_allowed)
				(pads allowed)
				(copperpour not_allowed)
				(footprints allowed)
			)
			(placement
				(enabled no)
				(sheetname "")
			)
			(fill
				(thermal_gap 0.5)
				(thermal_bridge_width 0.5)
				(island_removal_mode 0)
			)
			(polygon
				(pts
					(xy 320.2813 -56.1721) (xy 320.2813 -59.0804) (xy 317.2587 -59.0804) (xy 317.2587 -56.1848) (xy 317.2587 -55.8546)
					(xy 320.2813 -55.8546)
				)
			)
		)
	)
	(footprint ""
		(layer "F.Cu")
		(at 88.9 -41.275)
		(property "Reference" "PG8"
			(at 0 0 0)
			(layer "F.SilkS")
			(hide yes)
			(effects
				(font
					(size 1.27 1.27)
				)
			)
		)
		(property "Value" "GAP-CLOSE-PWR-3-GP"
			(at 0.0254 -6.5786 0)
			(unlocked yes)
			(layer "F.Fab")
			(hide yes)
			(effects
				(font
					(size 1.016 1.016)
					(thickness 0.1524)
				)
			)
		)
		(property "Device Type" "GAP-CLOSE-PWR-3"
			(at 0.0254 -8.255 0)
			(unlocked yes)
			(layer "F.Fab")
			(hide yes)
			(effects
				(font
					(size 1.016 1.016)
					(thickness 0.1524)
				)
			)
		)
		(duplicate_pad_numbers_are_jumpers no)
		(fp_rect
			(start -0.7112 0.4572)
			(end 0.7112 -0.4572)
			(stroke
				(width 0)
				(type default)
			)
			(fill no)
			(layer "F.CrtYd")
		)
		(fp_poly
			(pts
				(xy -0.7112 -0.4572) (xy 0.7112 -0.4572) (xy 0.7112 0.4572) (xy -0.7112 0.4572)
			)
			(stroke
				(width 0)
				(type default)
			)
			(fill no)
			(layer "F.Fab")
		)
		(pad "1" smd rect
			(at -0.3048 0)
			(size 0.6604 0.762)
			(layers "F.Cu" "F.Mask" "F.Paste")
			(net "P3V3_PWR")
		)
		(pad "2" smd rect
			(at 0.3048 0)
			(size 0.6604 0.762)
			(layers "F.Cu" "F.Mask" "F.Paste")
			(net "P3V3_STBY")
		)
	)
	(footprint ""
		(layer "F.Cu")
		(at 21.1582 -67.7672 -90)
		(property "Reference" "TP149"
			(at 0 0 270)
			(layer "F.SilkS")
			(hide yes)
			(effects
				(font
					(size 1.27 1.27)
				)
			)
		)
		(property "Value" "TPAD28-2-GP"
			(at -0.0127 -1.6637 270)
			(unlocked yes)
			(layer "F.Fab")
			(hide yes)
			(effects
				(font
					(size 1.016 1.016)
					(thickness 0.1524)
				)
			)
		)
		(property "Device Type" "TPAD28"
			(at -0.0127 -3.1877 270)
			(unlocked yes)
			(layer "F.Fab")
			(hide yes)
			(effects
				(font
					(size 1.016 1.016)
					(thickness 0.1524)
				)
			)
		)
		(duplicate_pad_numbers_are_jumpers no)
		(fp_poly
			(pts
				(arc
					(start 0 -0.3556)
					(mid 0 0.3556)
					(end 0 -0.3556)
				)
			)
			(stroke
				(width 0)
				(type default)
			)
			(fill no)
			(layer "F.CrtYd")
		)
		(fp_poly
			(pts
				(arc
					(start 0 -0.6096)
					(mid 0 0.6096)
					(end 0 -0.6096)
				)
			)
			(stroke
				(width 0)
				(type default)
			)
			(fill no)
			(layer "F.Fab")
		)
		(pad "1" smd circle
			(at 0 0 270)
			(size 0.7112 0.7112)
			(layers "F.Cu" "F.Mask" "F.Paste")
			(net "TP_SDP2")
		)
	)
	(footprint ""
		(layer "F.Cu")
		(at 224.536 -23.241 180)
		(property "Reference" "R3721"
			(at 0 0 180)
			(layer "F.SilkS")
			(hide yes)
			(effects
				(font
					(size 1.27 1.27)
				)
			)
		)
		(property "Value" "4K7R2F-GP"
			(at 0.064008 -3.993896 180)
			(unlocked yes)
			(layer "F.Fab")
			(hide yes)
			(effects
				(font
					(size 1.016 1.016)
					(thickness 0.1524)
				)
			)
		)
		(property "Device Type" "R402H16"
			(at 0.064008 -5.517896 180)
			(unlocked yes)
			(layer "F.Fab")
			(hide yes)
			(effects
				(font
					(size 1.016 1.016)
					(thickness 0.1524)
				)
			)
		)
		(duplicate_pad_numbers_are_jumpers no)
		(fp_line
			(start 0.508 -0.9398)
			(end -0.508 -0.9398)
			(stroke
				(width 0.1524)
				(type default)
			)
			(layer "F.SilkS")
		)
		(fp_line
			(start -0.508 -0.9398)
			(end -0.508 0.9398)
			(stroke
				(width 0.1524)
				(type default)
			)
			(layer "F.SilkS")
		)
		(fp_rect
			(start -0.508 0.9398)
			(end 0.508 -0.9398)
			(stroke
				(width 0)
				(type default)
			)
			(fill no)
			(layer "F.CrtYd")
		)
		(fp_rect
			(start -0.508 0.9398)
			(end 0.508 -0.9398)
			(stroke
				(width 0)
				(type default)
			)
			(fill no)
			(layer "F.Fab")
		)
		(pad "1" smd custom
			(at 0 -0.4445 180)
			(size 0.1397 0.1397)
			(layers "F.Cu" "F.Mask" "F.Paste")
			(net "HOST6_RST_N_LS")
			(options
				(clearance outline)
				(anchor circle)
			)
			(primitives
				(gr_poly
					(pts
						(arc
							(start -0.1778 -0.2794)
							(mid -0.249642 -0.249642)
							(end -0.2794 -0.1778)
						)
						(arc
							(start -0.2794 0.1778)
							(mid -0.249642 0.249642)
							(end -0.1778 0.2794)
						)
						(arc
							(start 0.1778 0.2794)
							(mid 0.249642 0.249642)
							(end 0.2794 0.1778)
						)
						(arc
							(start 0.2794 -0.1778)
							(mid 0.249642 -0.249642)
							(end 0.1778 -0.2794)
						)
					)
					(width 0)
					(fill yes)
				)
			)
		)
		(pad "2" smd custom
			(at 0 0.4445 180)
			(size 0.1397 0.1397)
			(layers "F.Cu" "F.Mask" "F.Paste")
			(net "GND")
			(options
				(clearance outline)
				(anchor circle)
			)
			(primitives
				(gr_poly
					(pts
						(arc
							(start -0.1778 -0.2794)
							(mid -0.249642 -0.249642)
							(end -0.2794 -0.1778)
						)
						(arc
							(start -0.2794 0.1778)
							(mid -0.249642 0.249642)
							(end -0.1778 0.2794)
						)
						(arc
							(start 0.1778 0.2794)
							(mid 0.249642 0.249642)
							(end 0.2794 0.1778)
						)
						(arc
							(start 0.2794 -0.1778)
							(mid 0.249642 -0.249642)
							(end 0.1778 -0.2794)
						)
					)
					(width 0)
					(fill yes)
				)
			)
		)
	)
	(footprint ""
		(layer "F.Cu")
		(at 160.528 -85.2424)
		(property "Reference" "R77"
			(at 0 0 0)
			(layer "F.SilkS")
			(hide yes)
			(effects
				(font
					(size 1.27 1.27)
				)
			)
		)
		(property "Value" "0R2J-2-GP"
			(at 0.064008 -3.993896 0)
			(unlocked yes)
			(layer "F.Fab")
			(hide yes)
			(effects
				(font
					(size 1.016 1.016)
					(thickness 0.1524)
				)
			)
		)
		(property "Device Type" "R402H16"
			(at 0.064008 -5.517896 0)
			(unlocked yes)
			(layer "F.Fab")
			(hide yes)
			(effects
				(font
					(size 1.016 1.016)
					(thickness 0.1524)
				)
			)
		)
		(duplicate_pad_numbers_are_jumpers no)
		(fp_line
			(start -0.508 -0.9398)
			(end -0.508 0.9398)
			(stroke
				(width 0.1524)
				(type default)
			)
			(layer "F.SilkS")
		)
		(fp_line
			(start 0.508 -0.9398)
			(end -0.508 -0.9398)
			(stroke
				(width 0.1524)
				(type default)
			)
			(layer "F.SilkS")
		)
		(fp_rect
			(start -0.508 0.9398)
			(end 0.508 -0.9398)
			(stroke
				(width 0)
				(type default)
			)
			(fill no)
			(layer "F.CrtYd")
		)
		(fp_rect
			(start -0.508 0.9398)
			(end 0.508 -0.9398)
			(stroke
				(width 0)
				(type default)
			)
			(fill no)
			(layer "F.Fab")
		)
		(pad "1" smd custom
			(at 0 -0.4445)
			(size 0.1397 0.1397)
			(layers "F.Cu" "F.Mask" "F.Paste")
			(net "PCIE_CLKGEN2_OE0_R")
			(options
				(clearance outline)
				(anchor circle)
			)
			(primitives
				(gr_poly
					(pts
						(arc
							(start -0.1778 -0.2794)
							(mid -0.249642 -0.249642)
							(end -0.2794 -0.1778)
						)
						(arc
							(start -0.2794 0.1778)
							(mid -0.249642 0.249642)
							(end -0.1778 0.2794)
						)
						(arc
							(start 0.1778 0.2794)
							(mid 0.249642 0.249642)
							(end 0.2794 0.1778)
						)
						(arc
							(start 0.2794 -0.1778)
							(mid 0.249642 -0.249642)
							(end 0.1778 -0.2794)
						)
					)
					(width 0)
					(fill yes)
				)
			)
		)
		(pad "2" smd custom
			(at 0 0.4445)
			(size 0.1397 0.1397)
			(layers "F.Cu" "F.Mask" "F.Paste")
			(net "PCIE_CLKGEN2_OE0")
			(options
				(clearance outline)
				(anchor circle)
			)
			(primitives
				(gr_poly
					(pts
						(arc
							(start -0.1778 -0.2794)
							(mid -0.249642 -0.249642)
							(end -0.2794 -0.1778)
						)
						(arc
							(start -0.2794 0.1778)
							(mid -0.249642 0.249642)
							(end -0.1778 0.2794)
						)
						(arc
							(start 0.1778 0.2794)
							(mid 0.249642 0.249642)
							(end 0.2794 0.1778)
						)
						(arc
							(start 0.2794 -0.1778)
							(mid 0.249642 -0.249642)
							(end 0.1778 -0.2794)
						)
					)
					(width 0)
					(fill yes)
				)
			)
		)
	)
	(footprint ""
		(layer "F.Cu")
		(at 212.6234 -26.8224 -90)
		(property "Reference" "R749"
			(at 0 0 270)
			(layer "F.SilkS")
			(hide yes)
			(effects
				(font
					(size 1.27 1.27)
				)
			)
		)
		(property "Value" "0R2J-2-GP"
			(at 0.064008 -3.993896 270)
			(unlocked yes)
			(layer "F.Fab")
			(hide yes)
			(effects
				(font
					(size 1.016 1.016)
					(thickness 0.1524)
				)
			)
		)
		(property "Device Type" "R402H16"
			(at 0.064008 -5.517896 270)
			(unlocked yes)
			(layer "F.Fab")
			(hide yes)
			(effects
				(font
					(size 1.016 1.016)
					(thickness 0.1524)
				)
			)
		)
		(duplicate_pad_numbers_are_jumpers no)
		(fp_line
			(start -0.508 -0.9398)
			(end -0.508 0.9398)
			(stroke
				(width 0.1524)
				(type default)
			)
			(layer "F.SilkS")
		)
		(fp_line
			(start 0.508 -0.9398)
			(end -0.508 -0.9398)
			(stroke
				(width 0.1524)
				(type default)
			)
			(layer "F.SilkS")
		)
		(fp_rect
			(start -0.508 0.9398)
			(end 0.508 -0.9398)
			(stroke
				(width 0)
				(type default)
			)
			(fill no)
			(layer "F.CrtYd")
		)
		(fp_rect
			(start -0.508 0.9398)
			(end 0.508 -0.9398)
			(stroke
				(width 0)
				(type default)
			)
			(fill no)
			(layer "F.Fab")
		)
		(pad "1" smd custom
			(at 0 -0.4445 270)
			(size 0.1397 0.1397)
			(layers "F.Cu" "F.Mask" "F.Paste")
			(net "DUT_TAP_SEL_R")
			(options
				(clearance outline)
				(anchor circle)
			)
			(primitives
				(gr_poly
					(pts
						(arc
							(start -0.1778 -0.2794)
							(mid -0.249642 -0.249642)
							(end -0.2794 -0.1778)
						)
						(arc
							(start -0.2794 0.1778)
							(mid -0.249642 0.249642)
							(end -0.1778 0.2794)
						)
						(arc
							(start 0.1778 0.2794)
							(mid 0.249642 0.249642)
							(end 0.2794 0.1778)
						)
						(arc
							(start 0.2794 -0.1778)
							(mid 0.249642 -0.249642)
							(end 0.1778 -0.2794)
						)
					)
					(width 0)
					(fill yes)
				)
			)
		)
		(pad "2" smd custom
			(at 0 0.4445 270)
			(size 0.1397 0.1397)
			(layers "F.Cu" "F.Mask" "F.Paste")
			(net "DUT_TAP_SEL")
			(options
				(clearance outline)
				(anchor circle)
			)
			(primitives
				(gr_poly
					(pts
						(arc
							(start -0.1778 -0.2794)
							(mid -0.249642 -0.249642)
							(end -0.2794 -0.1778)
						)
						(arc
							(start -0.2794 0.1778)
							(mid -0.249642 0.249642)
							(end -0.1778 0.2794)
						)
						(arc
							(start 0.1778 0.2794)
							(mid 0.249642 0.249642)
							(end 0.2794 0.1778)
						)
						(arc
							(start 0.2794 -0.1778)
							(mid 0.249642 -0.249642)
							(end 0.1778 -0.2794)
						)
					)
					(width 0)
					(fill yes)
				)
			)
		)
	)
	(footprint ""
		(layer "F.Cu")
		(at 16.889476 -141.456664)
		(property "Reference" "TP181"
			(at 0 0 0)
			(layer "F.SilkS")
			(hide yes)
			(effects
				(font
					(size 1.27 1.27)
				)
			)
		)
		(property "Value" "TPAD28-2-GP"
			(at -0.0127 -1.6637 0)
			(unlocked yes)
			(layer "F.Fab")
			(hide yes)
			(effects
				(font
					(size 1.016 1.016)
					(thickness 0.1524)
				)
			)
		)
		(property "Device Type" "TPAD28"
			(at -0.0127 -3.1877 0)
			(unlocked yes)
			(layer "F.Fab")
			(hide yes)
			(effects
				(font
					(size 1.016 1.016)
					(thickness 0.1524)
				)
			)
		)
		(duplicate_pad_numbers_are_jumpers no)
		(fp_poly
			(pts
				(arc
					(start 0.3556 0)
					(mid -0.3556 0)
					(end 0.3556 0)
				)
			)
			(stroke
				(width 0)
				(type default)
			)
			(fill no)
			(layer "F.CrtYd")
		)
		(fp_poly
			(pts
				(arc
					(start 0.6096 0)
					(mid -0.6096 0)
					(end 0.6096 0)
				)
			)
			(stroke
				(width 0)
				(type default)
			)
			(fill no)
			(layer "F.Fab")
		)
		(pad "1" smd circle
			(at 0 0)
			(size 0.7112 0.7112)
			(layers "F.Cu" "F.Mask" "F.Paste")
			(net "FM_BMC_RESET_N")
		)
	)
	(footprint ""
		(layer "F.Cu")
		(at 41.739058 -113.721134 90)
		(property "Reference" "R156"
			(at 0 0 90)
			(layer "F.SilkS")
			(hide yes)
			(effects
				(font
					(size 1.27 1.27)
				)
			)
		)
		(property "Value" "4K7R2F-GP"
			(at 0.064008 -3.993896 90)
			(unlocked yes)
			(layer "F.Fab")
			(hide yes)
			(effects
				(font
					(size 1.016 1.016)
					(thickness 0.1524)
				)
			)
		)
		(property "Device Type" "R402H16"
			(at 0.064008 -5.517896 90)
			(unlocked yes)
			(layer "F.Fab")
			(hide yes)
			(effects
				(font
					(size 1.016 1.016)
					(thickness 0.1524)
				)
			)
		)
		(duplicate_pad_numbers_are_jumpers no)
		(fp_line
			(start 0.508 -0.9398)
			(end -0.508 -0.9398)
			(stroke
				(width 0.1524)
				(type default)
			)
			(layer "F.SilkS")
		)
		(fp_line
			(start -0.508 -0.9398)
			(end -0.508 0.9398)
			(stroke
				(width 0.1524)
				(type default)
			)
			(layer "F.SilkS")
		)
		(fp_rect
			(start -0.508 0.9398)
			(end 0.508 -0.9398)
			(stroke
				(width 0)
				(type default)
			)
			(fill no)
			(layer "F.CrtYd")
		)
		(fp_rect
			(start -0.508 0.9398)
			(end 0.508 -0.9398)
			(stroke
				(width 0)
				(type default)
			)
			(fill no)
			(layer "F.Fab")
		)
		(pad "1" smd custom
			(at 0 -0.4445 90)
			(size 0.1397 0.1397)
			(layers "F.Cu" "F.Mask" "F.Paste")
			(net "BMC_ID_LED")
			(options
				(clearance outline)
				(anchor circle)
			)
			(primitives
				(gr_poly
					(pts
						(arc
							(start -0.1778 -0.2794)
							(mid -0.249642 -0.249642)
							(end -0.2794 -0.1778)
						)
						(arc
							(start -0.2794 0.1778)
							(mid -0.249642 0.249642)
							(end -0.1778 0.2794)
						)
						(arc
							(start 0.1778 0.2794)
							(mid 0.249642 0.249642)
							(end 0.2794 0.1778)
						)
						(arc
							(start 0.2794 -0.1778)
							(mid 0.249642 -0.249642)
							(end 0.1778 -0.2794)
						)
					)
					(width 0)
					(fill yes)
				)
			)
		)
		(pad "2" smd custom
			(at 0 0.4445 90)
			(size 0.1397 0.1397)
			(layers "F.Cu" "F.Mask" "F.Paste")
			(net "P3V3_STBY")
			(options
				(clearance outline)
				(anchor circle)
			)
			(primitives
				(gr_poly
					(pts
						(arc
							(start -0.1778 -0.2794)
							(mid -0.249642 -0.249642)
							(end -0.2794 -0.1778)
						)
						(arc
							(start -0.2794 0.1778)
							(mid -0.249642 0.249642)
							(end -0.1778 0.2794)
						)
						(arc
							(start 0.1778 0.2794)
							(mid 0.249642 0.249642)
							(end 0.2794 0.1778)
						)
						(arc
							(start 0.2794 -0.1778)
							(mid 0.249642 -0.249642)
							(end 0.1778 -0.2794)
						)
					)
					(width 0)
					(fill yes)
				)
			)
		)
	)
	(footprint ""
		(layer "F.Cu")
		(at 27.494738 -95.226124 180)
		(property "Reference" "Q41"
			(at 0 0 180)
			(layer "F.SilkS")
			(hide yes)
			(effects
				(font
					(size 1.27 1.27)
				)
			)
		)
		(property "Value" "TMBT3904-GP"
			(at 0.10287 -10.29843 180)
			(unlocked yes)
			(layer "F.Fab")
			(hide yes)
			(effects
				(font
					(size 1.016 1.016)
					(thickness 0.1524)
				)
			)
		)
		(property "Device Type" "SOT23CBE2D4H44"
			(at 0.10287 -12.20343 180)
			(unlocked yes)
			(layer "F.Fab")
			(hide yes)
			(effects
				(font
					(size 1.016 1.016)
					(thickness 0.1524)
				)
			)
		)
		(duplicate_pad_numbers_are_jumpers no)
		(fp_line
			(start 1.651 1.778)
			(end 1.651 -1.778)
			(stroke
				(width 0.1524)
				(type default)
			)
			(layer "F.SilkS")
		)
		(fp_line
			(start 1.651 -1.778)
			(end -1.651 -1.778)
			(stroke
				(width 0.1524)
				(type default)
			)
			(layer "F.SilkS")
		)
		(fp_line
			(start -1.651 1.778)
			(end 1.651 1.778)
			(stroke
				(width 0.1524)
				(type default)
			)
			(layer "F.SilkS")
		)
		(fp_line
			(start -1.651 -1.778)
			(end -1.651 1.778)
			(stroke
				(width 0.1524)
				(type default)
			)
			(layer "F.SilkS")
		)
		(fp_poly
			(pts
				(xy -1.778 1.8796) (xy -1.778 -1.8796) (xy 1.778 -1.8796) (xy 1.778 1.8796)
			)
			(stroke
				(width 0)
				(type default)
			)
			(fill no)
			(layer "F.CrtYd")
		)
		(fp_poly
			(pts
				(xy -1.778 1.8796) (xy -1.778 -1.8796) (xy 1.778 -1.8796) (xy 1.778 1.8796)
			)
			(stroke
				(width 0)
				(type default)
			)
			(fill no)
			(layer "F.Fab")
		)
		(pad "B" smd custom
			(at -0.98425 0.9525 180)
			(size 0.1905 0.1905)
			(layers "F.Cu" "F.Mask" "F.Paste")
			(net "FM_TPM_PRES_RST")
			(options
				(clearance outline)
				(anchor circle)
			)
			(primitives
				(gr_poly
					(pts
						(arc
							(start -0.1778 0.5715)
							(mid -0.321484 0.511984)
							(end -0.381 0.3683)
						)
						(arc
							(start -0.381 -0.3683)
							(mid -0.321484 -0.511984)
							(end -0.1778 -0.5715)
						)
						(arc
							(start 0.1778 -0.5715)
							(mid 0.321484 -0.511984)
							(end 0.381 -0.3683)
						)
						(arc
							(start 0.381 0.3683)
							(mid 0.321484 0.511984)
							(end 0.1778 0.5715)
						)
					)
					(width 0)
					(fill yes)
				)
			)
		)
		(pad "C" smd custom
			(at 0 -0.9525 180)
			(size 0.1905 0.1905)
			(layers "F.Cu" "F.Mask" "F.Paste")
			(net "RST_BMC_EXTRST_N")
			(options
				(clearance outline)
				(anchor circle)
			)
			(primitives
				(gr_poly
					(pts
						(arc
							(start -0.1778 0.5715)
							(mid -0.321484 0.511984)
							(end -0.381 0.3683)
						)
						(arc
							(start -0.381 -0.3683)
							(mid -0.321484 -0.511984)
							(end -0.1778 -0.5715)
						)
						(arc
							(start 0.1778 -0.5715)
							(mid 0.321484 -0.511984)
							(end 0.381 -0.3683)
						)
						(arc
							(start 0.381 0.3683)
							(mid 0.321484 0.511984)
							(end 0.1778 0.5715)
						)
					)
					(width 0)
					(fill yes)
				)
			)
		)
		(pad "E" smd custom
			(at 0.98425 0.9525 180)
			(size 0.1905 0.1905)
			(layers "F.Cu" "F.Mask" "F.Paste")
			(net "GND")
			(options
				(clearance outline)
				(anchor circle)
			)
			(primitives
				(gr_poly
					(pts
						(arc
							(start -0.1778 0.5715)
							(mid -0.321484 0.511984)
							(end -0.381 0.3683)
						)
						(arc
							(start -0.381 -0.3683)
							(mid -0.321484 -0.511984)
							(end -0.1778 -0.5715)
						)
						(arc
							(start 0.1778 -0.5715)
							(mid 0.321484 -0.511984)
							(end 0.381 -0.3683)
						)
						(arc
							(start 0.381 0.3683)
							(mid 0.321484 0.511984)
							(end 0.1778 0.5715)
						)
					)
					(width 0)
					(fill yes)
				)
			)
		)
	)
	(footprint ""
		(layer "F.Cu")
		(at 145.177002 -73.306432 -90)
		(property "Reference" "PC196"
			(at 0 0 270)
			(layer "F.SilkS")
			(hide yes)
			(effects
				(font
					(size 1.27 1.27)
				)
			)
		)
		(property "Value" "SC22U25V6KX-GP-U"
			(at -2.860802 -5.279644 270)
			(unlocked yes)
			(layer "F.Fab")
			(hide yes)
			(effects
				(font
					(size 1.016 1.016)
					(thickness 0.1524)
				)
			)
		)
		(property "Device Type" "C1206-TO0D3H75"
			(at -2.860802 -6.803644 270)
			(unlocked yes)
			(layer "F.Fab")
			(hide yes)
			(effects
				(font
					(size 1.016 1.016)
					(thickness 0.1524)
				)
			)
		)
		(duplicate_pad_numbers_are_jumpers no)
		(fp_line
			(start -1.3081 2.3749)
			(end -1.3081 -2.3749)
			(stroke
				(width 0.1524)
				(type default)
			)
			(layer "F.SilkS")
		)
		(fp_line
			(start 1.3081 2.3749)
			(end -1.3081 2.3749)
			(stroke
				(width 0.1524)
				(type default)
			)
			(layer "F.SilkS")
		)
		(fp_line
			(start -1.3081 -2.3749)
			(end 1.3081 -2.3749)
			(stroke
				(width 0.1524)
				(type default)
			)
			(layer "F.SilkS")
		)
		(fp_line
			(start 1.3081 -2.3749)
			(end 1.3081 2.3749)
			(stroke
				(width 0.1524)
				(type default)
			)
			(layer "F.SilkS")
		)
		(fp_rect
			(start -0.8001 1.6002)
			(end 0.8001 -1.6002)
			(stroke
				(width 0)
				(type default)
			)
			(fill no)
			(layer "F.CrtYd")
		)
		(fp_poly
			(pts
				(xy -1.5621 2.4511) (xy -1.5621 1.6002) (xy 0.8001 1.6002) (xy 0.8001 -1.6002) (xy -0.8001 -1.6002)
				(xy -0.8001 1.5875) (xy -1.5621 1.5875) (xy -1.5621 -2.4511) (xy 1.5621 -2.4511) (xy 1.5621 2.4511)
			)
			(stroke
				(width 0)
				(type default)
			)
			(fill no)
			(layer "F.CrtYd")
		)
		(fp_rect
			(start -1.5621 2.4511)
			(end 1.5621 -2.4511)
			(stroke
				(width 0)
				(type default)
			)
			(fill no)
			(layer "F.Fab")
		)
		(pad "1" smd rect
			(at 0 -1.392936 270)
			(size 2.1082 1.4478)
			(layers "F.Cu" "F.Mask" "F.Paste")
			(net "P0V9_VIN")
		)
		(pad "2" smd rect
			(at 0 1.392936 270)
			(size 2.1082 1.4478)
			(layers "F.Cu" "F.Mask" "F.Paste")
			(net "GND")
		)
	)
	(footprint ""
		(layer "F.Cu")
		(at 125.599952 -13.999972 90)
		(property "Reference" "LED9"
			(at 0 0 90)
			(layer "F.SilkS")
			(hide yes)
			(effects
				(font
					(size 1.27 1.27)
				)
			)
		)
		(property "Value" "LED-YG-51-GP"
			(at -2.6924 -1.4224 90)
			(unlocked yes)
			(layer "F.Fab")
			(hide yes)
			(effects
				(font
					(size 1.016 1.016)
					(thickness 0.1524)
				)
			)
		)
		(property "Device Type" "LED1608AKH40"
			(at -2.6924 -2.9464 90)
			(unlocked yes)
			(layer "F.Fab")
			(hide yes)
			(effects
				(font
					(size 1.016 1.016)
					(thickness 0.1524)
				)
			)
		)
		(duplicate_pad_numbers_are_jumpers no)
		(fp_line
			(start 0.6604 -1.3716)
			(end 0.6604 1.3716)
			(stroke
				(width 0.1524)
				(type default)
			)
			(layer "F.SilkS")
		)
		(fp_line
			(start -0.6604 -1.3716)
			(end 0.6604 -1.3716)
			(stroke
				(width 0.1524)
				(type default)
			)
			(layer "F.SilkS")
		)
		(fp_line
			(start 0.6604 1.3716)
			(end -0.6604 1.3716)
			(stroke
				(width 0.1524)
				(type default)
			)
			(layer "F.SilkS")
		)
		(fp_line
			(start -0.6604 1.3716)
			(end -0.6604 -1.3716)
			(stroke
				(width 0.1524)
				(type default)
			)
			(layer "F.SilkS")
		)
		(fp_line
			(start -0.5969 1.5494)
			(end 0.5842 1.5494)
			(stroke
				(width 0.508)
				(type default)
			)
			(layer "F.SilkS")
		)
		(fp_line
			(start 0.7493 1.651)
			(end 0.7493 1.1811)
			(stroke
				(width 0.3302)
				(type default)
			)
			(layer "F.SilkS")
		)
		(fp_line
			(start -0.7493 1.651)
			(end -0.7493 1.1811)
			(stroke
				(width 0.3302)
				(type default)
			)
			(layer "F.SilkS")
		)
		(fp_rect
			(start -0.6223 1.3335)
			(end 0.6223 -1.3335)
			(stroke
				(width 0)
				(type default)
			)
			(fill no)
			(layer "F.CrtYd")
		)
		(fp_rect
			(start -0.6223 1.3335)
			(end 0.6223 -1.3335)
			(stroke
				(width 0)
				(type default)
			)
			(fill no)
			(layer "F.Fab")
		)
		(pad "A" smd custom
			(at 0 -0.762 90)
			(size 0.2159 0.2159)
			(layers "F.Cu" "F.Mask" "F.Paste")
			(net "LED_R_2")
			(options
				(clearance outline)
				(anchor circle)
			)
			(primitives
				(gr_poly
					(pts
						(arc
							(start -0.3302 -0.4318)
							(mid -0.402042 -0.402042)
							(end -0.4318 -0.3302)
						)
						(arc
							(start -0.4318 0.3302)
							(mid -0.402042 0.402042)
							(end -0.3302 0.4318)
						)
						(arc
							(start 0.3302 0.4318)
							(mid 0.402042 0.402042)
							(end 0.4318 0.3302)
						)
						(arc
							(start 0.4318 -0.3302)
							(mid 0.402042 -0.402042)
							(end 0.3302 -0.4318)
						)
					)
					(width 0)
					(fill yes)
				)
			)
		)
		(pad "K" smd custom
			(at 0 0.762 90)
			(size 0.2159 0.2159)
			(layers "F.Cu" "F.Mask" "F.Paste")
			(net "LED_Q_2")
			(options
				(clearance outline)
				(anchor circle)
			)
			(primitives
				(gr_poly
					(pts
						(arc
							(start -0.3302 -0.4318)
							(mid -0.402042 -0.402042)
							(end -0.4318 -0.3302)
						)
						(arc
							(start -0.4318 0.3302)
							(mid -0.402042 0.402042)
							(end -0.3302 0.4318)
						)
						(arc
							(start 0.3302 0.4318)
							(mid 0.402042 0.402042)
							(end 0.4318 0.3302)
						)
						(arc
							(start 0.4318 -0.3302)
							(mid 0.402042 -0.402042)
							(end 0.3302 -0.4318)
						)
					)
					(width 0)
					(fill yes)
				)
			)
		)
	)
	(footprint ""
		(layer "F.Cu")
		(at 181.61 -22.479 -90)
		(property "Reference" "C404"
			(at 0 0 270)
			(layer "F.SilkS")
			(hide yes)
			(effects
				(font
					(size 1.27 1.27)
				)
			)
		)
		(property "Value" "SCD22U10V2KX-1GP"
			(at 1.1811 -2.7051 270)
			(unlocked yes)
			(layer "F.Fab")
			(hide yes)
			(effects
				(font
					(size 1.016 1.016)
					(thickness 0.1524)
				)
			)
		)
		(property "Device Type" "C402H22"
			(at 1.1811 -4.2291 270)
			(unlocked yes)
			(layer "F.Fab")
			(hide yes)
			(effects
				(font
					(size 1.016 1.016)
					(thickness 0.1524)
				)
			)
		)
		(duplicate_pad_numbers_are_jumpers no)
		(fp_rect
			(start -0.4318 0.9525)
			(end 0.4318 -0.9525)
			(stroke
				(width 0)
				(type default)
			)
			(fill no)
			(layer "F.CrtYd")
		)
		(fp_rect
			(start -0.4318 0.9525)
			(end 0.4318 -0.9525)
			(stroke
				(width 0)
				(type default)
			)
			(fill no)
			(layer "F.Fab")
		)
		(pad "1" smd custom
			(at 0 -0.4445 270)
			(size 0.1524 0.1524)
			(layers "F.Cu" "F.Mask" "F.Paste")
			(net "PCIE_TX_CAP_P92")
			(options
				(clearance outline)
				(anchor circle)
			)
			(primitives
				(gr_poly
					(pts
						(arc
							(start 0.3048 -0.2032)
							(mid 0.275042 -0.275042)
							(end 0.2032 -0.3048)
						)
						(arc
							(start -0.2032 -0.3048)
							(mid -0.275042 -0.275042)
							(end -0.3048 -0.2032)
						)
						(arc
							(start -0.3048 0.2032)
							(mid -0.275042 0.275042)
							(end -0.2032 0.3048)
						)
						(arc
							(start 0.2032 0.3048)
							(mid 0.275042 0.275042)
							(end 0.3048 0.2032)
						)
					)
					(width 0)
					(fill yes)
				)
			)
		)
		(pad "2" smd custom
			(at 0 0.4445 270)
			(size 0.1524 0.1524)
			(layers "F.Cu" "F.Mask" "F.Paste")
			(net "PCIE_TX_P92")
			(options
				(clearance outline)
				(anchor circle)
			)
			(primitives
				(gr_poly
					(pts
						(arc
							(start 0.3048 -0.2032)
							(mid 0.275042 -0.275042)
							(end 0.2032 -0.3048)
						)
						(arc
							(start -0.2032 -0.3048)
							(mid -0.275042 -0.275042)
							(end -0.3048 -0.2032)
						)
						(arc
							(start -0.3048 0.2032)
							(mid -0.275042 0.275042)
							(end -0.2032 0.3048)
						)
						(arc
							(start 0.2032 0.3048)
							(mid 0.275042 0.275042)
							(end 0.3048 0.2032)
						)
					)
					(width 0)
					(fill yes)
				)
			)
		)
	)
	(footprint ""
		(layer "F.Cu")
		(at 64.52108 -147.670774 -90)
		(property "Reference" "R200"
			(at 0 0 270)
			(layer "F.SilkS")
			(hide yes)
			(effects
				(font
					(size 1.27 1.27)
				)
			)
		)
		(property "Value" "8K2R2J-3-GP"
			(at 0.064008 -3.993896 270)
			(unlocked yes)
			(layer "F.Fab")
			(hide yes)
			(effects
				(font
					(size 1.016 1.016)
					(thickness 0.1524)
				)
			)
		)
		(property "Device Type" "R402H16"
			(at 0.064008 -5.517896 270)
			(unlocked yes)
			(layer "F.Fab")
			(hide yes)
			(effects
				(font
					(size 1.016 1.016)
					(thickness 0.1524)
				)
			)
		)
		(duplicate_pad_numbers_are_jumpers no)
		(fp_line
			(start -0.508 -0.9398)
			(end -0.508 0.9398)
			(stroke
				(width 0.1524)
				(type default)
			)
			(layer "F.SilkS")
		)
		(fp_line
			(start 0.508 -0.9398)
			(end -0.508 -0.9398)
			(stroke
				(width 0.1524)
				(type default)
			)
			(layer "F.SilkS")
		)
		(fp_rect
			(start -0.508 0.9398)
			(end 0.508 -0.9398)
			(stroke
				(width 0)
				(type default)
			)
			(fill no)
			(layer "F.CrtYd")
		)
		(fp_rect
			(start -0.508 0.9398)
			(end 0.508 -0.9398)
			(stroke
				(width 0)
				(type default)
			)
			(fill no)
			(layer "F.Fab")
		)
		(pad "1" smd custom
			(at 0 -0.4445 270)
			(size 0.1397 0.1397)
			(layers "F.Cu" "F.Mask" "F.Paste")
			(net "EEPROM_WP")
			(options
				(clearance outline)
				(anchor circle)
			)
			(primitives
				(gr_poly
					(pts
						(arc
							(start -0.1778 -0.2794)
							(mid -0.249642 -0.249642)
							(end -0.2794 -0.1778)
						)
						(arc
							(start -0.2794 0.1778)
							(mid -0.249642 0.249642)
							(end -0.1778 0.2794)
						)
						(arc
							(start 0.1778 0.2794)
							(mid 0.249642 0.249642)
							(end 0.2794 0.1778)
						)
						(arc
							(start 0.2794 -0.1778)
							(mid 0.249642 -0.249642)
							(end 0.1778 -0.2794)
						)
					)
					(width 0)
					(fill yes)
				)
			)
		)
		(pad "2" smd custom
			(at 0 0.4445 270)
			(size 0.1397 0.1397)
			(layers "F.Cu" "F.Mask" "F.Paste")
			(net "GND")
			(options
				(clearance outline)
				(anchor circle)
			)
			(primitives
				(gr_poly
					(pts
						(arc
							(start -0.1778 -0.2794)
							(mid -0.249642 -0.249642)
							(end -0.2794 -0.1778)
						)
						(arc
							(start -0.2794 0.1778)
							(mid -0.249642 0.249642)
							(end -0.1778 0.2794)
						)
						(arc
							(start 0.1778 0.2794)
							(mid 0.249642 0.249642)
							(end 0.2794 0.1778)
						)
						(arc
							(start 0.2794 -0.1778)
							(mid 0.249642 -0.249642)
							(end 0.1778 -0.2794)
						)
					)
					(width 0)
					(fill yes)
				)
			)
		)
	)
	(footprint ""
		(layer "F.Cu")
		(at 67.749166 -88.30056)
		(property "Reference" "R482"
			(at 0 0 0)
			(layer "F.SilkS")
			(hide yes)
			(effects
				(font
					(size 1.27 1.27)
				)
			)
		)
		(property "Value" "0R2J-2-GP"
			(at 0.064008 -3.993896 0)
			(unlocked yes)
			(layer "F.Fab")
			(hide yes)
			(effects
				(font
					(size 1.016 1.016)
					(thickness 0.1524)
				)
			)
		)
		(property "Device Type" "R402H16"
			(at 0.064008 -5.517896 0)
			(unlocked yes)
			(layer "F.Fab")
			(hide yes)
			(effects
				(font
					(size 1.016 1.016)
					(thickness 0.1524)
				)
			)
		)
		(duplicate_pad_numbers_are_jumpers no)
		(fp_line
			(start -0.508 -0.9398)
			(end -0.508 0.9398)
			(stroke
				(width 0.1524)
				(type default)
			)
			(layer "F.SilkS")
		)
		(fp_line
			(start 0.508 -0.9398)
			(end -0.508 -0.9398)
			(stroke
				(width 0.1524)
				(type default)
			)
			(layer "F.SilkS")
		)
		(fp_rect
			(start -0.508 0.9398)
			(end 0.508 -0.9398)
			(stroke
				(width 0)
				(type default)
			)
			(fill no)
			(layer "F.CrtYd")
		)
		(fp_rect
			(start -0.508 0.9398)
			(end 0.508 -0.9398)
			(stroke
				(width 0)
				(type default)
			)
			(fill no)
			(layer "F.Fab")
		)
		(pad "1" smd custom
			(at 0 -0.4445)
			(size 0.1397 0.1397)
			(layers "F.Cu" "F.Mask" "F.Paste")
			(net "HB_A_OUT")
			(options
				(clearance outline)
				(anchor circle)
			)
			(primitives
				(gr_poly
					(pts
						(arc
							(start -0.1778 -0.2794)
							(mid -0.249642 -0.249642)
							(end -0.2794 -0.1778)
						)
						(arc
							(start -0.2794 0.1778)
							(mid -0.249642 0.249642)
							(end -0.1778 0.2794)
						)
						(arc
							(start 0.1778 0.2794)
							(mid 0.249642 0.249642)
							(end 0.2794 0.1778)
						)
						(arc
							(start 0.2794 -0.1778)
							(mid 0.249642 -0.249642)
							(end 0.1778 -0.2794)
						)
					)
					(width 0)
					(fill yes)
				)
			)
		)
		(pad "2" smd custom
			(at 0 0.4445)
			(size 0.1397 0.1397)
			(layers "F.Cu" "F.Mask" "F.Paste")
			(net "INVERTER_G1")
			(options
				(clearance outline)
				(anchor circle)
			)
			(primitives
				(gr_poly
					(pts
						(arc
							(start -0.1778 -0.2794)
							(mid -0.249642 -0.249642)
							(end -0.2794 -0.1778)
						)
						(arc
							(start -0.2794 0.1778)
							(mid -0.249642 0.249642)
							(end -0.1778 0.2794)
						)
						(arc
							(start 0.1778 0.2794)
							(mid 0.249642 0.249642)
							(end 0.2794 0.1778)
						)
						(arc
							(start 0.2794 -0.1778)
							(mid 0.249642 -0.249642)
							(end 0.1778 -0.2794)
						)
					)
					(width 0)
					(fill yes)
				)
			)
		)
	)
	(footprint ""
		(layer "F.Cu")
		(at 159.385 -95.9104 180)
		(property "Reference" "R61"
			(at 0 0 180)
			(layer "F.SilkS")
			(hide yes)
			(effects
				(font
					(size 1.27 1.27)
				)
			)
		)
		(property "Value" "10KR2F-2-GP"
			(at 0.064008 -3.993896 180)
			(unlocked yes)
			(layer "F.Fab")
			(hide yes)
			(effects
				(font
					(size 1.016 1.016)
					(thickness 0.1524)
				)
			)
		)
		(property "Device Type" "R402H16"
			(at 0.064008 -5.517896 180)
			(unlocked yes)
			(layer "F.Fab")
			(hide yes)
			(effects
				(font
					(size 1.016 1.016)
					(thickness 0.1524)
				)
			)
		)
		(duplicate_pad_numbers_are_jumpers no)
		(fp_line
			(start 0.508 -0.9398)
			(end -0.508 -0.9398)
			(stroke
				(width 0.1524)
				(type default)
			)
			(layer "F.SilkS")
		)
		(fp_line
			(start -0.508 -0.9398)
			(end -0.508 0.9398)
			(stroke
				(width 0.1524)
				(type default)
			)
			(layer "F.SilkS")
		)
		(fp_rect
			(start -0.508 0.9398)
			(end 0.508 -0.9398)
			(stroke
				(width 0)
				(type default)
			)
			(fill no)
			(layer "F.CrtYd")
		)
		(fp_rect
			(start -0.508 0.9398)
			(end 0.508 -0.9398)
			(stroke
				(width 0)
				(type default)
			)
			(fill no)
			(layer "F.Fab")
		)
		(pad "1" smd custom
			(at 0 -0.4445 180)
			(size 0.1397 0.1397)
			(layers "F.Cu" "F.Mask" "F.Paste")
			(net "GND")
			(options
				(clearance outline)
				(anchor circle)
			)
			(primitives
				(gr_poly
					(pts
						(arc
							(start -0.1778 -0.2794)
							(mid -0.249642 -0.249642)
							(end -0.2794 -0.1778)
						)
						(arc
							(start -0.2794 0.1778)
							(mid -0.249642 0.249642)
							(end -0.1778 0.2794)
						)
						(arc
							(start 0.1778 0.2794)
							(mid 0.249642 0.249642)
							(end 0.2794 0.1778)
						)
						(arc
							(start 0.2794 -0.1778)
							(mid 0.249642 -0.249642)
							(end 0.1778 -0.2794)
						)
					)
					(width 0)
					(fill yes)
				)
			)
		)
		(pad "2" smd custom
			(at 0 0.4445 180)
			(size 0.1397 0.1397)
			(layers "F.Cu" "F.Mask" "F.Paste")
			(net "CLKGEN_OE3")
			(options
				(clearance outline)
				(anchor circle)
			)
			(primitives
				(gr_poly
					(pts
						(arc
							(start -0.1778 -0.2794)
							(mid -0.249642 -0.249642)
							(end -0.2794 -0.1778)
						)
						(arc
							(start -0.2794 0.1778)
							(mid -0.249642 0.249642)
							(end -0.1778 0.2794)
						)
						(arc
							(start 0.1778 0.2794)
							(mid 0.249642 0.249642)
							(end 0.2794 0.1778)
						)
						(arc
							(start 0.2794 -0.1778)
							(mid 0.249642 -0.249642)
							(end 0.1778 -0.2794)
						)
					)
					(width 0)
					(fill yes)
				)
			)
		)
	)
	(footprint ""
		(layer "F.Cu")
		(at 119.4816 -24.3078)
		(property "Reference" "U54"
			(at 0 0 0)
			(layer "F.SilkS")
			(hide yes)
			(effects
				(font
					(size 1.27 1.27)
				)
			)
		)
		(property "Value" "TCA9554PWR-GP"
			(at 0.127 -12.573 0)
			(unlocked yes)
			(layer "F.Fab")
			(hide yes)
			(effects
				(font
					(size 1.016 1.016)
					(thickness 0.1524)
				)
			)
		)
		(property "Device Type" "TSOIC16H48"
			(at 0.1016 -14.5796 0)
			(unlocked yes)
			(layer "F.Fab")
			(hide yes)
			(effects
				(font
					(size 1.016 1.016)
					(thickness 0.1524)
				)
			)
		)
		(duplicate_pad_numbers_are_jumpers no)
		(fp_line
			(start -3.0988 -1.778)
			(end -3.0988 1.778)
			(stroke
				(width 0.1524)
				(type default)
			)
			(layer "F.SilkS")
		)
		(fp_line
			(start -3.0988 -1.778)
			(end 2.3622 -1.778)
			(stroke
				(width 0.1524)
				(type default)
			)
			(layer "F.SilkS")
		)
		(fp_line
			(start -2.921 3.81)
			(end -2.921 1.778)
			(stroke
				(width 0.508)
				(type default)
			)
			(layer "F.SilkS")
		)
		(fp_line
			(start -2.54 0)
			(end -3.0988 -0.5588)
			(stroke
				(width 0.1524)
				(type default)
			)
			(layer "F.SilkS")
		)
		(fp_line
			(start -2.54 0)
			(end -3.0988 0.5588)
			(stroke
				(width 0.1524)
				(type default)
			)
			(layer "F.SilkS")
		)
		(fp_line
			(start 2.3622 -1.778)
			(end 2.3622 1.778)
			(stroke
				(width 0.1524)
				(type default)
			)
			(layer "F.SilkS")
		)
		(fp_line
			(start 2.3622 1.778)
			(end -2.921 1.778)
			(stroke
				(width 0.1524)
				(type default)
			)
			(layer "F.SilkS")
		)
		(fp_poly
			(pts
				(xy -2.4638 -1.778) (xy -2.4638 1.778) (xy 2.3622 1.778) (xy 2.3622 -1.778)
			)
			(stroke
				(width 0)
				(type default)
			)
			(fill yes)
			(layer "F.SilkS")
		)
		(fp_rect
			(start -3.175 4.064)
			(end 3.175 -4.064)
			(stroke
				(width 0)
				(type default)
			)
			(fill no)
			(layer "F.CrtYd")
		)
		(fp_poly
			(pts
				(xy -3.175 -4.064) (xy 3.175 -4.064) (xy 3.175 4.064) (xy -3.175 4.064)
			)
			(stroke
				(width 0)
				(type default)
			)
			(fill no)
			(layer "F.Fab")
		)
		(pad "1" smd rect
			(at -2.27584 2.8194)
			(size 0.3556 1.524)
			(layers "F.Cu" "F.Mask" "F.Paste")
			(net "U54_A0")
		)
		(pad "2" smd rect
			(at -1.6256 2.8194)
			(size 0.3556 1.524)
			(layers "F.Cu" "F.Mask" "F.Paste")
			(net "U54_A1")
		)
		(pad "3" smd rect
			(at -0.97536 2.8194)
			(size 0.3556 1.524)
			(layers "F.Cu" "F.Mask" "F.Paste")
			(net "U54_A2")
		)
		(pad "4" smd rect
			(at -0.32512 2.8194)
			(size 0.3556 1.524)
			(layers "F.Cu" "F.Mask" "F.Paste")
			(net "U54_P0")
		)
		(pad "5" smd rect
			(at 0.32512 2.8194)
			(size 0.3556 1.524)
			(layers "F.Cu" "F.Mask" "F.Paste")
			(net "Net_37")
		)
		(pad "6" smd rect
			(at 0.97536 2.8194)
			(size 0.3556 1.524)
			(layers "F.Cu" "F.Mask" "F.Paste")
			(net "Net_38")
		)
		(pad "7" smd rect
			(at 1.6256 2.8194)
			(size 0.3556 1.524)
			(layers "F.Cu" "F.Mask" "F.Paste")
			(net "Net_39")
		)
		(pad "8" smd rect
			(at 2.27584 2.8194)
			(size 0.3556 1.524)
			(layers "F.Cu" "F.Mask" "F.Paste")
			(net "GND")
		)
		(pad "9" smd rect
			(at 2.27584 -2.8194)
			(size 0.3556 1.524)
			(layers "F.Cu" "F.Mask" "F.Paste")
			(net "Net_40")
		)
		(pad "10" smd rect
			(at 1.6256 -2.8194)
			(size 0.3556 1.524)
			(layers "F.Cu" "F.Mask" "F.Paste")
			(net "Net_109")
		)
		(pad "11" smd rect
			(at 0.97536 -2.8194)
			(size 0.3556 1.524)
			(layers "F.Cu" "F.Mask" "F.Paste")
			(net "Net_110")
		)
		(pad "12" smd rect
			(at 0.32512 -2.8194)
			(size 0.3556 1.524)
			(layers "F.Cu" "F.Mask" "F.Paste")
			(net "Net_111")
		)
		(pad "13" smd rect
			(at -0.32512 -2.8194)
			(size 0.3556 1.524)
			(layers "F.Cu" "F.Mask" "F.Paste")
			(net "U54_INT_N")
		)
		(pad "14" smd rect
			(at -0.97536 -2.8194)
			(size 0.3556 1.524)
			(layers "F.Cu" "F.Mask" "F.Paste")
			(net "U54_SCL")
		)
		(pad "15" smd rect
			(at -1.6256 -2.8194)
			(size 0.3556 1.524)
			(layers "F.Cu" "F.Mask" "F.Paste")
			(net "U54_SDA")
		)
		(pad "16" smd rect
			(at -2.27584 -2.8194)
			(size 0.3556 1.524)
			(layers "F.Cu" "F.Mask" "F.Paste")
			(net "P3V3_STBY")
		)
	)
	(footprint ""
		(layer "F.Cu")
		(at 102.208076 -212.420454 180)
		(property "Reference" "C150"
			(at 0 0 180)
			(layer "F.SilkS")
			(hide yes)
			(effects
				(font
					(size 1.27 1.27)
				)
			)
		)
		(property "Value" "SCD22U10V2KX-1GP"
			(at 1.1811 -2.7051 180)
			(unlocked yes)
			(layer "F.Fab")
			(hide yes)
			(effects
				(font
					(size 1.016 1.016)
					(thickness 0.1524)
				)
			)
		)
		(property "Device Type" "C402H22"
			(at 1.1811 -4.2291 180)
			(unlocked yes)
			(layer "F.Fab")
			(hide yes)
			(effects
				(font
					(size 1.016 1.016)
					(thickness 0.1524)
				)
			)
		)
		(duplicate_pad_numbers_are_jumpers no)
		(fp_rect
			(start -0.4318 0.9525)
			(end 0.4318 -0.9525)
			(stroke
				(width 0)
				(type default)
			)
			(fill no)
			(layer "F.CrtYd")
		)
		(fp_rect
			(start -0.4318 0.9525)
			(end 0.4318 -0.9525)
			(stroke
				(width 0)
				(type default)
			)
			(fill no)
			(layer "F.Fab")
		)
		(pad "1" smd custom
			(at 0 -0.4445 180)
			(size 0.1524 0.1524)
			(layers "F.Cu" "F.Mask" "F.Paste")
			(net "PCIE_TX_CAP_N62")
			(options
				(clearance outline)
				(anchor circle)
			)
			(primitives
				(gr_poly
					(pts
						(arc
							(start 0.3048 -0.2032)
							(mid 0.275042 -0.275042)
							(end 0.2032 -0.3048)
						)
						(arc
							(start -0.2032 -0.3048)
							(mid -0.275042 -0.275042)
							(end -0.3048 -0.2032)
						)
						(arc
							(start -0.3048 0.2032)
							(mid -0.275042 0.275042)
							(end -0.2032 0.3048)
						)
						(arc
							(start 0.2032 0.3048)
							(mid 0.275042 0.275042)
							(end 0.3048 0.2032)
						)
					)
					(width 0)
					(fill yes)
				)
			)
		)
		(pad "2" smd custom
			(at 0 0.4445 180)
			(size 0.1524 0.1524)
			(layers "F.Cu" "F.Mask" "F.Paste")
			(net "PCIE_TX_N62")
			(options
				(clearance outline)
				(anchor circle)
			)
			(primitives
				(gr_poly
					(pts
						(arc
							(start 0.3048 -0.2032)
							(mid 0.275042 -0.275042)
							(end 0.2032 -0.3048)
						)
						(arc
							(start -0.2032 -0.3048)
							(mid -0.275042 -0.275042)
							(end -0.3048 -0.2032)
						)
						(arc
							(start -0.3048 0.2032)
							(mid -0.275042 0.275042)
							(end -0.2032 0.3048)
						)
						(arc
							(start 0.2032 0.3048)
							(mid 0.275042 0.275042)
							(end 0.3048 0.2032)
						)
					)
					(width 0)
					(fill yes)
				)
			)
		)
	)
	(footprint ""
		(layer "F.Cu")
		(at 64.135 -45.649388 90)
		(property "Reference" "PC21"
			(at 0 0 90)
			(layer "F.SilkS")
			(hide yes)
			(effects
				(font
					(size 1.27 1.27)
				)
			)
		)
		(property "Value" "SC10U25V5KX-GP"
			(at -0.0762 -6.1214 90)
			(unlocked yes)
			(layer "F.Fab")
			(hide yes)
			(effects
				(font
					(size 1.016 1.016)
					(thickness 0.1524)
				)
			)
		)
		(property "Device Type" "C805H56"
			(at -0.0762 -8.1534 90)
			(unlocked yes)
			(layer "F.Fab")
			(hide yes)
			(effects
				(font
					(size 1.016 1.016)
					(thickness 0.1524)
				)
			)
		)
		(duplicate_pad_numbers_are_jumpers no)
		(fp_line
			(start 0.635 0)
			(end -0.635 0)
			(stroke
				(width 0.508)
				(type default)
			)
			(layer "F.SilkS")
		)
		(fp_rect
			(start -0.9652 1.778)
			(end 0.9652 -1.778)
			(stroke
				(width 0)
				(type default)
			)
			(fill no)
			(layer "F.CrtYd")
		)
		(fp_poly
			(pts
				(xy -0.9652 -1.778) (xy 0.9652 -1.778) (xy 0.9652 1.778) (xy -0.9652 1.778)
			)
			(stroke
				(width 0)
				(type default)
			)
			(fill no)
			(layer "F.Fab")
		)
		(pad "1" smd rect
			(at 0 -0.9652 90)
			(size 1.397 1.143)
			(layers "F.Cu" "F.Mask" "F.Paste")
			(net "P3V3_STBY_VIN")
		)
		(pad "2" smd rect
			(at 0 0.9652 90)
			(size 1.397 1.143)
			(layers "F.Cu" "F.Mask" "F.Paste")
			(net "GND")
		)
	)
	(footprint ""
		(layer "F.Cu")
		(at 53.721 -124.46 -90)
		(property "Reference" "R804"
			(at 0 0 270)
			(layer "F.SilkS")
			(hide yes)
			(effects
				(font
					(size 1.27 1.27)
				)
			)
		)
		(property "Value" "4K7R2F-GP"
			(at 0.064008 -3.993896 270)
			(unlocked yes)
			(layer "F.Fab")
			(hide yes)
			(effects
				(font
					(size 1.016 1.016)
					(thickness 0.1524)
				)
			)
		)
		(property "Device Type" "R402H16"
			(at 0.064008 -5.517896 270)
			(unlocked yes)
			(layer "F.Fab")
			(hide yes)
			(effects
				(font
					(size 1.016 1.016)
					(thickness 0.1524)
				)
			)
		)
		(duplicate_pad_numbers_are_jumpers no)
		(fp_line
			(start -0.508 -0.9398)
			(end -0.508 0.9398)
			(stroke
				(width 0.1524)
				(type default)
			)
			(layer "F.SilkS")
		)
		(fp_line
			(start 0.508 -0.9398)
			(end -0.508 -0.9398)
			(stroke
				(width 0.1524)
				(type default)
			)
			(layer "F.SilkS")
		)
		(fp_rect
			(start -0.508 0.9398)
			(end 0.508 -0.9398)
			(stroke
				(width 0)
				(type default)
			)
			(fill no)
			(layer "F.CrtYd")
		)
		(fp_rect
			(start -0.508 0.9398)
			(end 0.508 -0.9398)
			(stroke
				(width 0)
				(type default)
			)
			(fill no)
			(layer "F.Fab")
		)
		(pad "1" smd custom
			(at 0 -0.4445 270)
			(size 0.1397 0.1397)
			(layers "F.Cu" "F.Mask" "F.Paste")
			(net "P3V3_STBY")
			(options
				(clearance outline)
				(anchor circle)
			)
			(primitives
				(gr_poly
					(pts
						(arc
							(start -0.1778 -0.2794)
							(mid -0.249642 -0.249642)
							(end -0.2794 -0.1778)
						)
						(arc
							(start -0.2794 0.1778)
							(mid -0.249642 0.249642)
							(end -0.1778 0.2794)
						)
						(arc
							(start 0.1778 0.2794)
							(mid 0.249642 0.249642)
							(end 0.2794 0.1778)
						)
						(arc
							(start 0.2794 -0.1778)
							(mid 0.249642 -0.249642)
							(end 0.1778 -0.2794)
						)
					)
					(width 0)
					(fill yes)
				)
			)
		)
		(pad "2" smd custom
			(at 0 0.4445 270)
			(size 0.1397 0.1397)
			(layers "F.Cu" "F.Mask" "F.Paste")
			(net "JTAG_BMC_TCK")
			(options
				(clearance outline)
				(anchor circle)
			)
			(primitives
				(gr_poly
					(pts
						(arc
							(start -0.1778 -0.2794)
							(mid -0.249642 -0.249642)
							(end -0.2794 -0.1778)
						)
						(arc
							(start -0.2794 0.1778)
							(mid -0.249642 0.249642)
							(end -0.1778 0.2794)
						)
						(arc
							(start 0.1778 0.2794)
							(mid 0.249642 0.249642)
							(end 0.2794 0.1778)
						)
						(arc
							(start 0.2794 -0.1778)
							(mid 0.249642 -0.249642)
							(end 0.1778 -0.2794)
						)
					)
					(width 0)
					(fill yes)
				)
			)
		)
	)
	(footprint ""
		(layer "F.Cu")
		(at 34.166556 -94.99219 -90)
		(property "Reference" "R48"
			(at 0 0 270)
			(layer "F.SilkS")
			(hide yes)
			(effects
				(font
					(size 1.27 1.27)
				)
			)
		)
		(property "Value" "0R2J-2-GP"
			(at 0.064008 -3.993896 270)
			(unlocked yes)
			(layer "F.Fab")
			(hide yes)
			(effects
				(font
					(size 1.016 1.016)
					(thickness 0.1524)
				)
			)
		)
		(property "Device Type" "R402H16"
			(at 0.064008 -5.517896 270)
			(unlocked yes)
			(layer "F.Fab")
			(hide yes)
			(effects
				(font
					(size 1.016 1.016)
					(thickness 0.1524)
				)
			)
		)
		(duplicate_pad_numbers_are_jumpers no)
		(fp_line
			(start -0.508 -0.9398)
			(end -0.508 0.9398)
			(stroke
				(width 0.1524)
				(type default)
			)
			(layer "F.SilkS")
		)
		(fp_line
			(start 0.508 -0.9398)
			(end -0.508 -0.9398)
			(stroke
				(width 0.1524)
				(type default)
			)
			(layer "F.SilkS")
		)
		(fp_rect
			(start -0.508 0.9398)
			(end 0.508 -0.9398)
			(stroke
				(width 0)
				(type default)
			)
			(fill no)
			(layer "F.CrtYd")
		)
		(fp_rect
			(start -0.508 0.9398)
			(end 0.508 -0.9398)
			(stroke
				(width 0)
				(type default)
			)
			(fill no)
			(layer "F.Fab")
		)
		(pad "1" smd custom
			(at 0 -0.4445 270)
			(size 0.1397 0.1397)
			(layers "F.Cu" "F.Mask" "F.Paste")
			(net "NVM_SK_R")
			(options
				(clearance outline)
				(anchor circle)
			)
			(primitives
				(gr_poly
					(pts
						(arc
							(start -0.1778 -0.2794)
							(mid -0.249642 -0.249642)
							(end -0.2794 -0.1778)
						)
						(arc
							(start -0.2794 0.1778)
							(mid -0.249642 0.249642)
							(end -0.1778 0.2794)
						)
						(arc
							(start 0.1778 0.2794)
							(mid 0.249642 0.249642)
							(end 0.2794 0.1778)
						)
						(arc
							(start 0.2794 -0.1778)
							(mid 0.249642 -0.249642)
							(end 0.1778 -0.2794)
						)
					)
					(width 0)
					(fill yes)
				)
			)
		)
		(pad "2" smd custom
			(at 0 0.4445 270)
			(size 0.1397 0.1397)
			(layers "F.Cu" "F.Mask" "F.Paste")
			(net "I2C_MUX_2A")
			(options
				(clearance outline)
				(anchor circle)
			)
			(primitives
				(gr_poly
					(pts
						(arc
							(start -0.1778 -0.2794)
							(mid -0.249642 -0.249642)
							(end -0.2794 -0.1778)
						)
						(arc
							(start -0.2794 0.1778)
							(mid -0.249642 0.249642)
							(end -0.1778 0.2794)
						)
						(arc
							(start 0.1778 0.2794)
							(mid 0.249642 0.249642)
							(end 0.2794 0.1778)
						)
						(arc
							(start 0.2794 -0.1778)
							(mid 0.249642 -0.249642)
							(end 0.1778 -0.2794)
						)
					)
					(width 0)
					(fill yes)
				)
			)
		)
	)
	(footprint ""
		(layer "F.Cu")
		(at 39.243 -118.364)
		(property "Reference" "TP326"
			(at 0 0 0)
			(layer "F.SilkS")
			(hide yes)
			(effects
				(font
					(size 1.27 1.27)
				)
			)
		)
		(property "Value" "TPAD28-2-GP"
			(at -0.0127 -1.6637 0)
			(unlocked yes)
			(layer "F.Fab")
			(hide yes)
			(effects
				(font
					(size 1.016 1.016)
					(thickness 0.1524)
				)
			)
		)
		(property "Device Type" "TPAD28"
			(at -0.0127 -3.1877 0)
			(unlocked yes)
			(layer "F.Fab")
			(hide yes)
			(effects
				(font
					(size 1.016 1.016)
					(thickness 0.1524)
				)
			)
		)
		(duplicate_pad_numbers_are_jumpers no)
		(fp_poly
			(pts
				(arc
					(start 0.3556 0)
					(mid -0.3556 0)
					(end 0.3556 0)
				)
			)
			(stroke
				(width 0)
				(type default)
			)
			(fill no)
			(layer "F.CrtYd")
		)
		(fp_poly
			(pts
				(arc
					(start 0.6096 0)
					(mid -0.6096 0)
					(end 0.6096 0)
				)
			)
			(stroke
				(width 0)
				(type default)
			)
			(fill no)
			(layer "F.Fab")
		)
		(pad "1" smd circle
			(at 0 0)
			(size 0.7112 0.7112)
			(layers "F.Cu" "F.Mask" "F.Paste")
			(net "TP_GPIOU1")
		)
	)
	(footprint ""
		(layer "F.Cu")
		(at 27.7622 -51.6382 -90)
		(property "Reference" "C414"
			(at 0 0 270)
			(layer "F.SilkS")
			(hide yes)
			(effects
				(font
					(size 1.27 1.27)
				)
			)
		)
		(property "Value" "SCD1U16V2KX-3GP"
			(at 1.1811 -2.7051 270)
			(unlocked yes)
			(layer "F.Fab")
			(hide yes)
			(effects
				(font
					(size 1.016 1.016)
					(thickness 0.1524)
				)
			)
		)
		(property "Device Type" "C402H22"
			(at 1.1811 -4.2291 270)
			(unlocked yes)
			(layer "F.Fab")
			(hide yes)
			(effects
				(font
					(size 1.016 1.016)
					(thickness 0.1524)
				)
			)
		)
		(duplicate_pad_numbers_are_jumpers no)
		(fp_rect
			(start -0.4318 0.9525)
			(end 0.4318 -0.9525)
			(stroke
				(width 0)
				(type default)
			)
			(fill no)
			(layer "F.CrtYd")
		)
		(fp_rect
			(start -0.4318 0.9525)
			(end 0.4318 -0.9525)
			(stroke
				(width 0)
				(type default)
			)
			(fill no)
			(layer "F.Fab")
		)
		(pad "1" smd custom
			(at 0 -0.4445 270)
			(size 0.1524 0.1524)
			(layers "F.Cu" "F.Mask" "F.Paste")
			(net "LED_MDI0_1G_N_R")
			(options
				(clearance outline)
				(anchor circle)
			)
			(primitives
				(gr_poly
					(pts
						(arc
							(start 0.3048 -0.2032)
							(mid 0.275042 -0.275042)
							(end 0.2032 -0.3048)
						)
						(arc
							(start -0.2032 -0.3048)
							(mid -0.275042 -0.275042)
							(end -0.3048 -0.2032)
						)
						(arc
							(start -0.3048 0.2032)
							(mid -0.275042 0.275042)
							(end -0.2032 0.3048)
						)
						(arc
							(start 0.2032 0.3048)
							(mid 0.275042 0.275042)
							(end 0.3048 0.2032)
						)
					)
					(width 0)
					(fill yes)
				)
			)
		)
		(pad "2" smd custom
			(at 0 0.4445 270)
			(size 0.1524 0.1524)
			(layers "F.Cu" "F.Mask" "F.Paste")
			(net "GND")
			(options
				(clearance outline)
				(anchor circle)
			)
			(primitives
				(gr_poly
					(pts
						(arc
							(start 0.3048 -0.2032)
							(mid 0.275042 -0.275042)
							(end 0.2032 -0.3048)
						)
						(arc
							(start -0.2032 -0.3048)
							(mid -0.275042 -0.275042)
							(end -0.3048 -0.2032)
						)
						(arc
							(start -0.3048 0.2032)
							(mid -0.275042 0.275042)
							(end -0.2032 0.3048)
						)
						(arc
							(start 0.2032 0.3048)
							(mid 0.275042 0.275042)
							(end 0.3048 0.2032)
						)
					)
					(width 0)
					(fill yes)
				)
			)
		)
	)
	(footprint ""
		(layer "F.Cu")
		(at 56.604916 -37.785294)
		(property "Reference" "Q43"
			(at 0 0 0)
			(layer "F.SilkS")
			(hide yes)
			(effects
				(font
					(size 1.27 1.27)
				)
			)
		)
		(property "Value" "DSS4240T-7-GP"
			(at 0.10287 -10.29843 0)
			(unlocked yes)
			(layer "F.Fab")
			(hide yes)
			(effects
				(font
					(size 1.016 1.016)
					(thickness 0.1524)
				)
			)
		)
		(property "Device Type" "SOT23CBE2D4H44"
			(at 0.10287 -12.20343 0)
			(unlocked yes)
			(layer "F.Fab")
			(hide yes)
			(effects
				(font
					(size 1.016 1.016)
					(thickness 0.1524)
				)
			)
		)
		(duplicate_pad_numbers_are_jumpers no)
		(fp_line
			(start -1.651 -1.778)
			(end -1.651 1.778)
			(stroke
				(width 0.1524)
				(type default)
			)
			(layer "F.SilkS")
		)
		(fp_line
			(start -1.651 1.778)
			(end 1.651 1.778)
			(stroke
				(width 0.1524)
				(type default)
			)
			(layer "F.SilkS")
		)
		(fp_line
			(start 1.651 -1.778)
			(end -1.651 -1.778)
			(stroke
				(width 0.1524)
				(type default)
			)
			(layer "F.SilkS")
		)
		(fp_line
			(start 1.651 1.778)
			(end 1.651 -1.778)
			(stroke
				(width 0.1524)
				(type default)
			)
			(layer "F.SilkS")
		)
		(fp_poly
			(pts
				(xy -1.778 1.8796) (xy -1.778 -1.8796) (xy 1.778 -1.8796) (xy 1.778 1.8796)
			)
			(stroke
				(width 0)
				(type default)
			)
			(fill no)
			(layer "F.CrtYd")
		)
		(fp_poly
			(pts
				(xy -1.778 1.8796) (xy -1.778 -1.8796) (xy 1.778 -1.8796) (xy 1.778 1.8796)
			)
			(stroke
				(width 0)
				(type default)
			)
			(fill no)
			(layer "F.Fab")
		)
		(pad "B" smd custom
			(at -0.98425 0.9525)
			(size 0.1905 0.1905)
			(layers "F.Cu" "F.Mask" "F.Paste")
			(net "Q43_B")
			(options
				(clearance outline)
				(anchor circle)
			)
			(primitives
				(gr_poly
					(pts
						(arc
							(start -0.1778 0.5715)
							(mid -0.321484 0.511984)
							(end -0.381 0.3683)
						)
						(arc
							(start -0.381 -0.3683)
							(mid -0.321484 -0.511984)
							(end -0.1778 -0.5715)
						)
						(arc
							(start 0.1778 -0.5715)
							(mid 0.321484 -0.511984)
							(end 0.381 -0.3683)
						)
						(arc
							(start 0.381 0.3683)
							(mid 0.321484 0.511984)
							(end 0.1778 0.5715)
						)
					)
					(width 0)
					(fill yes)
				)
			)
		)
		(pad "C" smd custom
			(at 0 -0.9525)
			(size 0.1905 0.1905)
			(layers "F.Cu" "F.Mask" "F.Paste")
			(net "Q43_C")
			(options
				(clearance outline)
				(anchor circle)
			)
			(primitives
				(gr_poly
					(pts
						(arc
							(start -0.1778 0.5715)
							(mid -0.321484 0.511984)
							(end -0.381 0.3683)
						)
						(arc
							(start -0.381 -0.3683)
							(mid -0.321484 -0.511984)
							(end -0.1778 -0.5715)
						)
						(arc
							(start 0.1778 -0.5715)
							(mid 0.321484 -0.511984)
							(end 0.381 -0.3683)
						)
						(arc
							(start 0.381 0.3683)
							(mid 0.321484 0.511984)
							(end 0.1778 0.5715)
						)
					)
					(width 0)
					(fill yes)
				)
			)
		)
		(pad "E" smd custom
			(at 0.98425 0.9525)
			(size 0.1905 0.1905)
			(layers "F.Cu" "F.Mask" "F.Paste")
			(net "GND")
			(options
				(clearance outline)
				(anchor circle)
			)
			(primitives
				(gr_poly
					(pts
						(arc
							(start -0.1778 0.5715)
							(mid -0.321484 0.511984)
							(end -0.381 0.3683)
						)
						(arc
							(start -0.381 -0.3683)
							(mid -0.321484 -0.511984)
							(end -0.1778 -0.5715)
						)
						(arc
							(start 0.1778 -0.5715)
							(mid 0.321484 -0.511984)
							(end 0.381 -0.3683)
						)
						(arc
							(start 0.381 0.3683)
							(mid 0.321484 0.511984)
							(end 0.1778 0.5715)
						)
					)
					(width 0)
					(fill yes)
				)
			)
		)
	)
	(footprint ""
		(layer "F.Cu")
		(at 328.835512 -184.878218 180)
		(property "Reference" "C417"
			(at 0 0 180)
			(layer "F.SilkS")
			(hide yes)
			(effects
				(font
					(size 1.27 1.27)
				)
			)
		)
		(property "Value" "SCD1U25V2KX-2-GP"
			(at 1.1811 -2.7051 180)
			(unlocked yes)
			(layer "F.Fab")
			(hide yes)
			(effects
				(font
					(size 1.016 1.016)
					(thickness 0.1524)
				)
			)
		)
		(property "Device Type" "C402H22"
			(at 1.1811 -4.2291 180)
			(unlocked yes)
			(layer "F.Fab")
			(hide yes)
			(effects
				(font
					(size 1.016 1.016)
					(thickness 0.1524)
				)
			)
		)
		(duplicate_pad_numbers_are_jumpers no)
		(fp_rect
			(start -0.4318 0.9525)
			(end 0.4318 -0.9525)
			(stroke
				(width 0)
				(type default)
			)
			(fill no)
			(layer "F.CrtYd")
		)
		(fp_rect
			(start -0.4318 0.9525)
			(end 0.4318 -0.9525)
			(stroke
				(width 0)
				(type default)
			)
			(fill no)
			(layer "F.Fab")
		)
		(pad "1" smd custom
			(at 0 -0.4445 180)
			(size 0.1524 0.1524)
			(layers "F.Cu" "F.Mask" "F.Paste")
			(net "P3V3_STBY")
			(options
				(clearance outline)
				(anchor circle)
			)
			(primitives
				(gr_poly
					(pts
						(arc
							(start 0.3048 -0.2032)
							(mid 0.275042 -0.275042)
							(end 0.2032 -0.3048)
						)
						(arc
							(start -0.2032 -0.3048)
							(mid -0.275042 -0.275042)
							(end -0.3048 -0.2032)
						)
						(arc
							(start -0.3048 0.2032)
							(mid -0.275042 0.275042)
							(end -0.2032 0.3048)
						)
						(arc
							(start 0.2032 0.3048)
							(mid 0.275042 0.275042)
							(end 0.3048 0.2032)
						)
					)
					(width 0)
					(fill yes)
				)
			)
		)
		(pad "2" smd custom
			(at 0 0.4445 180)
			(size 0.1524 0.1524)
			(layers "F.Cu" "F.Mask" "F.Paste")
			(net "GND")
			(options
				(clearance outline)
				(anchor circle)
			)
			(primitives
				(gr_poly
					(pts
						(arc
							(start 0.3048 -0.2032)
							(mid 0.275042 -0.275042)
							(end 0.2032 -0.3048)
						)
						(arc
							(start -0.2032 -0.3048)
							(mid -0.275042 -0.275042)
							(end -0.3048 -0.2032)
						)
						(arc
							(start -0.3048 0.2032)
							(mid -0.275042 0.275042)
							(end -0.2032 0.3048)
						)
						(arc
							(start 0.2032 0.3048)
							(mid 0.275042 0.275042)
							(end 0.3048 0.2032)
						)
					)
					(width 0)
					(fill yes)
				)
			)
		)
	)
	(footprint ""
		(layer "F.Cu")
		(at 330.099924 -1.999996 -90)
		(property "Reference" "LED16"
			(at 0 0 270)
			(layer "F.SilkS")
			(hide yes)
			(effects
				(font
					(size 1.27 1.27)
				)
			)
		)
		(property "Value" "LED-YG-51-GP"
			(at -2.6924 -1.4224 270)
			(unlocked yes)
			(layer "F.Fab")
			(hide yes)
			(effects
				(font
					(size 1.016 1.016)
					(thickness 0.1524)
				)
			)
		)
		(property "Device Type" "LED1608AKH40"
			(at -2.6924 -2.9464 270)
			(unlocked yes)
			(layer "F.Fab")
			(hide yes)
			(effects
				(font
					(size 1.016 1.016)
					(thickness 0.1524)
				)
			)
		)
		(duplicate_pad_numbers_are_jumpers no)
		(fp_line
			(start -0.7493 1.651)
			(end -0.7493 1.1811)
			(stroke
				(width 0.3302)
				(type default)
			)
			(layer "F.SilkS")
		)
		(fp_line
			(start 0.7493 1.651)
			(end 0.7493 1.1811)
			(stroke
				(width 0.3302)
				(type default)
			)
			(layer "F.SilkS")
		)
		(fp_line
			(start -0.5969 1.5494)
			(end 0.5842 1.5494)
			(stroke
				(width 0.508)
				(type default)
			)
			(layer "F.SilkS")
		)
		(fp_line
			(start -0.6604 1.3716)
			(end -0.6604 -1.3716)
			(stroke
				(width 0.1524)
				(type default)
			)
			(layer "F.SilkS")
		)
		(fp_line
			(start 0.6604 1.3716)
			(end -0.6604 1.3716)
			(stroke
				(width 0.1524)
				(type default)
			)
			(layer "F.SilkS")
		)
		(fp_line
			(start -0.6604 -1.3716)
			(end 0.6604 -1.3716)
			(stroke
				(width 0.1524)
				(type default)
			)
			(layer "F.SilkS")
		)
		(fp_line
			(start 0.6604 -1.3716)
			(end 0.6604 1.3716)
			(stroke
				(width 0.1524)
				(type default)
			)
			(layer "F.SilkS")
		)
		(fp_rect
			(start -0.6223 1.3335)
			(end 0.6223 -1.3335)
			(stroke
				(width 0)
				(type default)
			)
			(fill no)
			(layer "F.CrtYd")
		)
		(fp_rect
			(start -0.6223 1.3335)
			(end 0.6223 -1.3335)
			(stroke
				(width 0)
				(type default)
			)
			(fill no)
			(layer "F.Fab")
		)
		(pad "A" smd custom
			(at 0 -0.762 270)
			(size 0.2159 0.2159)
			(layers "F.Cu" "F.Mask" "F.Paste")
			(net "LED_R_8")
			(options
				(clearance outline)
				(anchor circle)
			)
			(primitives
				(gr_poly
					(pts
						(arc
							(start -0.3302 -0.4318)
							(mid -0.402042 -0.402042)
							(end -0.4318 -0.3302)
						)
						(arc
							(start -0.4318 0.3302)
							(mid -0.402042 0.402042)
							(end -0.3302 0.4318)
						)
						(arc
							(start 0.3302 0.4318)
							(mid 0.402042 0.402042)
							(end 0.4318 0.3302)
						)
						(arc
							(start 0.4318 -0.3302)
							(mid 0.402042 -0.402042)
							(end 0.3302 -0.4318)
						)
					)
					(width 0)
					(fill yes)
				)
			)
		)
		(pad "K" smd custom
			(at 0 0.762 270)
			(size 0.2159 0.2159)
			(layers "F.Cu" "F.Mask" "F.Paste")
			(net "LED_Q_8")
			(options
				(clearance outline)
				(anchor circle)
			)
			(primitives
				(gr_poly
					(pts
						(arc
							(start -0.3302 -0.4318)
							(mid -0.402042 -0.402042)
							(end -0.4318 -0.3302)
						)
						(arc
							(start -0.4318 0.3302)
							(mid -0.402042 0.402042)
							(end -0.3302 0.4318)
						)
						(arc
							(start 0.3302 0.4318)
							(mid 0.402042 0.402042)
							(end 0.4318 0.3302)
						)
						(arc
							(start 0.4318 -0.3302)
							(mid 0.402042 -0.402042)
							(end 0.3302 -0.4318)
						)
					)
					(width 0)
					(fill yes)
				)
			)
		)
	)
	(footprint ""
		(layer "F.Cu")
		(at 183.073802 0.9271 90)
		(property "Reference" "SLED28"
			(at 0 0 90)
			(layer "F.SilkS")
			(hide yes)
			(effects
				(font
					(size 1.27 1.27)
				)
			)
		)
		(property "Value" "LED-YG-51-GP"
			(at -2.6924 -1.4224 90)
			(unlocked yes)
			(layer "F.Fab")
			(hide yes)
			(effects
				(font
					(size 1.016 1.016)
					(thickness 0.1524)
				)
			)
		)
		(property "Device Type" "LED1608AKH40"
			(at -2.6924 -2.9464 90)
			(unlocked yes)
			(layer "F.Fab")
			(hide yes)
			(effects
				(font
					(size 1.016 1.016)
					(thickness 0.1524)
				)
			)
		)
		(duplicate_pad_numbers_are_jumpers no)
		(fp_line
			(start 0.6604 -1.3716)
			(end 0.6604 1.3716)
			(stroke
				(width 0.1524)
				(type default)
			)
			(layer "F.SilkS")
		)
		(fp_line
			(start -0.6604 -1.3716)
			(end 0.6604 -1.3716)
			(stroke
				(width 0.1524)
				(type default)
			)
			(layer "F.SilkS")
		)
		(fp_line
			(start 0.6604 1.3716)
			(end -0.6604 1.3716)
			(stroke
				(width 0.1524)
				(type default)
			)
			(layer "F.SilkS")
		)
		(fp_line
			(start -0.6604 1.3716)
			(end -0.6604 -1.3716)
			(stroke
				(width 0.1524)
				(type default)
			)
			(layer "F.SilkS")
		)
		(fp_line
			(start -0.5969 1.5494)
			(end 0.5842 1.5494)
			(stroke
				(width 0.508)
				(type default)
			)
			(layer "F.SilkS")
		)
		(fp_line
			(start 0.7493 1.651)
			(end 0.7493 1.1811)
			(stroke
				(width 0.3302)
				(type default)
			)
			(layer "F.SilkS")
		)
		(fp_line
			(start -0.7493 1.651)
			(end -0.7493 1.1811)
			(stroke
				(width 0.3302)
				(type default)
			)
			(layer "F.SilkS")
		)
		(fp_rect
			(start -0.6223 1.3335)
			(end 0.6223 -1.3335)
			(stroke
				(width 0)
				(type default)
			)
			(fill no)
			(layer "F.CrtYd")
		)
		(fp_rect
			(start -0.6223 1.3335)
			(end 0.6223 -1.3335)
			(stroke
				(width 0)
				(type default)
			)
			(fill no)
			(layer "F.Fab")
		)
		(pad "A" smd custom
			(at 0 -0.762 90)
			(size 0.2159 0.2159)
			(layers "F.Cu" "F.Mask" "F.Paste")
			(net "EXP_BMC_HB_LED_R")
			(options
				(clearance outline)
				(anchor circle)
			)
			(primitives
				(gr_poly
					(pts
						(arc
							(start -0.3302 -0.4318)
							(mid -0.402042 -0.402042)
							(end -0.4318 -0.3302)
						)
						(arc
							(start -0.4318 0.3302)
							(mid -0.402042 0.402042)
							(end -0.3302 0.4318)
						)
						(arc
							(start 0.3302 0.4318)
							(mid 0.402042 0.402042)
							(end 0.4318 0.3302)
						)
						(arc
							(start 0.4318 -0.3302)
							(mid 0.402042 -0.402042)
							(end 0.3302 -0.4318)
						)
					)
					(width 0)
					(fill yes)
				)
			)
		)
		(pad "K" smd custom
			(at 0 0.762 90)
			(size 0.2159 0.2159)
			(layers "F.Cu" "F.Mask" "F.Paste")
			(net "EXP_BMC_HB_LED_D")
			(options
				(clearance outline)
				(anchor circle)
			)
			(primitives
				(gr_poly
					(pts
						(arc
							(start -0.3302 -0.4318)
							(mid -0.402042 -0.402042)
							(end -0.4318 -0.3302)
						)
						(arc
							(start -0.4318 0.3302)
							(mid -0.402042 0.402042)
							(end -0.3302 0.4318)
						)
						(arc
							(start 0.3302 0.4318)
							(mid 0.402042 0.402042)
							(end 0.4318 0.3302)
						)
						(arc
							(start 0.4318 -0.3302)
							(mid 0.402042 -0.402042)
							(end 0.3302 -0.4318)
						)
					)
					(width 0)
					(fill yes)
				)
			)
		)
	)
	(footprint ""
		(layer "F.Cu")
		(at 18.7452 -53.6194 180)
		(property "Reference" "R582"
			(at 0 0 180)
			(layer "F.SilkS")
			(hide yes)
			(effects
				(font
					(size 1.27 1.27)
				)
			)
		)
		(property "Value" "0R2J-2-GP"
			(at 0.064008 -3.993896 180)
			(unlocked yes)
			(layer "F.Fab")
			(hide yes)
			(effects
				(font
					(size 1.016 1.016)
					(thickness 0.1524)
				)
			)
		)
		(property "Device Type" "R402H16"
			(at 0.064008 -5.517896 180)
			(unlocked yes)
			(layer "F.Fab")
			(hide yes)
			(effects
				(font
					(size 1.016 1.016)
					(thickness 0.1524)
				)
			)
		)
		(duplicate_pad_numbers_are_jumpers no)
		(fp_line
			(start 0.508 -0.9398)
			(end -0.508 -0.9398)
			(stroke
				(width 0.1524)
				(type default)
			)
			(layer "F.SilkS")
		)
		(fp_line
			(start -0.508 -0.9398)
			(end -0.508 0.9398)
			(stroke
				(width 0.1524)
				(type default)
			)
			(layer "F.SilkS")
		)
		(fp_rect
			(start -0.508 0.9398)
			(end 0.508 -0.9398)
			(stroke
				(width 0)
				(type default)
			)
			(fill no)
			(layer "F.CrtYd")
		)
		(fp_rect
			(start -0.508 0.9398)
			(end 0.508 -0.9398)
			(stroke
				(width 0)
				(type default)
			)
			(fill no)
			(layer "F.Fab")
		)
		(pad "1" smd custom
			(at 0 -0.4445 180)
			(size 0.1397 0.1397)
			(layers "F.Cu" "F.Mask" "F.Paste")
			(net "NIC0_MDI0_P2_R")
			(options
				(clearance outline)
				(anchor circle)
			)
			(primitives
				(gr_poly
					(pts
						(arc
							(start -0.1778 -0.2794)
							(mid -0.249642 -0.249642)
							(end -0.2794 -0.1778)
						)
						(arc
							(start -0.2794 0.1778)
							(mid -0.249642 0.249642)
							(end -0.1778 0.2794)
						)
						(arc
							(start 0.1778 0.2794)
							(mid 0.249642 0.249642)
							(end 0.2794 0.1778)
						)
						(arc
							(start 0.2794 -0.1778)
							(mid 0.249642 -0.249642)
							(end 0.1778 -0.2794)
						)
					)
					(width 0)
					(fill yes)
				)
			)
		)
		(pad "2" smd custom
			(at 0 0.4445 180)
			(size 0.1397 0.1397)
			(layers "F.Cu" "F.Mask" "F.Paste")
			(net "NIC0_MDI0_P2")
			(options
				(clearance outline)
				(anchor circle)
			)
			(primitives
				(gr_poly
					(pts
						(arc
							(start -0.1778 -0.2794)
							(mid -0.249642 -0.249642)
							(end -0.2794 -0.1778)
						)
						(arc
							(start -0.2794 0.1778)
							(mid -0.249642 0.249642)
							(end -0.1778 0.2794)
						)
						(arc
							(start 0.1778 0.2794)
							(mid 0.249642 0.249642)
							(end 0.2794 0.1778)
						)
						(arc
							(start 0.2794 -0.1778)
							(mid 0.249642 -0.249642)
							(end 0.1778 -0.2794)
						)
					)
					(width 0)
					(fill yes)
				)
			)
		)
	)
	(footprint ""
		(layer "F.Cu")
		(at 14.224 -113.411 90)
		(property "Reference" "PG12"
			(at 0 0 90)
			(layer "F.SilkS")
			(hide yes)
			(effects
				(font
					(size 1.27 1.27)
				)
			)
		)
		(property "Value" "GAP-CLOSE-PWR-3-GP"
			(at 0.0254 -6.5786 90)
			(unlocked yes)
			(layer "F.Fab")
			(hide yes)
			(effects
				(font
					(size 1.016 1.016)
					(thickness 0.1524)
				)
			)
		)
		(property "Device Type" "GAP-CLOSE-PWR-3"
			(at 0.0254 -8.255 90)
			(unlocked yes)
			(layer "F.Fab")
			(hide yes)
			(effects
				(font
					(size 1.016 1.016)
					(thickness 0.1524)
				)
			)
		)
		(duplicate_pad_numbers_are_jumpers no)
		(fp_rect
			(start -0.7112 0.4572)
			(end 0.7112 -0.4572)
			(stroke
				(width 0)
				(type default)
			)
			(fill no)
			(layer "F.CrtYd")
		)
		(fp_poly
			(pts
				(xy -0.7112 -0.4572) (xy 0.7112 -0.4572) (xy 0.7112 0.4572) (xy -0.7112 0.4572)
			)
			(stroke
				(width 0)
				(type default)
			)
			(fill no)
			(layer "F.Fab")
		)
		(pad "1" smd rect
			(at -0.3048 0 90)
			(size 0.6604 0.762)
			(layers "F.Cu" "F.Mask" "F.Paste")
			(net "P1V26_PWR")
		)
		(pad "2" smd rect
			(at 0.3048 0 90)
			(size 0.6604 0.762)
			(layers "F.Cu" "F.Mask" "F.Paste")
			(net "P1V26_STBY")
		)
	)
	(footprint ""
		(layer "F.Cu")
		(at 287.808162 -212.420454 180)
		(property "Reference" "C92"
			(at 0 0 180)
			(layer "F.SilkS")
			(hide yes)
			(effects
				(font
					(size 1.27 1.27)
				)
			)
		)
		(property "Value" "SCD22U10V2KX-1GP"
			(at 1.1811 -2.7051 180)
			(unlocked yes)
			(layer "F.Fab")
			(hide yes)
			(effects
				(font
					(size 1.016 1.016)
					(thickness 0.1524)
				)
			)
		)
		(property "Device Type" "C402H22"
			(at 1.1811 -4.2291 180)
			(unlocked yes)
			(layer "F.Fab")
			(hide yes)
			(effects
				(font
					(size 1.016 1.016)
					(thickness 0.1524)
				)
			)
		)
		(duplicate_pad_numbers_are_jumpers no)
		(fp_rect
			(start -0.4318 0.9525)
			(end 0.4318 -0.9525)
			(stroke
				(width 0)
				(type default)
			)
			(fill no)
			(layer "F.CrtYd")
		)
		(fp_rect
			(start -0.4318 0.9525)
			(end 0.4318 -0.9525)
			(stroke
				(width 0)
				(type default)
			)
			(fill no)
			(layer "F.Fab")
		)
		(pad "1" smd custom
			(at 0 -0.4445 180)
			(size 0.1524 0.1524)
			(layers "F.Cu" "F.Mask" "F.Paste")
			(net "PCIE_TX_CAP_N30")
			(options
				(clearance outline)
				(anchor circle)
			)
			(primitives
				(gr_poly
					(pts
						(arc
							(start 0.3048 -0.2032)
							(mid 0.275042 -0.275042)
							(end 0.2032 -0.3048)
						)
						(arc
							(start -0.2032 -0.3048)
							(mid -0.275042 -0.275042)
							(end -0.3048 -0.2032)
						)
						(arc
							(start -0.3048 0.2032)
							(mid -0.275042 0.275042)
							(end -0.2032 0.3048)
						)
						(arc
							(start 0.2032 0.3048)
							(mid 0.275042 0.275042)
							(end 0.3048 0.2032)
						)
					)
					(width 0)
					(fill yes)
				)
			)
		)
		(pad "2" smd custom
			(at 0 0.4445 180)
			(size 0.1524 0.1524)
			(layers "F.Cu" "F.Mask" "F.Paste")
			(net "PCIE_TX_N30")
			(options
				(clearance outline)
				(anchor circle)
			)
			(primitives
				(gr_poly
					(pts
						(arc
							(start 0.3048 -0.2032)
							(mid 0.275042 -0.275042)
							(end 0.2032 -0.3048)
						)
						(arc
							(start -0.2032 -0.3048)
							(mid -0.275042 -0.275042)
							(end -0.3048 -0.2032)
						)
						(arc
							(start -0.3048 0.2032)
							(mid -0.275042 0.275042)
							(end -0.2032 0.3048)
						)
						(arc
							(start 0.2032 0.3048)
							(mid 0.275042 0.275042)
							(end 0.3048 0.2032)
						)
					)
					(width 0)
					(fill yes)
				)
			)
		)
	)
	(footprint ""
		(layer "F.Cu")
		(at 24.2951 -50.6476 90)
		(property "Reference" "D19"
			(at 0 0 90)
			(layer "F.SilkS")
			(hide yes)
			(effects
				(font
					(size 1.27 1.27)
				)
			)
		)
		(property "Value" "PGB1010603MR-GP"
			(at -0.0254 -2.8956 90)
			(unlocked yes)
			(layer "F.Fab")
			(hide yes)
			(effects
				(font
					(size 1.016 1.016)
					(thickness 0.1524)
				)
			)
		)
		(property "Device Type" "L1608-UH15"
			(at -0.0254 -4.4196 90)
			(unlocked yes)
			(layer "F.Fab")
			(hide yes)
			(effects
				(font
					(size 1.016 1.016)
					(thickness 0.1524)
				)
			)
		)
		(duplicate_pad_numbers_are_jumpers no)
		(fp_line
			(start 0.254 0)
			(end -0.254 0)
			(stroke
				(width 0.2032)
				(type default)
			)
			(layer "F.SilkS")
		)
		(fp_rect
			(start -0.5842 1.3335)
			(end 0.5842 -1.3335)
			(stroke
				(width 0)
				(type default)
			)
			(fill no)
			(layer "F.CrtYd")
		)
		(fp_rect
			(start -0.5842 1.3335)
			(end 0.5842 -1.3335)
			(stroke
				(width 0)
				(type default)
			)
			(fill no)
			(layer "F.Fab")
		)
		(pad "1" smd custom
			(at 0 -0.762 90)
			(size 0.2159 0.2159)
			(layers "F.Cu" "F.Mask" "F.Paste")
			(net "NIC0_MDI0_P3_R")
			(options
				(clearance outline)
				(anchor circle)
			)
			(primitives
				(gr_poly
					(pts
						(arc
							(start -0.3302 -0.4318)
							(mid -0.402042 -0.402042)
							(end -0.4318 -0.3302)
						)
						(arc
							(start -0.4318 0.3302)
							(mid -0.402042 0.402042)
							(end -0.3302 0.4318)
						)
						(arc
							(start 0.3302 0.4318)
							(mid 0.402042 0.402042)
							(end 0.4318 0.3302)
						)
						(arc
							(start 0.4318 -0.3302)
							(mid 0.402042 -0.402042)
							(end 0.3302 -0.4318)
						)
					)
					(width 0)
					(fill yes)
				)
			)
		)
		(pad "2" smd custom
			(at 0 0.762 90)
			(size 0.2159 0.2159)
			(layers "F.Cu" "F.Mask" "F.Paste")
			(net "GND")
			(options
				(clearance outline)
				(anchor circle)
			)
			(primitives
				(gr_poly
					(pts
						(arc
							(start -0.3302 -0.4318)
							(mid -0.402042 -0.402042)
							(end -0.4318 -0.3302)
						)
						(arc
							(start -0.4318 0.3302)
							(mid -0.402042 0.402042)
							(end -0.3302 0.4318)
						)
						(arc
							(start 0.3302 0.4318)
							(mid 0.402042 0.402042)
							(end 0.4318 0.3302)
						)
						(arc
							(start 0.4318 -0.3302)
							(mid 0.402042 -0.402042)
							(end 0.3302 -0.4318)
						)
					)
					(width 0)
					(fill yes)
				)
			)
		)
	)
	(footprint ""
		(layer "F.Cu")
		(at 335.153 -184.404)
		(property "Reference" "TP184"
			(at 0 0 0)
			(layer "F.SilkS")
			(hide yes)
			(effects
				(font
					(size 1.27 1.27)
				)
			)
		)
		(property "Value" "TPAD28-2-GP"
			(at -0.0127 -1.6637 0)
			(unlocked yes)
			(layer "F.Fab")
			(hide yes)
			(effects
				(font
					(size 1.016 1.016)
					(thickness 0.1524)
				)
			)
		)
		(property "Device Type" "TPAD28"
			(at -0.0127 -3.1877 0)
			(unlocked yes)
			(layer "F.Fab")
			(hide yes)
			(effects
				(font
					(size 1.016 1.016)
					(thickness 0.1524)
				)
			)
		)
		(duplicate_pad_numbers_are_jumpers no)
		(fp_poly
			(pts
				(arc
					(start 0.3556 0)
					(mid -0.3556 0)
					(end 0.3556 0)
				)
			)
			(stroke
				(width 0)
				(type default)
			)
			(fill no)
			(layer "F.CrtYd")
		)
		(fp_poly
			(pts
				(arc
					(start 0.6096 0)
					(mid -0.6096 0)
					(end 0.6096 0)
				)
			)
			(stroke
				(width 0)
				(type default)
			)
			(fill no)
			(layer "F.Fab")
		)
		(pad "1" smd circle
			(at 0 0)
			(size 0.7112 0.7112)
			(layers "F.Cu" "F.Mask" "F.Paste")
			(net "IOEXP4_GPIO14")
		)
	)
	(footprint ""
		(layer "F.Cu")
		(at 48.641 -150.495 180)
		(property "Reference" "R161"
			(at 0 0 180)
			(layer "F.SilkS")
			(hide yes)
			(effects
				(font
					(size 1.27 1.27)
				)
			)
		)
		(property "Value" "4K7R2F-GP"
			(at 0.064008 -3.993896 180)
			(unlocked yes)
			(layer "F.Fab")
			(hide yes)
			(effects
				(font
					(size 1.016 1.016)
					(thickness 0.1524)
				)
			)
		)
		(property "Device Type" "R402H16"
			(at 0.064008 -5.517896 180)
			(unlocked yes)
			(layer "F.Fab")
			(hide yes)
			(effects
				(font
					(size 1.016 1.016)
					(thickness 0.1524)
				)
			)
		)
		(duplicate_pad_numbers_are_jumpers no)
		(fp_line
			(start 0.508 -0.9398)
			(end -0.508 -0.9398)
			(stroke
				(width 0.1524)
				(type default)
			)
			(layer "F.SilkS")
		)
		(fp_line
			(start -0.508 -0.9398)
			(end -0.508 0.9398)
			(stroke
				(width 0.1524)
				(type default)
			)
			(layer "F.SilkS")
		)
		(fp_rect
			(start -0.508 0.9398)
			(end 0.508 -0.9398)
			(stroke
				(width 0)
				(type default)
			)
			(fill no)
			(layer "F.CrtYd")
		)
		(fp_rect
			(start -0.508 0.9398)
			(end 0.508 -0.9398)
			(stroke
				(width 0)
				(type default)
			)
			(fill no)
			(layer "F.Fab")
		)
		(pad "1" smd custom
			(at 0 -0.4445 180)
			(size 0.1397 0.1397)
			(layers "F.Cu" "F.Mask" "F.Paste")
			(net "P3V3_STBY")
			(options
				(clearance outline)
				(anchor circle)
			)
			(primitives
				(gr_poly
					(pts
						(arc
							(start -0.1778 -0.2794)
							(mid -0.249642 -0.249642)
							(end -0.2794 -0.1778)
						)
						(arc
							(start -0.2794 0.1778)
							(mid -0.249642 0.249642)
							(end -0.1778 0.2794)
						)
						(arc
							(start 0.1778 0.2794)
							(mid 0.249642 0.249642)
							(end 0.2794 0.1778)
						)
						(arc
							(start 0.2794 -0.1778)
							(mid 0.249642 -0.249642)
							(end 0.1778 -0.2794)
						)
					)
					(width 0)
					(fill yes)
				)
			)
		)
		(pad "2" smd custom
			(at 0 0.4445 180)
			(size 0.1397 0.1397)
			(layers "F.Cu" "F.Mask" "F.Paste")
			(net "TEMP_2_A1")
			(options
				(clearance outline)
				(anchor circle)
			)
			(primitives
				(gr_poly
					(pts
						(arc
							(start -0.1778 -0.2794)
							(mid -0.249642 -0.249642)
							(end -0.2794 -0.1778)
						)
						(arc
							(start -0.2794 0.1778)
							(mid -0.249642 0.249642)
							(end -0.1778 0.2794)
						)
						(arc
							(start 0.1778 0.2794)
							(mid 0.249642 0.249642)
							(end 0.2794 0.1778)
						)
						(arc
							(start 0.2794 -0.1778)
							(mid 0.249642 -0.249642)
							(end 0.1778 -0.2794)
						)
					)
					(width 0)
					(fill yes)
				)
			)
		)
	)
	(footprint ""
		(layer "F.Cu")
		(at 11.4554 -100.1776 90)
		(property "Reference" "C232"
			(at 0 0 90)
			(layer "F.SilkS")
			(hide yes)
			(effects
				(font
					(size 1.27 1.27)
				)
			)
		)
		(property "Value" "SC1U10V2KX-4-GP"
			(at 1.1811 -2.7051 90)
			(unlocked yes)
			(layer "F.Fab")
			(hide yes)
			(effects
				(font
					(size 1.016 1.016)
					(thickness 0.1524)
				)
			)
		)
		(property "Device Type" "C402H22"
			(at 1.1811 -4.2291 90)
			(unlocked yes)
			(layer "F.Fab")
			(hide yes)
			(effects
				(font
					(size 1.016 1.016)
					(thickness 0.1524)
				)
			)
		)
		(duplicate_pad_numbers_are_jumpers no)
		(fp_rect
			(start -0.4318 0.9525)
			(end 0.4318 -0.9525)
			(stroke
				(width 0)
				(type default)
			)
			(fill no)
			(layer "F.CrtYd")
		)
		(fp_rect
			(start -0.4318 0.9525)
			(end 0.4318 -0.9525)
			(stroke
				(width 0)
				(type default)
			)
			(fill no)
			(layer "F.Fab")
		)
		(pad "1" smd custom
			(at 0 -0.4445 90)
			(size 0.1524 0.1524)
			(layers "F.Cu" "F.Mask" "F.Paste")
			(net "P3V3_STBY")
			(options
				(clearance outline)
				(anchor circle)
			)
			(primitives
				(gr_poly
					(pts
						(arc
							(start 0.3048 -0.2032)
							(mid 0.275042 -0.275042)
							(end 0.2032 -0.3048)
						)
						(arc
							(start -0.2032 -0.3048)
							(mid -0.275042 -0.275042)
							(end -0.3048 -0.2032)
						)
						(arc
							(start -0.3048 0.2032)
							(mid -0.275042 0.275042)
							(end -0.2032 0.3048)
						)
						(arc
							(start 0.2032 0.3048)
							(mid 0.275042 0.275042)
							(end 0.3048 0.2032)
						)
					)
					(width 0)
					(fill yes)
				)
			)
		)
		(pad "2" smd custom
			(at 0 0.4445 90)
			(size 0.1524 0.1524)
			(layers "F.Cu" "F.Mask" "F.Paste")
			(net "GND")
			(options
				(clearance outline)
				(anchor circle)
			)
			(primitives
				(gr_poly
					(pts
						(arc
							(start 0.3048 -0.2032)
							(mid 0.275042 -0.275042)
							(end 0.2032 -0.3048)
						)
						(arc
							(start -0.2032 -0.3048)
							(mid -0.275042 -0.275042)
							(end -0.3048 -0.2032)
						)
						(arc
							(start -0.3048 0.2032)
							(mid -0.275042 0.275042)
							(end -0.2032 0.3048)
						)
						(arc
							(start 0.2032 0.3048)
							(mid 0.275042 0.275042)
							(end 0.3048 0.2032)
						)
					)
					(width 0)
					(fill yes)
				)
			)
		)
	)
	(footprint ""
		(layer "F.Cu")
		(at 37.183314 -65.01892 90)
		(property "Reference" "TC14"
			(at 0 0 90)
			(layer "F.SilkS")
			(hide yes)
			(effects
				(font
					(size 1.27 1.27)
				)
			)
		)
		(property "Value" "SC22U25V6KX-GP-U"
			(at -2.860802 -5.279644 90)
			(unlocked yes)
			(layer "F.Fab")
			(hide yes)
			(effects
				(font
					(size 1.016 1.016)
					(thickness 0.1524)
				)
			)
		)
		(property "Device Type" "C1206-TO0D3H75"
			(at -2.860802 -6.803644 90)
			(unlocked yes)
			(layer "F.Fab")
			(hide yes)
			(effects
				(font
					(size 1.016 1.016)
					(thickness 0.1524)
				)
			)
		)
		(duplicate_pad_numbers_are_jumpers no)
		(fp_line
			(start 1.3081 -2.3749)
			(end 1.3081 2.3749)
			(stroke
				(width 0.1524)
				(type default)
			)
			(layer "F.SilkS")
		)
		(fp_line
			(start -1.3081 -2.3749)
			(end 1.3081 -2.3749)
			(stroke
				(width 0.1524)
				(type default)
			)
			(layer "F.SilkS")
		)
		(fp_line
			(start 1.3081 2.3749)
			(end -1.3081 2.3749)
			(stroke
				(width 0.1524)
				(type default)
			)
			(layer "F.SilkS")
		)
		(fp_line
			(start -1.3081 2.3749)
			(end -1.3081 -2.3749)
			(stroke
				(width 0.1524)
				(type default)
			)
			(layer "F.SilkS")
		)
		(fp_rect
			(start -0.8001 1.6002)
			(end 0.8001 -1.6002)
			(stroke
				(width 0)
				(type default)
			)
			(fill no)
			(layer "F.CrtYd")
		)
		(fp_poly
			(pts
				(xy -1.5621 2.4511) (xy -1.5621 1.6002) (xy 0.8001 1.6002) (xy 0.8001 -1.6002) (xy -0.8001 -1.6002)
				(xy -0.8001 1.5875) (xy -1.5621 1.5875) (xy -1.5621 -2.4511) (xy 1.5621 -2.4511) (xy 1.5621 2.4511)
			)
			(stroke
				(width 0)
				(type default)
			)
			(fill no)
			(layer "F.CrtYd")
		)
		(fp_rect
			(start -1.5621 2.4511)
			(end 1.5621 -2.4511)
			(stroke
				(width 0)
				(type default)
			)
			(fill no)
			(layer "F.Fab")
		)
		(pad "1" smd rect
			(at 0 -1.392936 90)
			(size 2.1082 1.4478)
			(layers "F.Cu" "F.Mask" "F.Paste")
			(net "P5V_USB_BP1_F")
		)
		(pad "2" smd rect
			(at 0 1.392936 90)
			(size 2.1082 1.4478)
			(layers "F.Cu" "F.Mask" "F.Paste")
			(net "GND")
		)
	)
	(footprint ""
		(layer "F.Cu")
		(at 181.61 -25.908 -90)
		(property "Reference" "C406"
			(at 0 0 270)
			(layer "F.SilkS")
			(hide yes)
			(effects
				(font
					(size 1.27 1.27)
				)
			)
		)
		(property "Value" "SCD22U10V2KX-1GP"
			(at 1.1811 -2.7051 270)
			(unlocked yes)
			(layer "F.Fab")
			(hide yes)
			(effects
				(font
					(size 1.016 1.016)
					(thickness 0.1524)
				)
			)
		)
		(property "Device Type" "C402H22"
			(at 1.1811 -4.2291 270)
			(unlocked yes)
			(layer "F.Fab")
			(hide yes)
			(effects
				(font
					(size 1.016 1.016)
					(thickness 0.1524)
				)
			)
		)
		(duplicate_pad_numbers_are_jumpers no)
		(fp_rect
			(start -0.4318 0.9525)
			(end 0.4318 -0.9525)
			(stroke
				(width 0)
				(type default)
			)
			(fill no)
			(layer "F.CrtYd")
		)
		(fp_rect
			(start -0.4318 0.9525)
			(end 0.4318 -0.9525)
			(stroke
				(width 0)
				(type default)
			)
			(fill no)
			(layer "F.Fab")
		)
		(pad "1" smd custom
			(at 0 -0.4445 270)
			(size 0.1524 0.1524)
			(layers "F.Cu" "F.Mask" "F.Paste")
			(net "PCIE_TX_CAP_N93")
			(options
				(clearance outline)
				(anchor circle)
			)
			(primitives
				(gr_poly
					(pts
						(arc
							(start 0.3048 -0.2032)
							(mid 0.275042 -0.275042)
							(end 0.2032 -0.3048)
						)
						(arc
							(start -0.2032 -0.3048)
							(mid -0.275042 -0.275042)
							(end -0.3048 -0.2032)
						)
						(arc
							(start -0.3048 0.2032)
							(mid -0.275042 0.275042)
							(end -0.2032 0.3048)
						)
						(arc
							(start 0.2032 0.3048)
							(mid 0.275042 0.275042)
							(end 0.3048 0.2032)
						)
					)
					(width 0)
					(fill yes)
				)
			)
		)
		(pad "2" smd custom
			(at 0 0.4445 270)
			(size 0.1524 0.1524)
			(layers "F.Cu" "F.Mask" "F.Paste")
			(net "PCIE_TX_N93")
			(options
				(clearance outline)
				(anchor circle)
			)
			(primitives
				(gr_poly
					(pts
						(arc
							(start 0.3048 -0.2032)
							(mid 0.275042 -0.275042)
							(end 0.2032 -0.3048)
						)
						(arc
							(start -0.2032 -0.3048)
							(mid -0.275042 -0.275042)
							(end -0.3048 -0.2032)
						)
						(arc
							(start -0.3048 0.2032)
							(mid -0.275042 0.275042)
							(end -0.2032 0.3048)
						)
						(arc
							(start 0.2032 0.3048)
							(mid 0.275042 0.275042)
							(end 0.3048 0.2032)
						)
					)
					(width 0)
					(fill yes)
				)
			)
		)
	)
	(footprint ""
		(layer "F.Cu")
		(at 20.6502 -194.7926 -90)
		(property "Reference" "R2106"
			(at 0 0 270)
			(layer "F.SilkS")
			(hide yes)
			(effects
				(font
					(size 1.27 1.27)
				)
			)
		)
		(property "Value" "49K9R2F-L-GP"
			(at 0.064008 -3.993896 270)
			(unlocked yes)
			(layer "F.Fab")
			(hide yes)
			(effects
				(font
					(size 1.016 1.016)
					(thickness 0.1524)
				)
			)
		)
		(property "Device Type" "R402H16"
			(at 0.064008 -5.517896 270)
			(unlocked yes)
			(layer "F.Fab")
			(hide yes)
			(effects
				(font
					(size 1.016 1.016)
					(thickness 0.1524)
				)
			)
		)
		(duplicate_pad_numbers_are_jumpers no)
		(fp_line
			(start -0.508 -0.9398)
			(end -0.508 0.9398)
			(stroke
				(width 0.1524)
				(type default)
			)
			(layer "F.SilkS")
		)
		(fp_line
			(start 0.508 -0.9398)
			(end -0.508 -0.9398)
			(stroke
				(width 0.1524)
				(type default)
			)
			(layer "F.SilkS")
		)
		(fp_rect
			(start -0.508 0.9398)
			(end 0.508 -0.9398)
			(stroke
				(width 0)
				(type default)
			)
			(fill no)
			(layer "F.CrtYd")
		)
		(fp_rect
			(start -0.508 0.9398)
			(end 0.508 -0.9398)
			(stroke
				(width 0)
				(type default)
			)
			(fill no)
			(layer "F.Fab")
		)
		(pad "1" smd custom
			(at 0 -0.4445 270)
			(size 0.1397 0.1397)
			(layers "F.Cu" "F.Mask" "F.Paste")
			(net "P12V_PCIE")
			(options
				(clearance outline)
				(anchor circle)
			)
			(primitives
				(gr_poly
					(pts
						(arc
							(start -0.1778 -0.2794)
							(mid -0.249642 -0.249642)
							(end -0.2794 -0.1778)
						)
						(arc
							(start -0.2794 0.1778)
							(mid -0.249642 0.249642)
							(end -0.1778 0.2794)
						)
						(arc
							(start 0.1778 0.2794)
							(mid 0.249642 0.249642)
							(end 0.2794 0.1778)
						)
						(arc
							(start 0.2794 -0.1778)
							(mid 0.249642 -0.249642)
							(end 0.1778 -0.2794)
						)
					)
					(width 0)
					(fill yes)
				)
			)
		)
		(pad "2" smd custom
			(at 0 0.4445 270)
			(size 0.1397 0.1397)
			(layers "F.Cu" "F.Mask" "F.Paste")
			(net "MB0_CM_OV_R")
			(options
				(clearance outline)
				(anchor circle)
			)
			(primitives
				(gr_poly
					(pts
						(arc
							(start -0.1778 -0.2794)
							(mid -0.249642 -0.249642)
							(end -0.2794 -0.1778)
						)
						(arc
							(start -0.2794 0.1778)
							(mid -0.249642 0.249642)
							(end -0.1778 0.2794)
						)
						(arc
							(start 0.1778 0.2794)
							(mid 0.249642 0.249642)
							(end 0.2794 0.1778)
						)
						(arc
							(start 0.2794 -0.1778)
							(mid 0.249642 -0.249642)
							(end 0.1778 -0.2794)
						)
					)
					(width 0)
					(fill yes)
				)
			)
		)
	)
	(footprint ""
		(layer "F.Cu")
		(at 23.876 -131.699 90)
		(property "Reference" "R363"
			(at 0 0 90)
			(layer "F.SilkS")
			(hide yes)
			(effects
				(font
					(size 1.27 1.27)
				)
			)
		)
		(property "Value" "3K3R2F-2-GP"
			(at 0.064008 -3.993896 90)
			(unlocked yes)
			(layer "F.Fab")
			(hide yes)
			(effects
				(font
					(size 1.016 1.016)
					(thickness 0.1524)
				)
			)
		)
		(property "Device Type" "R402H16"
			(at 0.064008 -5.517896 90)
			(unlocked yes)
			(layer "F.Fab")
			(hide yes)
			(effects
				(font
					(size 1.016 1.016)
					(thickness 0.1524)
				)
			)
		)
		(duplicate_pad_numbers_are_jumpers no)
		(fp_line
			(start 0.508 -0.9398)
			(end -0.508 -0.9398)
			(stroke
				(width 0.1524)
				(type default)
			)
			(layer "F.SilkS")
		)
		(fp_line
			(start -0.508 -0.9398)
			(end -0.508 0.9398)
			(stroke
				(width 0.1524)
				(type default)
			)
			(layer "F.SilkS")
		)
		(fp_rect
			(start -0.508 0.9398)
			(end 0.508 -0.9398)
			(stroke
				(width 0)
				(type default)
			)
			(fill no)
			(layer "F.CrtYd")
		)
		(fp_rect
			(start -0.508 0.9398)
			(end 0.508 -0.9398)
			(stroke
				(width 0)
				(type default)
			)
			(fill no)
			(layer "F.Fab")
		)
		(pad "1" smd custom
			(at 0 -0.4445 90)
			(size 0.1397 0.1397)
			(layers "F.Cu" "F.Mask" "F.Paste")
			(net "P3V3_STBY")
			(options
				(clearance outline)
				(anchor circle)
			)
			(primitives
				(gr_poly
					(pts
						(arc
							(start -0.1778 -0.2794)
							(mid -0.249642 -0.249642)
							(end -0.2794 -0.1778)
						)
						(arc
							(start -0.2794 0.1778)
							(mid -0.249642 0.249642)
							(end -0.1778 0.2794)
						)
						(arc
							(start 0.1778 0.2794)
							(mid 0.249642 0.249642)
							(end 0.2794 0.1778)
						)
						(arc
							(start 0.2794 -0.1778)
							(mid 0.249642 -0.249642)
							(end 0.1778 -0.2794)
						)
					)
					(width 0)
					(fill yes)
				)
			)
		)
		(pad "2" smd custom
			(at 0 0.4445 90)
			(size 0.1397 0.1397)
			(layers "F.Cu" "F.Mask" "F.Paste")
			(net "ROMA6")
			(options
				(clearance outline)
				(anchor circle)
			)
			(primitives
				(gr_poly
					(pts
						(arc
							(start -0.1778 -0.2794)
							(mid -0.249642 -0.249642)
							(end -0.2794 -0.1778)
						)
						(arc
							(start -0.2794 0.1778)
							(mid -0.249642 0.249642)
							(end -0.1778 0.2794)
						)
						(arc
							(start 0.1778 0.2794)
							(mid 0.249642 0.249642)
							(end 0.2794 0.1778)
						)
						(arc
							(start 0.2794 -0.1778)
							(mid 0.249642 -0.249642)
							(end 0.1778 -0.2794)
						)
					)
					(width 0)
					(fill yes)
				)
			)
		)
	)
	(footprint ""
		(layer "F.Cu")
		(at 146.2024 -41.3766 180)
		(property "Reference" "R767"
			(at 0 0 180)
			(layer "F.SilkS")
			(hide yes)
			(effects
				(font
					(size 1.27 1.27)
				)
			)
		)
		(property "Value" "4K7R2F-GP"
			(at 0.064008 -3.993896 180)
			(unlocked yes)
			(layer "F.Fab")
			(hide yes)
			(effects
				(font
					(size 1.016 1.016)
					(thickness 0.1524)
				)
			)
		)
		(property "Device Type" "R402H16"
			(at 0.064008 -5.517896 180)
			(unlocked yes)
			(layer "F.Fab")
			(hide yes)
			(effects
				(font
					(size 1.016 1.016)
					(thickness 0.1524)
				)
			)
		)
		(duplicate_pad_numbers_are_jumpers no)
		(fp_line
			(start 0.508 -0.9398)
			(end -0.508 -0.9398)
			(stroke
				(width 0.1524)
				(type default)
			)
			(layer "F.SilkS")
		)
		(fp_line
			(start -0.508 -0.9398)
			(end -0.508 0.9398)
			(stroke
				(width 0.1524)
				(type default)
			)
			(layer "F.SilkS")
		)
		(fp_rect
			(start -0.508 0.9398)
			(end 0.508 -0.9398)
			(stroke
				(width 0)
				(type default)
			)
			(fill no)
			(layer "F.CrtYd")
		)
		(fp_rect
			(start -0.508 0.9398)
			(end 0.508 -0.9398)
			(stroke
				(width 0)
				(type default)
			)
			(fill no)
			(layer "F.Fab")
		)
		(pad "1" smd custom
			(at 0 -0.4445 180)
			(size 0.1397 0.1397)
			(layers "F.Cu" "F.Mask" "F.Paste")
			(net "DUT_VDDO")
			(options
				(clearance outline)
				(anchor circle)
			)
			(primitives
				(gr_poly
					(pts
						(arc
							(start -0.1778 -0.2794)
							(mid -0.249642 -0.249642)
							(end -0.2794 -0.1778)
						)
						(arc
							(start -0.2794 0.1778)
							(mid -0.249642 0.249642)
							(end -0.1778 0.2794)
						)
						(arc
							(start 0.1778 0.2794)
							(mid 0.249642 0.249642)
							(end 0.2794 0.1778)
						)
						(arc
							(start 0.2794 -0.1778)
							(mid 0.249642 -0.249642)
							(end 0.1778 -0.2794)
						)
					)
					(width 0)
					(fill yes)
				)
			)
		)
		(pad "2" smd custom
			(at 0 0.4445 180)
			(size 0.1397 0.1397)
			(layers "F.Cu" "F.Mask" "F.Paste")
			(net "EJTAG_DINT")
			(options
				(clearance outline)
				(anchor circle)
			)
			(primitives
				(gr_poly
					(pts
						(arc
							(start -0.1778 -0.2794)
							(mid -0.249642 -0.249642)
							(end -0.2794 -0.1778)
						)
						(arc
							(start -0.2794 0.1778)
							(mid -0.249642 0.249642)
							(end -0.1778 0.2794)
						)
						(arc
							(start 0.1778 0.2794)
							(mid 0.249642 0.249642)
							(end 0.2794 0.1778)
						)
						(arc
							(start 0.2794 -0.1778)
							(mid 0.249642 -0.249642)
							(end 0.1778 -0.2794)
						)
					)
					(width 0)
					(fill yes)
				)
			)
		)
	)
	(footprint ""
		(layer "F.Cu")
		(at 155.882086 -33.421574 180)
		(property "Reference" "R669"
			(at 0 0 180)
			(layer "F.SilkS")
			(hide yes)
			(effects
				(font
					(size 1.27 1.27)
				)
			)
		)
		(property "Value" "0R2J-2-GP"
			(at 0.064008 -3.993896 180)
			(unlocked yes)
			(layer "F.Fab")
			(hide yes)
			(effects
				(font
					(size 1.016 1.016)
					(thickness 0.1524)
				)
			)
		)
		(property "Device Type" "R402H16"
			(at 0.064008 -5.517896 180)
			(unlocked yes)
			(layer "F.Fab")
			(hide yes)
			(effects
				(font
					(size 1.016 1.016)
					(thickness 0.1524)
				)
			)
		)
		(duplicate_pad_numbers_are_jumpers no)
		(fp_line
			(start 0.508 -0.9398)
			(end -0.508 -0.9398)
			(stroke
				(width 0.1524)
				(type default)
			)
			(layer "F.SilkS")
		)
		(fp_line
			(start -0.508 -0.9398)
			(end -0.508 0.9398)
			(stroke
				(width 0.1524)
				(type default)
			)
			(layer "F.SilkS")
		)
		(fp_rect
			(start -0.508 0.9398)
			(end 0.508 -0.9398)
			(stroke
				(width 0)
				(type default)
			)
			(fill no)
			(layer "F.CrtYd")
		)
		(fp_rect
			(start -0.508 0.9398)
			(end 0.508 -0.9398)
			(stroke
				(width 0)
				(type default)
			)
			(fill no)
			(layer "F.Fab")
		)
		(pad "1" smd custom
			(at 0 -0.4445 180)
			(size 0.1397 0.1397)
			(layers "F.Cu" "F.Mask" "F.Paste")
			(net "8644_USB_DN3")
			(options
				(clearance outline)
				(anchor circle)
			)
			(primitives
				(gr_poly
					(pts
						(arc
							(start -0.1778 -0.2794)
							(mid -0.249642 -0.249642)
							(end -0.2794 -0.1778)
						)
						(arc
							(start -0.2794 0.1778)
							(mid -0.249642 0.249642)
							(end -0.1778 0.2794)
						)
						(arc
							(start 0.1778 0.2794)
							(mid 0.249642 0.249642)
							(end 0.2794 0.1778)
						)
						(arc
							(start 0.2794 -0.1778)
							(mid 0.249642 -0.249642)
							(end 0.1778 -0.2794)
						)
					)
					(width 0)
					(fill yes)
				)
			)
		)
		(pad "2" smd custom
			(at 0 0.4445 180)
			(size 0.1397 0.1397)
			(layers "F.Cu" "F.Mask" "F.Paste")
			(net "P3V3_STBY")
			(options
				(clearance outline)
				(anchor circle)
			)
			(primitives
				(gr_poly
					(pts
						(arc
							(start -0.1778 -0.2794)
							(mid -0.249642 -0.249642)
							(end -0.2794 -0.1778)
						)
						(arc
							(start -0.2794 0.1778)
							(mid -0.249642 0.249642)
							(end -0.1778 0.2794)
						)
						(arc
							(start 0.1778 0.2794)
							(mid 0.249642 0.249642)
							(end 0.2794 0.1778)
						)
						(arc
							(start 0.2794 -0.1778)
							(mid 0.249642 -0.249642)
							(end 0.1778 -0.2794)
						)
					)
					(width 0)
					(fill yes)
				)
			)
		)
	)
	(footprint ""
		(layer "F.Cu")
		(at 219.813124 -190.601092)
		(property "Reference" "R7923"
			(at 0 0 0)
			(layer "F.SilkS")
			(hide yes)
			(effects
				(font
					(size 1.27 1.27)
				)
			)
		)
		(property "Value" "0R2J-2-GP"
			(at 0.064008 -3.993896 0)
			(unlocked yes)
			(layer "F.Fab")
			(hide yes)
			(effects
				(font
					(size 1.016 1.016)
					(thickness 0.1524)
				)
			)
		)
		(property "Device Type" "R402H16"
			(at 0.064008 -5.517896 0)
			(unlocked yes)
			(layer "F.Fab")
			(hide yes)
			(effects
				(font
					(size 1.016 1.016)
					(thickness 0.1524)
				)
			)
		)
		(duplicate_pad_numbers_are_jumpers no)
		(fp_line
			(start -0.508 -0.9398)
			(end -0.508 0.9398)
			(stroke
				(width 0.1524)
				(type default)
			)
			(layer "F.SilkS")
		)
		(fp_line
			(start 0.508 -0.9398)
			(end -0.508 -0.9398)
			(stroke
				(width 0.1524)
				(type default)
			)
			(layer "F.SilkS")
		)
		(fp_rect
			(start -0.508 0.9398)
			(end 0.508 -0.9398)
			(stroke
				(width 0)
				(type default)
			)
			(fill no)
			(layer "F.CrtYd")
		)
		(fp_rect
			(start -0.508 0.9398)
			(end 0.508 -0.9398)
			(stroke
				(width 0)
				(type default)
			)
			(fill no)
			(layer "F.Fab")
		)
		(pad "1" smd custom
			(at 0 -0.4445)
			(size 0.1397 0.1397)
			(layers "F.Cu" "F.Mask" "F.Paste")
			(net "SSD_PRSNT#3")
			(options
				(clearance outline)
				(anchor circle)
			)
			(primitives
				(gr_poly
					(pts
						(arc
							(start -0.1778 -0.2794)
							(mid -0.249642 -0.249642)
							(end -0.2794 -0.1778)
						)
						(arc
							(start -0.2794 0.1778)
							(mid -0.249642 0.249642)
							(end -0.1778 0.2794)
						)
						(arc
							(start 0.1778 0.2794)
							(mid 0.249642 0.249642)
							(end 0.2794 0.1778)
						)
						(arc
							(start 0.2794 -0.1778)
							(mid 0.249642 -0.249642)
							(end 0.1778 -0.2794)
						)
					)
					(width 0)
					(fill yes)
				)
			)
		)
		(pad "2" smd custom
			(at 0 0.4445)
			(size 0.1397 0.1397)
			(layers "F.Cu" "F.Mask" "F.Paste")
			(net "SSD_PRSNT#3_R")
			(options
				(clearance outline)
				(anchor circle)
			)
			(primitives
				(gr_poly
					(pts
						(arc
							(start -0.1778 -0.2794)
							(mid -0.249642 -0.249642)
							(end -0.2794 -0.1778)
						)
						(arc
							(start -0.2794 0.1778)
							(mid -0.249642 0.249642)
							(end -0.1778 0.2794)
						)
						(arc
							(start 0.1778 0.2794)
							(mid 0.249642 0.249642)
							(end 0.2794 0.1778)
						)
						(arc
							(start 0.2794 -0.1778)
							(mid 0.249642 -0.249642)
							(end 0.1778 -0.2794)
						)
					)
					(width 0)
					(fill yes)
				)
			)
		)
	)
	(footprint ""
		(layer "F.Cu")
		(at 164.8206 -206.883 -90)
		(property "Reference" "C4140"
			(at 0 0 270)
			(layer "F.SilkS")
			(hide yes)
			(effects
				(font
					(size 1.27 1.27)
				)
			)
		)
		(property "Value" "SCD1U25V3KX-GP"
			(at 0 -2.8194 270)
			(unlocked yes)
			(layer "F.Fab")
			(hide yes)
			(effects
				(font
					(size 1.016 1.016)
					(thickness 0.1524)
				)
			)
		)
		(property "Device Type" "C603H36"
			(at 0 -4.3434 270)
			(unlocked yes)
			(layer "F.Fab")
			(hide yes)
			(effects
				(font
					(size 1.016 1.016)
					(thickness 0.1524)
				)
			)
		)
		(duplicate_pad_numbers_are_jumpers no)
		(fp_line
			(start 0.508 0)
			(end -0.508 0)
			(stroke
				(width 0.2032)
				(type default)
			)
			(layer "F.SilkS")
		)
		(fp_rect
			(start -0.5842 1.3335)
			(end 0.5842 -1.3335)
			(stroke
				(width 0)
				(type default)
			)
			(fill no)
			(layer "F.CrtYd")
		)
		(fp_rect
			(start -0.5842 1.3335)
			(end 0.5842 -1.3335)
			(stroke
				(width 0)
				(type default)
			)
			(fill no)
			(layer "F.Fab")
		)
		(pad "1" smd custom
			(at 0 -0.762 270)
			(size 0.2159 0.2159)
			(layers "F.Cu" "F.Mask" "F.Paste")
			(net "GND")
			(options
				(clearance outline)
				(anchor circle)
			)
			(primitives
				(gr_poly
					(pts
						(arc
							(start -0.3302 -0.4318)
							(mid -0.402042 -0.402042)
							(end -0.4318 -0.3302)
						)
						(arc
							(start -0.4318 0.3302)
							(mid -0.402042 0.402042)
							(end -0.3302 0.4318)
						)
						(arc
							(start 0.3302 0.4318)
							(mid 0.402042 0.402042)
							(end 0.4318 0.3302)
						)
						(arc
							(start 0.4318 -0.3302)
							(mid 0.402042 -0.402042)
							(end 0.3302 -0.4318)
						)
					)
					(width 0)
					(fill yes)
				)
			)
		)
		(pad "2" smd custom
			(at 0 0.762 270)
			(size 0.2159 0.2159)
			(layers "F.Cu" "F.Mask" "F.Paste")
			(net "SSD_PWREN2_R")
			(options
				(clearance outline)
				(anchor circle)
			)
			(primitives
				(gr_poly
					(pts
						(arc
							(start -0.3302 -0.4318)
							(mid -0.402042 -0.402042)
							(end -0.4318 -0.3302)
						)
						(arc
							(start -0.4318 0.3302)
							(mid -0.402042 0.402042)
							(end -0.3302 0.4318)
						)
						(arc
							(start 0.3302 0.4318)
							(mid 0.402042 0.402042)
							(end 0.4318 0.3302)
						)
						(arc
							(start 0.4318 -0.3302)
							(mid 0.402042 -0.402042)
							(end 0.3302 -0.4318)
						)
					)
					(width 0)
					(fill yes)
				)
			)
		)
	)
	(footprint ""
		(layer "F.Cu")
		(at 13.7922 -186.6646)
		(property "Reference" "U2"
			(at 0 0 0)
			(layer "F.SilkS")
			(hide yes)
			(effects
				(font
					(size 1.27 1.27)
				)
			)
		)
		(property "Value" "ADM1278-2ACPZ-RL-1-GP"
			(at -4.7625 -7.4422 0)
			(unlocked yes)
			(layer "F.Fab")
			(hide yes)
			(effects
				(font
					(size 1.016 1.016)
					(thickness 0.1524)
				)
			)
		)
		(property "Device Type" "QFN32-G3D45-UH32"
			(at -4.7625 -8.9662 0)
			(unlocked yes)
			(layer "F.Fab")
			(hide yes)
			(effects
				(font
					(size 1.016 1.016)
					(thickness 0.1524)
				)
			)
		)
		(duplicate_pad_numbers_are_jumpers no)
		(fp_line
			(start -4.0513 -1.24968)
			(end -3.2893 -1.24968)
			(stroke
				(width 0.1524)
				(type default)
			)
			(layer "F.SilkS")
		)
		(fp_line
			(start -3.7973 1.24968)
			(end -3.2893 1.24968)
			(stroke
				(width 0.1524)
				(type default)
			)
			(layer "F.SilkS")
		)
		(fp_line
			(start -3.5179 -3.5179)
			(end -2.2479 -3.5179)
			(stroke
				(width 0.1524)
				(type default)
			)
			(layer "F.SilkS")
		)
		(fp_line
			(start -3.5179 -2.2479)
			(end -3.5179 -3.5179)
			(stroke
				(width 0.1524)
				(type default)
			)
			(layer "F.SilkS")
		)
		(fp_line
			(start -3.5179 2.2479)
			(end -3.5179 3.5179)
			(stroke
				(width 0.1524)
				(type default)
			)
			(layer "F.SilkS")
		)
		(fp_line
			(start -3.5179 3.5179)
			(end -2.2479 3.5179)
			(stroke
				(width 0.1524)
				(type default)
			)
			(layer "F.SilkS")
		)
		(fp_line
			(start -0.250698 -3.7973)
			(end -0.250698 -3.2893)
			(stroke
				(width 0.1524)
				(type default)
			)
			(layer "F.SilkS")
		)
		(fp_line
			(start -0.250698 4.0513)
			(end -0.250698 3.2893)
			(stroke
				(width 0.1524)
				(type default)
			)
			(layer "F.SilkS")
		)
		(fp_line
			(start 3.5179 2.2479)
			(end 3.5179 3.5179)
			(stroke
				(width 0.1524)
				(type default)
			)
			(layer "F.SilkS")
		)
		(fp_line
			(start 3.5179 3.5179)
			(end 2.2479 3.5179)
			(stroke
				(width 0.1524)
				(type default)
			)
			(layer "F.SilkS")
		)
		(fp_line
			(start 3.7973 1.749552)
			(end 3.2893 1.749552)
			(stroke
				(width 0.1524)
				(type default)
			)
			(layer "F.SilkS")
		)
		(fp_line
			(start 4.0513 -0.749808)
			(end 3.2893 -0.749808)
			(stroke
				(width 0.1524)
				(type default)
			)
			(layer "F.SilkS")
		)
		(fp_poly
			(pts
				(xy 2.2479 -3.5179) (xy 3.5179 -2.2479) (xy 3.5179 -3.5179)
			)
			(stroke
				(width 0)
				(type default)
			)
			(fill yes)
			(layer "F.SilkS")
		)
		(fp_rect
			(start -2.5019 2.5019)
			(end 2.5019 -2.5019)
			(stroke
				(width 0)
				(type default)
			)
			(fill no)
			(layer "F.CrtYd")
		)
		(fp_poly
			(pts
				(xy -3.5179 3.5179) (xy -3.5179 -3.5179) (xy 3.5179 -3.5179) (xy 3.5179 3.5179) (xy -2.49682 3.5179)
				(xy -2.49682 2.5019) (xy 2.5019 2.5019) (xy 2.5019 -2.5019) (xy -2.5019 -2.5019) (xy -2.5019 3.5179)
			)
			(stroke
				(width 0)
				(type default)
			)
			(fill no)
			(layer "F.CrtYd")
		)
		(fp_rect
			(start -3.5179 3.5179)
			(end 3.5179 -3.5179)
			(stroke
				(width 0)
				(type default)
			)
			(fill no)
			(layer "F.Fab")
		)
		(pad "1" smd rect
			(at 1.75006 -2.5527)
			(size 0.3048 0.9144)
			(layers "F.Cu" "F.Mask" "F.Paste")
			(net "MB0_PSET_R")
		)
		(pad "2" smd rect
			(at 1.249934 -2.4765)
			(size 0.3048 1.0668)
			(layers "F.Cu" "F.Mask" "F.Paste")
			(net "MB0_VCAP_R")
		)
		(pad "3" smd rect
			(at 0.750062 -2.4765)
			(size 0.3048 1.0668)
			(layers "F.Cu" "F.Mask" "F.Paste")
			(net "MB0_ISET_R")
		)
		(pad "4" smd rect
			(at 0.249936 -2.4765)
			(size 0.3048 1.0668)
			(layers "F.Cu" "F.Mask" "F.Paste")
			(net "MB0_ISTART_R")
		)
		(pad "5" smd rect
			(at -0.249936 -2.4765)
			(size 0.3048 1.0668)
			(layers "F.Cu" "F.Mask" "F.Paste")
			(net "MB0_TIME_R")
		)
		(pad "6" smd rect
			(at -0.750062 -2.4765)
			(size 0.3048 1.0668)
			(layers "F.Cu" "F.Mask" "F.Paste")
			(net "Net_2092")
		)
		(pad "7" smd rect
			(at -1.249934 -2.4765)
			(size 0.3048 1.0668)
			(layers "F.Cu" "F.Mask" "F.Paste")
			(net "MB0_CM_ADR1_R")
		)
		(pad "8" smd rect
			(at -1.75006 -2.5527)
			(size 0.3048 0.9144)
			(layers "F.Cu" "F.Mask" "F.Paste")
			(net "MB0_CM_ADR2_R")
		)
		(pad "9" smd rect
			(at -2.5527 -1.75006)
			(size 0.9144 0.3048)
			(layers "F.Cu" "F.Mask" "F.Paste")
			(net "MB0_SPISS_PD")
		)
		(pad "10" smd rect
			(at -2.4765 -1.249934)
			(size 1.0668 0.3048)
			(layers "F.Cu" "F.Mask" "F.Paste")
			(net "Net_2096")
		)
		(pad "11" smd rect
			(at -2.4765 -0.750062)
			(size 1.0668 0.3048)
			(layers "F.Cu" "F.Mask" "F.Paste")
			(net "Net_2095")
		)
		(pad "12" smd rect
			(at -2.4765 -0.249936)
			(size 1.0668 0.3048)
			(layers "F.Cu" "F.Mask" "F.Paste")
			(net "MB0_HS_ENABLE")
		)
		(pad "13" smd rect
			(at -2.4765 0.249936)
			(size 1.0668 0.3048)
			(layers "F.Cu" "F.Mask" "F.Paste")
			(net "Net_2094")
		)
		(pad "14" smd rect
			(at -2.4765 0.750062)
			(size 1.0668 0.3048)
			(layers "F.Cu" "F.Mask" "F.Paste")
			(net "Net_2093")
		)
		(pad "15" smd rect
			(at -2.4765 1.249934)
			(size 1.0668 0.3048)
			(layers "F.Cu" "F.Mask" "F.Paste")
			(net "HSW_SDA_2")
		)
		(pad "16" smd rect
			(at -2.5527 1.75006)
			(size 0.9144 0.3048)
			(layers "F.Cu" "F.Mask" "F.Paste")
			(net "HSW_SCL_2")
		)
		(pad "17" smd rect
			(at -1.75006 2.5527)
			(size 0.3048 0.9144)
			(layers "F.Cu" "F.Mask" "F.Paste")
			(net "MB0_RETRY_R")
		)
		(pad "18" smd rect
			(at -1.249934 2.4765)
			(size 0.3048 1.0668)
			(layers "F.Cu" "F.Mask" "F.Paste")
			(net "MB0_P12V_PWRGOOD")
		)
		(pad "19" smd rect
			(at -0.750062 2.4765)
			(size 0.3048 1.0668)
			(layers "F.Cu" "F.Mask" "F.Paste")
			(net "Net_2097")
		)
		(pad "20" smd rect
			(at -0.249936 2.4765)
			(size 0.3048 1.0668)
			(layers "F.Cu" "F.Mask" "F.Paste")
			(net "MB0_CM_VOUT_R")
		)
		(pad "21" smd rect
			(at 0.249936 2.4765)
			(size 0.3048 1.0668)
			(layers "F.Cu" "F.Mask" "F.Paste")
			(net "MB0_P12V_PWGIN_R")
		)
		(pad "22" smd rect
			(at 0.750062 2.4765)
			(size 0.3048 1.0668)
			(layers "F.Cu" "F.Mask" "F.Paste")
			(net "AGND_CURRENT_MON")
		)
		(pad "23" smd rect
			(at 1.249934 2.4765)
			(size 0.3048 1.0668)
			(layers "F.Cu" "F.Mask" "F.Paste")
			(net "GND")
		)
		(pad "24" smd rect
			(at 1.75006 2.5527)
			(size 0.3048 0.9144)
			(layers "F.Cu" "F.Mask" "F.Paste")
			(net "MB0_CM_GATE")
		)
		(pad "25" smd rect
			(at 2.5527 1.75006)
			(size 0.9144 0.3048)
			(layers "F.Cu" "F.Mask" "F.Paste")
			(net "MB0_TEMP")
		)
		(pad "26" smd rect
			(at 2.4765 1.249934)
			(size 1.0668 0.3048)
			(layers "F.Cu" "F.Mask" "F.Paste")
			(net "MB0_CM_SENSE_N")
		)
		(pad "27" smd rect
			(at 2.4765 0.750062)
			(size 1.0668 0.3048)
			(layers "F.Cu" "F.Mask" "F.Paste")
			(net "ADM1278_HS_N")
		)
		(pad "28" smd rect
			(at 2.4765 0.249936)
			(size 1.0668 0.3048)
			(layers "F.Cu" "F.Mask" "F.Paste")
			(net "ADM1278_HS_P")
		)
		(pad "29" smd rect
			(at 2.4765 -0.249936)
			(size 1.0668 0.3048)
			(layers "F.Cu" "F.Mask" "F.Paste")
			(net "MB0_CM_SENSE_P")
		)
		(pad "30" smd rect
			(at 2.4765 -0.750062)
			(size 1.0668 0.3048)
			(layers "F.Cu" "F.Mask" "F.Paste")
			(net "MB0_VCC")
		)
		(pad "31" smd rect
			(at 2.4765 -1.249934)
			(size 1.0668 0.3048)
			(layers "F.Cu" "F.Mask" "F.Paste")
			(net "MB0_CM_UV_R")
		)
		(pad "32" smd rect
			(at 2.5527 -1.75006)
			(size 0.9144 0.3048)
			(layers "F.Cu" "F.Mask" "F.Paste")
			(net "MB0_CM_OV_R")
		)
		(pad "33" smd rect
			(at 0 0)
			(size 3.4544 3.4544)
			(layers "F.Cu" "F.Mask" "F.Paste")
			(net "AGND_CURRENT_MON")
		)
	)
	(footprint ""
		(layer "F.Cu")
		(at 134.1882 -41.10101 -90)
		(property "Reference" "R756"
			(at 0 0 270)
			(layer "F.SilkS")
			(hide yes)
			(effects
				(font
					(size 1.27 1.27)
				)
			)
		)
		(property "Value" "0R2J-2-GP"
			(at 0.064008 -3.993896 270)
			(unlocked yes)
			(layer "F.Fab")
			(hide yes)
			(effects
				(font
					(size 1.016 1.016)
					(thickness 0.1524)
				)
			)
		)
		(property "Device Type" "R402H16"
			(at 0.064008 -5.517896 270)
			(unlocked yes)
			(layer "F.Fab")
			(hide yes)
			(effects
				(font
					(size 1.016 1.016)
					(thickness 0.1524)
				)
			)
		)
		(duplicate_pad_numbers_are_jumpers no)
		(fp_line
			(start -0.508 -0.9398)
			(end -0.508 0.9398)
			(stroke
				(width 0.1524)
				(type default)
			)
			(layer "F.SilkS")
		)
		(fp_line
			(start 0.508 -0.9398)
			(end -0.508 -0.9398)
			(stroke
				(width 0.1524)
				(type default)
			)
			(layer "F.SilkS")
		)
		(fp_rect
			(start -0.508 0.9398)
			(end 0.508 -0.9398)
			(stroke
				(width 0)
				(type default)
			)
			(fill no)
			(layer "F.CrtYd")
		)
		(fp_rect
			(start -0.508 0.9398)
			(end 0.508 -0.9398)
			(stroke
				(width 0)
				(type default)
			)
			(fill no)
			(layer "F.Fab")
		)
		(pad "1" smd custom
			(at 0 -0.4445 270)
			(size 0.1397 0.1397)
			(layers "F.Cu" "F.Mask" "F.Paste")
			(net "DUT_TDI")
			(options
				(clearance outline)
				(anchor circle)
			)
			(primitives
				(gr_poly
					(pts
						(arc
							(start -0.1778 -0.2794)
							(mid -0.249642 -0.249642)
							(end -0.2794 -0.1778)
						)
						(arc
							(start -0.2794 0.1778)
							(mid -0.249642 0.249642)
							(end -0.1778 0.2794)
						)
						(arc
							(start 0.1778 0.2794)
							(mid 0.249642 0.249642)
							(end 0.2794 0.1778)
						)
						(arc
							(start 0.2794 -0.1778)
							(mid 0.249642 -0.249642)
							(end 0.1778 -0.2794)
						)
					)
					(width 0)
					(fill yes)
				)
			)
		)
		(pad "2" smd custom
			(at 0 0.4445 270)
			(size 0.1397 0.1397)
			(layers "F.Cu" "F.Mask" "F.Paste")
			(net "EJTAG_TDI")
			(options
				(clearance outline)
				(anchor circle)
			)
			(primitives
				(gr_poly
					(pts
						(arc
							(start -0.1778 -0.2794)
							(mid -0.249642 -0.249642)
							(end -0.2794 -0.1778)
						)
						(arc
							(start -0.2794 0.1778)
							(mid -0.249642 0.249642)
							(end -0.1778 0.2794)
						)
						(arc
							(start 0.1778 0.2794)
							(mid 0.249642 0.249642)
							(end 0.2794 0.1778)
						)
						(arc
							(start 0.2794 -0.1778)
							(mid 0.249642 -0.249642)
							(end 0.1778 -0.2794)
						)
					)
					(width 0)
					(fill yes)
				)
			)
		)
	)
	(footprint ""
		(layer "F.Cu")
		(at 210.884008 -4.064)
		(property "Reference" "R680"
			(at 0 0 0)
			(layer "F.SilkS")
			(hide yes)
			(effects
				(font
					(size 1.27 1.27)
				)
			)
		)
		(property "Value" "100KR2F-L1-GP"
			(at 0.064008 -3.993896 0)
			(unlocked yes)
			(layer "F.Fab")
			(hide yes)
			(effects
				(font
					(size 1.016 1.016)
					(thickness 0.1524)
				)
			)
		)
		(property "Device Type" "R402H16"
			(at 0.064008 -5.517896 0)
			(unlocked yes)
			(layer "F.Fab")
			(hide yes)
			(effects
				(font
					(size 1.016 1.016)
					(thickness 0.1524)
				)
			)
		)
		(duplicate_pad_numbers_are_jumpers no)
		(fp_line
			(start -0.508 -0.9398)
			(end -0.508 0.9398)
			(stroke
				(width 0.1524)
				(type default)
			)
			(layer "F.SilkS")
		)
		(fp_line
			(start 0.508 -0.9398)
			(end -0.508 -0.9398)
			(stroke
				(width 0.1524)
				(type default)
			)
			(layer "F.SilkS")
		)
		(fp_rect
			(start -0.508 0.9398)
			(end 0.508 -0.9398)
			(stroke
				(width 0)
				(type default)
			)
			(fill no)
			(layer "F.CrtYd")
		)
		(fp_rect
			(start -0.508 0.9398)
			(end 0.508 -0.9398)
			(stroke
				(width 0)
				(type default)
			)
			(fill no)
			(layer "F.Fab")
		)
		(pad "1" smd custom
			(at 0 -0.4445)
			(size 0.1397 0.1397)
			(layers "F.Cu" "F.Mask" "F.Paste")
			(net "HOST6_RST_N")
			(options
				(clearance outline)
				(anchor circle)
			)
			(primitives
				(gr_poly
					(pts
						(arc
							(start -0.1778 -0.2794)
							(mid -0.249642 -0.249642)
							(end -0.2794 -0.1778)
						)
						(arc
							(start -0.2794 0.1778)
							(mid -0.249642 0.249642)
							(end -0.1778 0.2794)
						)
						(arc
							(start 0.1778 0.2794)
							(mid 0.249642 0.249642)
							(end 0.2794 0.1778)
						)
						(arc
							(start 0.2794 -0.1778)
							(mid 0.249642 -0.249642)
							(end 0.1778 -0.2794)
						)
					)
					(width 0)
					(fill yes)
				)
			)
		)
		(pad "2" smd custom
			(at 0 0.4445)
			(size 0.1397 0.1397)
			(layers "F.Cu" "F.Mask" "F.Paste")
			(net "GND")
			(options
				(clearance outline)
				(anchor circle)
			)
			(primitives
				(gr_poly
					(pts
						(arc
							(start -0.1778 -0.2794)
							(mid -0.249642 -0.249642)
							(end -0.2794 -0.1778)
						)
						(arc
							(start -0.2794 0.1778)
							(mid -0.249642 0.249642)
							(end -0.1778 0.2794)
						)
						(arc
							(start 0.1778 0.2794)
							(mid 0.249642 0.249642)
							(end 0.2794 0.1778)
						)
						(arc
							(start 0.2794 -0.1778)
							(mid 0.249642 -0.249642)
							(end 0.1778 -0.2794)
						)
					)
					(width 0)
					(fill yes)
				)
			)
		)
	)
	(footprint ""
		(layer "F.Cu")
		(at 124.069348 -48.453294 -90)
		(property "Reference" "JP4"
			(at 0 0 270)
			(layer "F.SilkS")
			(hide yes)
			(effects
				(font
					(size 1.27 1.27)
				)
			)
		)
		(property "Value" "PIN-CON3-S-GP"
			(at -5.588 -5.3086 270)
			(unlocked yes)
			(layer "F.Fab")
			(hide yes)
			(effects
				(font
					(size 1.016 1.016)
					(thickness 0.1524)
				)
			)
		)
		(property "Device Type" "21S-91-03GB01"
			(at -5.588 -6.8326 270)
			(unlocked yes)
			(layer "F.Fab")
			(hide yes)
			(effects
				(font
					(size 1.016 1.016)
					(thickness 0.1524)
				)
			)
		)
		(duplicate_pad_numbers_are_jumpers no)
		(fp_line
			(start -3.8862 1.4986)
			(end 3.8862 1.4986)
			(stroke
				(width 0.1524)
				(type default)
			)
			(layer "F.SilkS")
		)
		(fp_line
			(start 3.8862 1.4986)
			(end 3.8862 -1.4986)
			(stroke
				(width 0.1524)
				(type default)
			)
			(layer "F.SilkS")
		)
		(fp_line
			(start -4.0132 -0.3556)
			(end -4.0132 -1.6256)
			(stroke
				(width 0.4064)
				(type default)
			)
			(layer "F.SilkS")
		)
		(fp_line
			(start -3.8862 -1.4986)
			(end -3.8862 1.4986)
			(stroke
				(width 0.1524)
				(type default)
			)
			(layer "F.SilkS")
		)
		(fp_line
			(start 3.8862 -1.4986)
			(end -3.8862 -1.4986)
			(stroke
				(width 0.1524)
				(type default)
			)
			(layer "F.SilkS")
		)
		(fp_line
			(start -4.0132 -1.6256)
			(end -2.7432 -1.6256)
			(stroke
				(width 0.4064)
				(type default)
			)
			(layer "F.SilkS")
		)
		(fp_circle
			(center -2.54 0)
			(end -2.54 -1.0668)
			(stroke
				(width 0.3048)
				(type default)
			)
			(fill no)
			(layer "F.SilkS")
		)
		(fp_circle
			(center 0 0)
			(end 0 -1.0668)
			(stroke
				(width 0.3048)
				(type default)
			)
			(fill no)
			(layer "F.SilkS")
		)
		(fp_circle
			(center 2.54 0)
			(end 2.54 -1.0668)
			(stroke
				(width 0.3048)
				(type default)
			)
			(fill no)
			(layer "F.SilkS")
		)
		(fp_rect
			(start -3.6322 1.2446)
			(end 3.6322 -1.2446)
			(stroke
				(width 0)
				(type default)
			)
			(fill no)
			(layer "F.CrtYd")
		)
		(fp_poly
			(pts
				(xy 4.1402 -1.2446) (xy -3.6322 -1.2446) (xy -3.6322 1.2446) (xy 3.6322 1.2446) (xy 3.6322 -1.2319)
				(xy 4.1402 -1.2319) (xy 4.1402 1.7526) (xy -4.1402 1.7526) (xy -4.1402 -1.7526) (xy 4.1402 -1.7526)
			)
			(stroke
				(width 0)
				(type default)
			)
			(fill no)
			(layer "F.CrtYd")
		)
		(fp_rect
			(start -4.1402 1.7526)
			(end 4.1402 -1.7526)
			(stroke
				(width 0)
				(type default)
			)
			(fill no)
			(layer "F.Fab")
		)
		(pad "1" thru_hole circle
			(at -2.54 0 270)
			(size 1.4224 1.4224)
			(drill 1.016)
			(layers "*.Cu" "*.Mask")
			(remove_unused_layers no)
			(net "BMC_ADD1_PWR")
			(clearance 0.1524)
			(thermal_gap 0.1524)
		)
		(pad "2" thru_hole circle
			(at 0 0 270)
			(size 1.4224 1.4224)
			(drill 1.016)
			(layers "*.Cu" "*.Mask")
			(remove_unused_layers no)
			(net "BMC_ADD1")
			(clearance 0.1524)
			(thermal_gap 0.1524)
		)
		(pad "3" thru_hole circle
			(at 2.54 0 270)
			(size 1.4224 1.4224)
			(drill 1.016)
			(layers "*.Cu" "*.Mask")
			(remove_unused_layers no)
			(net "BMC_ADD1_GND")
			(clearance 0.1524)
			(thermal_gap 0.1524)
		)
	)
	(footprint ""
		(layer "F.Cu")
		(at 23.517352 -102.20071)
		(property "Reference" "U204"
			(at 0 0 0)
			(layer "F.SilkS")
			(hide yes)
			(effects
				(font
					(size 1.27 1.27)
				)
			)
		)
		(property "Value" "LMV331IDCKRG4-GP"
			(at -2.3368 -8.6868 0)
			(unlocked yes)
			(layer "F.Fab")
			(hide yes)
			(effects
				(font
					(size 1.016 1.016)
					(thickness 0.1524)
				)
			)
		)
		(property "Device Type" "SC70-5H44"
			(at -2.3114 -10.414 0)
			(unlocked yes)
			(layer "F.Fab")
			(hide yes)
			(effects
				(font
					(size 1.016 1.016)
					(thickness 0.1524)
				)
			)
		)
		(duplicate_pad_numbers_are_jumpers no)
		(fp_line
			(start -1.27 -1.7018)
			(end 1.27 -1.7018)
			(stroke
				(width 0.1524)
				(type default)
			)
			(layer "F.SilkS")
		)
		(fp_line
			(start -1.27 1.7018)
			(end -1.27 -1.7018)
			(stroke
				(width 0.1524)
				(type default)
			)
			(layer "F.SilkS")
		)
		(fp_line
			(start 0.6604 -1.8034)
			(end 1.3843 -1.8034)
			(stroke
				(width 0.3302)
				(type default)
			)
			(layer "F.SilkS")
		)
		(fp_line
			(start 1.27 -1.7018)
			(end 1.27 1.7018)
			(stroke
				(width 0.1524)
				(type default)
			)
			(layer "F.SilkS")
		)
		(fp_line
			(start 1.27 1.7018)
			(end -1.27 1.7018)
			(stroke
				(width 0.1524)
				(type default)
			)
			(layer "F.SilkS")
		)
		(fp_line
			(start 1.3843 -1.8034)
			(end 1.3843 -1.1176)
			(stroke
				(width 0.3302)
				(type default)
			)
			(layer "F.SilkS")
		)
		(fp_rect
			(start -1.524 1.9558)
			(end 1.524 -1.9558)
			(stroke
				(width 0)
				(type default)
			)
			(fill no)
			(layer "F.CrtYd")
		)
		(fp_poly
			(pts
				(xy -1.524 -1.9558) (xy 1.524 -1.9558) (xy 1.524 1.9558) (xy -1.524 1.9558)
			)
			(stroke
				(width 0)
				(type default)
			)
			(fill no)
			(layer "F.Fab")
		)
		(pad "1" smd rect
			(at 0.65024 -0.8255)
			(size 0.4064 1.2192)
			(layers "F.Cu" "F.Mask" "F.Paste")
			(net "FM_TPM_PRES_RST_N")
		)
		(pad "2" smd rect
			(at 0 -0.8255)
			(size 0.4064 1.2192)
			(layers "F.Cu" "F.Mask" "F.Paste")
			(net "GND")
		)
		(pad "3" smd rect
			(at -0.65024 -0.8255)
			(size 0.4064 1.2192)
			(layers "F.Cu" "F.Mask" "F.Paste")
			(net "VREF_2V2")
		)
		(pad "4" smd rect
			(at -0.65024 0.8255)
			(size 0.4064 1.2192)
			(layers "F.Cu" "F.Mask" "F.Paste")
			(net "FM_TPM_PRES_N")
		)
		(pad "5" smd rect
			(at 0.65024 0.8255)
			(size 0.4064 1.2192)
			(layers "F.Cu" "F.Mask" "F.Paste")
			(net "P5V_STBY")
		)
	)
	(footprint ""
		(layer "F.Cu")
		(at 53.721 -139.827 90)
		(property "Reference" "R150"
			(at 0 0 90)
			(layer "F.SilkS")
			(hide yes)
			(effects
				(font
					(size 1.27 1.27)
				)
			)
		)
		(property "Value" "4K7R2F-GP"
			(at 0.064008 -3.993896 90)
			(unlocked yes)
			(layer "F.Fab")
			(hide yes)
			(effects
				(font
					(size 1.016 1.016)
					(thickness 0.1524)
				)
			)
		)
		(property "Device Type" "R402H16"
			(at 0.064008 -5.517896 90)
			(unlocked yes)
			(layer "F.Fab")
			(hide yes)
			(effects
				(font
					(size 1.016 1.016)
					(thickness 0.1524)
				)
			)
		)
		(duplicate_pad_numbers_are_jumpers no)
		(fp_line
			(start 0.508 -0.9398)
			(end -0.508 -0.9398)
			(stroke
				(width 0.1524)
				(type default)
			)
			(layer "F.SilkS")
		)
		(fp_line
			(start -0.508 -0.9398)
			(end -0.508 0.9398)
			(stroke
				(width 0.1524)
				(type default)
			)
			(layer "F.SilkS")
		)
		(fp_rect
			(start -0.508 0.9398)
			(end 0.508 -0.9398)
			(stroke
				(width 0)
				(type default)
			)
			(fill no)
			(layer "F.CrtYd")
		)
		(fp_rect
			(start -0.508 0.9398)
			(end 0.508 -0.9398)
			(stroke
				(width 0)
				(type default)
			)
			(fill no)
			(layer "F.Fab")
		)
		(pad "1" smd custom
			(at 0 -0.4445 90)
			(size 0.1397 0.1397)
			(layers "F.Cu" "F.Mask" "F.Paste")
			(net "CBL_PRSNT_N_7")
			(options
				(clearance outline)
				(anchor circle)
			)
			(primitives
				(gr_poly
					(pts
						(arc
							(start -0.1778 -0.2794)
							(mid -0.249642 -0.249642)
							(end -0.2794 -0.1778)
						)
						(arc
							(start -0.2794 0.1778)
							(mid -0.249642 0.249642)
							(end -0.1778 0.2794)
						)
						(arc
							(start 0.1778 0.2794)
							(mid 0.249642 0.249642)
							(end 0.2794 0.1778)
						)
						(arc
							(start 0.2794 -0.1778)
							(mid 0.249642 -0.249642)
							(end 0.1778 -0.2794)
						)
					)
					(width 0)
					(fill yes)
				)
			)
		)
		(pad "2" smd custom
			(at 0 0.4445 90)
			(size 0.1397 0.1397)
			(layers "F.Cu" "F.Mask" "F.Paste")
			(net "P3V3_STBY")
			(options
				(clearance outline)
				(anchor circle)
			)
			(primitives
				(gr_poly
					(pts
						(arc
							(start -0.1778 -0.2794)
							(mid -0.249642 -0.249642)
							(end -0.2794 -0.1778)
						)
						(arc
							(start -0.2794 0.1778)
							(mid -0.249642 0.249642)
							(end -0.1778 0.2794)
						)
						(arc
							(start 0.1778 0.2794)
							(mid 0.249642 0.249642)
							(end 0.2794 0.1778)
						)
						(arc
							(start 0.2794 -0.1778)
							(mid 0.249642 -0.249642)
							(end 0.1778 -0.2794)
						)
					)
					(width 0)
					(fill yes)
				)
			)
		)
	)
	(footprint ""
		(layer "B.Cu")
		(at 227.6856 -35.0012 -90)
		(property "Reference" "C567"
			(at 0 0 90)
			(layer "B.SilkS")
			(hide yes)
			(effects
				(font
					(size 1.27 1.27)
				)
				(justify mirror)
			)
		)
		(property "Value" "SCD1U16V1KX-1-GP"
			(at 2.8321 -1.7399 270)
			(unlocked yes)
			(layer "B.Fab")
			(hide yes)
			(effects
				(font
					(size 1.016 1.016)
					(thickness 0.1524)
				)
				(justify mirror)
			)
		)
		(property "Device Type" "C0201H13"
			(at 2.8321 -3.2639 270)
			(unlocked yes)
			(layer "B.Fab")
			(hide yes)
			(effects
				(font
					(size 1.016 1.016)
					(thickness 0.1524)
				)
				(justify mirror)
			)
		)
		(duplicate_pad_numbers_are_jumpers no)
		(fp_rect
			(start 0.2794 0.6477)
			(end -0.2794 -0.6477)
			(stroke
				(width 0)
				(type default)
			)
			(fill no)
			(layer "B.CrtYd")
		)
		(fp_rect
			(start 0.2794 0.6477)
			(end -0.2794 -0.6477)
			(stroke
				(width 0)
				(type default)
			)
			(fill no)
			(layer "B.Fab")
		)
		(pad "1" smd custom
			(at 0 -0.2794 90)
			(size 0.0762 0.0762)
			(layers "B.Cu" "B.Mask" "B.Paste")
			(net "DUT_AVD_PCIE")
			(options
				(clearance outline)
				(anchor circle)
			)
			(primitives
				(gr_poly
					(pts
						(arc
							(start 0.1524 0.127)
							(mid 0.137521 0.162921)
							(end 0.1016 0.1778)
						)
						(arc
							(start -0.1016 0.1778)
							(mid -0.137521 0.162921)
							(end -0.1524 0.127)
						)
						(arc
							(start -0.1524 -0.127)
							(mid -0.137521 -0.162921)
							(end -0.1016 -0.1778)
						)
						(arc
							(start 0.1016 -0.1778)
							(mid 0.137521 -0.162921)
							(end 0.1524 -0.127)
						)
					)
					(width 0)
					(fill yes)
				)
			)
		)
		(pad "2" smd custom
			(at 0 0.2794 90)
			(size 0.0762 0.0762)
			(layers "B.Cu" "B.Mask" "B.Paste")
			(net "GND")
			(options
				(clearance outline)
				(anchor circle)
			)
			(primitives
				(gr_poly
					(pts
						(arc
							(start 0.1524 0.127)
							(mid 0.137521 0.162921)
							(end 0.1016 0.1778)
						)
						(arc
							(start -0.1016 0.1778)
							(mid -0.137521 0.162921)
							(end -0.1524 0.127)
						)
						(arc
							(start -0.1524 -0.127)
							(mid -0.137521 -0.162921)
							(end -0.1016 -0.1778)
						)
						(arc
							(start 0.1016 -0.1778)
							(mid 0.137521 -0.162921)
							(end 0.1524 -0.127)
						)
					)
					(width 0)
					(fill yes)
				)
			)
		)
	)
	(footprint ""
		(layer "B.Cu")
		(at 135.808212 -205.849474)
		(property "Reference" "R3220"
			(at 0 0 0)
			(layer "B.SilkS")
			(hide yes)
			(effects
				(font
					(size 1.27 1.27)
				)
				(justify mirror)
			)
		)
		(property "Value" "0R2J-2-GP"
			(at -0.064008 -3.993896 0)
			(unlocked yes)
			(layer "B.Fab")
			(hide yes)
			(effects
				(font
					(size 1.016 1.016)
					(thickness 0.1524)
				)
				(justify mirror)
			)
		)
		(property "Device Type" "R402H16"
			(at -0.064008 -5.517896 0)
			(unlocked yes)
			(layer "B.Fab")
			(hide yes)
			(effects
				(font
					(size 1.016 1.016)
					(thickness 0.1524)
				)
				(justify mirror)
			)
		)
		(duplicate_pad_numbers_are_jumpers no)
		(fp_line
			(start -0.508 -0.9398)
			(end 0.508 -0.9398)
			(stroke
				(width 0.1524)
				(type default)
			)
			(layer "B.SilkS")
		)
		(fp_line
			(start 0.508 -0.9398)
			(end 0.508 0.9398)
			(stroke
				(width 0.1524)
				(type default)
			)
			(layer "B.SilkS")
		)
		(fp_rect
			(start 0.508 0.9398)
			(end -0.508 -0.9398)
			(stroke
				(width 0)
				(type default)
			)
			(fill no)
			(layer "B.CrtYd")
		)
		(fp_rect
			(start 0.508 0.9398)
			(end -0.508 -0.9398)
			(stroke
				(width 0)
				(type default)
			)
			(fill no)
			(layer "B.Fab")
		)
		(pad "1" smd custom
			(at 0 -0.4445 180)
			(size 0.1397 0.1397)
			(layers "B.Cu" "B.Mask" "B.Paste")
			(net "BMC_SSD_RST#6")
			(options
				(clearance outline)
				(anchor circle)
			)
			(primitives
				(gr_poly
					(pts
						(arc
							(start -0.1778 0.2794)
							(mid -0.249642 0.249642)
							(end -0.2794 0.1778)
						)
						(arc
							(start -0.2794 -0.1778)
							(mid -0.249642 -0.249642)
							(end -0.1778 -0.2794)
						)
						(arc
							(start 0.1778 -0.2794)
							(mid 0.249642 -0.249642)
							(end 0.2794 -0.1778)
						)
						(arc
							(start 0.2794 0.1778)
							(mid 0.249642 0.249642)
							(end 0.1778 0.2794)
						)
					)
					(width 0)
					(fill yes)
				)
			)
		)
		(pad "2" smd custom
			(at 0 0.4445 180)
			(size 0.1397 0.1397)
			(layers "B.Cu" "B.Mask" "B.Paste")
			(net "BMC_SSD_RST#0_A6")
			(options
				(clearance outline)
				(anchor circle)
			)
			(primitives
				(gr_poly
					(pts
						(arc
							(start -0.1778 0.2794)
							(mid -0.249642 0.249642)
							(end -0.2794 0.1778)
						)
						(arc
							(start -0.2794 -0.1778)
							(mid -0.249642 -0.249642)
							(end -0.1778 -0.2794)
						)
						(arc
							(start 0.1778 -0.2794)
							(mid 0.249642 -0.249642)
							(end 0.2794 -0.1778)
						)
						(arc
							(start 0.2794 0.1778)
							(mid 0.249642 0.249642)
							(end 0.1778 0.2794)
						)
					)
					(width 0)
					(fill yes)
				)
			)
		)
	)
	(footprint ""
		(layer "B.Cu")
		(at 51.2572 -113.157)
		(property "Reference" "R314"
			(at 0 0 0)
			(layer "B.SilkS")
			(hide yes)
			(effects
				(font
					(size 1.27 1.27)
				)
				(justify mirror)
			)
		)
		(property "Value" "4K7R2F-GP"
			(at -0.064008 -3.993896 0)
			(unlocked yes)
			(layer "B.Fab")
			(hide yes)
			(effects
				(font
					(size 1.016 1.016)
					(thickness 0.1524)
				)
				(justify mirror)
			)
		)
		(property "Device Type" "R402H16"
			(at -0.064008 -5.517896 0)
			(unlocked yes)
			(layer "B.Fab")
			(hide yes)
			(effects
				(font
					(size 1.016 1.016)
					(thickness 0.1524)
				)
				(justify mirror)
			)
		)
		(duplicate_pad_numbers_are_jumpers no)
		(fp_line
			(start -0.508 -0.9398)
			(end 0.508 -0.9398)
			(stroke
				(width 0.1524)
				(type default)
			)
			(layer "B.SilkS")
		)
		(fp_line
			(start 0.508 -0.9398)
			(end 0.508 0.9398)
			(stroke
				(width 0.1524)
				(type default)
			)
			(layer "B.SilkS")
		)
		(fp_rect
			(start 0.508 0.9398)
			(end -0.508 -0.9398)
			(stroke
				(width 0)
				(type default)
			)
			(fill no)
			(layer "B.CrtYd")
		)
		(fp_rect
			(start 0.508 0.9398)
			(end -0.508 -0.9398)
			(stroke
				(width 0)
				(type default)
			)
			(fill no)
			(layer "B.Fab")
		)
		(pad "1" smd custom
			(at 0 -0.4445 180)
			(size 0.1397 0.1397)
			(layers "B.Cu" "B.Mask" "B.Paste")
			(net "BMC_I2C10_8536_SDA")
			(options
				(clearance outline)
				(anchor circle)
			)
			(primitives
				(gr_poly
					(pts
						(arc
							(start -0.1778 0.2794)
							(mid -0.249642 0.249642)
							(end -0.2794 0.1778)
						)
						(arc
							(start -0.2794 -0.1778)
							(mid -0.249642 -0.249642)
							(end -0.1778 -0.2794)
						)
						(arc
							(start 0.1778 -0.2794)
							(mid 0.249642 -0.249642)
							(end 0.2794 -0.1778)
						)
						(arc
							(start 0.2794 0.1778)
							(mid 0.249642 0.249642)
							(end 0.1778 0.2794)
						)
					)
					(width 0)
					(fill yes)
				)
			)
		)
		(pad "2" smd custom
			(at 0 0.4445 180)
			(size 0.1397 0.1397)
			(layers "B.Cu" "B.Mask" "B.Paste")
			(net "P3V3_STBY")
			(options
				(clearance outline)
				(anchor circle)
			)
			(primitives
				(gr_poly
					(pts
						(arc
							(start -0.1778 0.2794)
							(mid -0.249642 0.249642)
							(end -0.2794 0.1778)
						)
						(arc
							(start -0.2794 -0.1778)
							(mid -0.249642 -0.249642)
							(end -0.1778 -0.2794)
						)
						(arc
							(start 0.1778 -0.2794)
							(mid 0.249642 -0.249642)
							(end 0.2794 -0.1778)
						)
						(arc
							(start 0.2794 0.1778)
							(mid 0.249642 0.249642)
							(end 0.1778 0.2794)
						)
					)
					(width 0)
					(fill yes)
				)
			)
		)
	)
	(footprint ""
		(layer "B.Cu")
		(at 209.839052 -3.887216)
		(property "Reference" "R3713"
			(at 0 0 0)
			(layer "B.SilkS")
			(hide yes)
			(effects
				(font
					(size 1.27 1.27)
				)
				(justify mirror)
			)
		)
		(property "Value" "1KR2F-3-GP"
			(at -0.064008 -3.993896 0)
			(unlocked yes)
			(layer "B.Fab")
			(hide yes)
			(effects
				(font
					(size 1.016 1.016)
					(thickness 0.1524)
				)
				(justify mirror)
			)
		)
		(property "Device Type" "R402H16"
			(at -0.064008 -5.517896 0)
			(unlocked yes)
			(layer "B.Fab")
			(hide yes)
			(effects
				(font
					(size 1.016 1.016)
					(thickness 0.1524)
				)
				(justify mirror)
			)
		)
		(duplicate_pad_numbers_are_jumpers no)
		(fp_line
			(start -0.508 -0.9398)
			(end 0.508 -0.9398)
			(stroke
				(width 0.1524)
				(type default)
			)
			(layer "B.SilkS")
		)
		(fp_line
			(start 0.508 -0.9398)
			(end 0.508 0.9398)
			(stroke
				(width 0.1524)
				(type default)
			)
			(layer "B.SilkS")
		)
		(fp_rect
			(start 0.508 0.9398)
			(end -0.508 -0.9398)
			(stroke
				(width 0)
				(type default)
			)
			(fill no)
			(layer "B.CrtYd")
		)
		(fp_rect
			(start 0.508 0.9398)
			(end -0.508 -0.9398)
			(stroke
				(width 0)
				(type default)
			)
			(fill no)
			(layer "B.Fab")
		)
		(pad "1" smd custom
			(at 0 -0.4445 180)
			(size 0.1397 0.1397)
			(layers "B.Cu" "B.Mask" "B.Paste")
			(net "HOST7_RST_N")
			(options
				(clearance outline)
				(anchor circle)
			)
			(primitives
				(gr_poly
					(pts
						(arc
							(start -0.1778 0.2794)
							(mid -0.249642 0.249642)
							(end -0.2794 0.1778)
						)
						(arc
							(start -0.2794 -0.1778)
							(mid -0.249642 -0.249642)
							(end -0.1778 -0.2794)
						)
						(arc
							(start 0.1778 -0.2794)
							(mid 0.249642 -0.249642)
							(end 0.2794 -0.1778)
						)
						(arc
							(start 0.2794 0.1778)
							(mid 0.249642 0.249642)
							(end 0.1778 0.2794)
						)
					)
					(width 0)
					(fill yes)
				)
			)
		)
		(pad "2" smd custom
			(at 0 0.4445 180)
			(size 0.1397 0.1397)
			(layers "B.Cu" "B.Mask" "B.Paste")
			(net "P3V3_STBY")
			(options
				(clearance outline)
				(anchor circle)
			)
			(primitives
				(gr_poly
					(pts
						(arc
							(start -0.1778 0.2794)
							(mid -0.249642 0.249642)
							(end -0.2794 0.1778)
						)
						(arc
							(start -0.2794 -0.1778)
							(mid -0.249642 -0.249642)
							(end -0.1778 -0.2794)
						)
						(arc
							(start 0.1778 -0.2794)
							(mid 0.249642 -0.249642)
							(end 0.2794 -0.1778)
						)
						(arc
							(start 0.2794 0.1778)
							(mid 0.249642 0.249642)
							(end 0.1778 0.2794)
						)
					)
					(width 0)
					(fill yes)
				)
			)
		)
	)
	(footprint ""
		(layer "B.Cu")
		(at 153.396696 -33.541462 180)
		(property "Reference" "C222"
			(at 0 0 0)
			(layer "B.SilkS")
			(hide yes)
			(effects
				(font
					(size 1.27 1.27)
				)
				(justify mirror)
			)
		)
		(property "Value" "SCD1U10V2KX-5GP"
			(at -1.1811 -2.7051 180)
			(unlocked yes)
			(layer "B.Fab")
			(hide yes)
			(effects
				(font
					(size 1.016 1.016)
					(thickness 0.1524)
				)
				(justify mirror)
			)
		)
		(property "Device Type" "C402H22"
			(at -1.1811 -4.2291 180)
			(unlocked yes)
			(layer "B.Fab")
			(hide yes)
			(effects
				(font
					(size 1.016 1.016)
					(thickness 0.1524)
				)
				(justify mirror)
			)
		)
		(duplicate_pad_numbers_are_jumpers no)
		(fp_rect
			(start 0.4318 0.9525)
			(end -0.4318 -0.9525)
			(stroke
				(width 0)
				(type default)
			)
			(fill no)
			(layer "B.CrtYd")
		)
		(fp_rect
			(start 0.4318 0.9525)
			(end -0.4318 -0.9525)
			(stroke
				(width 0)
				(type default)
			)
			(fill no)
			(layer "B.Fab")
		)
		(pad "1" smd custom
			(at 0 -0.4445)
			(size 0.1524 0.1524)
			(layers "B.Cu" "B.Mask" "B.Paste")
			(net "GND")
			(options
				(clearance outline)
				(anchor circle)
			)
			(primitives
				(gr_poly
					(pts
						(arc
							(start 0.3048 0.2032)
							(mid 0.275042 0.275042)
							(end 0.2032 0.3048)
						)
						(arc
							(start -0.2032 0.3048)
							(mid -0.275042 0.275042)
							(end -0.3048 0.2032)
						)
						(arc
							(start -0.3048 -0.2032)
							(mid -0.275042 -0.275042)
							(end -0.2032 -0.3048)
						)
						(arc
							(start 0.2032 -0.3048)
							(mid 0.275042 -0.275042)
							(end 0.3048 -0.2032)
						)
					)
					(width 0)
					(fill yes)
				)
			)
		)
		(pad "2" smd custom
			(at 0 0.4445)
			(size 0.1524 0.1524)
			(layers "B.Cu" "B.Mask" "B.Paste")
			(net "P3V3_STBY")
			(options
				(clearance outline)
				(anchor circle)
			)
			(primitives
				(gr_poly
					(pts
						(arc
							(start 0.3048 0.2032)
							(mid 0.275042 0.275042)
							(end 0.2032 0.3048)
						)
						(arc
							(start -0.2032 0.3048)
							(mid -0.275042 0.275042)
							(end -0.3048 0.2032)
						)
						(arc
							(start -0.3048 -0.2032)
							(mid -0.275042 -0.275042)
							(end -0.2032 -0.3048)
						)
						(arc
							(start 0.2032 -0.3048)
							(mid 0.275042 -0.275042)
							(end 0.3048 -0.2032)
						)
					)
					(width 0)
					(fill yes)
				)
			)
		)
	)
	(footprint ""
		(layer "B.Cu")
		(at 48.5902 -104.5464 90)
		(property "Reference" "U39"
			(at 0 0 90)
			(layer "B.SilkS")
			(hide yes)
			(effects
				(font
					(size 1.27 1.27)
				)
				(justify mirror)
			)
		)
		(property "Value" "2N7002DW-7F-GP"
			(at 2.3622 -8.2042 90)
			(unlocked yes)
			(layer "B.Fab")
			(hide yes)
			(effects
				(font
					(size 1.016 1.016)
					(thickness 0.1524)
				)
				(justify mirror)
			)
		)
		(property "Device Type" "SOT-363H44"
			(at 2.3622 -10.1092 90)
			(unlocked yes)
			(layer "B.Fab")
			(hide yes)
			(effects
				(font
					(size 1.016 1.016)
					(thickness 0.1524)
				)
				(justify mirror)
			)
		)
		(duplicate_pad_numbers_are_jumpers no)
		(fp_line
			(start 1.4478 -1.7018)
			(end 1.4478 1.7018)
			(stroke
				(width 0.1524)
				(type default)
			)
			(layer "B.SilkS")
		)
		(fp_line
			(start -1.4478 -1.7018)
			(end 1.4478 -1.7018)
			(stroke
				(width 0.1524)
				(type default)
			)
			(layer "B.SilkS")
		)
		(fp_line
			(start 1.27 1.524)
			(end 1.27 0.6604)
			(stroke
				(width 0.4826)
				(type default)
			)
			(layer "B.SilkS")
		)
		(fp_line
			(start 1.4478 1.7018)
			(end -1.4478 1.7018)
			(stroke
				(width 0.1524)
				(type default)
			)
			(layer "B.SilkS")
		)
		(fp_line
			(start -1.4478 1.7018)
			(end -1.4478 -1.7018)
			(stroke
				(width 0.1524)
				(type default)
			)
			(layer "B.SilkS")
		)
		(fp_poly
			(pts
				(xy 1.524 -1.778) (xy -1.524 -1.778) (xy -1.524 1.778) (xy 1.524 1.778)
			)
			(stroke
				(width 0)
				(type default)
			)
			(fill no)
			(layer "B.CrtYd")
		)
		(fp_poly
			(pts
				(xy 1.524 -1.778) (xy -1.524 -1.778) (xy -1.524 1.778) (xy 1.524 1.778)
			)
			(stroke
				(width 0)
				(type default)
			)
			(fill no)
			(layer "B.Fab")
		)
		(pad "1" smd rect
			(at 0.65024 0.9398 270)
			(size 0.4064 1.016)
			(layers "B.Cu" "B.Mask" "B.Paste")
			(net "BMC_I2C14_MINI8_SCL_S")
		)
		(pad "2" smd rect
			(at 0 0.9398 270)
			(size 0.4064 1.016)
			(layers "B.Cu" "B.Mask" "B.Paste")
			(net "I2C8_LS_G2")
		)
		(pad "3" smd rect
			(at -0.65024 0.9398 270)
			(size 0.4064 1.016)
			(layers "B.Cu" "B.Mask" "B.Paste")
			(net "BMC_I2C14_MINI8_SDA")
		)
		(pad "4" smd rect
			(at -0.65024 -0.9398 270)
			(size 0.4064 1.016)
			(layers "B.Cu" "B.Mask" "B.Paste")
			(net "BMC_I2C14_MINI8_SDA_S")
		)
		(pad "5" smd rect
			(at 0 -0.9398 270)
			(size 0.4064 1.016)
			(layers "B.Cu" "B.Mask" "B.Paste")
			(net "I2C8_LS_G1")
		)
		(pad "6" smd rect
			(at 0.65024 -0.9398 270)
			(size 0.4064 1.016)
			(layers "B.Cu" "B.Mask" "B.Paste")
			(net "BMC_I2C14_MINI8_SCL")
		)
	)
	(footprint ""
		(layer "B.Cu")
		(at 336.804 -63.5 90)
		(property "Reference" "PC188"
			(at 0 0 90)
			(layer "B.SilkS")
			(hide yes)
			(effects
				(font
					(size 1.27 1.27)
				)
				(justify mirror)
			)
		)
		(property "Value" "SC470P50V2KX-3GP"
			(at -1.1811 -2.7051 90)
			(unlocked yes)
			(layer "B.Fab")
			(hide yes)
			(effects
				(font
					(size 1.016 1.016)
					(thickness 0.1524)
				)
				(justify mirror)
			)
		)
		(property "Device Type" "C402H22"
			(at -1.1811 -4.2291 90)
			(unlocked yes)
			(layer "B.Fab")
			(hide yes)
			(effects
				(font
					(size 1.016 1.016)
					(thickness 0.1524)
				)
				(justify mirror)
			)
		)
		(duplicate_pad_numbers_are_jumpers no)
		(fp_rect
			(start 0.4318 0.9525)
			(end -0.4318 -0.9525)
			(stroke
				(width 0)
				(type default)
			)
			(fill no)
			(layer "B.CrtYd")
		)
		(fp_rect
			(start 0.4318 0.9525)
			(end -0.4318 -0.9525)
			(stroke
				(width 0)
				(type default)
			)
			(fill no)
			(layer "B.Fab")
		)
		(pad "1" smd custom
			(at 0 -0.4445 270)
			(size 0.1524 0.1524)
			(layers "B.Cu" "B.Mask" "B.Paste")
			(net "P0V9_E_SNB")
			(options
				(clearance outline)
				(anchor circle)
			)
			(primitives
				(gr_poly
					(pts
						(arc
							(start 0.3048 0.2032)
							(mid 0.275042 0.275042)
							(end 0.2032 0.3048)
						)
						(arc
							(start -0.2032 0.3048)
							(mid -0.275042 0.275042)
							(end -0.3048 0.2032)
						)
						(arc
							(start -0.3048 -0.2032)
							(mid -0.275042 -0.275042)
							(end -0.2032 -0.3048)
						)
						(arc
							(start 0.2032 -0.3048)
							(mid 0.275042 -0.275042)
							(end 0.3048 -0.2032)
						)
					)
					(width 0)
					(fill yes)
				)
			)
		)
		(pad "2" smd custom
			(at 0 0.4445 270)
			(size 0.1524 0.1524)
			(layers "B.Cu" "B.Mask" "B.Paste")
			(net "GND")
			(options
				(clearance outline)
				(anchor circle)
			)
			(primitives
				(gr_poly
					(pts
						(arc
							(start 0.3048 0.2032)
							(mid 0.275042 0.275042)
							(end 0.2032 0.3048)
						)
						(arc
							(start -0.2032 0.3048)
							(mid -0.275042 0.275042)
							(end -0.3048 0.2032)
						)
						(arc
							(start -0.3048 -0.2032)
							(mid -0.275042 -0.275042)
							(end -0.2032 -0.3048)
						)
						(arc
							(start 0.2032 -0.3048)
							(mid 0.275042 -0.275042)
							(end 0.3048 -0.2032)
						)
					)
					(width 0)
					(fill yes)
				)
			)
		)
	)
	(footprint ""
		(layer "B.Cu")
		(at 159.258 -88.4174 180)
		(property "Reference" "C712"
			(at 0 0 0)
			(layer "B.SilkS")
			(hide yes)
			(effects
				(font
					(size 1.27 1.27)
				)
				(justify mirror)
			)
		)
		(property "Value" "SCD1U10V2KX-5GP"
			(at -1.1811 -2.7051 180)
			(unlocked yes)
			(layer "B.Fab")
			(hide yes)
			(effects
				(font
					(size 1.016 1.016)
					(thickness 0.1524)
				)
				(justify mirror)
			)
		)
		(property "Device Type" "C402H22"
			(at -1.1811 -4.2291 180)
			(unlocked yes)
			(layer "B.Fab")
			(hide yes)
			(effects
				(font
					(size 1.016 1.016)
					(thickness 0.1524)
				)
				(justify mirror)
			)
		)
		(duplicate_pad_numbers_are_jumpers no)
		(fp_rect
			(start 0.4318 0.9525)
			(end -0.4318 -0.9525)
			(stroke
				(width 0)
				(type default)
			)
			(fill no)
			(layer "B.CrtYd")
		)
		(fp_rect
			(start 0.4318 0.9525)
			(end -0.4318 -0.9525)
			(stroke
				(width 0)
				(type default)
			)
			(fill no)
			(layer "B.Fab")
		)
		(pad "1" smd custom
			(at 0 -0.4445)
			(size 0.1524 0.1524)
			(layers "B.Cu" "B.Mask" "B.Paste")
			(net "P1V8_CLKGEN")
			(options
				(clearance outline)
				(anchor circle)
			)
			(primitives
				(gr_poly
					(pts
						(arc
							(start 0.3048 0.2032)
							(mid 0.275042 0.275042)
							(end 0.2032 0.3048)
						)
						(arc
							(start -0.2032 0.3048)
							(mid -0.275042 0.275042)
							(end -0.3048 0.2032)
						)
						(arc
							(start -0.3048 -0.2032)
							(mid -0.275042 -0.275042)
							(end -0.2032 -0.3048)
						)
						(arc
							(start 0.2032 -0.3048)
							(mid 0.275042 -0.275042)
							(end 0.3048 -0.2032)
						)
					)
					(width 0)
					(fill yes)
				)
			)
		)
		(pad "2" smd custom
			(at 0 0.4445)
			(size 0.1524 0.1524)
			(layers "B.Cu" "B.Mask" "B.Paste")
			(net "GND")
			(options
				(clearance outline)
				(anchor circle)
			)
			(primitives
				(gr_poly
					(pts
						(arc
							(start 0.3048 0.2032)
							(mid 0.275042 0.275042)
							(end 0.2032 0.3048)
						)
						(arc
							(start -0.2032 0.3048)
							(mid -0.275042 0.275042)
							(end -0.3048 0.2032)
						)
						(arc
							(start -0.3048 -0.2032)
							(mid -0.275042 -0.275042)
							(end -0.2032 -0.3048)
						)
						(arc
							(start 0.2032 -0.3048)
							(mid 0.275042 -0.275042)
							(end 0.3048 -0.2032)
						)
					)
					(width 0)
					(fill yes)
				)
			)
		)
	)
	(footprint ""
		(layer "B.Cu")
		(at 20.909788 -142.948406 -90)
		(property "Reference" "R538"
			(at 0 0 90)
			(layer "B.SilkS")
			(hide yes)
			(effects
				(font
					(size 1.27 1.27)
				)
				(justify mirror)
			)
		)
		(property "Value" "0R2J-2-GP"
			(at -0.064008 -3.993896 270)
			(unlocked yes)
			(layer "B.Fab")
			(hide yes)
			(effects
				(font
					(size 1.016 1.016)
					(thickness 0.1524)
				)
				(justify mirror)
			)
		)
		(property "Device Type" "R402H16"
			(at -0.064008 -5.517896 270)
			(unlocked yes)
			(layer "B.Fab")
			(hide yes)
			(effects
				(font
					(size 1.016 1.016)
					(thickness 0.1524)
				)
				(justify mirror)
			)
		)
		(duplicate_pad_numbers_are_jumpers no)
		(fp_line
			(start -0.508 -0.9398)
			(end 0.508 -0.9398)
			(stroke
				(width 0.1524)
				(type default)
			)
			(layer "B.SilkS")
		)
		(fp_line
			(start 0.508 -0.9398)
			(end 0.508 0.9398)
			(stroke
				(width 0.1524)
				(type default)
			)
			(layer "B.SilkS")
		)
		(fp_rect
			(start 0.508 0.9398)
			(end -0.508 -0.9398)
			(stroke
				(width 0)
				(type default)
			)
			(fill no)
			(layer "B.CrtYd")
		)
		(fp_rect
			(start 0.508 0.9398)
			(end -0.508 -0.9398)
			(stroke
				(width 0)
				(type default)
			)
			(fill no)
			(layer "B.Fab")
		)
		(pad "1" smd custom
			(at 0 -0.4445 90)
			(size 0.1397 0.1397)
			(layers "B.Cu" "B.Mask" "B.Paste")
			(net "RST_BMC_EXTRST_N_R")
			(options
				(clearance outline)
				(anchor circle)
			)
			(primitives
				(gr_poly
					(pts
						(arc
							(start -0.1778 0.2794)
							(mid -0.249642 0.249642)
							(end -0.2794 0.1778)
						)
						(arc
							(start -0.2794 -0.1778)
							(mid -0.249642 -0.249642)
							(end -0.1778 -0.2794)
						)
						(arc
							(start 0.1778 -0.2794)
							(mid 0.249642 -0.249642)
							(end 0.2794 -0.1778)
						)
						(arc
							(start 0.2794 0.1778)
							(mid 0.249642 0.249642)
							(end 0.1778 0.2794)
						)
					)
					(width 0)
					(fill yes)
				)
			)
		)
		(pad "2" smd custom
			(at 0 0.4445 90)
			(size 0.1397 0.1397)
			(layers "B.Cu" "B.Mask" "B.Paste")
			(net "RST_BMC_EXTRST_N")
			(options
				(clearance outline)
				(anchor circle)
			)
			(primitives
				(gr_poly
					(pts
						(arc
							(start -0.1778 0.2794)
							(mid -0.249642 0.249642)
							(end -0.2794 0.1778)
						)
						(arc
							(start -0.2794 -0.1778)
							(mid -0.249642 -0.249642)
							(end -0.1778 -0.2794)
						)
						(arc
							(start 0.1778 -0.2794)
							(mid 0.249642 -0.249642)
							(end 0.2794 -0.1778)
						)
						(arc
							(start 0.2794 0.1778)
							(mid 0.249642 0.249642)
							(end 0.1778 0.2794)
						)
					)
					(width 0)
					(fill yes)
				)
			)
		)
	)
	(footprint ""
		(layer "B.Cu")
		(at 227.2919 -28.46324)
		(property "Reference" "TP309"
			(at 0 0 0)
			(layer "B.SilkS")
			(hide yes)
			(effects
				(font
					(size 1.27 1.27)
				)
				(justify mirror)
			)
		)
		(property "Value" "TPAD28-2-GP"
			(at 0.0127 -1.6637 0)
			(unlocked yes)
			(layer "B.Fab")
			(hide yes)
			(effects
				(font
					(size 1.016 1.016)
					(thickness 0.1524)
				)
				(justify mirror)
			)
		)
		(property "Device Type" "TPAD28"
			(at 0.0127 -3.1877 0)
			(unlocked yes)
			(layer "B.Fab")
			(hide yes)
			(effects
				(font
					(size 1.016 1.016)
					(thickness 0.1524)
				)
				(justify mirror)
			)
		)
		(duplicate_pad_numbers_are_jumpers no)
		(fp_poly
			(pts
				(arc
					(start 0.3556 0)
					(mid -0.3556 0)
					(end 0.3556 0)
				)
			)
			(stroke
				(width 0)
				(type default)
			)
			(fill no)
			(layer "B.CrtYd")
		)
		(fp_poly
			(pts
				(arc
					(start 0.6096 0)
					(mid -0.6096 0)
					(end 0.6096 0)
				)
			)
			(stroke
				(width 0)
				(type default)
			)
			(fill no)
			(layer "B.Fab")
		)
		(pad "1" smd circle
			(at 0 0 180)
			(size 0.7112 0.7112)
			(layers "B.Cu" "B.Mask" "B.Paste")
			(net "LBI_DATA13_R")
		)
	)
	(footprint ""
		(layer "B.Cu")
		(at 76.454 -189.484)
		(property "Reference" "R146"
			(at 0 0 0)
			(layer "B.SilkS")
			(hide yes)
			(effects
				(font
					(size 1.27 1.27)
				)
				(justify mirror)
			)
		)
		(property "Value" "4K7R2F-GP"
			(at -0.064008 -3.993896 0)
			(unlocked yes)
			(layer "B.Fab")
			(hide yes)
			(effects
				(font
					(size 1.016 1.016)
					(thickness 0.1524)
				)
				(justify mirror)
			)
		)
		(property "Device Type" "R402H16"
			(at -0.064008 -5.517896 0)
			(unlocked yes)
			(layer "B.Fab")
			(hide yes)
			(effects
				(font
					(size 1.016 1.016)
					(thickness 0.1524)
				)
				(justify mirror)
			)
		)
		(duplicate_pad_numbers_are_jumpers no)
		(fp_line
			(start -0.508 -0.9398)
			(end 0.508 -0.9398)
			(stroke
				(width 0.1524)
				(type default)
			)
			(layer "B.SilkS")
		)
		(fp_line
			(start 0.508 -0.9398)
			(end 0.508 0.9398)
			(stroke
				(width 0.1524)
				(type default)
			)
			(layer "B.SilkS")
		)
		(fp_rect
			(start 0.508 0.9398)
			(end -0.508 -0.9398)
			(stroke
				(width 0)
				(type default)
			)
			(fill no)
			(layer "B.CrtYd")
		)
		(fp_rect
			(start 0.508 0.9398)
			(end -0.508 -0.9398)
			(stroke
				(width 0)
				(type default)
			)
			(fill no)
			(layer "B.Fab")
		)
		(pad "1" smd custom
			(at 0 -0.4445 180)
			(size 0.1397 0.1397)
			(layers "B.Cu" "B.Mask" "B.Paste")
			(net "BMC_SSD_RST#0_A5")
			(options
				(clearance outline)
				(anchor circle)
			)
			(primitives
				(gr_poly
					(pts
						(arc
							(start -0.1778 0.2794)
							(mid -0.249642 0.249642)
							(end -0.2794 0.1778)
						)
						(arc
							(start -0.2794 -0.1778)
							(mid -0.249642 -0.249642)
							(end -0.1778 -0.2794)
						)
						(arc
							(start 0.1778 -0.2794)
							(mid 0.249642 -0.249642)
							(end 0.2794 -0.1778)
						)
						(arc
							(start 0.2794 0.1778)
							(mid 0.249642 0.249642)
							(end 0.1778 0.2794)
						)
					)
					(width 0)
					(fill yes)
				)
			)
		)
		(pad "2" smd custom
			(at 0 0.4445 180)
			(size 0.1397 0.1397)
			(layers "B.Cu" "B.Mask" "B.Paste")
			(net "P3V3_STBY")
			(options
				(clearance outline)
				(anchor circle)
			)
			(primitives
				(gr_poly
					(pts
						(arc
							(start -0.1778 0.2794)
							(mid -0.249642 0.249642)
							(end -0.2794 0.1778)
						)
						(arc
							(start -0.2794 -0.1778)
							(mid -0.249642 -0.249642)
							(end -0.1778 -0.2794)
						)
						(arc
							(start 0.1778 -0.2794)
							(mid 0.249642 -0.249642)
							(end 0.2794 -0.1778)
						)
						(arc
							(start 0.2794 0.1778)
							(mid 0.249642 0.249642)
							(end 0.1778 0.2794)
						)
					)
					(width 0)
					(fill yes)
				)
			)
		)
	)
	(footprint ""
		(layer "B.Cu")
		(at 23.90648 -138.602974 90)
		(property "Reference" "R362"
			(at 0 0 90)
			(layer "B.SilkS")
			(hide yes)
			(effects
				(font
					(size 1.27 1.27)
				)
				(justify mirror)
			)
		)
		(property "Value" "3K3R2F-2-GP"
			(at -0.064008 -3.993896 90)
			(unlocked yes)
			(layer "B.Fab")
			(hide yes)
			(effects
				(font
					(size 1.016 1.016)
					(thickness 0.1524)
				)
				(justify mirror)
			)
		)
		(property "Device Type" "R402H16"
			(at -0.064008 -5.517896 90)
			(unlocked yes)
			(layer "B.Fab")
			(hide yes)
			(effects
				(font
					(size 1.016 1.016)
					(thickness 0.1524)
				)
				(justify mirror)
			)
		)
		(duplicate_pad_numbers_are_jumpers no)
		(fp_line
			(start 0.508 -0.9398)
			(end 0.508 0.9398)
			(stroke
				(width 0.1524)
				(type default)
			)
			(layer "B.SilkS")
		)
		(fp_line
			(start -0.508 -0.9398)
			(end 0.508 -0.9398)
			(stroke
				(width 0.1524)
				(type default)
			)
			(layer "B.SilkS")
		)
		(fp_rect
			(start 0.508 0.9398)
			(end -0.508 -0.9398)
			(stroke
				(width 0)
				(type default)
			)
			(fill no)
			(layer "B.CrtYd")
		)
		(fp_rect
			(start 0.508 0.9398)
			(end -0.508 -0.9398)
			(stroke
				(width 0)
				(type default)
			)
			(fill no)
			(layer "B.Fab")
		)
		(pad "1" smd custom
			(at 0 -0.4445 270)
			(size 0.1397 0.1397)
			(layers "B.Cu" "B.Mask" "B.Paste")
			(net "P3V3_STBY")
			(options
				(clearance outline)
				(anchor circle)
			)
			(primitives
				(gr_poly
					(pts
						(arc
							(start -0.1778 0.2794)
							(mid -0.249642 0.249642)
							(end -0.2794 0.1778)
						)
						(arc
							(start -0.2794 -0.1778)
							(mid -0.249642 -0.249642)
							(end -0.1778 -0.2794)
						)
						(arc
							(start 0.1778 -0.2794)
							(mid 0.249642 -0.249642)
							(end 0.2794 -0.1778)
						)
						(arc
							(start 0.2794 0.1778)
							(mid 0.249642 0.249642)
							(end 0.1778 0.2794)
						)
					)
					(width 0)
					(fill yes)
				)
			)
		)
		(pad "2" smd custom
			(at 0 0.4445 270)
			(size 0.1397 0.1397)
			(layers "B.Cu" "B.Mask" "B.Paste")
			(net "ROMD5")
			(options
				(clearance outline)
				(anchor circle)
			)
			(primitives
				(gr_poly
					(pts
						(arc
							(start -0.1778 0.2794)
							(mid -0.249642 0.249642)
							(end -0.2794 0.1778)
						)
						(arc
							(start -0.2794 -0.1778)
							(mid -0.249642 -0.249642)
							(end -0.1778 -0.2794)
						)
						(arc
							(start 0.1778 -0.2794)
							(mid 0.249642 -0.249642)
							(end 0.2794 -0.1778)
						)
						(arc
							(start 0.2794 0.1778)
							(mid 0.249642 0.249642)
							(end 0.1778 0.2794)
						)
					)
					(width 0)
					(fill yes)
				)
			)
		)
	)
	(footprint ""
		(layer "B.Cu")
		(at 235.1024 -43.997372 90)
		(property "Reference" "C433"
			(at 0 0 90)
			(layer "B.SilkS")
			(hide yes)
			(effects
				(font
					(size 1.27 1.27)
				)
				(justify mirror)
			)
		)
		(property "Value" "SCD1U16V1KX-1-GP"
			(at 2.8321 -1.7399 90)
			(unlocked yes)
			(layer "B.Fab")
			(hide yes)
			(effects
				(font
					(size 1.016 1.016)
					(thickness 0.1524)
				)
				(justify mirror)
			)
		)
		(property "Device Type" "C0201H13"
			(at 2.8321 -3.2639 90)
			(unlocked yes)
			(layer "B.Fab")
			(hide yes)
			(effects
				(font
					(size 1.016 1.016)
					(thickness 0.1524)
				)
				(justify mirror)
			)
		)
		(duplicate_pad_numbers_are_jumpers no)
		(fp_rect
			(start 0.2794 0.6477)
			(end -0.2794 -0.6477)
			(stroke
				(width 0)
				(type default)
			)
			(fill no)
			(layer "B.CrtYd")
		)
		(fp_rect
			(start 0.2794 0.6477)
			(end -0.2794 -0.6477)
			(stroke
				(width 0)
				(type default)
			)
			(fill no)
			(layer "B.Fab")
		)
		(pad "1" smd custom
			(at 0 -0.2794 270)
			(size 0.0762 0.0762)
			(layers "B.Cu" "B.Mask" "B.Paste")
			(net "DUT_VDD")
			(options
				(clearance outline)
				(anchor circle)
			)
			(primitives
				(gr_poly
					(pts
						(arc
							(start 0.1524 0.127)
							(mid 0.137521 0.162921)
							(end 0.1016 0.1778)
						)
						(arc
							(start -0.1016 0.1778)
							(mid -0.137521 0.162921)
							(end -0.1524 0.127)
						)
						(arc
							(start -0.1524 -0.127)
							(mid -0.137521 -0.162921)
							(end -0.1016 -0.1778)
						)
						(arc
							(start 0.1016 -0.1778)
							(mid 0.137521 -0.162921)
							(end 0.1524 -0.127)
						)
					)
					(width 0)
					(fill yes)
				)
			)
		)
		(pad "2" smd custom
			(at 0 0.2794 270)
			(size 0.0762 0.0762)
			(layers "B.Cu" "B.Mask" "B.Paste")
			(net "GND")
			(options
				(clearance outline)
				(anchor circle)
			)
			(primitives
				(gr_poly
					(pts
						(arc
							(start 0.1524 0.127)
							(mid 0.137521 0.162921)
							(end 0.1016 0.1778)
						)
						(arc
							(start -0.1016 0.1778)
							(mid -0.137521 0.162921)
							(end -0.1524 0.127)
						)
						(arc
							(start -0.1524 -0.127)
							(mid -0.137521 -0.162921)
							(end -0.1016 -0.1778)
						)
						(arc
							(start 0.1016 -0.1778)
							(mid 0.137521 -0.162921)
							(end 0.1524 -0.127)
						)
					)
					(width 0)
					(fill yes)
				)
			)
		)
	)
	(footprint ""
		(layer "B.Cu")
		(at 269.580868 -18.820384 180)
		(property "Reference" "R728"
			(at 0 0 0)
			(layer "B.SilkS")
			(hide yes)
			(effects
				(font
					(size 1.27 1.27)
				)
				(justify mirror)
			)
		)
		(property "Value" "0R2J-2-GP"
			(at -0.064008 -3.993896 180)
			(unlocked yes)
			(layer "B.Fab")
			(hide yes)
			(effects
				(font
					(size 1.016 1.016)
					(thickness 0.1524)
				)
				(justify mirror)
			)
		)
		(property "Device Type" "R402H16"
			(at -0.064008 -5.517896 180)
			(unlocked yes)
			(layer "B.Fab")
			(hide yes)
			(effects
				(font
					(size 1.016 1.016)
					(thickness 0.1524)
				)
				(justify mirror)
			)
		)
		(duplicate_pad_numbers_are_jumpers no)
		(fp_line
			(start 0.508 -0.9398)
			(end 0.508 0.9398)
			(stroke
				(width 0.1524)
				(type default)
			)
			(layer "B.SilkS")
		)
		(fp_line
			(start -0.508 -0.9398)
			(end 0.508 -0.9398)
			(stroke
				(width 0.1524)
				(type default)
			)
			(layer "B.SilkS")
		)
		(fp_rect
			(start 0.508 0.9398)
			(end -0.508 -0.9398)
			(stroke
				(width 0)
				(type default)
			)
			(fill no)
			(layer "B.CrtYd")
		)
		(fp_rect
			(start 0.508 0.9398)
			(end -0.508 -0.9398)
			(stroke
				(width 0)
				(type default)
			)
			(fill no)
			(layer "B.Fab")
		)
		(pad "1" smd custom
			(at 0 -0.4445)
			(size 0.1397 0.1397)
			(layers "B.Cu" "B.Mask" "B.Paste")
			(net "8644_USB_DN5")
			(options
				(clearance outline)
				(anchor circle)
			)
			(primitives
				(gr_poly
					(pts
						(arc
							(start -0.1778 0.2794)
							(mid -0.249642 0.249642)
							(end -0.2794 0.1778)
						)
						(arc
							(start -0.2794 -0.1778)
							(mid -0.249642 -0.249642)
							(end -0.1778 -0.2794)
						)
						(arc
							(start 0.1778 -0.2794)
							(mid 0.249642 -0.249642)
							(end 0.2794 -0.1778)
						)
						(arc
							(start 0.2794 0.1778)
							(mid 0.249642 0.249642)
							(end 0.1778 0.2794)
						)
					)
					(width 0)
					(fill yes)
				)
			)
		)
		(pad "2" smd custom
			(at 0 0.4445)
			(size 0.1397 0.1397)
			(layers "B.Cu" "B.Mask" "B.Paste")
			(net "P3V3_STBY")
			(options
				(clearance outline)
				(anchor circle)
			)
			(primitives
				(gr_poly
					(pts
						(arc
							(start -0.1778 0.2794)
							(mid -0.249642 0.249642)
							(end -0.2794 0.1778)
						)
						(arc
							(start -0.2794 -0.1778)
							(mid -0.249642 -0.249642)
							(end -0.1778 -0.2794)
						)
						(arc
							(start 0.1778 -0.2794)
							(mid 0.249642 -0.249642)
							(end 0.2794 -0.1778)
						)
						(arc
							(start 0.2794 0.1778)
							(mid 0.249642 0.249642)
							(end 0.1778 0.2794)
						)
					)
					(width 0)
					(fill yes)
				)
			)
		)
	)
	(footprint ""
		(layer "B.Cu")
		(at 51.5366 -129.7686 90)
		(property "Reference" "R533"
			(at 0 0 90)
			(layer "B.SilkS")
			(hide yes)
			(effects
				(font
					(size 1.27 1.27)
				)
				(justify mirror)
			)
		)
		(property "Value" "0R2J-2-GP"
			(at -0.064008 -3.993896 90)
			(unlocked yes)
			(layer "B.Fab")
			(hide yes)
			(effects
				(font
					(size 1.016 1.016)
					(thickness 0.1524)
				)
				(justify mirror)
			)
		)
		(property "Device Type" "R402H16"
			(at -0.064008 -5.517896 90)
			(unlocked yes)
			(layer "B.Fab")
			(hide yes)
			(effects
				(font
					(size 1.016 1.016)
					(thickness 0.1524)
				)
				(justify mirror)
			)
		)
		(duplicate_pad_numbers_are_jumpers no)
		(fp_line
			(start 0.508 -0.9398)
			(end 0.508 0.9398)
			(stroke
				(width 0.1524)
				(type default)
			)
			(layer "B.SilkS")
		)
		(fp_line
			(start -0.508 -0.9398)
			(end 0.508 -0.9398)
			(stroke
				(width 0.1524)
				(type default)
			)
			(layer "B.SilkS")
		)
		(fp_rect
			(start 0.508 0.9398)
			(end -0.508 -0.9398)
			(stroke
				(width 0)
				(type default)
			)
			(fill no)
			(layer "B.CrtYd")
		)
		(fp_rect
			(start 0.508 0.9398)
			(end -0.508 -0.9398)
			(stroke
				(width 0)
				(type default)
			)
			(fill no)
			(layer "B.Fab")
		)
		(pad "1" smd custom
			(at 0 -0.4445 270)
			(size 0.1397 0.1397)
			(layers "B.Cu" "B.Mask" "B.Paste")
			(net "BMC_USB1_HDP2")
			(options
				(clearance outline)
				(anchor circle)
			)
			(primitives
				(gr_poly
					(pts
						(arc
							(start -0.1778 0.2794)
							(mid -0.249642 0.249642)
							(end -0.2794 0.1778)
						)
						(arc
							(start -0.2794 -0.1778)
							(mid -0.249642 -0.249642)
							(end -0.1778 -0.2794)
						)
						(arc
							(start 0.1778 -0.2794)
							(mid 0.249642 -0.249642)
							(end 0.2794 -0.1778)
						)
						(arc
							(start 0.2794 0.1778)
							(mid 0.249642 0.249642)
							(end 0.1778 0.2794)
						)
					)
					(width 0)
					(fill yes)
				)
			)
		)
		(pad "2" smd custom
			(at 0 0.4445 270)
			(size 0.1397 0.1397)
			(layers "B.Cu" "B.Mask" "B.Paste")
			(net "USB_P4_DP_BMC")
			(options
				(clearance outline)
				(anchor circle)
			)
			(primitives
				(gr_poly
					(pts
						(arc
							(start -0.1778 0.2794)
							(mid -0.249642 0.249642)
							(end -0.2794 0.1778)
						)
						(arc
							(start -0.2794 -0.1778)
							(mid -0.249642 -0.249642)
							(end -0.1778 -0.2794)
						)
						(arc
							(start 0.1778 -0.2794)
							(mid 0.249642 -0.249642)
							(end 0.2794 -0.1778)
						)
						(arc
							(start 0.2794 0.1778)
							(mid 0.249642 0.249642)
							(end 0.1778 0.2794)
						)
					)
					(width 0)
					(fill yes)
				)
			)
		)
	)
	(footprint ""
		(layer "B.Cu")
		(at 35.814 -116.84 180)
		(property "Reference" "R285"
			(at 0 0 0)
			(layer "B.SilkS")
			(hide yes)
			(effects
				(font
					(size 1.27 1.27)
				)
				(justify mirror)
			)
		)
		(property "Value" "22R2J-2-GP"
			(at -0.064008 -3.993896 180)
			(unlocked yes)
			(layer "B.Fab")
			(hide yes)
			(effects
				(font
					(size 1.016 1.016)
					(thickness 0.1524)
				)
				(justify mirror)
			)
		)
		(property "Device Type" "R402H16"
			(at -0.064008 -5.517896 180)
			(unlocked yes)
			(layer "B.Fab")
			(hide yes)
			(effects
				(font
					(size 1.016 1.016)
					(thickness 0.1524)
				)
				(justify mirror)
			)
		)
		(duplicate_pad_numbers_are_jumpers no)
		(fp_line
			(start 0.508 -0.9398)
			(end 0.508 0.9398)
			(stroke
				(width 0.1524)
				(type default)
			)
			(layer "B.SilkS")
		)
		(fp_line
			(start -0.508 -0.9398)
			(end 0.508 -0.9398)
			(stroke
				(width 0.1524)
				(type default)
			)
			(layer "B.SilkS")
		)
		(fp_rect
			(start 0.508 0.9398)
			(end -0.508 -0.9398)
			(stroke
				(width 0)
				(type default)
			)
			(fill no)
			(layer "B.CrtYd")
		)
		(fp_rect
			(start 0.508 0.9398)
			(end -0.508 -0.9398)
			(stroke
				(width 0)
				(type default)
			)
			(fill no)
			(layer "B.Fab")
		)
		(pad "1" smd custom
			(at 0 -0.4445)
			(size 0.1397 0.1397)
			(layers "B.Cu" "B.Mask" "B.Paste")
			(net "RMII_BMC_PHY_TXD1")
			(options
				(clearance outline)
				(anchor circle)
			)
			(primitives
				(gr_poly
					(pts
						(arc
							(start -0.1778 0.2794)
							(mid -0.249642 0.249642)
							(end -0.2794 0.1778)
						)
						(arc
							(start -0.2794 -0.1778)
							(mid -0.249642 -0.249642)
							(end -0.1778 -0.2794)
						)
						(arc
							(start 0.1778 -0.2794)
							(mid 0.249642 -0.249642)
							(end 0.2794 -0.1778)
						)
						(arc
							(start 0.2794 0.1778)
							(mid 0.249642 0.249642)
							(end 0.1778 0.2794)
						)
					)
					(width 0)
					(fill yes)
				)
			)
		)
		(pad "2" smd custom
			(at 0 0.4445)
			(size 0.1397 0.1397)
			(layers "B.Cu" "B.Mask" "B.Paste")
			(net "RMII0_BMC_C_PHY_TXD1")
			(options
				(clearance outline)
				(anchor circle)
			)
			(primitives
				(gr_poly
					(pts
						(arc
							(start -0.1778 0.2794)
							(mid -0.249642 0.249642)
							(end -0.2794 0.1778)
						)
						(arc
							(start -0.2794 -0.1778)
							(mid -0.249642 -0.249642)
							(end -0.1778 -0.2794)
						)
						(arc
							(start 0.1778 -0.2794)
							(mid 0.249642 -0.249642)
							(end 0.2794 -0.1778)
						)
						(arc
							(start 0.2794 0.1778)
							(mid 0.249642 0.249642)
							(end 0.1778 0.2794)
						)
					)
					(width 0)
					(fill yes)
				)
			)
		)
	)
	(footprint ""
		(layer "B.Cu")
		(at 319.659 -55.372)
		(property "Reference" "PC176"
			(at 0 0 0)
			(layer "B.SilkS")
			(hide yes)
			(effects
				(font
					(size 1.27 1.27)
				)
				(justify mirror)
			)
		)
		(property "Value" "SC22U6D3V5MX-5-GP"
			(at 0.0762 -6.1214 0)
			(unlocked yes)
			(layer "B.Fab")
			(hide yes)
			(effects
				(font
					(size 1.016 1.016)
					(thickness 0.1524)
				)
				(justify mirror)
			)
		)
		(property "Device Type" "C805H56"
			(at 0.0762 -8.1534 0)
			(unlocked yes)
			(layer "B.Fab")
			(hide yes)
			(effects
				(font
					(size 1.016 1.016)
					(thickness 0.1524)
				)
				(justify mirror)
			)
		)
		(duplicate_pad_numbers_are_jumpers no)
		(fp_line
			(start -0.635 0)
			(end 0.635 0)
			(stroke
				(width 0.508)
				(type default)
			)
			(layer "B.SilkS")
		)
		(fp_rect
			(start 0.9652 1.778)
			(end -0.9652 -1.778)
			(stroke
				(width 0)
				(type default)
			)
			(fill no)
			(layer "B.CrtYd")
		)
		(fp_poly
			(pts
				(xy 0.9652 -1.778) (xy -0.9652 -1.778) (xy -0.9652 1.778) (xy 0.9652 1.778)
			)
			(stroke
				(width 0)
				(type default)
			)
			(fill no)
			(layer "B.Fab")
		)
		(pad "1" smd rect
			(at 0 -0.9652 180)
			(size 1.397 1.143)
			(layers "B.Cu" "B.Mask" "B.Paste")
			(net "P0V9_E")
		)
		(pad "2" smd rect
			(at 0 0.9652 180)
			(size 1.397 1.143)
			(layers "B.Cu" "B.Mask" "B.Paste")
			(net "GND")
		)
	)
	(footprint ""
		(layer "B.Cu")
		(at 246.126 -69.977 90)
		(property "Reference" "C495"
			(at 0 0 90)
			(layer "B.SilkS")
			(hide yes)
			(effects
				(font
					(size 1.27 1.27)
				)
				(justify mirror)
			)
		)
		(property "Value" "SC100U4V5MX-1-GP"
			(at 0.0762 -6.1214 90)
			(unlocked yes)
			(layer "B.Fab")
			(hide yes)
			(effects
				(font
					(size 1.016 1.016)
					(thickness 0.1524)
				)
				(justify mirror)
			)
		)
		(property "Device Type" "C805H58"
			(at 0.0762 -8.1534 90)
			(unlocked yes)
			(layer "B.Fab")
			(hide yes)
			(effects
				(font
					(size 1.016 1.016)
					(thickness 0.1524)
				)
				(justify mirror)
			)
		)
		(duplicate_pad_numbers_are_jumpers no)
		(fp_line
			(start -0.635 0)
			(end 0.635 0)
			(stroke
				(width 0.508)
				(type default)
			)
			(layer "B.SilkS")
		)
		(fp_rect
			(start 0.9652 1.778)
			(end -0.9652 -1.778)
			(stroke
				(width 0)
				(type default)
			)
			(fill no)
			(layer "B.CrtYd")
		)
		(fp_poly
			(pts
				(xy 0.9652 -1.778) (xy -0.9652 -1.778) (xy -0.9652 1.778) (xy 0.9652 1.778)
			)
			(stroke
				(width 0)
				(type default)
			)
			(fill no)
			(layer "B.Fab")
		)
		(pad "1" smd rect
			(at 0 -0.9652 270)
			(size 1.397 1.143)
			(layers "B.Cu" "B.Mask" "B.Paste")
			(net "DUT_AVD_TX")
		)
		(pad "2" smd rect
			(at 0 0.9652 270)
			(size 1.397 1.143)
			(layers "B.Cu" "B.Mask" "B.Paste")
			(net "GND")
		)
	)
	(footprint ""
		(layer "B.Cu")
		(at 130.51028 -33.54578)
		(property "Reference" "R2925"
			(at 0 0 0)
			(layer "B.SilkS")
			(hide yes)
			(effects
				(font
					(size 1.27 1.27)
				)
				(justify mirror)
			)
		)
		(property "Value" "0R2J-2-GP"
			(at -0.064008 -3.993896 0)
			(unlocked yes)
			(layer "B.Fab")
			(hide yes)
			(effects
				(font
					(size 1.016 1.016)
					(thickness 0.1524)
				)
				(justify mirror)
			)
		)
		(property "Device Type" "R402H16"
			(at -0.064008 -5.517896 0)
			(unlocked yes)
			(layer "B.Fab")
			(hide yes)
			(effects
				(font
					(size 1.016 1.016)
					(thickness 0.1524)
				)
				(justify mirror)
			)
		)
		(duplicate_pad_numbers_are_jumpers no)
		(fp_line
			(start -0.508 -0.9398)
			(end 0.508 -0.9398)
			(stroke
				(width 0.1524)
				(type default)
			)
			(layer "B.SilkS")
		)
		(fp_line
			(start 0.508 -0.9398)
			(end 0.508 0.9398)
			(stroke
				(width 0.1524)
				(type default)
			)
			(layer "B.SilkS")
		)
		(fp_rect
			(start 0.508 0.9398)
			(end -0.508 -0.9398)
			(stroke
				(width 0)
				(type default)
			)
			(fill no)
			(layer "B.CrtYd")
		)
		(fp_rect
			(start 0.508 0.9398)
			(end -0.508 -0.9398)
			(stroke
				(width 0)
				(type default)
			)
			(fill no)
			(layer "B.Fab")
		)
		(pad "1" smd custom
			(at 0 -0.4445 180)
			(size 0.1397 0.1397)
			(layers "B.Cu" "B.Mask" "B.Paste")
			(net "CBL_PRSNT_N_1")
			(options
				(clearance outline)
				(anchor circle)
			)
			(primitives
				(gr_poly
					(pts
						(arc
							(start -0.1778 0.2794)
							(mid -0.249642 0.249642)
							(end -0.2794 0.1778)
						)
						(arc
							(start -0.2794 -0.1778)
							(mid -0.249642 -0.249642)
							(end -0.1778 -0.2794)
						)
						(arc
							(start 0.1778 -0.2794)
							(mid 0.249642 -0.249642)
							(end 0.2794 -0.1778)
						)
						(arc
							(start 0.2794 0.1778)
							(mid 0.249642 0.249642)
							(end 0.1778 0.2794)
						)
					)
					(width 0)
					(fill yes)
				)
			)
		)
		(pad "2" smd custom
			(at 0 0.4445 180)
			(size 0.1397 0.1397)
			(layers "B.Cu" "B.Mask" "B.Paste")
			(net "8644_SDA_R_1")
			(options
				(clearance outline)
				(anchor circle)
			)
			(primitives
				(gr_poly
					(pts
						(arc
							(start -0.1778 0.2794)
							(mid -0.249642 0.249642)
							(end -0.2794 0.1778)
						)
						(arc
							(start -0.2794 -0.1778)
							(mid -0.249642 -0.249642)
							(end -0.1778 -0.2794)
						)
						(arc
							(start 0.1778 -0.2794)
							(mid 0.249642 -0.249642)
							(end 0.2794 -0.1778)
						)
						(arc
							(start 0.2794 0.1778)
							(mid 0.249642 0.249642)
							(end 0.1778 0.2794)
						)
					)
					(width 0)
					(fill yes)
				)
			)
		)
	)
	(footprint ""
		(layer "B.Cu")
		(at 246.599964 -40.999918 -90)
		(property "Reference" "TP288"
			(at 0 0 90)
			(layer "B.SilkS")
			(hide yes)
			(effects
				(font
					(size 1.27 1.27)
				)
				(justify mirror)
			)
		)
		(property "Value" "TPAD28-2-GP"
			(at 0.0127 -1.6637 270)
			(unlocked yes)
			(layer "B.Fab")
			(hide yes)
			(effects
				(font
					(size 1.016 1.016)
					(thickness 0.1524)
				)
				(justify mirror)
			)
		)
		(property "Device Type" "TPAD28"
			(at 0.0127 -3.1877 270)
			(unlocked yes)
			(layer "B.Fab")
			(hide yes)
			(effects
				(font
					(size 1.016 1.016)
					(thickness 0.1524)
				)
				(justify mirror)
			)
		)
		(duplicate_pad_numbers_are_jumpers no)
		(fp_poly
			(pts
				(arc
					(start 0 -0.3556)
					(mid 0 0.3556)
					(end 0 -0.3556)
				)
			)
			(stroke
				(width 0)
				(type default)
			)
			(fill no)
			(layer "B.CrtYd")
		)
		(fp_poly
			(pts
				(arc
					(start 0 -0.6096)
					(mid 0 0.6096)
					(end 0 -0.6096)
				)
			)
			(stroke
				(width 0)
				(type default)
			)
			(fill no)
			(layer "B.Fab")
		)
		(pad "1" smd circle
			(at 0 0 90)
			(size 0.7112 0.7112)
			(layers "B.Cu" "B.Mask" "B.Paste")
			(net "TWI_SRST#5")
		)
	)
	(footprint ""
		(layer "B.Cu")
		(at 310.007 -66.167 180)
		(property "Reference" "PG67"
			(at 0 0 0)
			(layer "B.SilkS")
			(hide yes)
			(effects
				(font
					(size 1.27 1.27)
				)
				(justify mirror)
			)
		)
		(property "Value" "GAP-CLOSE-PWR-3-GP"
			(at -0.0254 -6.5786 180)
			(unlocked yes)
			(layer "B.Fab")
			(hide yes)
			(effects
				(font
					(size 1.016 1.016)
					(thickness 0.1524)
				)
				(justify mirror)
			)
		)
		(property "Device Type" "GAP-CLOSE-PWR-3"
			(at -0.0254 -8.255 180)
			(unlocked yes)
			(layer "B.Fab")
			(hide yes)
			(effects
				(font
					(size 1.016 1.016)
					(thickness 0.1524)
				)
				(justify mirror)
			)
		)
		(duplicate_pad_numbers_are_jumpers no)
		(fp_rect
			(start 0.7112 0.4572)
			(end -0.7112 -0.4572)
			(stroke
				(width 0)
				(type default)
			)
			(fill no)
			(layer "B.CrtYd")
		)
		(fp_poly
			(pts
				(xy 0.7112 -0.4572) (xy -0.7112 -0.4572) (xy -0.7112 0.4572) (xy 0.7112 0.4572)
			)
			(stroke
				(width 0)
				(type default)
			)
			(fill no)
			(layer "B.Fab")
		)
		(pad "1" smd rect
			(at 0.3048 0)
			(size 0.6604 0.762)
			(layers "B.Cu" "B.Mask" "B.Paste")
			(net "DUT_VDD")
		)
		(pad "2" smd rect
			(at -0.3048 0)
			(size 0.6604 0.762)
			(layers "B.Cu" "B.Mask" "B.Paste")
			(net "P0V9_E")
		)
	)
	(footprint ""
		(layer "B.Cu")
		(at 178.9938 -71.628 180)
		(property "Reference" "C617"
			(at 0 0 0)
			(layer "B.SilkS")
			(hide yes)
			(effects
				(font
					(size 1.27 1.27)
				)
				(justify mirror)
			)
		)
		(property "Value" "SC4D7U16V5KX-1-GP"
			(at 0.0762 -6.1214 180)
			(unlocked yes)
			(layer "B.Fab")
			(hide yes)
			(effects
				(font
					(size 1.016 1.016)
					(thickness 0.1524)
				)
				(justify mirror)
			)
		)
		(property "Device Type" "C805H56"
			(at 0.0762 -8.1534 180)
			(unlocked yes)
			(layer "B.Fab")
			(hide yes)
			(effects
				(font
					(size 1.016 1.016)
					(thickness 0.1524)
				)
				(justify mirror)
			)
		)
		(duplicate_pad_numbers_are_jumpers no)
		(fp_line
			(start -0.635 0)
			(end 0.635 0)
			(stroke
				(width 0.508)
				(type default)
			)
			(layer "B.SilkS")
		)
		(fp_rect
			(start 0.9652 1.778)
			(end -0.9652 -1.778)
			(stroke
				(width 0)
				(type default)
			)
			(fill no)
			(layer "B.CrtYd")
		)
		(fp_poly
			(pts
				(xy 0.9652 -1.778) (xy -0.9652 -1.778) (xy -0.9652 1.778) (xy 0.9652 1.778)
			)
			(stroke
				(width 0)
				(type default)
			)
			(fill no)
			(layer "B.Fab")
		)
		(pad "1" smd rect
			(at 0 -0.9652)
			(size 1.397 1.143)
			(layers "B.Cu" "B.Mask" "B.Paste")
			(net "DUT_AVD_PCIE")
		)
		(pad "2" smd rect
			(at 0 0.9652)
			(size 1.397 1.143)
			(layers "B.Cu" "B.Mask" "B.Paste")
			(net "GND")
		)
	)
	(footprint ""
		(layer "B.Cu")
		(at 234.59948 -41.0083)
		(property "Reference" "TP120"
			(at 0 0 0)
			(layer "B.SilkS")
			(hide yes)
			(effects
				(font
					(size 1.27 1.27)
				)
				(justify mirror)
			)
		)
		(property "Value" "TPAD28-2-GP"
			(at 0.0127 -1.6637 0)
			(unlocked yes)
			(layer "B.Fab")
			(hide yes)
			(effects
				(font
					(size 1.016 1.016)
					(thickness 0.1524)
				)
				(justify mirror)
			)
		)
		(property "Device Type" "TPAD28"
			(at 0.0127 -3.1877 0)
			(unlocked yes)
			(layer "B.Fab")
			(hide yes)
			(effects
				(font
					(size 1.016 1.016)
					(thickness 0.1524)
				)
				(justify mirror)
			)
		)
		(duplicate_pad_numbers_are_jumpers no)
		(fp_poly
			(pts
				(arc
					(start 0.3556 0)
					(mid -0.3556 0)
					(end 0.3556 0)
				)
			)
			(stroke
				(width 0)
				(type default)
			)
			(fill no)
			(layer "B.CrtYd")
		)
		(fp_poly
			(pts
				(arc
					(start 0.6096 0)
					(mid -0.6096 0)
					(end 0.6096 0)
				)
			)
			(stroke
				(width 0)
				(type default)
			)
			(fill no)
			(layer "B.Fab")
		)
		(pad "1" smd circle
			(at 0 0 180)
			(size 0.7112 0.7112)
			(layers "B.Cu" "B.Mask" "B.Paste")
			(net "LBI_ADDR_8")
		)
	)
	(footprint ""
		(layer "B.Cu")
		(at 247.651016 -25.424638 90)
		(property "Reference" "TP303"
			(at 0 0 90)
			(layer "B.SilkS")
			(hide yes)
			(effects
				(font
					(size 1.27 1.27)
				)
				(justify mirror)
			)
		)
		(property "Value" "TPAD28-2-GP"
			(at 0.0127 -1.6637 90)
			(unlocked yes)
			(layer "B.Fab")
			(hide yes)
			(effects
				(font
					(size 1.016 1.016)
					(thickness 0.1524)
				)
				(justify mirror)
			)
		)
		(property "Device Type" "TPAD28"
			(at 0.0127 -3.1877 90)
			(unlocked yes)
			(layer "B.Fab")
			(hide yes)
			(effects
				(font
					(size 1.016 1.016)
					(thickness 0.1524)
				)
				(justify mirror)
			)
		)
		(duplicate_pad_numbers_are_jumpers no)
		(fp_poly
			(pts
				(arc
					(start 0 0.3556)
					(mid 0 -0.3556)
					(end 0 0.3556)
				)
			)
			(stroke
				(width 0)
				(type default)
			)
			(fill no)
			(layer "B.CrtYd")
		)
		(fp_poly
			(pts
				(arc
					(start 0 0.6096)
					(mid 0 -0.6096)
					(end 0 0.6096)
				)
			)
			(stroke
				(width 0)
				(type default)
			)
			(fill no)
			(layer "B.Fab")
		)
		(pad "1" smd circle
			(at 0 0 270)
			(size 0.7112 0.7112)
			(layers "B.Cu" "B.Mask" "B.Paste")
			(net "TWI_SCL10")
		)
	)
	(footprint ""
		(layer "B.Cu")
		(at 224.536 -20.447)
		(property "Reference" "R3707"
			(at 0 0 0)
			(layer "B.SilkS")
			(hide yes)
			(effects
				(font
					(size 1.27 1.27)
				)
				(justify mirror)
			)
		)
		(property "Value" "4K7R2F-GP"
			(at -0.064008 -3.993896 0)
			(unlocked yes)
			(layer "B.Fab")
			(hide yes)
			(effects
				(font
					(size 1.016 1.016)
					(thickness 0.1524)
				)
				(justify mirror)
			)
		)
		(property "Device Type" "R402H16"
			(at -0.064008 -5.517896 0)
			(unlocked yes)
			(layer "B.Fab")
			(hide yes)
			(effects
				(font
					(size 1.016 1.016)
					(thickness 0.1524)
				)
				(justify mirror)
			)
		)
		(duplicate_pad_numbers_are_jumpers no)
		(fp_line
			(start -0.508 -0.9398)
			(end 0.508 -0.9398)
			(stroke
				(width 0.1524)
				(type default)
			)
			(layer "B.SilkS")
		)
		(fp_line
			(start 0.508 -0.9398)
			(end 0.508 0.9398)
			(stroke
				(width 0.1524)
				(type default)
			)
			(layer "B.SilkS")
		)
		(fp_rect
			(start 0.508 0.9398)
			(end -0.508 -0.9398)
			(stroke
				(width 0)
				(type default)
			)
			(fill no)
			(layer "B.CrtYd")
		)
		(fp_rect
			(start 0.508 0.9398)
			(end -0.508 -0.9398)
			(stroke
				(width 0)
				(type default)
			)
			(fill no)
			(layer "B.Fab")
		)
		(pad "1" smd custom
			(at 0 -0.4445 180)
			(size 0.1397 0.1397)
			(layers "B.Cu" "B.Mask" "B.Paste")
			(net "HOST6_RST_N_LS")
			(options
				(clearance outline)
				(anchor circle)
			)
			(primitives
				(gr_poly
					(pts
						(arc
							(start -0.1778 0.2794)
							(mid -0.249642 0.249642)
							(end -0.2794 0.1778)
						)
						(arc
							(start -0.2794 -0.1778)
							(mid -0.249642 -0.249642)
							(end -0.1778 -0.2794)
						)
						(arc
							(start 0.1778 -0.2794)
							(mid 0.249642 -0.249642)
							(end 0.2794 -0.1778)
						)
						(arc
							(start 0.2794 0.1778)
							(mid 0.249642 0.249642)
							(end 0.1778 0.2794)
						)
					)
					(width 0)
					(fill yes)
				)
			)
		)
		(pad "2" smd custom
			(at 0 0.4445 180)
			(size 0.1397 0.1397)
			(layers "B.Cu" "B.Mask" "B.Paste")
			(net "DUT_VDDO")
			(options
				(clearance outline)
				(anchor circle)
			)
			(primitives
				(gr_poly
					(pts
						(arc
							(start -0.1778 0.2794)
							(mid -0.249642 0.249642)
							(end -0.2794 0.1778)
						)
						(arc
							(start -0.2794 -0.1778)
							(mid -0.249642 -0.249642)
							(end -0.1778 -0.2794)
						)
						(arc
							(start 0.1778 -0.2794)
							(mid 0.249642 -0.249642)
							(end 0.2794 -0.1778)
						)
						(arc
							(start 0.2794 0.1778)
							(mid 0.249642 0.249642)
							(end 0.1778 0.2794)
						)
					)
					(width 0)
					(fill yes)
				)
			)
		)
	)
	(footprint ""
		(layer "B.Cu")
		(at 253.5936 -36.999672 90)
		(property "Reference" "C593"
			(at 0 0 90)
			(layer "B.SilkS")
			(hide yes)
			(effects
				(font
					(size 1.27 1.27)
				)
				(justify mirror)
			)
		)
		(property "Value" "SCD1U16V1KX-1-GP"
			(at 2.8321 -1.7399 90)
			(unlocked yes)
			(layer "B.Fab")
			(hide yes)
			(effects
				(font
					(size 1.016 1.016)
					(thickness 0.1524)
				)
				(justify mirror)
			)
		)
		(property "Device Type" "C0201H13"
			(at 2.8321 -3.2639 90)
			(unlocked yes)
			(layer "B.Fab")
			(hide yes)
			(effects
				(font
					(size 1.016 1.016)
					(thickness 0.1524)
				)
				(justify mirror)
			)
		)
		(duplicate_pad_numbers_are_jumpers no)
		(fp_rect
			(start 0.2794 0.6477)
			(end -0.2794 -0.6477)
			(stroke
				(width 0)
				(type default)
			)
			(fill no)
			(layer "B.CrtYd")
		)
		(fp_rect
			(start 0.2794 0.6477)
			(end -0.2794 -0.6477)
			(stroke
				(width 0)
				(type default)
			)
			(fill no)
			(layer "B.Fab")
		)
		(pad "1" smd custom
			(at 0 -0.2794 270)
			(size 0.0762 0.0762)
			(layers "B.Cu" "B.Mask" "B.Paste")
			(net "DUT_AVD_PCIE")
			(options
				(clearance outline)
				(anchor circle)
			)
			(primitives
				(gr_poly
					(pts
						(arc
							(start 0.1524 0.127)
							(mid 0.137521 0.162921)
							(end 0.1016 0.1778)
						)
						(arc
							(start -0.1016 0.1778)
							(mid -0.137521 0.162921)
							(end -0.1524 0.127)
						)
						(arc
							(start -0.1524 -0.127)
							(mid -0.137521 -0.162921)
							(end -0.1016 -0.1778)
						)
						(arc
							(start 0.1016 -0.1778)
							(mid 0.137521 -0.162921)
							(end 0.1524 -0.127)
						)
					)
					(width 0)
					(fill yes)
				)
			)
		)
		(pad "2" smd custom
			(at 0 0.2794 270)
			(size 0.0762 0.0762)
			(layers "B.Cu" "B.Mask" "B.Paste")
			(net "GND")
			(options
				(clearance outline)
				(anchor circle)
			)
			(primitives
				(gr_poly
					(pts
						(arc
							(start 0.1524 0.127)
							(mid 0.137521 0.162921)
							(end 0.1016 0.1778)
						)
						(arc
							(start -0.1016 0.1778)
							(mid -0.137521 0.162921)
							(end -0.1524 0.127)
						)
						(arc
							(start -0.1524 -0.127)
							(mid -0.137521 -0.162921)
							(end -0.1016 -0.1778)
						)
						(arc
							(start 0.1016 -0.1778)
							(mid 0.137521 -0.162921)
							(end 0.1524 -0.127)
						)
					)
					(width 0)
					(fill yes)
				)
			)
		)
	)
	(footprint ""
		(layer "B.Cu")
		(at 38.840664 -126.932944 180)
		(property "Reference" "C217"
			(at 0 0 0)
			(layer "B.SilkS")
			(hide yes)
			(effects
				(font
					(size 1.27 1.27)
				)
				(justify mirror)
			)
		)
		(property "Value" "SC1U10V2KX-4-GP"
			(at -1.1811 -2.7051 180)
			(unlocked yes)
			(layer "B.Fab")
			(hide yes)
			(effects
				(font
					(size 1.016 1.016)
					(thickness 0.1524)
				)
				(justify mirror)
			)
		)
		(property "Device Type" "C402H22"
			(at -1.1811 -4.2291 180)
			(unlocked yes)
			(layer "B.Fab")
			(hide yes)
			(effects
				(font
					(size 1.016 1.016)
					(thickness 0.1524)
				)
				(justify mirror)
			)
		)
		(duplicate_pad_numbers_are_jumpers no)
		(fp_rect
			(start 0.4318 0.9525)
			(end -0.4318 -0.9525)
			(stroke
				(width 0)
				(type default)
			)
			(fill no)
			(layer "B.CrtYd")
		)
		(fp_rect
			(start 0.4318 0.9525)
			(end -0.4318 -0.9525)
			(stroke
				(width 0)
				(type default)
			)
			(fill no)
			(layer "B.Fab")
		)
		(pad "1" smd custom
			(at 0 -0.4445)
			(size 0.1524 0.1524)
			(layers "B.Cu" "B.Mask" "B.Paste")
			(net "P3V3_STBY")
			(options
				(clearance outline)
				(anchor circle)
			)
			(primitives
				(gr_poly
					(pts
						(arc
							(start 0.3048 0.2032)
							(mid 0.275042 0.275042)
							(end 0.2032 0.3048)
						)
						(arc
							(start -0.2032 0.3048)
							(mid -0.275042 0.275042)
							(end -0.3048 0.2032)
						)
						(arc
							(start -0.3048 -0.2032)
							(mid -0.275042 -0.275042)
							(end -0.2032 -0.3048)
						)
						(arc
							(start 0.2032 -0.3048)
							(mid 0.275042 -0.275042)
							(end 0.3048 -0.2032)
						)
					)
					(width 0)
					(fill yes)
				)
			)
		)
		(pad "2" smd custom
			(at 0 0.4445)
			(size 0.1524 0.1524)
			(layers "B.Cu" "B.Mask" "B.Paste")
			(net "GND")
			(options
				(clearance outline)
				(anchor circle)
			)
			(primitives
				(gr_poly
					(pts
						(arc
							(start 0.3048 0.2032)
							(mid 0.275042 0.275042)
							(end 0.2032 0.3048)
						)
						(arc
							(start -0.2032 0.3048)
							(mid -0.275042 0.275042)
							(end -0.3048 0.2032)
						)
						(arc
							(start -0.3048 -0.2032)
							(mid -0.275042 -0.275042)
							(end -0.2032 -0.3048)
						)
						(arc
							(start 0.2032 -0.3048)
							(mid 0.275042 -0.275042)
							(end 0.3048 -0.2032)
						)
					)
					(width 0)
					(fill yes)
				)
			)
		)
	)
	(footprint ""
		(layer "B.Cu")
		(at 253.5936 -32.9946 90)
		(property "Reference" "C605"
			(at 0 0 90)
			(layer "B.SilkS")
			(hide yes)
			(effects
				(font
					(size 1.27 1.27)
				)
				(justify mirror)
			)
		)
		(property "Value" "SCD1U16V1KX-1-GP"
			(at 2.8321 -1.7399 90)
			(unlocked yes)
			(layer "B.Fab")
			(hide yes)
			(effects
				(font
					(size 1.016 1.016)
					(thickness 0.1524)
				)
				(justify mirror)
			)
		)
		(property "Device Type" "C0201H13"
			(at 2.8321 -3.2639 90)
			(unlocked yes)
			(layer "B.Fab")
			(hide yes)
			(effects
				(font
					(size 1.016 1.016)
					(thickness 0.1524)
				)
				(justify mirror)
			)
		)
		(duplicate_pad_numbers_are_jumpers no)
		(fp_rect
			(start 0.2794 0.6477)
			(end -0.2794 -0.6477)
			(stroke
				(width 0)
				(type default)
			)
			(fill no)
			(layer "B.CrtYd")
		)
		(fp_rect
			(start 0.2794 0.6477)
			(end -0.2794 -0.6477)
			(stroke
				(width 0)
				(type default)
			)
			(fill no)
			(layer "B.Fab")
		)
		(pad "1" smd custom
			(at 0 -0.2794 270)
			(size 0.0762 0.0762)
			(layers "B.Cu" "B.Mask" "B.Paste")
			(net "DUT_AVD_PCIE")
			(options
				(clearance outline)
				(anchor circle)
			)
			(primitives
				(gr_poly
					(pts
						(arc
							(start 0.1524 0.127)
							(mid 0.137521 0.162921)
							(end 0.1016 0.1778)
						)
						(arc
							(start -0.1016 0.1778)
							(mid -0.137521 0.162921)
							(end -0.1524 0.127)
						)
						(arc
							(start -0.1524 -0.127)
							(mid -0.137521 -0.162921)
							(end -0.1016 -0.1778)
						)
						(arc
							(start 0.1016 -0.1778)
							(mid 0.137521 -0.162921)
							(end 0.1524 -0.127)
						)
					)
					(width 0)
					(fill yes)
				)
			)
		)
		(pad "2" smd custom
			(at 0 0.2794 270)
			(size 0.0762 0.0762)
			(layers "B.Cu" "B.Mask" "B.Paste")
			(net "GND")
			(options
				(clearance outline)
				(anchor circle)
			)
			(primitives
				(gr_poly
					(pts
						(arc
							(start 0.1524 0.127)
							(mid 0.137521 0.162921)
							(end 0.1016 0.1778)
						)
						(arc
							(start -0.1016 0.1778)
							(mid -0.137521 0.162921)
							(end -0.1524 0.127)
						)
						(arc
							(start -0.1524 -0.127)
							(mid -0.137521 -0.162921)
							(end -0.1016 -0.1778)
						)
						(arc
							(start 0.1016 -0.1778)
							(mid 0.137521 -0.162921)
							(end 0.1524 -0.127)
						)
					)
					(width 0)
					(fill yes)
				)
			)
		)
	)
	(footprint ""
		(layer "B.Cu")
		(at 158.766002 -64.670432 -90)
		(property "Reference" "PR166"
			(at 0 0 90)
			(layer "B.SilkS")
			(hide yes)
			(effects
				(font
					(size 1.27 1.27)
				)
				(justify mirror)
			)
		)
		(property "Value" "3D01R5F-GP"
			(at 0 -8.9535 270)
			(unlocked yes)
			(layer "B.Fab")
			(hide yes)
			(effects
				(font
					(size 1.27 1.016)
					(thickness 0.1524)
				)
				(justify mirror)
			)
		)
		(property "Device Type" "R805H24"
			(at 0 -10.6299 270)
			(unlocked yes)
			(layer "B.Fab")
			(hide yes)
			(effects
				(font
					(size 1.27 1.016)
					(thickness 0.1524)
				)
				(justify mirror)
			)
		)
		(duplicate_pad_numbers_are_jumpers no)
		(fp_line
			(start -0.889 1.7018)
			(end -0.889 -0.508)
			(stroke
				(width 0.1524)
				(type default)
			)
			(layer "B.SilkS")
		)
		(fp_line
			(start 0.889 1.7018)
			(end -0.889 1.7018)
			(stroke
				(width 0.1524)
				(type default)
			)
			(layer "B.SilkS")
		)
		(fp_line
			(start 0.889 0.0762)
			(end 0.889 1.7018)
			(stroke
				(width 0.1524)
				(type default)
			)
			(layer "B.SilkS")
		)
		(fp_line
			(start -0.889 -1.7018)
			(end -0.889 -0.381)
			(stroke
				(width 0.1524)
				(type default)
			)
			(layer "B.SilkS")
		)
		(fp_line
			(start -0.889 -1.7018)
			(end 0.889 -1.7018)
			(stroke
				(width 0.1524)
				(type default)
			)
			(layer "B.SilkS")
		)
		(fp_line
			(start 0.889 -1.7018)
			(end 0.889 0.2794)
			(stroke
				(width 0.1524)
				(type default)
			)
			(layer "B.SilkS")
		)
		(fp_poly
			(pts
				(xy -0.9652 -1.778) (xy -0.9652 1.778) (xy 0.9652 1.778) (xy 0.9652 -1.778)
			)
			(stroke
				(width 0)
				(type default)
			)
			(fill no)
			(layer "B.CrtYd")
		)
		(fp_rect
			(start 0.9652 1.778)
			(end -0.9652 -1.778)
			(stroke
				(width 0)
				(type default)
			)
			(fill no)
			(layer "B.Fab")
		)
		(pad "1" smd rect
			(at 0 -0.9652 90)
			(size 1.397 1.143)
			(layers "B.Cu" "B.Mask" "B.Paste")
			(net "P0V9_LX")
		)
		(pad "2" smd rect
			(at 0 0.9652 90)
			(size 1.397 1.143)
			(layers "B.Cu" "B.Mask" "B.Paste")
			(net "P0V9_SNB")
		)
	)
	(footprint ""
		(layer "B.Cu")
		(at 22.5298 -133.3246)
		(property "Reference" "TP96"
			(at 0 0 0)
			(layer "B.SilkS")
			(hide yes)
			(effects
				(font
					(size 1.27 1.27)
				)
				(justify mirror)
			)
		)
		(property "Value" "TPAD28-2-GP"
			(at 0.0127 -1.6637 0)
			(unlocked yes)
			(layer "B.Fab")
			(hide yes)
			(effects
				(font
					(size 1.016 1.016)
					(thickness 0.1524)
				)
				(justify mirror)
			)
		)
		(property "Device Type" "TPAD28"
			(at 0.0127 -3.1877 0)
			(unlocked yes)
			(layer "B.Fab")
			(hide yes)
			(effects
				(font
					(size 1.016 1.016)
					(thickness 0.1524)
				)
				(justify mirror)
			)
		)
		(duplicate_pad_numbers_are_jumpers no)
		(fp_poly
			(pts
				(arc
					(start 0.3556 0)
					(mid -0.3556 0)
					(end 0.3556 0)
				)
			)
			(stroke
				(width 0)
				(type default)
			)
			(fill no)
			(layer "B.CrtYd")
		)
		(fp_poly
			(pts
				(arc
					(start 0.6096 0)
					(mid -0.6096 0)
					(end 0.6096 0)
				)
			)
			(stroke
				(width 0)
				(type default)
			)
			(fill no)
			(layer "B.Fab")
		)
		(pad "1" smd circle
			(at 0 0 180)
			(size 0.7112 0.7112)
			(layers "B.Cu" "B.Mask" "B.Paste")
			(net "TP_GPIOS4")
		)
	)
	(footprint ""
		(layer "B.Cu")
		(at 45.085 -116.713)
		(property "Reference" "R537"
			(at 0 0 0)
			(layer "B.SilkS")
			(hide yes)
			(effects
				(font
					(size 1.27 1.27)
				)
				(justify mirror)
			)
		)
		(property "Value" "0R2J-2-GP"
			(at -0.064008 -3.993896 0)
			(unlocked yes)
			(layer "B.Fab")
			(hide yes)
			(effects
				(font
					(size 1.016 1.016)
					(thickness 0.1524)
				)
				(justify mirror)
			)
		)
		(property "Device Type" "R402H16"
			(at -0.064008 -5.517896 0)
			(unlocked yes)
			(layer "B.Fab")
			(hide yes)
			(effects
				(font
					(size 1.016 1.016)
					(thickness 0.1524)
				)
				(justify mirror)
			)
		)
		(duplicate_pad_numbers_are_jumpers no)
		(fp_line
			(start -0.508 -0.9398)
			(end 0.508 -0.9398)
			(stroke
				(width 0.1524)
				(type default)
			)
			(layer "B.SilkS")
		)
		(fp_line
			(start 0.508 -0.9398)
			(end 0.508 0.9398)
			(stroke
				(width 0.1524)
				(type default)
			)
			(layer "B.SilkS")
		)
		(fp_rect
			(start 0.508 0.9398)
			(end -0.508 -0.9398)
			(stroke
				(width 0)
				(type default)
			)
			(fill no)
			(layer "B.CrtYd")
		)
		(fp_rect
			(start 0.508 0.9398)
			(end -0.508 -0.9398)
			(stroke
				(width 0)
				(type default)
			)
			(fill no)
			(layer "B.Fab")
		)
		(pad "1" smd custom
			(at 0 -0.4445 180)
			(size 0.1397 0.1397)
			(layers "B.Cu" "B.Mask" "B.Paste")
			(net "PEER_TRAY_BMC")
			(options
				(clearance outline)
				(anchor circle)
			)
			(primitives
				(gr_poly
					(pts
						(arc
							(start -0.1778 0.2794)
							(mid -0.249642 0.249642)
							(end -0.2794 0.1778)
						)
						(arc
							(start -0.2794 -0.1778)
							(mid -0.249642 -0.249642)
							(end -0.1778 -0.2794)
						)
						(arc
							(start 0.1778 -0.2794)
							(mid 0.249642 -0.249642)
							(end 0.2794 -0.1778)
						)
						(arc
							(start 0.2794 0.1778)
							(mid 0.249642 0.249642)
							(end 0.1778 0.2794)
						)
					)
					(width 0)
					(fill yes)
				)
			)
		)
		(pad "2" smd custom
			(at 0 0.4445 180)
			(size 0.1397 0.1397)
			(layers "B.Cu" "B.Mask" "B.Paste")
			(net "PEER_TRAY_R")
			(options
				(clearance outline)
				(anchor circle)
			)
			(primitives
				(gr_poly
					(pts
						(arc
							(start -0.1778 0.2794)
							(mid -0.249642 0.249642)
							(end -0.2794 0.1778)
						)
						(arc
							(start -0.2794 -0.1778)
							(mid -0.249642 -0.249642)
							(end -0.1778 -0.2794)
						)
						(arc
							(start 0.1778 -0.2794)
							(mid 0.249642 -0.249642)
							(end 0.2794 -0.1778)
						)
						(arc
							(start 0.2794 0.1778)
							(mid 0.249642 0.249642)
							(end 0.1778 0.2794)
						)
					)
					(width 0)
					(fill yes)
				)
			)
		)
	)
	(footprint ""
		(layer "B.Cu")
		(at 69.469 -186.5376)
		(property "Reference" "C3213"
			(at 0 0 0)
			(layer "B.SilkS")
			(hide yes)
			(effects
				(font
					(size 1.27 1.27)
				)
				(justify mirror)
			)
		)
		(property "Value" "SCD1U25V2KX-2-GP"
			(at -1.1811 -2.7051 0)
			(unlocked yes)
			(layer "B.Fab")
			(hide yes)
			(effects
				(font
					(size 1.016 1.016)
					(thickness 0.1524)
				)
				(justify mirror)
			)
		)
		(property "Device Type" "C402H22"
			(at -1.1811 -4.2291 0)
			(unlocked yes)
			(layer "B.Fab")
			(hide yes)
			(effects
				(font
					(size 1.016 1.016)
					(thickness 0.1524)
				)
				(justify mirror)
			)
		)
		(duplicate_pad_numbers_are_jumpers no)
		(fp_rect
			(start 0.4318 0.9525)
			(end -0.4318 -0.9525)
			(stroke
				(width 0)
				(type default)
			)
			(fill no)
			(layer "B.CrtYd")
		)
		(fp_rect
			(start 0.4318 0.9525)
			(end -0.4318 -0.9525)
			(stroke
				(width 0)
				(type default)
			)
			(fill no)
			(layer "B.Fab")
		)
		(pad "1" smd custom
			(at 0 -0.4445 180)
			(size 0.1524 0.1524)
			(layers "B.Cu" "B.Mask" "B.Paste")
			(net "P3V3_STBY")
			(options
				(clearance outline)
				(anchor circle)
			)
			(primitives
				(gr_poly
					(pts
						(arc
							(start 0.3048 0.2032)
							(mid 0.275042 0.275042)
							(end 0.2032 0.3048)
						)
						(arc
							(start -0.2032 0.3048)
							(mid -0.275042 0.275042)
							(end -0.3048 0.2032)
						)
						(arc
							(start -0.3048 -0.2032)
							(mid -0.275042 -0.275042)
							(end -0.2032 -0.3048)
						)
						(arc
							(start 0.2032 -0.3048)
							(mid 0.275042 -0.275042)
							(end 0.3048 -0.2032)
						)
					)
					(width 0)
					(fill yes)
				)
			)
		)
		(pad "2" smd custom
			(at 0 0.4445 180)
			(size 0.1524 0.1524)
			(layers "B.Cu" "B.Mask" "B.Paste")
			(net "GND")
			(options
				(clearance outline)
				(anchor circle)
			)
			(primitives
				(gr_poly
					(pts
						(arc
							(start 0.3048 0.2032)
							(mid 0.275042 0.275042)
							(end 0.2032 0.3048)
						)
						(arc
							(start -0.2032 0.3048)
							(mid -0.275042 0.275042)
							(end -0.3048 0.2032)
						)
						(arc
							(start -0.3048 -0.2032)
							(mid -0.275042 -0.275042)
							(end -0.2032 -0.3048)
						)
						(arc
							(start 0.2032 -0.3048)
							(mid 0.275042 -0.275042)
							(end 0.3048 -0.2032)
						)
					)
					(width 0)
					(fill yes)
				)
			)
		)
	)
	(footprint ""
		(layer "B.Cu")
		(at 162.306 -88.4174 180)
		(property "Reference" "C713"
			(at 0 0 0)
			(layer "B.SilkS")
			(hide yes)
			(effects
				(font
					(size 1.27 1.27)
				)
				(justify mirror)
			)
		)
		(property "Value" "SCD1U10V2KX-5GP"
			(at -1.1811 -2.7051 180)
			(unlocked yes)
			(layer "B.Fab")
			(hide yes)
			(effects
				(font
					(size 1.016 1.016)
					(thickness 0.1524)
				)
				(justify mirror)
			)
		)
		(property "Device Type" "C402H22"
			(at -1.1811 -4.2291 180)
			(unlocked yes)
			(layer "B.Fab")
			(hide yes)
			(effects
				(font
					(size 1.016 1.016)
					(thickness 0.1524)
				)
				(justify mirror)
			)
		)
		(duplicate_pad_numbers_are_jumpers no)
		(fp_rect
			(start 0.4318 0.9525)
			(end -0.4318 -0.9525)
			(stroke
				(width 0)
				(type default)
			)
			(fill no)
			(layer "B.CrtYd")
		)
		(fp_rect
			(start 0.4318 0.9525)
			(end -0.4318 -0.9525)
			(stroke
				(width 0)
				(type default)
			)
			(fill no)
			(layer "B.Fab")
		)
		(pad "1" smd custom
			(at 0 -0.4445)
			(size 0.1524 0.1524)
			(layers "B.Cu" "B.Mask" "B.Paste")
			(net "P1V8_CLKGEN")
			(options
				(clearance outline)
				(anchor circle)
			)
			(primitives
				(gr_poly
					(pts
						(arc
							(start 0.3048 0.2032)
							(mid 0.275042 0.275042)
							(end 0.2032 0.3048)
						)
						(arc
							(start -0.2032 0.3048)
							(mid -0.275042 0.275042)
							(end -0.3048 0.2032)
						)
						(arc
							(start -0.3048 -0.2032)
							(mid -0.275042 -0.275042)
							(end -0.2032 -0.3048)
						)
						(arc
							(start 0.2032 -0.3048)
							(mid 0.275042 -0.275042)
							(end 0.3048 -0.2032)
						)
					)
					(width 0)
					(fill yes)
				)
			)
		)
		(pad "2" smd custom
			(at 0 0.4445)
			(size 0.1524 0.1524)
			(layers "B.Cu" "B.Mask" "B.Paste")
			(net "GND")
			(options
				(clearance outline)
				(anchor circle)
			)
			(primitives
				(gr_poly
					(pts
						(arc
							(start 0.3048 0.2032)
							(mid 0.275042 0.275042)
							(end 0.2032 0.3048)
						)
						(arc
							(start -0.2032 0.3048)
							(mid -0.275042 0.275042)
							(end -0.3048 0.2032)
						)
						(arc
							(start -0.3048 -0.2032)
							(mid -0.275042 -0.275042)
							(end -0.2032 -0.3048)
						)
						(arc
							(start 0.2032 -0.3048)
							(mid 0.275042 -0.275042)
							(end 0.3048 -0.2032)
						)
					)
					(width 0)
					(fill yes)
				)
			)
		)
	)
	(footprint ""
		(layer "B.Cu")
		(at 241.2746 -37.9984 -90)
		(property "Reference" "C468"
			(at 0 0 90)
			(layer "B.SilkS")
			(hide yes)
			(effects
				(font
					(size 1.27 1.27)
				)
				(justify mirror)
			)
		)
		(property "Value" "SCD1U16V1KX-1-GP"
			(at 2.8321 -1.7399 270)
			(unlocked yes)
			(layer "B.Fab")
			(hide yes)
			(effects
				(font
					(size 1.016 1.016)
					(thickness 0.1524)
				)
				(justify mirror)
			)
		)
		(property "Device Type" "C0201H13"
			(at 2.8321 -3.2639 270)
			(unlocked yes)
			(layer "B.Fab")
			(hide yes)
			(effects
				(font
					(size 1.016 1.016)
					(thickness 0.1524)
				)
				(justify mirror)
			)
		)
		(duplicate_pad_numbers_are_jumpers no)
		(fp_rect
			(start 0.2794 0.6477)
			(end -0.2794 -0.6477)
			(stroke
				(width 0)
				(type default)
			)
			(fill no)
			(layer "B.CrtYd")
		)
		(fp_rect
			(start 0.2794 0.6477)
			(end -0.2794 -0.6477)
			(stroke
				(width 0)
				(type default)
			)
			(fill no)
			(layer "B.Fab")
		)
		(pad "1" smd custom
			(at 0 -0.2794 90)
			(size 0.0762 0.0762)
			(layers "B.Cu" "B.Mask" "B.Paste")
			(net "DUT_VDDO_REF")
			(options
				(clearance outline)
				(anchor circle)
			)
			(primitives
				(gr_poly
					(pts
						(arc
							(start 0.1524 0.127)
							(mid 0.137521 0.162921)
							(end 0.1016 0.1778)
						)
						(arc
							(start -0.1016 0.1778)
							(mid -0.137521 0.162921)
							(end -0.1524 0.127)
						)
						(arc
							(start -0.1524 -0.127)
							(mid -0.137521 -0.162921)
							(end -0.1016 -0.1778)
						)
						(arc
							(start 0.1016 -0.1778)
							(mid 0.137521 -0.162921)
							(end 0.1524 -0.127)
						)
					)
					(width 0)
					(fill yes)
				)
			)
		)
		(pad "2" smd custom
			(at 0 0.2794 90)
			(size 0.0762 0.0762)
			(layers "B.Cu" "B.Mask" "B.Paste")
			(net "GND")
			(options
				(clearance outline)
				(anchor circle)
			)
			(primitives
				(gr_poly
					(pts
						(arc
							(start 0.1524 0.127)
							(mid 0.137521 0.162921)
							(end 0.1016 0.1778)
						)
						(arc
							(start -0.1016 0.1778)
							(mid -0.137521 0.162921)
							(end -0.1524 0.127)
						)
						(arc
							(start -0.1524 -0.127)
							(mid -0.137521 -0.162921)
							(end -0.1016 -0.1778)
						)
						(arc
							(start 0.1016 -0.1778)
							(mid 0.137521 -0.162921)
							(end 0.1524 -0.127)
						)
					)
					(width 0)
					(fill yes)
				)
			)
		)
	)
	(footprint ""
		(layer "B.Cu")
		(at 224.536 -23.241 180)
		(property "Reference" "R830"
			(at 0 0 0)
			(layer "B.SilkS")
			(hide yes)
			(effects
				(font
					(size 1.27 1.27)
				)
				(justify mirror)
			)
		)
		(property "Value" "0R2J-2-GP"
			(at -0.064008 -3.993896 180)
			(unlocked yes)
			(layer "B.Fab")
			(hide yes)
			(effects
				(font
					(size 1.016 1.016)
					(thickness 0.1524)
				)
				(justify mirror)
			)
		)
		(property "Device Type" "R402H16"
			(at -0.064008 -5.517896 180)
			(unlocked yes)
			(layer "B.Fab")
			(hide yes)
			(effects
				(font
					(size 1.016 1.016)
					(thickness 0.1524)
				)
				(justify mirror)
			)
		)
		(duplicate_pad_numbers_are_jumpers no)
		(fp_line
			(start 0.508 -0.9398)
			(end 0.508 0.9398)
			(stroke
				(width 0.1524)
				(type default)
			)
			(layer "B.SilkS")
		)
		(fp_line
			(start -0.508 -0.9398)
			(end 0.508 -0.9398)
			(stroke
				(width 0.1524)
				(type default)
			)
			(layer "B.SilkS")
		)
		(fp_rect
			(start 0.508 0.9398)
			(end -0.508 -0.9398)
			(stroke
				(width 0)
				(type default)
			)
			(fill no)
			(layer "B.CrtYd")
		)
		(fp_rect
			(start 0.508 0.9398)
			(end -0.508 -0.9398)
			(stroke
				(width 0)
				(type default)
			)
			(fill no)
			(layer "B.Fab")
		)
		(pad "1" smd custom
			(at 0 -0.4445)
			(size 0.1397 0.1397)
			(layers "B.Cu" "B.Mask" "B.Paste")
			(net "HOST6_RST_N_LS")
			(options
				(clearance outline)
				(anchor circle)
			)
			(primitives
				(gr_poly
					(pts
						(arc
							(start -0.1778 0.2794)
							(mid -0.249642 0.249642)
							(end -0.2794 0.1778)
						)
						(arc
							(start -0.2794 -0.1778)
							(mid -0.249642 -0.249642)
							(end -0.1778 -0.2794)
						)
						(arc
							(start 0.1778 -0.2794)
							(mid 0.249642 -0.249642)
							(end 0.2794 -0.1778)
						)
						(arc
							(start 0.2794 0.1778)
							(mid 0.249642 0.249642)
							(end 0.1778 0.2794)
						)
					)
					(width 0)
					(fill yes)
				)
			)
		)
		(pad "2" smd custom
			(at 0 0.4445)
			(size 0.1397 0.1397)
			(layers "B.Cu" "B.Mask" "B.Paste")
			(net "LBI_ADDR_5_R")
			(options
				(clearance outline)
				(anchor circle)
			)
			(primitives
				(gr_poly
					(pts
						(arc
							(start -0.1778 0.2794)
							(mid -0.249642 0.249642)
							(end -0.2794 0.1778)
						)
						(arc
							(start -0.2794 -0.1778)
							(mid -0.249642 -0.249642)
							(end -0.1778 -0.2794)
						)
						(arc
							(start 0.1778 -0.2794)
							(mid 0.249642 -0.249642)
							(end 0.2794 -0.1778)
						)
						(arc
							(start 0.2794 0.1778)
							(mid 0.249642 0.249642)
							(end 0.1778 0.2794)
						)
					)
					(width 0)
					(fill yes)
				)
			)
		)
	)
	(footprint ""
		(layer "B.Cu")
		(at 228.6254 -42.994072 90)
		(property "Reference" "C574"
			(at 0 0 90)
			(layer "B.SilkS")
			(hide yes)
			(effects
				(font
					(size 1.27 1.27)
				)
				(justify mirror)
			)
		)
		(property "Value" "SCD1U16V1KX-1-GP"
			(at 2.8321 -1.7399 90)
			(unlocked yes)
			(layer "B.Fab")
			(hide yes)
			(effects
				(font
					(size 1.016 1.016)
					(thickness 0.1524)
				)
				(justify mirror)
			)
		)
		(property "Device Type" "C0201H13"
			(at 2.8321 -3.2639 90)
			(unlocked yes)
			(layer "B.Fab")
			(hide yes)
			(effects
				(font
					(size 1.016 1.016)
					(thickness 0.1524)
				)
				(justify mirror)
			)
		)
		(duplicate_pad_numbers_are_jumpers no)
		(fp_rect
			(start 0.2794 0.6477)
			(end -0.2794 -0.6477)
			(stroke
				(width 0)
				(type default)
			)
			(fill no)
			(layer "B.CrtYd")
		)
		(fp_rect
			(start 0.2794 0.6477)
			(end -0.2794 -0.6477)
			(stroke
				(width 0)
				(type default)
			)
			(fill no)
			(layer "B.Fab")
		)
		(pad "1" smd custom
			(at 0 -0.2794 270)
			(size 0.0762 0.0762)
			(layers "B.Cu" "B.Mask" "B.Paste")
			(net "DUT_AVD_PCIE")
			(options
				(clearance outline)
				(anchor circle)
			)
			(primitives
				(gr_poly
					(pts
						(arc
							(start 0.1524 0.127)
							(mid 0.137521 0.162921)
							(end 0.1016 0.1778)
						)
						(arc
							(start -0.1016 0.1778)
							(mid -0.137521 0.162921)
							(end -0.1524 0.127)
						)
						(arc
							(start -0.1524 -0.127)
							(mid -0.137521 -0.162921)
							(end -0.1016 -0.1778)
						)
						(arc
							(start 0.1016 -0.1778)
							(mid 0.137521 -0.162921)
							(end 0.1524 -0.127)
						)
					)
					(width 0)
					(fill yes)
				)
			)
		)
		(pad "2" smd custom
			(at 0 0.2794 270)
			(size 0.0762 0.0762)
			(layers "B.Cu" "B.Mask" "B.Paste")
			(net "GND")
			(options
				(clearance outline)
				(anchor circle)
			)
			(primitives
				(gr_poly
					(pts
						(arc
							(start 0.1524 0.127)
							(mid 0.137521 0.162921)
							(end 0.1016 0.1778)
						)
						(arc
							(start -0.1016 0.1778)
							(mid -0.137521 0.162921)
							(end -0.1524 0.127)
						)
						(arc
							(start -0.1524 -0.127)
							(mid -0.137521 -0.162921)
							(end -0.1016 -0.1778)
						)
						(arc
							(start 0.1016 -0.1778)
							(mid 0.137521 -0.162921)
							(end 0.1524 -0.127)
						)
					)
					(width 0)
					(fill yes)
				)
			)
		)
	)
	(footprint ""
		(layer "B.Cu")
		(at 48.5648 -102.4382 -90)
		(property "Reference" "R66"
			(at 0 0 90)
			(layer "B.SilkS")
			(hide yes)
			(effects
				(font
					(size 1.27 1.27)
				)
				(justify mirror)
			)
		)
		(property "Value" "0R2J-2-GP"
			(at -0.064008 -3.993896 270)
			(unlocked yes)
			(layer "B.Fab")
			(hide yes)
			(effects
				(font
					(size 1.016 1.016)
					(thickness 0.1524)
				)
				(justify mirror)
			)
		)
		(property "Device Type" "R402H16"
			(at -0.064008 -5.517896 270)
			(unlocked yes)
			(layer "B.Fab")
			(hide yes)
			(effects
				(font
					(size 1.016 1.016)
					(thickness 0.1524)
				)
				(justify mirror)
			)
		)
		(duplicate_pad_numbers_are_jumpers no)
		(fp_line
			(start -0.508 -0.9398)
			(end 0.508 -0.9398)
			(stroke
				(width 0.1524)
				(type default)
			)
			(layer "B.SilkS")
		)
		(fp_line
			(start 0.508 -0.9398)
			(end 0.508 0.9398)
			(stroke
				(width 0.1524)
				(type default)
			)
			(layer "B.SilkS")
		)
		(fp_rect
			(start 0.508 0.9398)
			(end -0.508 -0.9398)
			(stroke
				(width 0)
				(type default)
			)
			(fill no)
			(layer "B.CrtYd")
		)
		(fp_rect
			(start 0.508 0.9398)
			(end -0.508 -0.9398)
			(stroke
				(width 0)
				(type default)
			)
			(fill no)
			(layer "B.Fab")
		)
		(pad "1" smd custom
			(at 0 -0.4445 90)
			(size 0.1397 0.1397)
			(layers "B.Cu" "B.Mask" "B.Paste")
			(net "BMC_I2C14_MINI8_SDA")
			(options
				(clearance outline)
				(anchor circle)
			)
			(primitives
				(gr_poly
					(pts
						(arc
							(start -0.1778 0.2794)
							(mid -0.249642 0.249642)
							(end -0.2794 0.1778)
						)
						(arc
							(start -0.2794 -0.1778)
							(mid -0.249642 -0.249642)
							(end -0.1778 -0.2794)
						)
						(arc
							(start 0.1778 -0.2794)
							(mid 0.249642 -0.249642)
							(end 0.2794 -0.1778)
						)
						(arc
							(start 0.2794 0.1778)
							(mid 0.249642 0.249642)
							(end 0.1778 0.2794)
						)
					)
					(width 0)
					(fill yes)
				)
			)
		)
		(pad "2" smd custom
			(at 0 0.4445 90)
			(size 0.1397 0.1397)
			(layers "B.Cu" "B.Mask" "B.Paste")
			(net "BMC_I2C14_MINI8_SDA_S")
			(options
				(clearance outline)
				(anchor circle)
			)
			(primitives
				(gr_poly
					(pts
						(arc
							(start -0.1778 0.2794)
							(mid -0.249642 0.249642)
							(end -0.2794 0.1778)
						)
						(arc
							(start -0.2794 -0.1778)
							(mid -0.249642 -0.249642)
							(end -0.1778 -0.2794)
						)
						(arc
							(start 0.1778 -0.2794)
							(mid 0.249642 -0.249642)
							(end 0.2794 -0.1778)
						)
						(arc
							(start 0.2794 0.1778)
							(mid 0.249642 0.249642)
							(end 0.1778 0.2794)
						)
					)
					(width 0)
					(fill yes)
				)
			)
		)
	)
	(footprint ""
		(layer "B.Cu")
		(at 133.141212 -205.849474)
		(property "Reference" "R3207"
			(at 0 0 0)
			(layer "B.SilkS")
			(hide yes)
			(effects
				(font
					(size 1.27 1.27)
				)
				(justify mirror)
			)
		)
		(property "Value" "0R2J-2-GP"
			(at -0.064008 -3.993896 0)
			(unlocked yes)
			(layer "B.Fab")
			(hide yes)
			(effects
				(font
					(size 1.016 1.016)
					(thickness 0.1524)
				)
				(justify mirror)
			)
		)
		(property "Device Type" "R402H16"
			(at -0.064008 -5.517896 0)
			(unlocked yes)
			(layer "B.Fab")
			(hide yes)
			(effects
				(font
					(size 1.016 1.016)
					(thickness 0.1524)
				)
				(justify mirror)
			)
		)
		(duplicate_pad_numbers_are_jumpers no)
		(fp_line
			(start -0.508 -0.9398)
			(end 0.508 -0.9398)
			(stroke
				(width 0.1524)
				(type default)
			)
			(layer "B.SilkS")
		)
		(fp_line
			(start 0.508 -0.9398)
			(end 0.508 0.9398)
			(stroke
				(width 0.1524)
				(type default)
			)
			(layer "B.SilkS")
		)
		(fp_rect
			(start 0.508 0.9398)
			(end -0.508 -0.9398)
			(stroke
				(width 0)
				(type default)
			)
			(fill no)
			(layer "B.CrtYd")
		)
		(fp_rect
			(start 0.508 0.9398)
			(end -0.508 -0.9398)
			(stroke
				(width 0)
				(type default)
			)
			(fill no)
			(layer "B.Fab")
		)
		(pad "1" smd custom
			(at 0 -0.4445 180)
			(size 0.1397 0.1397)
			(layers "B.Cu" "B.Mask" "B.Paste")
			(net "SSD_PERST#2")
			(options
				(clearance outline)
				(anchor circle)
			)
			(primitives
				(gr_poly
					(pts
						(arc
							(start -0.1778 0.2794)
							(mid -0.249642 0.249642)
							(end -0.2794 0.1778)
						)
						(arc
							(start -0.2794 -0.1778)
							(mid -0.249642 -0.249642)
							(end -0.1778 -0.2794)
						)
						(arc
							(start 0.1778 -0.2794)
							(mid 0.249642 -0.249642)
							(end 0.2794 -0.1778)
						)
						(arc
							(start 0.2794 0.1778)
							(mid 0.249642 0.249642)
							(end 0.1778 0.2794)
						)
					)
					(width 0)
					(fill yes)
				)
			)
		)
		(pad "2" smd custom
			(at 0 0.4445 180)
			(size 0.1397 0.1397)
			(layers "B.Cu" "B.Mask" "B.Paste")
			(net "SSD_PERST#0_B2")
			(options
				(clearance outline)
				(anchor circle)
			)
			(primitives
				(gr_poly
					(pts
						(arc
							(start -0.1778 0.2794)
							(mid -0.249642 0.249642)
							(end -0.2794 0.1778)
						)
						(arc
							(start -0.2794 -0.1778)
							(mid -0.249642 -0.249642)
							(end -0.1778 -0.2794)
						)
						(arc
							(start 0.1778 -0.2794)
							(mid 0.249642 -0.249642)
							(end 0.2794 -0.1778)
						)
						(arc
							(start 0.2794 0.1778)
							(mid 0.249642 0.249642)
							(end 0.1778 0.2794)
						)
					)
					(width 0)
					(fill yes)
				)
			)
		)
	)
	(footprint ""
		(layer "B.Cu")
		(at 161.417 -92.7354)
		(property "Reference" "C717"
			(at 0 0 0)
			(layer "B.SilkS")
			(hide yes)
			(effects
				(font
					(size 1.27 1.27)
				)
				(justify mirror)
			)
		)
		(property "Value" "SCD1U10V2KX-5GP"
			(at -1.1811 -2.7051 0)
			(unlocked yes)
			(layer "B.Fab")
			(hide yes)
			(effects
				(font
					(size 1.016 1.016)
					(thickness 0.1524)
				)
				(justify mirror)
			)
		)
		(property "Device Type" "C402H22"
			(at -1.1811 -4.2291 0)
			(unlocked yes)
			(layer "B.Fab")
			(hide yes)
			(effects
				(font
					(size 1.016 1.016)
					(thickness 0.1524)
				)
				(justify mirror)
			)
		)
		(duplicate_pad_numbers_are_jumpers no)
		(fp_rect
			(start 0.4318 0.9525)
			(end -0.4318 -0.9525)
			(stroke
				(width 0)
				(type default)
			)
			(fill no)
			(layer "B.CrtYd")
		)
		(fp_rect
			(start 0.4318 0.9525)
			(end -0.4318 -0.9525)
			(stroke
				(width 0)
				(type default)
			)
			(fill no)
			(layer "B.Fab")
		)
		(pad "1" smd custom
			(at 0 -0.4445 180)
			(size 0.1524 0.1524)
			(layers "B.Cu" "B.Mask" "B.Paste")
			(net "P1V8_CLKGEN")
			(options
				(clearance outline)
				(anchor circle)
			)
			(primitives
				(gr_poly
					(pts
						(arc
							(start 0.3048 0.2032)
							(mid 0.275042 0.275042)
							(end 0.2032 0.3048)
						)
						(arc
							(start -0.2032 0.3048)
							(mid -0.275042 0.275042)
							(end -0.3048 0.2032)
						)
						(arc
							(start -0.3048 -0.2032)
							(mid -0.275042 -0.275042)
							(end -0.2032 -0.3048)
						)
						(arc
							(start 0.2032 -0.3048)
							(mid 0.275042 -0.275042)
							(end 0.3048 -0.2032)
						)
					)
					(width 0)
					(fill yes)
				)
			)
		)
		(pad "2" smd custom
			(at 0 0.4445 180)
			(size 0.1524 0.1524)
			(layers "B.Cu" "B.Mask" "B.Paste")
			(net "GND")
			(options
				(clearance outline)
				(anchor circle)
			)
			(primitives
				(gr_poly
					(pts
						(arc
							(start 0.3048 0.2032)
							(mid 0.275042 0.275042)
							(end 0.2032 0.3048)
						)
						(arc
							(start -0.2032 0.3048)
							(mid -0.275042 0.275042)
							(end -0.3048 0.2032)
						)
						(arc
							(start -0.3048 -0.2032)
							(mid -0.275042 -0.275042)
							(end -0.2032 -0.3048)
						)
						(arc
							(start 0.2032 -0.3048)
							(mid 0.275042 -0.275042)
							(end 0.3048 -0.2032)
						)
					)
					(width 0)
					(fill yes)
				)
			)
		)
	)
	(footprint ""
		(layer "B.Cu")
		(at 72.874124 -195.681092 180)
		(property "Reference" "R4116"
			(at 0 0 0)
			(layer "B.SilkS")
			(hide yes)
			(effects
				(font
					(size 1.27 1.27)
				)
				(justify mirror)
			)
		)
		(property "Value" "4K7R2F-GP"
			(at -0.064008 -3.993896 180)
			(unlocked yes)
			(layer "B.Fab")
			(hide yes)
			(effects
				(font
					(size 1.016 1.016)
					(thickness 0.1524)
				)
				(justify mirror)
			)
		)
		(property "Device Type" "R402H16"
			(at -0.064008 -5.517896 180)
			(unlocked yes)
			(layer "B.Fab")
			(hide yes)
			(effects
				(font
					(size 1.016 1.016)
					(thickness 0.1524)
				)
				(justify mirror)
			)
		)
		(duplicate_pad_numbers_are_jumpers no)
		(fp_line
			(start 0.508 -0.9398)
			(end 0.508 0.9398)
			(stroke
				(width 0.1524)
				(type default)
			)
			(layer "B.SilkS")
		)
		(fp_line
			(start -0.508 -0.9398)
			(end 0.508 -0.9398)
			(stroke
				(width 0.1524)
				(type default)
			)
			(layer "B.SilkS")
		)
		(fp_rect
			(start 0.508 0.9398)
			(end -0.508 -0.9398)
			(stroke
				(width 0)
				(type default)
			)
			(fill no)
			(layer "B.CrtYd")
		)
		(fp_rect
			(start 0.508 0.9398)
			(end -0.508 -0.9398)
			(stroke
				(width 0)
				(type default)
			)
			(fill no)
			(layer "B.Fab")
		)
		(pad "1" smd custom
			(at 0 -0.4445)
			(size 0.1397 0.1397)
			(layers "B.Cu" "B.Mask" "B.Paste")
			(net "SSD_PERST#11")
			(options
				(clearance outline)
				(anchor circle)
			)
			(primitives
				(gr_poly
					(pts
						(arc
							(start -0.1778 0.2794)
							(mid -0.249642 0.249642)
							(end -0.2794 0.1778)
						)
						(arc
							(start -0.2794 -0.1778)
							(mid -0.249642 -0.249642)
							(end -0.1778 -0.2794)
						)
						(arc
							(start 0.1778 -0.2794)
							(mid 0.249642 -0.249642)
							(end 0.2794 -0.1778)
						)
						(arc
							(start 0.2794 0.1778)
							(mid 0.249642 0.249642)
							(end 0.1778 0.2794)
						)
					)
					(width 0)
					(fill yes)
				)
			)
		)
		(pad "2" smd custom
			(at 0 0.4445)
			(size 0.1397 0.1397)
			(layers "B.Cu" "B.Mask" "B.Paste")
			(net "P3V3_STBY")
			(options
				(clearance outline)
				(anchor circle)
			)
			(primitives
				(gr_poly
					(pts
						(arc
							(start -0.1778 0.2794)
							(mid -0.249642 0.249642)
							(end -0.2794 0.1778)
						)
						(arc
							(start -0.2794 -0.1778)
							(mid -0.249642 -0.249642)
							(end -0.1778 -0.2794)
						)
						(arc
							(start 0.1778 -0.2794)
							(mid 0.249642 -0.249642)
							(end 0.2794 -0.1778)
						)
						(arc
							(start 0.2794 0.1778)
							(mid 0.249642 0.249642)
							(end 0.1778 0.2794)
						)
					)
					(width 0)
					(fill yes)
				)
			)
		)
	)
	(footprint ""
		(layer "B.Cu")
		(at 251.333 -47.117 -90)
		(property "Reference" "C611"
			(at 0 0 90)
			(layer "B.SilkS")
			(hide yes)
			(effects
				(font
					(size 1.27 1.27)
				)
				(justify mirror)
			)
		)
		(property "Value" "SCD1U16V1KX-1-GP"
			(at 2.8321 -1.7399 270)
			(unlocked yes)
			(layer "B.Fab")
			(hide yes)
			(effects
				(font
					(size 1.016 1.016)
					(thickness 0.1524)
				)
				(justify mirror)
			)
		)
		(property "Device Type" "C0201H13"
			(at 2.8321 -3.2639 270)
			(unlocked yes)
			(layer "B.Fab")
			(hide yes)
			(effects
				(font
					(size 1.016 1.016)
					(thickness 0.1524)
				)
				(justify mirror)
			)
		)
		(duplicate_pad_numbers_are_jumpers no)
		(fp_rect
			(start 0.2794 0.6477)
			(end -0.2794 -0.6477)
			(stroke
				(width 0)
				(type default)
			)
			(fill no)
			(layer "B.CrtYd")
		)
		(fp_rect
			(start 0.2794 0.6477)
			(end -0.2794 -0.6477)
			(stroke
				(width 0)
				(type default)
			)
			(fill no)
			(layer "B.Fab")
		)
		(pad "1" smd custom
			(at 0 -0.2794 90)
			(size 0.0762 0.0762)
			(layers "B.Cu" "B.Mask" "B.Paste")
			(net "DUT_AVD_PCIE")
			(options
				(clearance outline)
				(anchor circle)
			)
			(primitives
				(gr_poly
					(pts
						(arc
							(start 0.1524 0.127)
							(mid 0.137521 0.162921)
							(end 0.1016 0.1778)
						)
						(arc
							(start -0.1016 0.1778)
							(mid -0.137521 0.162921)
							(end -0.1524 0.127)
						)
						(arc
							(start -0.1524 -0.127)
							(mid -0.137521 -0.162921)
							(end -0.1016 -0.1778)
						)
						(arc
							(start 0.1016 -0.1778)
							(mid 0.137521 -0.162921)
							(end 0.1524 -0.127)
						)
					)
					(width 0)
					(fill yes)
				)
			)
		)
		(pad "2" smd custom
			(at 0 0.2794 90)
			(size 0.0762 0.0762)
			(layers "B.Cu" "B.Mask" "B.Paste")
			(net "GND")
			(options
				(clearance outline)
				(anchor circle)
			)
			(primitives
				(gr_poly
					(pts
						(arc
							(start 0.1524 0.127)
							(mid 0.137521 0.162921)
							(end 0.1016 0.1778)
						)
						(arc
							(start -0.1016 0.1778)
							(mid -0.137521 0.162921)
							(end -0.1524 0.127)
						)
						(arc
							(start -0.1524 -0.127)
							(mid -0.137521 -0.162921)
							(end -0.1016 -0.1778)
						)
						(arc
							(start 0.1016 -0.1778)
							(mid 0.137521 -0.162921)
							(end 0.1524 -0.127)
						)
					)
					(width 0)
					(fill yes)
				)
			)
		)
	)
	(footprint ""
		(layer "B.Cu")
		(at 232.6005 -38.989 -90)
		(property "Reference" "TP201"
			(at 0 0 90)
			(layer "B.SilkS")
			(hide yes)
			(effects
				(font
					(size 1.27 1.27)
				)
				(justify mirror)
			)
		)
		(property "Value" "TPAD28-2-GP"
			(at 0.0127 -1.6637 270)
			(unlocked yes)
			(layer "B.Fab")
			(hide yes)
			(effects
				(font
					(size 1.016 1.016)
					(thickness 0.1524)
				)
				(justify mirror)
			)
		)
		(property "Device Type" "TPAD28"
			(at 0.0127 -3.1877 270)
			(unlocked yes)
			(layer "B.Fab")
			(hide yes)
			(effects
				(font
					(size 1.016 1.016)
					(thickness 0.1524)
				)
				(justify mirror)
			)
		)
		(duplicate_pad_numbers_are_jumpers no)
		(fp_poly
			(pts
				(arc
					(start 0 -0.3556)
					(mid 0 0.3556)
					(end 0 -0.3556)
				)
			)
			(stroke
				(width 0)
				(type default)
			)
			(fill no)
			(layer "B.CrtYd")
		)
		(fp_poly
			(pts
				(arc
					(start 0 -0.6096)
					(mid 0 0.6096)
					(end 0 -0.6096)
				)
			)
			(stroke
				(width 0)
				(type default)
			)
			(fill no)
			(layer "B.Fab")
		)
		(pad "1" smd circle
			(at 0 0 90)
			(size 0.7112 0.7112)
			(layers "B.Cu" "B.Mask" "B.Paste")
			(net "RMII_REF_CLK")
		)
	)
	(footprint ""
		(layer "B.Cu")
		(at 305.90109 -34.719514)
		(property "Reference" "C134"
			(at 0 0 0)
			(layer "B.SilkS")
			(hide yes)
			(effects
				(font
					(size 1.27 1.27)
				)
				(justify mirror)
			)
		)
		(property "Value" "SCD1U10V2KX-5GP"
			(at -1.1811 -2.7051 0)
			(unlocked yes)
			(layer "B.Fab")
			(hide yes)
			(effects
				(font
					(size 1.016 1.016)
					(thickness 0.1524)
				)
				(justify mirror)
			)
		)
		(property "Device Type" "C402H22"
			(at -1.1811 -4.2291 0)
			(unlocked yes)
			(layer "B.Fab")
			(hide yes)
			(effects
				(font
					(size 1.016 1.016)
					(thickness 0.1524)
				)
				(justify mirror)
			)
		)
		(duplicate_pad_numbers_are_jumpers no)
		(fp_rect
			(start 0.4318 0.9525)
			(end -0.4318 -0.9525)
			(stroke
				(width 0)
				(type default)
			)
			(fill no)
			(layer "B.CrtYd")
		)
		(fp_rect
			(start 0.4318 0.9525)
			(end -0.4318 -0.9525)
			(stroke
				(width 0)
				(type default)
			)
			(fill no)
			(layer "B.Fab")
		)
		(pad "1" smd custom
			(at 0 -0.4445 180)
			(size 0.1524 0.1524)
			(layers "B.Cu" "B.Mask" "B.Paste")
			(net "GND")
			(options
				(clearance outline)
				(anchor circle)
			)
			(primitives
				(gr_poly
					(pts
						(arc
							(start 0.3048 0.2032)
							(mid 0.275042 0.275042)
							(end 0.2032 0.3048)
						)
						(arc
							(start -0.2032 0.3048)
							(mid -0.275042 0.275042)
							(end -0.3048 0.2032)
						)
						(arc
							(start -0.3048 -0.2032)
							(mid -0.275042 -0.275042)
							(end -0.2032 -0.3048)
						)
						(arc
							(start 0.2032 -0.3048)
							(mid 0.275042 -0.275042)
							(end 0.3048 -0.2032)
						)
					)
					(width 0)
					(fill yes)
				)
			)
		)
		(pad "2" smd custom
			(at 0 0.4445 180)
			(size 0.1524 0.1524)
			(layers "B.Cu" "B.Mask" "B.Paste")
			(net "P3V3_STBY")
			(options
				(clearance outline)
				(anchor circle)
			)
			(primitives
				(gr_poly
					(pts
						(arc
							(start 0.3048 0.2032)
							(mid 0.275042 0.275042)
							(end 0.2032 0.3048)
						)
						(arc
							(start -0.2032 0.3048)
							(mid -0.275042 0.275042)
							(end -0.3048 0.2032)
						)
						(arc
							(start -0.3048 -0.2032)
							(mid -0.275042 -0.275042)
							(end -0.2032 -0.3048)
						)
						(arc
							(start 0.2032 -0.3048)
							(mid 0.275042 -0.275042)
							(end 0.3048 -0.2032)
						)
					)
					(width 0)
					(fill yes)
				)
			)
		)
	)
	(footprint ""
		(layer "B.Cu")
		(at 66.802 -191.516)
		(property "Reference" "R3235"
			(at 0 0 0)
			(layer "B.SilkS")
			(hide yes)
			(effects
				(font
					(size 1.27 1.27)
				)
				(justify mirror)
			)
		)
		(property "Value" "0R2J-2-GP"
			(at -0.064008 -3.993896 0)
			(unlocked yes)
			(layer "B.Fab")
			(hide yes)
			(effects
				(font
					(size 1.016 1.016)
					(thickness 0.1524)
				)
				(justify mirror)
			)
		)
		(property "Device Type" "R402H16"
			(at -0.064008 -5.517896 0)
			(unlocked yes)
			(layer "B.Fab")
			(hide yes)
			(effects
				(font
					(size 1.016 1.016)
					(thickness 0.1524)
				)
				(justify mirror)
			)
		)
		(duplicate_pad_numbers_are_jumpers no)
		(fp_line
			(start -0.508 -0.9398)
			(end 0.508 -0.9398)
			(stroke
				(width 0.1524)
				(type default)
			)
			(layer "B.SilkS")
		)
		(fp_line
			(start 0.508 -0.9398)
			(end 0.508 0.9398)
			(stroke
				(width 0.1524)
				(type default)
			)
			(layer "B.SilkS")
		)
		(fp_rect
			(start 0.508 0.9398)
			(end -0.508 -0.9398)
			(stroke
				(width 0)
				(type default)
			)
			(fill no)
			(layer "B.CrtYd")
		)
		(fp_rect
			(start 0.508 0.9398)
			(end -0.508 -0.9398)
			(stroke
				(width 0)
				(type default)
			)
			(fill no)
			(layer "B.Fab")
		)
		(pad "1" smd custom
			(at 0 -0.4445 180)
			(size 0.1397 0.1397)
			(layers "B.Cu" "B.Mask" "B.Paste")
			(net "BMC_SSD_RST#11")
			(options
				(clearance outline)
				(anchor circle)
			)
			(primitives
				(gr_poly
					(pts
						(arc
							(start -0.1778 0.2794)
							(mid -0.249642 0.249642)
							(end -0.2794 0.1778)
						)
						(arc
							(start -0.2794 -0.1778)
							(mid -0.249642 -0.249642)
							(end -0.1778 -0.2794)
						)
						(arc
							(start 0.1778 -0.2794)
							(mid 0.249642 -0.249642)
							(end 0.2794 -0.1778)
						)
						(arc
							(start 0.2794 0.1778)
							(mid 0.249642 0.249642)
							(end 0.1778 0.2794)
						)
					)
					(width 0)
					(fill yes)
				)
			)
		)
		(pad "2" smd custom
			(at 0 0.4445 180)
			(size 0.1397 0.1397)
			(layers "B.Cu" "B.Mask" "B.Paste")
			(net "BMC_SSD_RST#0_A11")
			(options
				(clearance outline)
				(anchor circle)
			)
			(primitives
				(gr_poly
					(pts
						(arc
							(start -0.1778 0.2794)
							(mid -0.249642 0.249642)
							(end -0.2794 0.1778)
						)
						(arc
							(start -0.2794 -0.1778)
							(mid -0.249642 -0.249642)
							(end -0.1778 -0.2794)
						)
						(arc
							(start 0.1778 -0.2794)
							(mid 0.249642 -0.249642)
							(end 0.2794 -0.1778)
						)
						(arc
							(start 0.2794 0.1778)
							(mid 0.249642 0.249642)
							(end 0.1778 0.2794)
						)
					)
					(width 0)
					(fill yes)
				)
			)
		)
	)
	(footprint ""
		(layer "B.Cu")
		(at 33.456372 -126.665228)
		(property "Reference" "TP270"
			(at 0 0 0)
			(layer "B.SilkS")
			(hide yes)
			(effects
				(font
					(size 1.27 1.27)
				)
				(justify mirror)
			)
		)
		(property "Value" "TPAD28-2-GP"
			(at 0.0127 -1.6637 0)
			(unlocked yes)
			(layer "B.Fab")
			(hide yes)
			(effects
				(font
					(size 1.016 1.016)
					(thickness 0.1524)
				)
				(justify mirror)
			)
		)
		(property "Device Type" "TPAD28"
			(at 0.0127 -3.1877 0)
			(unlocked yes)
			(layer "B.Fab")
			(hide yes)
			(effects
				(font
					(size 1.016 1.016)
					(thickness 0.1524)
				)
				(justify mirror)
			)
		)
		(duplicate_pad_numbers_are_jumpers no)
		(fp_poly
			(pts
				(arc
					(start 0.3556 0)
					(mid -0.3556 0)
					(end 0.3556 0)
				)
			)
			(stroke
				(width 0)
				(type default)
			)
			(fill no)
			(layer "B.CrtYd")
		)
		(fp_poly
			(pts
				(arc
					(start 0.6096 0)
					(mid -0.6096 0)
					(end 0.6096 0)
				)
			)
			(stroke
				(width 0)
				(type default)
			)
			(fill no)
			(layer "B.Fab")
		)
		(pad "1" smd circle
			(at 0 0 180)
			(size 0.7112 0.7112)
			(layers "B.Cu" "B.Mask" "B.Paste")
			(net "TP_GPIOI1")
		)
	)
	(footprint ""
		(layer "B.Cu")
		(at 227.965 -23.241 180)
		(property "Reference" "R827"
			(at 0 0 0)
			(layer "B.SilkS")
			(hide yes)
			(effects
				(font
					(size 1.27 1.27)
				)
				(justify mirror)
			)
		)
		(property "Value" "0R2J-2-GP"
			(at -0.064008 -3.993896 180)
			(unlocked yes)
			(layer "B.Fab")
			(hide yes)
			(effects
				(font
					(size 1.016 1.016)
					(thickness 0.1524)
				)
				(justify mirror)
			)
		)
		(property "Device Type" "R402H16"
			(at -0.064008 -5.517896 180)
			(unlocked yes)
			(layer "B.Fab")
			(hide yes)
			(effects
				(font
					(size 1.016 1.016)
					(thickness 0.1524)
				)
				(justify mirror)
			)
		)
		(duplicate_pad_numbers_are_jumpers no)
		(fp_line
			(start 0.508 -0.9398)
			(end 0.508 0.9398)
			(stroke
				(width 0.1524)
				(type default)
			)
			(layer "B.SilkS")
		)
		(fp_line
			(start -0.508 -0.9398)
			(end 0.508 -0.9398)
			(stroke
				(width 0.1524)
				(type default)
			)
			(layer "B.SilkS")
		)
		(fp_rect
			(start 0.508 0.9398)
			(end -0.508 -0.9398)
			(stroke
				(width 0)
				(type default)
			)
			(fill no)
			(layer "B.CrtYd")
		)
		(fp_rect
			(start 0.508 0.9398)
			(end -0.508 -0.9398)
			(stroke
				(width 0)
				(type default)
			)
			(fill no)
			(layer "B.Fab")
		)
		(pad "1" smd custom
			(at 0 -0.4445)
			(size 0.1397 0.1397)
			(layers "B.Cu" "B.Mask" "B.Paste")
			(net "HOST3_RST_N_LS")
			(options
				(clearance outline)
				(anchor circle)
			)
			(primitives
				(gr_poly
					(pts
						(arc
							(start -0.1778 0.2794)
							(mid -0.249642 0.249642)
							(end -0.2794 0.1778)
						)
						(arc
							(start -0.2794 -0.1778)
							(mid -0.249642 -0.249642)
							(end -0.1778 -0.2794)
						)
						(arc
							(start 0.1778 -0.2794)
							(mid 0.249642 -0.249642)
							(end 0.2794 -0.1778)
						)
						(arc
							(start 0.2794 0.1778)
							(mid 0.249642 0.249642)
							(end 0.1778 0.2794)
						)
					)
					(width 0)
					(fill yes)
				)
			)
		)
		(pad "2" smd custom
			(at 0 0.4445)
			(size 0.1397 0.1397)
			(layers "B.Cu" "B.Mask" "B.Paste")
			(net "LBI_ADDR_2_R")
			(options
				(clearance outline)
				(anchor circle)
			)
			(primitives
				(gr_poly
					(pts
						(arc
							(start -0.1778 0.2794)
							(mid -0.249642 0.249642)
							(end -0.2794 0.1778)
						)
						(arc
							(start -0.2794 -0.1778)
							(mid -0.249642 -0.249642)
							(end -0.1778 -0.2794)
						)
						(arc
							(start 0.1778 -0.2794)
							(mid 0.249642 -0.249642)
							(end 0.2794 -0.1778)
						)
						(arc
							(start 0.2794 0.1778)
							(mid 0.249642 0.249642)
							(end 0.1778 0.2794)
						)
					)
					(width 0)
					(fill yes)
				)
			)
		)
	)
	(footprint ""
		(layer "B.Cu")
		(at 332.772512 -172.432218)
		(property "Reference" "R4163"
			(at 0 0 0)
			(layer "B.SilkS")
			(hide yes)
			(effects
				(font
					(size 1.27 1.27)
				)
				(justify mirror)
			)
		)
		(property "Value" "4K7R2F-GP"
			(at -0.064008 -3.993896 0)
			(unlocked yes)
			(layer "B.Fab")
			(hide yes)
			(effects
				(font
					(size 1.016 1.016)
					(thickness 0.1524)
				)
				(justify mirror)
			)
		)
		(property "Device Type" "R402H16"
			(at -0.064008 -5.517896 0)
			(unlocked yes)
			(layer "B.Fab")
			(hide yes)
			(effects
				(font
					(size 1.016 1.016)
					(thickness 0.1524)
				)
				(justify mirror)
			)
		)
		(duplicate_pad_numbers_are_jumpers no)
		(fp_line
			(start -0.508 -0.9398)
			(end 0.508 -0.9398)
			(stroke
				(width 0.1524)
				(type default)
			)
			(layer "B.SilkS")
		)
		(fp_line
			(start 0.508 -0.9398)
			(end 0.508 0.9398)
			(stroke
				(width 0.1524)
				(type default)
			)
			(layer "B.SilkS")
		)
		(fp_rect
			(start 0.508 0.9398)
			(end -0.508 -0.9398)
			(stroke
				(width 0)
				(type default)
			)
			(fill no)
			(layer "B.CrtYd")
		)
		(fp_rect
			(start 0.508 0.9398)
			(end -0.508 -0.9398)
			(stroke
				(width 0)
				(type default)
			)
			(fill no)
			(layer "B.Fab")
		)
		(pad "1" smd custom
			(at 0 -0.4445 180)
			(size 0.1397 0.1397)
			(layers "B.Cu" "B.Mask" "B.Paste")
			(net "SSD_PRSNT#4")
			(options
				(clearance outline)
				(anchor circle)
			)
			(primitives
				(gr_poly
					(pts
						(arc
							(start -0.1778 0.2794)
							(mid -0.249642 0.249642)
							(end -0.2794 0.1778)
						)
						(arc
							(start -0.2794 -0.1778)
							(mid -0.249642 -0.249642)
							(end -0.1778 -0.2794)
						)
						(arc
							(start 0.1778 -0.2794)
							(mid 0.249642 -0.249642)
							(end 0.2794 -0.1778)
						)
						(arc
							(start 0.2794 0.1778)
							(mid 0.249642 0.249642)
							(end 0.1778 0.2794)
						)
					)
					(width 0)
					(fill yes)
				)
			)
		)
		(pad "2" smd custom
			(at 0 0.4445 180)
			(size 0.1397 0.1397)
			(layers "B.Cu" "B.Mask" "B.Paste")
			(net "P3V3_STBY")
			(options
				(clearance outline)
				(anchor circle)
			)
			(primitives
				(gr_poly
					(pts
						(arc
							(start -0.1778 0.2794)
							(mid -0.249642 0.249642)
							(end -0.2794 0.1778)
						)
						(arc
							(start -0.2794 -0.1778)
							(mid -0.249642 -0.249642)
							(end -0.1778 -0.2794)
						)
						(arc
							(start 0.1778 -0.2794)
							(mid 0.249642 -0.249642)
							(end 0.2794 -0.1778)
						)
						(arc
							(start 0.2794 0.1778)
							(mid 0.249642 0.249642)
							(end 0.1778 0.2794)
						)
					)
					(width 0)
					(fill yes)
				)
			)
		)
	)
	(footprint ""
		(layer "B.Cu")
		(at 18.415 -126.619 -90)
		(property "Reference" "R236"
			(at 0 0 90)
			(layer "B.SilkS")
			(hide yes)
			(effects
				(font
					(size 1.27 1.27)
				)
				(justify mirror)
			)
		)
		(property "Value" "100KR2F-L1-GP"
			(at -0.064008 -3.993896 270)
			(unlocked yes)
			(layer "B.Fab")
			(hide yes)
			(effects
				(font
					(size 1.016 1.016)
					(thickness 0.1524)
				)
				(justify mirror)
			)
		)
		(property "Device Type" "R402H16"
			(at -0.064008 -5.517896 270)
			(unlocked yes)
			(layer "B.Fab")
			(hide yes)
			(effects
				(font
					(size 1.016 1.016)
					(thickness 0.1524)
				)
				(justify mirror)
			)
		)
		(duplicate_pad_numbers_are_jumpers no)
		(fp_line
			(start -0.508 -0.9398)
			(end 0.508 -0.9398)
			(stroke
				(width 0.1524)
				(type default)
			)
			(layer "B.SilkS")
		)
		(fp_line
			(start 0.508 -0.9398)
			(end 0.508 0.9398)
			(stroke
				(width 0.1524)
				(type default)
			)
			(layer "B.SilkS")
		)
		(fp_rect
			(start 0.508 0.9398)
			(end -0.508 -0.9398)
			(stroke
				(width 0)
				(type default)
			)
			(fill no)
			(layer "B.CrtYd")
		)
		(fp_rect
			(start 0.508 0.9398)
			(end -0.508 -0.9398)
			(stroke
				(width 0)
				(type default)
			)
			(fill no)
			(layer "B.Fab")
		)
		(pad "1" smd custom
			(at 0 -0.4445 90)
			(size 0.1397 0.1397)
			(layers "B.Cu" "B.Mask" "B.Paste")
			(net "GND")
			(options
				(clearance outline)
				(anchor circle)
			)
			(primitives
				(gr_poly
					(pts
						(arc
							(start -0.1778 0.2794)
							(mid -0.249642 0.249642)
							(end -0.2794 0.1778)
						)
						(arc
							(start -0.2794 -0.1778)
							(mid -0.249642 -0.249642)
							(end -0.1778 -0.2794)
						)
						(arc
							(start 0.1778 -0.2794)
							(mid 0.249642 -0.249642)
							(end 0.2794 -0.1778)
						)
						(arc
							(start 0.2794 0.1778)
							(mid 0.249642 0.249642)
							(end 0.1778 0.2794)
						)
					)
					(width 0)
					(fill yes)
				)
			)
		)
		(pad "2" smd custom
			(at 0 0.4445 90)
			(size 0.1397 0.1397)
			(layers "B.Cu" "B.Mask" "B.Paste")
			(net "TP_BMC0_LPC_LAD2")
			(options
				(clearance outline)
				(anchor circle)
			)
			(primitives
				(gr_poly
					(pts
						(arc
							(start -0.1778 0.2794)
							(mid -0.249642 0.249642)
							(end -0.2794 0.1778)
						)
						(arc
							(start -0.2794 -0.1778)
							(mid -0.249642 -0.249642)
							(end -0.1778 -0.2794)
						)
						(arc
							(start 0.1778 -0.2794)
							(mid 0.249642 -0.249642)
							(end 0.2794 -0.1778)
						)
						(arc
							(start 0.2794 0.1778)
							(mid 0.249642 0.249642)
							(end 0.1778 0.2794)
						)
					)
					(width 0)
					(fill yes)
				)
			)
		)
	)
	(footprint ""
		(layer "B.Cu")
		(at 273.2532 -0.889 90)
		(property "Reference" "R2913"
			(at 0 0 90)
			(layer "B.SilkS")
			(hide yes)
			(effects
				(font
					(size 1.27 1.27)
				)
				(justify mirror)
			)
		)
		(property "Value" "0R2J-2-GP"
			(at -0.064008 -3.993896 90)
			(unlocked yes)
			(layer "B.Fab")
			(hide yes)
			(effects
				(font
					(size 1.016 1.016)
					(thickness 0.1524)
				)
				(justify mirror)
			)
		)
		(property "Device Type" "R402H16"
			(at -0.064008 -5.517896 90)
			(unlocked yes)
			(layer "B.Fab")
			(hide yes)
			(effects
				(font
					(size 1.016 1.016)
					(thickness 0.1524)
				)
				(justify mirror)
			)
		)
		(duplicate_pad_numbers_are_jumpers no)
		(fp_line
			(start 0.508 -0.9398)
			(end 0.508 0.9398)
			(stroke
				(width 0.1524)
				(type default)
			)
			(layer "B.SilkS")
		)
		(fp_line
			(start -0.508 -0.9398)
			(end 0.508 -0.9398)
			(stroke
				(width 0.1524)
				(type default)
			)
			(layer "B.SilkS")
		)
		(fp_rect
			(start 0.508 0.9398)
			(end -0.508 -0.9398)
			(stroke
				(width 0)
				(type default)
			)
			(fill no)
			(layer "B.CrtYd")
		)
		(fp_rect
			(start 0.508 0.9398)
			(end -0.508 -0.9398)
			(stroke
				(width 0)
				(type default)
			)
			(fill no)
			(layer "B.Fab")
		)
		(pad "1" smd custom
			(at 0 -0.4445 270)
			(size 0.1397 0.1397)
			(layers "B.Cu" "B.Mask" "B.Paste")
			(net "CBL_PRSNT_N_8")
			(options
				(clearance outline)
				(anchor circle)
			)
			(primitives
				(gr_poly
					(pts
						(arc
							(start -0.1778 0.2794)
							(mid -0.249642 0.249642)
							(end -0.2794 0.1778)
						)
						(arc
							(start -0.2794 -0.1778)
							(mid -0.249642 -0.249642)
							(end -0.1778 -0.2794)
						)
						(arc
							(start 0.1778 -0.2794)
							(mid 0.249642 -0.249642)
							(end 0.2794 -0.1778)
						)
						(arc
							(start 0.2794 0.1778)
							(mid 0.249642 0.249642)
							(end 0.1778 0.2794)
						)
					)
					(width 0)
					(fill yes)
				)
			)
		)
		(pad "2" smd custom
			(at 0 0.4445 270)
			(size 0.1397 0.1397)
			(layers "B.Cu" "B.Mask" "B.Paste")
			(net "8644_SDA_R_8")
			(options
				(clearance outline)
				(anchor circle)
			)
			(primitives
				(gr_poly
					(pts
						(arc
							(start -0.1778 0.2794)
							(mid -0.249642 0.249642)
							(end -0.2794 0.1778)
						)
						(arc
							(start -0.2794 -0.1778)
							(mid -0.249642 -0.249642)
							(end -0.1778 -0.2794)
						)
						(arc
							(start 0.1778 -0.2794)
							(mid 0.249642 -0.249642)
							(end 0.2794 -0.1778)
						)
						(arc
							(start 0.2794 0.1778)
							(mid 0.249642 0.249642)
							(end 0.1778 0.2794)
						)
					)
					(width 0)
					(fill yes)
				)
			)
		)
	)
	(footprint ""
		(layer "B.Cu")
		(at 252.603 -58.005472 -90)
		(property "Reference" "C587"
			(at 0 0 90)
			(layer "B.SilkS")
			(hide yes)
			(effects
				(font
					(size 1.27 1.27)
				)
				(justify mirror)
			)
		)
		(property "Value" "SCD1U16V1KX-1-GP"
			(at 2.8321 -1.7399 270)
			(unlocked yes)
			(layer "B.Fab")
			(hide yes)
			(effects
				(font
					(size 1.016 1.016)
					(thickness 0.1524)
				)
				(justify mirror)
			)
		)
		(property "Device Type" "C0201H13"
			(at 2.8321 -3.2639 270)
			(unlocked yes)
			(layer "B.Fab")
			(hide yes)
			(effects
				(font
					(size 1.016 1.016)
					(thickness 0.1524)
				)
				(justify mirror)
			)
		)
		(duplicate_pad_numbers_are_jumpers no)
		(fp_rect
			(start 0.2794 0.6477)
			(end -0.2794 -0.6477)
			(stroke
				(width 0)
				(type default)
			)
			(fill no)
			(layer "B.CrtYd")
		)
		(fp_rect
			(start 0.2794 0.6477)
			(end -0.2794 -0.6477)
			(stroke
				(width 0)
				(type default)
			)
			(fill no)
			(layer "B.Fab")
		)
		(pad "1" smd custom
			(at 0 -0.2794 90)
			(size 0.0762 0.0762)
			(layers "B.Cu" "B.Mask" "B.Paste")
			(net "DUT_AVD_PCIE")
			(options
				(clearance outline)
				(anchor circle)
			)
			(primitives
				(gr_poly
					(pts
						(arc
							(start 0.1524 0.127)
							(mid 0.137521 0.162921)
							(end 0.1016 0.1778)
						)
						(arc
							(start -0.1016 0.1778)
							(mid -0.137521 0.162921)
							(end -0.1524 0.127)
						)
						(arc
							(start -0.1524 -0.127)
							(mid -0.137521 -0.162921)
							(end -0.1016 -0.1778)
						)
						(arc
							(start 0.1016 -0.1778)
							(mid 0.137521 -0.162921)
							(end 0.1524 -0.127)
						)
					)
					(width 0)
					(fill yes)
				)
			)
		)
		(pad "2" smd custom
			(at 0 0.2794 90)
			(size 0.0762 0.0762)
			(layers "B.Cu" "B.Mask" "B.Paste")
			(net "GND")
			(options
				(clearance outline)
				(anchor circle)
			)
			(primitives
				(gr_poly
					(pts
						(arc
							(start 0.1524 0.127)
							(mid 0.137521 0.162921)
							(end 0.1016 0.1778)
						)
						(arc
							(start -0.1016 0.1778)
							(mid -0.137521 0.162921)
							(end -0.1524 0.127)
						)
						(arc
							(start -0.1524 -0.127)
							(mid -0.137521 -0.162921)
							(end -0.1016 -0.1778)
						)
						(arc
							(start 0.1016 -0.1778)
							(mid 0.137521 -0.162921)
							(end 0.1524 -0.127)
						)
					)
					(width 0)
					(fill yes)
				)
			)
		)
	)
	(footprint ""
		(layer "B.Cu")
		(at 215.265 -194.0306)
		(property "Reference" "C3202"
			(at 0 0 0)
			(layer "B.SilkS")
			(hide yes)
			(effects
				(font
					(size 1.27 1.27)
				)
				(justify mirror)
			)
		)
		(property "Value" "SCD1U25V2KX-2-GP"
			(at -1.1811 -2.7051 0)
			(unlocked yes)
			(layer "B.Fab")
			(hide yes)
			(effects
				(font
					(size 1.016 1.016)
					(thickness 0.1524)
				)
				(justify mirror)
			)
		)
		(property "Device Type" "C402H22"
			(at -1.1811 -4.2291 0)
			(unlocked yes)
			(layer "B.Fab")
			(hide yes)
			(effects
				(font
					(size 1.016 1.016)
					(thickness 0.1524)
				)
				(justify mirror)
			)
		)
		(duplicate_pad_numbers_are_jumpers no)
		(fp_rect
			(start 0.4318 0.9525)
			(end -0.4318 -0.9525)
			(stroke
				(width 0)
				(type default)
			)
			(fill no)
			(layer "B.CrtYd")
		)
		(fp_rect
			(start 0.4318 0.9525)
			(end -0.4318 -0.9525)
			(stroke
				(width 0)
				(type default)
			)
			(fill no)
			(layer "B.Fab")
		)
		(pad "1" smd custom
			(at 0 -0.4445 180)
			(size 0.1524 0.1524)
			(layers "B.Cu" "B.Mask" "B.Paste")
			(net "P3V3_STBY")
			(options
				(clearance outline)
				(anchor circle)
			)
			(primitives
				(gr_poly
					(pts
						(arc
							(start 0.3048 0.2032)
							(mid 0.275042 0.275042)
							(end 0.2032 0.3048)
						)
						(arc
							(start -0.2032 0.3048)
							(mid -0.275042 0.275042)
							(end -0.3048 0.2032)
						)
						(arc
							(start -0.3048 -0.2032)
							(mid -0.275042 -0.275042)
							(end -0.2032 -0.3048)
						)
						(arc
							(start 0.2032 -0.3048)
							(mid 0.275042 -0.275042)
							(end 0.3048 -0.2032)
						)
					)
					(width 0)
					(fill yes)
				)
			)
		)
		(pad "2" smd custom
			(at 0 0.4445 180)
			(size 0.1524 0.1524)
			(layers "B.Cu" "B.Mask" "B.Paste")
			(net "GND")
			(options
				(clearance outline)
				(anchor circle)
			)
			(primitives
				(gr_poly
					(pts
						(arc
							(start 0.3048 0.2032)
							(mid 0.275042 0.275042)
							(end 0.2032 0.3048)
						)
						(arc
							(start -0.2032 0.3048)
							(mid -0.275042 0.275042)
							(end -0.3048 0.2032)
						)
						(arc
							(start -0.3048 -0.2032)
							(mid -0.275042 -0.275042)
							(end -0.2032 -0.3048)
						)
						(arc
							(start 0.2032 -0.3048)
							(mid 0.275042 -0.275042)
							(end 0.3048 -0.2032)
						)
					)
					(width 0)
					(fill yes)
				)
			)
		)
	)
	(footprint ""
		(layer "B.Cu")
		(at 53.756052 -110.19663 -90)
		(property "Reference" "U32"
			(at 0 0 90)
			(layer "B.SilkS")
			(hide yes)
			(effects
				(font
					(size 1.27 1.27)
				)
				(justify mirror)
			)
		)
		(property "Value" "2N7002DW-7F-GP"
			(at 2.3622 -8.2042 270)
			(unlocked yes)
			(layer "B.Fab")
			(hide yes)
			(effects
				(font
					(size 1.016 1.016)
					(thickness 0.1524)
				)
				(justify mirror)
			)
		)
		(property "Device Type" "SOT-363H44"
			(at 2.3622 -10.1092 270)
			(unlocked yes)
			(layer "B.Fab")
			(hide yes)
			(effects
				(font
					(size 1.016 1.016)
					(thickness 0.1524)
				)
				(justify mirror)
			)
		)
		(duplicate_pad_numbers_are_jumpers no)
		(fp_line
			(start -1.4478 1.7018)
			(end -1.4478 -1.7018)
			(stroke
				(width 0.1524)
				(type default)
			)
			(layer "B.SilkS")
		)
		(fp_line
			(start 1.4478 1.7018)
			(end -1.4478 1.7018)
			(stroke
				(width 0.1524)
				(type default)
			)
			(layer "B.SilkS")
		)
		(fp_line
			(start 1.27 1.524)
			(end 1.27 0.6604)
			(stroke
				(width 0.4826)
				(type default)
			)
			(layer "B.SilkS")
		)
		(fp_line
			(start -1.4478 -1.7018)
			(end 1.4478 -1.7018)
			(stroke
				(width 0.1524)
				(type default)
			)
			(layer "B.SilkS")
		)
		(fp_line
			(start 1.4478 -1.7018)
			(end 1.4478 1.7018)
			(stroke
				(width 0.1524)
				(type default)
			)
			(layer "B.SilkS")
		)
		(fp_poly
			(pts
				(xy 1.524 -1.778) (xy -1.524 -1.778) (xy -1.524 1.778) (xy 1.524 1.778)
			)
			(stroke
				(width 0)
				(type default)
			)
			(fill no)
			(layer "B.CrtYd")
		)
		(fp_poly
			(pts
				(xy 1.524 -1.778) (xy -1.524 -1.778) (xy -1.524 1.778) (xy 1.524 1.778)
			)
			(stroke
				(width 0)
				(type default)
			)
			(fill no)
			(layer "B.Fab")
		)
		(pad "1" smd rect
			(at 0.65024 0.9398 90)
			(size 0.4064 1.016)
			(layers "B.Cu" "B.Mask" "B.Paste")
			(net "BMC_I2C12_MINI6_SCL_S")
		)
		(pad "2" smd rect
			(at 0 0.9398 90)
			(size 0.4064 1.016)
			(layers "B.Cu" "B.Mask" "B.Paste")
			(net "I2C6_LS_G2")
		)
		(pad "3" smd rect
			(at -0.65024 0.9398 90)
			(size 0.4064 1.016)
			(layers "B.Cu" "B.Mask" "B.Paste")
			(net "BMC_I2C12_MINI6_SDA")
		)
		(pad "4" smd rect
			(at -0.65024 -0.9398 90)
			(size 0.4064 1.016)
			(layers "B.Cu" "B.Mask" "B.Paste")
			(net "BMC_I2C12_MINI6_SDA_S")
		)
		(pad "5" smd rect
			(at 0 -0.9398 90)
			(size 0.4064 1.016)
			(layers "B.Cu" "B.Mask" "B.Paste")
			(net "I2C6_LS_G1")
		)
		(pad "6" smd rect
			(at 0.65024 -0.9398 90)
			(size 0.4064 1.016)
			(layers "B.Cu" "B.Mask" "B.Paste")
			(net "BMC_I2C12_MINI6_SCL")
		)
	)
	(footprint ""
		(layer "B.Cu")
		(at 66.548 -150.622 -90)
		(property "Reference" "R212"
			(at 0 0 90)
			(layer "B.SilkS")
			(hide yes)
			(effects
				(font
					(size 1.27 1.27)
				)
				(justify mirror)
			)
		)
		(property "Value" "0R2J-2-GP"
			(at -0.064008 -3.993896 270)
			(unlocked yes)
			(layer "B.Fab")
			(hide yes)
			(effects
				(font
					(size 1.016 1.016)
					(thickness 0.1524)
				)
				(justify mirror)
			)
		)
		(property "Device Type" "R402H16"
			(at -0.064008 -5.517896 270)
			(unlocked yes)
			(layer "B.Fab")
			(hide yes)
			(effects
				(font
					(size 1.016 1.016)
					(thickness 0.1524)
				)
				(justify mirror)
			)
		)
		(duplicate_pad_numbers_are_jumpers no)
		(fp_line
			(start -0.508 -0.9398)
			(end 0.508 -0.9398)
			(stroke
				(width 0.1524)
				(type default)
			)
			(layer "B.SilkS")
		)
		(fp_line
			(start 0.508 -0.9398)
			(end 0.508 0.9398)
			(stroke
				(width 0.1524)
				(type default)
			)
			(layer "B.SilkS")
		)
		(fp_rect
			(start 0.508 0.9398)
			(end -0.508 -0.9398)
			(stroke
				(width 0)
				(type default)
			)
			(fill no)
			(layer "B.CrtYd")
		)
		(fp_rect
			(start 0.508 0.9398)
			(end -0.508 -0.9398)
			(stroke
				(width 0)
				(type default)
			)
			(fill no)
			(layer "B.Fab")
		)
		(pad "1" smd custom
			(at 0 -0.4445 90)
			(size 0.1397 0.1397)
			(layers "B.Cu" "B.Mask" "B.Paste")
			(net "EEPROM_SDA")
			(options
				(clearance outline)
				(anchor circle)
			)
			(primitives
				(gr_poly
					(pts
						(arc
							(start -0.1778 0.2794)
							(mid -0.249642 0.249642)
							(end -0.2794 0.1778)
						)
						(arc
							(start -0.2794 -0.1778)
							(mid -0.249642 -0.249642)
							(end -0.1778 -0.2794)
						)
						(arc
							(start 0.1778 -0.2794)
							(mid 0.249642 -0.249642)
							(end 0.2794 -0.1778)
						)
						(arc
							(start 0.2794 0.1778)
							(mid 0.249642 0.249642)
							(end 0.1778 0.2794)
						)
					)
					(width 0)
					(fill yes)
				)
			)
		)
		(pad "2" smd custom
			(at 0 0.4445 90)
			(size 0.1397 0.1397)
			(layers "B.Cu" "B.Mask" "B.Paste")
			(net "BMC_I2C5_D_PEB_SDA")
			(options
				(clearance outline)
				(anchor circle)
			)
			(primitives
				(gr_poly
					(pts
						(arc
							(start -0.1778 0.2794)
							(mid -0.249642 0.249642)
							(end -0.2794 0.1778)
						)
						(arc
							(start -0.2794 -0.1778)
							(mid -0.249642 -0.249642)
							(end -0.1778 -0.2794)
						)
						(arc
							(start 0.1778 -0.2794)
							(mid 0.249642 -0.249642)
							(end 0.2794 -0.1778)
						)
						(arc
							(start 0.2794 0.1778)
							(mid 0.249642 0.249642)
							(end 0.1778 0.2794)
						)
					)
					(width 0)
					(fill yes)
				)
			)
		)
	)
	(footprint ""
		(layer "B.Cu")
		(at 231.5972 -45.9994 -90)
		(property "Reference" "C499"
			(at 0 0 90)
			(layer "B.SilkS")
			(hide yes)
			(effects
				(font
					(size 1.27 1.27)
				)
				(justify mirror)
			)
		)
		(property "Value" "SCD1U16V1KX-1-GP"
			(at 2.8321 -1.7399 270)
			(unlocked yes)
			(layer "B.Fab")
			(hide yes)
			(effects
				(font
					(size 1.016 1.016)
					(thickness 0.1524)
				)
				(justify mirror)
			)
		)
		(property "Device Type" "C0201H13"
			(at 2.8321 -3.2639 270)
			(unlocked yes)
			(layer "B.Fab")
			(hide yes)
			(effects
				(font
					(size 1.016 1.016)
					(thickness 0.1524)
				)
				(justify mirror)
			)
		)
		(duplicate_pad_numbers_are_jumpers no)
		(fp_rect
			(start 0.2794 0.6477)
			(end -0.2794 -0.6477)
			(stroke
				(width 0)
				(type default)
			)
			(fill no)
			(layer "B.CrtYd")
		)
		(fp_rect
			(start 0.2794 0.6477)
			(end -0.2794 -0.6477)
			(stroke
				(width 0)
				(type default)
			)
			(fill no)
			(layer "B.Fab")
		)
		(pad "1" smd custom
			(at 0 -0.2794 90)
			(size 0.0762 0.0762)
			(layers "B.Cu" "B.Mask" "B.Paste")
			(net "DUT_AVD_PCIE_Q")
			(options
				(clearance outline)
				(anchor circle)
			)
			(primitives
				(gr_poly
					(pts
						(arc
							(start 0.1524 0.127)
							(mid 0.137521 0.162921)
							(end 0.1016 0.1778)
						)
						(arc
							(start -0.1016 0.1778)
							(mid -0.137521 0.162921)
							(end -0.1524 0.127)
						)
						(arc
							(start -0.1524 -0.127)
							(mid -0.137521 -0.162921)
							(end -0.1016 -0.1778)
						)
						(arc
							(start 0.1016 -0.1778)
							(mid 0.137521 -0.162921)
							(end 0.1524 -0.127)
						)
					)
					(width 0)
					(fill yes)
				)
			)
		)
		(pad "2" smd custom
			(at 0 0.2794 90)
			(size 0.0762 0.0762)
			(layers "B.Cu" "B.Mask" "B.Paste")
			(net "GND")
			(options
				(clearance outline)
				(anchor circle)
			)
			(primitives
				(gr_poly
					(pts
						(arc
							(start 0.1524 0.127)
							(mid 0.137521 0.162921)
							(end 0.1016 0.1778)
						)
						(arc
							(start -0.1016 0.1778)
							(mid -0.137521 0.162921)
							(end -0.1524 0.127)
						)
						(arc
							(start -0.1524 -0.127)
							(mid -0.137521 -0.162921)
							(end -0.1016 -0.1778)
						)
						(arc
							(start 0.1016 -0.1778)
							(mid 0.137521 -0.162921)
							(end 0.1524 -0.127)
						)
					)
					(width 0)
					(fill yes)
				)
			)
		)
	)
	(footprint ""
		(layer "B.Cu")
		(at 227.6856 -32.995362 -90)
		(property "Reference" "C565"
			(at 0 0 90)
			(layer "B.SilkS")
			(hide yes)
			(effects
				(font
					(size 1.27 1.27)
				)
				(justify mirror)
			)
		)
		(property "Value" "SCD1U16V1KX-1-GP"
			(at 2.8321 -1.7399 270)
			(unlocked yes)
			(layer "B.Fab")
			(hide yes)
			(effects
				(font
					(size 1.016 1.016)
					(thickness 0.1524)
				)
				(justify mirror)
			)
		)
		(property "Device Type" "C0201H13"
			(at 2.8321 -3.2639 270)
			(unlocked yes)
			(layer "B.Fab")
			(hide yes)
			(effects
				(font
					(size 1.016 1.016)
					(thickness 0.1524)
				)
				(justify mirror)
			)
		)
		(duplicate_pad_numbers_are_jumpers no)
		(fp_rect
			(start 0.2794 0.6477)
			(end -0.2794 -0.6477)
			(stroke
				(width 0)
				(type default)
			)
			(fill no)
			(layer "B.CrtYd")
		)
		(fp_rect
			(start 0.2794 0.6477)
			(end -0.2794 -0.6477)
			(stroke
				(width 0)
				(type default)
			)
			(fill no)
			(layer "B.Fab")
		)
		(pad "1" smd custom
			(at 0 -0.2794 90)
			(size 0.0762 0.0762)
			(layers "B.Cu" "B.Mask" "B.Paste")
			(net "DUT_AVD_PCIE")
			(options
				(clearance outline)
				(anchor circle)
			)
			(primitives
				(gr_poly
					(pts
						(arc
							(start 0.1524 0.127)
							(mid 0.137521 0.162921)
							(end 0.1016 0.1778)
						)
						(arc
							(start -0.1016 0.1778)
							(mid -0.137521 0.162921)
							(end -0.1524 0.127)
						)
						(arc
							(start -0.1524 -0.127)
							(mid -0.137521 -0.162921)
							(end -0.1016 -0.1778)
						)
						(arc
							(start 0.1016 -0.1778)
							(mid 0.137521 -0.162921)
							(end 0.1524 -0.127)
						)
					)
					(width 0)
					(fill yes)
				)
			)
		)
		(pad "2" smd custom
			(at 0 0.2794 90)
			(size 0.0762 0.0762)
			(layers "B.Cu" "B.Mask" "B.Paste")
			(net "GND")
			(options
				(clearance outline)
				(anchor circle)
			)
			(primitives
				(gr_poly
					(pts
						(arc
							(start 0.1524 0.127)
							(mid 0.137521 0.162921)
							(end 0.1016 0.1778)
						)
						(arc
							(start -0.1016 0.1778)
							(mid -0.137521 0.162921)
							(end -0.1524 0.127)
						)
						(arc
							(start -0.1524 -0.127)
							(mid -0.137521 -0.162921)
							(end -0.1016 -0.1778)
						)
						(arc
							(start 0.1016 -0.1778)
							(mid 0.137521 -0.162921)
							(end 0.1524 -0.127)
						)
					)
					(width 0)
					(fill yes)
				)
			)
		)
	)
	(footprint ""
		(layer "B.Cu")
		(at 60.325 -34.036 180)
		(property "Reference" "PR30"
			(at 0 0 0)
			(layer "B.SilkS")
			(hide yes)
			(effects
				(font
					(size 1.27 1.27)
				)
				(justify mirror)
			)
		)
		(property "Value" "100KR2F-L1-GP"
			(at -0.064008 -3.993896 180)
			(unlocked yes)
			(layer "B.Fab")
			(hide yes)
			(effects
				(font
					(size 1.016 1.016)
					(thickness 0.1524)
				)
				(justify mirror)
			)
		)
		(property "Device Type" "R402H16"
			(at -0.064008 -5.517896 180)
			(unlocked yes)
			(layer "B.Fab")
			(hide yes)
			(effects
				(font
					(size 1.016 1.016)
					(thickness 0.1524)
				)
				(justify mirror)
			)
		)
		(duplicate_pad_numbers_are_jumpers no)
		(fp_line
			(start 0.508 -0.9398)
			(end 0.508 0.9398)
			(stroke
				(width 0.1524)
				(type default)
			)
			(layer "B.SilkS")
		)
		(fp_line
			(start -0.508 -0.9398)
			(end 0.508 -0.9398)
			(stroke
				(width 0.1524)
				(type default)
			)
			(layer "B.SilkS")
		)
		(fp_rect
			(start 0.508 0.9398)
			(end -0.508 -0.9398)
			(stroke
				(width 0)
				(type default)
			)
			(fill no)
			(layer "B.CrtYd")
		)
		(fp_rect
			(start 0.508 0.9398)
			(end -0.508 -0.9398)
			(stroke
				(width 0)
				(type default)
			)
			(fill no)
			(layer "B.Fab")
		)
		(pad "1" smd custom
			(at 0 -0.4445)
			(size 0.1397 0.1397)
			(layers "B.Cu" "B.Mask" "B.Paste")
			(net "AGND_P3V3_STBY")
			(options
				(clearance outline)
				(anchor circle)
			)
			(primitives
				(gr_poly
					(pts
						(arc
							(start -0.1778 0.2794)
							(mid -0.249642 0.249642)
							(end -0.2794 0.1778)
						)
						(arc
							(start -0.2794 -0.1778)
							(mid -0.249642 -0.249642)
							(end -0.1778 -0.2794)
						)
						(arc
							(start 0.1778 -0.2794)
							(mid 0.249642 -0.249642)
							(end 0.2794 -0.1778)
						)
						(arc
							(start 0.2794 0.1778)
							(mid 0.249642 0.249642)
							(end 0.1778 0.2794)
						)
					)
					(width 0)
					(fill yes)
				)
			)
		)
		(pad "2" smd custom
			(at 0 0.4445)
			(size 0.1397 0.1397)
			(layers "B.Cu" "B.Mask" "B.Paste")
			(net "P3V3_STBY_MODE")
			(options
				(clearance outline)
				(anchor circle)
			)
			(primitives
				(gr_poly
					(pts
						(arc
							(start -0.1778 0.2794)
							(mid -0.249642 0.249642)
							(end -0.2794 0.1778)
						)
						(arc
							(start -0.2794 -0.1778)
							(mid -0.249642 -0.249642)
							(end -0.1778 -0.2794)
						)
						(arc
							(start 0.1778 -0.2794)
							(mid 0.249642 -0.249642)
							(end 0.2794 -0.1778)
						)
						(arc
							(start 0.2794 0.1778)
							(mid 0.249642 0.249642)
							(end 0.1778 0.2794)
						)
					)
					(width 0)
					(fill yes)
				)
			)
		)
	)
	(footprint ""
		(layer "B.Cu")
		(at 310.007 -67.691 180)
		(property "Reference" "PG64"
			(at 0 0 0)
			(layer "B.SilkS")
			(hide yes)
			(effects
				(font
					(size 1.27 1.27)
				)
				(justify mirror)
			)
		)
		(property "Value" "GAP-CLOSE-PWR-3-GP"
			(at -0.0254 -6.5786 180)
			(unlocked yes)
			(layer "B.Fab")
			(hide yes)
			(effects
				(font
					(size 1.016 1.016)
					(thickness 0.1524)
				)
				(justify mirror)
			)
		)
		(property "Device Type" "GAP-CLOSE-PWR-3"
			(at -0.0254 -8.255 180)
			(unlocked yes)
			(layer "B.Fab")
			(hide yes)
			(effects
				(font
					(size 1.016 1.016)
					(thickness 0.1524)
				)
				(justify mirror)
			)
		)
		(duplicate_pad_numbers_are_jumpers no)
		(fp_rect
			(start 0.7112 0.4572)
			(end -0.7112 -0.4572)
			(stroke
				(width 0)
				(type default)
			)
			(fill no)
			(layer "B.CrtYd")
		)
		(fp_poly
			(pts
				(xy 0.7112 -0.4572) (xy -0.7112 -0.4572) (xy -0.7112 0.4572) (xy 0.7112 0.4572)
			)
			(stroke
				(width 0)
				(type default)
			)
			(fill no)
			(layer "B.Fab")
		)
		(pad "1" smd rect
			(at 0.3048 0)
			(size 0.6604 0.762)
			(layers "B.Cu" "B.Mask" "B.Paste")
			(net "DUT_VDD")
		)
		(pad "2" smd rect
			(at -0.3048 0)
			(size 0.6604 0.762)
			(layers "B.Cu" "B.Mask" "B.Paste")
			(net "P0V9_E")
		)
	)
	(footprint ""
		(layer "B.Cu")
		(at 334.2386 -67.691 -90)
		(property "Reference" "PC185"
			(at 0 0 90)
			(layer "B.SilkS")
			(hide yes)
			(effects
				(font
					(size 1.27 1.27)
				)
				(justify mirror)
			)
		)
		(property "Value" "SCD1U50V3KX-GP"
			(at 0 -2.8194 270)
			(unlocked yes)
			(layer "B.Fab")
			(hide yes)
			(effects
				(font
					(size 1.016 1.016)
					(thickness 0.1524)
				)
				(justify mirror)
			)
		)
		(property "Device Type" "C603H36"
			(at 0 -4.3434 270)
			(unlocked yes)
			(layer "B.Fab")
			(hide yes)
			(effects
				(font
					(size 1.016 1.016)
					(thickness 0.1524)
				)
				(justify mirror)
			)
		)
		(duplicate_pad_numbers_are_jumpers no)
		(fp_line
			(start -0.508 0)
			(end 0.508 0)
			(stroke
				(width 0.2032)
				(type default)
			)
			(layer "B.SilkS")
		)
		(fp_rect
			(start 0.5842 1.3335)
			(end -0.5842 -1.3335)
			(stroke
				(width 0)
				(type default)
			)
			(fill no)
			(layer "B.CrtYd")
		)
		(fp_rect
			(start 0.5842 1.3335)
			(end -0.5842 -1.3335)
			(stroke
				(width 0)
				(type default)
			)
			(fill no)
			(layer "B.Fab")
		)
		(pad "1" smd custom
			(at 0 -0.762 90)
			(size 0.2159 0.2159)
			(layers "B.Cu" "B.Mask" "B.Paste")
			(net "P0V9_E_VBST")
			(options
				(clearance outline)
				(anchor circle)
			)
			(primitives
				(gr_poly
					(pts
						(arc
							(start -0.3302 0.4318)
							(mid -0.402042 0.402042)
							(end -0.4318 0.3302)
						)
						(arc
							(start -0.4318 -0.3302)
							(mid -0.402042 -0.402042)
							(end -0.3302 -0.4318)
						)
						(arc
							(start 0.3302 -0.4318)
							(mid 0.402042 -0.402042)
							(end 0.4318 -0.3302)
						)
						(arc
							(start 0.4318 0.3302)
							(mid 0.402042 0.402042)
							(end 0.3302 0.4318)
						)
					)
					(width 0)
					(fill yes)
				)
			)
		)
		(pad "2" smd custom
			(at 0 0.762 90)
			(size 0.2159 0.2159)
			(layers "B.Cu" "B.Mask" "B.Paste")
			(net "P0V9_E_VBST_RC")
			(options
				(clearance outline)
				(anchor circle)
			)
			(primitives
				(gr_poly
					(pts
						(arc
							(start -0.3302 0.4318)
							(mid -0.402042 0.402042)
							(end -0.4318 0.3302)
						)
						(arc
							(start -0.4318 -0.3302)
							(mid -0.402042 -0.402042)
							(end -0.3302 -0.4318)
						)
						(arc
							(start 0.3302 -0.4318)
							(mid 0.402042 -0.402042)
							(end 0.4318 -0.3302)
						)
						(arc
							(start 0.4318 0.3302)
							(mid 0.402042 0.402042)
							(end 0.3302 0.4318)
						)
					)
					(width 0)
					(fill yes)
				)
			)
		)
	)
	(footprint ""
		(layer "B.Cu")
		(at 129.179066 -208.8769 180)
		(property "Reference" "R4127"
			(at 0 0 0)
			(layer "B.SilkS")
			(hide yes)
			(effects
				(font
					(size 1.27 1.27)
				)
				(justify mirror)
			)
		)
		(property "Value" "4K7R2F-GP"
			(at -0.064008 -3.993896 180)
			(unlocked yes)
			(layer "B.Fab")
			(hide yes)
			(effects
				(font
					(size 1.016 1.016)
					(thickness 0.1524)
				)
				(justify mirror)
			)
		)
		(property "Device Type" "R402H16"
			(at -0.064008 -5.517896 180)
			(unlocked yes)
			(layer "B.Fab")
			(hide yes)
			(effects
				(font
					(size 1.016 1.016)
					(thickness 0.1524)
				)
				(justify mirror)
			)
		)
		(duplicate_pad_numbers_are_jumpers no)
		(fp_line
			(start 0.508 -0.9398)
			(end 0.508 0.9398)
			(stroke
				(width 0.1524)
				(type default)
			)
			(layer "B.SilkS")
		)
		(fp_line
			(start -0.508 -0.9398)
			(end 0.508 -0.9398)
			(stroke
				(width 0.1524)
				(type default)
			)
			(layer "B.SilkS")
		)
		(fp_rect
			(start 0.508 0.9398)
			(end -0.508 -0.9398)
			(stroke
				(width 0)
				(type default)
			)
			(fill no)
			(layer "B.CrtYd")
		)
		(fp_rect
			(start 0.508 0.9398)
			(end -0.508 -0.9398)
			(stroke
				(width 0)
				(type default)
			)
			(fill no)
			(layer "B.Fab")
		)
		(pad "1" smd custom
			(at 0 -0.4445)
			(size 0.1397 0.1397)
			(layers "B.Cu" "B.Mask" "B.Paste")
			(net "SSD_ATNLED#7")
			(options
				(clearance outline)
				(anchor circle)
			)
			(primitives
				(gr_poly
					(pts
						(arc
							(start -0.1778 0.2794)
							(mid -0.249642 0.249642)
							(end -0.2794 0.1778)
						)
						(arc
							(start -0.2794 -0.1778)
							(mid -0.249642 -0.249642)
							(end -0.1778 -0.2794)
						)
						(arc
							(start 0.1778 -0.2794)
							(mid 0.249642 -0.249642)
							(end 0.2794 -0.1778)
						)
						(arc
							(start 0.2794 0.1778)
							(mid 0.249642 0.249642)
							(end 0.1778 0.2794)
						)
					)
					(width 0)
					(fill yes)
				)
			)
		)
		(pad "2" smd custom
			(at 0 0.4445)
			(size 0.1397 0.1397)
			(layers "B.Cu" "B.Mask" "B.Paste")
			(net "P3V3_STBY")
			(options
				(clearance outline)
				(anchor circle)
			)
			(primitives
				(gr_poly
					(pts
						(arc
							(start -0.1778 0.2794)
							(mid -0.249642 0.249642)
							(end -0.2794 0.1778)
						)
						(arc
							(start -0.2794 -0.1778)
							(mid -0.249642 -0.249642)
							(end -0.1778 -0.2794)
						)
						(arc
							(start 0.1778 -0.2794)
							(mid 0.249642 -0.249642)
							(end 0.2794 -0.1778)
						)
						(arc
							(start 0.2794 0.1778)
							(mid 0.249642 0.249642)
							(end 0.1778 0.2794)
						)
					)
					(width 0)
					(fill yes)
				)
			)
		)
	)
	(footprint ""
		(layer "B.Cu")
		(at 315.468 -55.372)
		(property "Reference" "PC183"
			(at 0 0 0)
			(layer "B.SilkS")
			(hide yes)
			(effects
				(font
					(size 1.27 1.27)
				)
				(justify mirror)
			)
		)
		(property "Value" "SC22U6D3V5MX-5-GP"
			(at 0.0762 -6.1214 0)
			(unlocked yes)
			(layer "B.Fab")
			(hide yes)
			(effects
				(font
					(size 1.016 1.016)
					(thickness 0.1524)
				)
				(justify mirror)
			)
		)
		(property "Device Type" "C805H56"
			(at 0.0762 -8.1534 0)
			(unlocked yes)
			(layer "B.Fab")
			(hide yes)
			(effects
				(font
					(size 1.016 1.016)
					(thickness 0.1524)
				)
				(justify mirror)
			)
		)
		(duplicate_pad_numbers_are_jumpers no)
		(fp_line
			(start -0.635 0)
			(end 0.635 0)
			(stroke
				(width 0.508)
				(type default)
			)
			(layer "B.SilkS")
		)
		(fp_rect
			(start 0.9652 1.778)
			(end -0.9652 -1.778)
			(stroke
				(width 0)
				(type default)
			)
			(fill no)
			(layer "B.CrtYd")
		)
		(fp_poly
			(pts
				(xy 0.9652 -1.778) (xy -0.9652 -1.778) (xy -0.9652 1.778) (xy 0.9652 1.778)
			)
			(stroke
				(width 0)
				(type default)
			)
			(fill no)
			(layer "B.Fab")
		)
		(pad "1" smd rect
			(at 0 -0.9652 180)
			(size 1.397 1.143)
			(layers "B.Cu" "B.Mask" "B.Paste")
			(net "P0V9_E")
		)
		(pad "2" smd rect
			(at 0 0.9652 180)
			(size 1.397 1.143)
			(layers "B.Cu" "B.Mask" "B.Paste")
			(net "GND")
		)
	)
	(footprint ""
		(layer "B.Cu")
		(at 227.6856 -35.995356 -90)
		(property "Reference" "C568"
			(at 0 0 90)
			(layer "B.SilkS")
			(hide yes)
			(effects
				(font
					(size 1.27 1.27)
				)
				(justify mirror)
			)
		)
		(property "Value" "SCD1U16V1KX-1-GP"
			(at 2.8321 -1.7399 270)
			(unlocked yes)
			(layer "B.Fab")
			(hide yes)
			(effects
				(font
					(size 1.016 1.016)
					(thickness 0.1524)
				)
				(justify mirror)
			)
		)
		(property "Device Type" "C0201H13"
			(at 2.8321 -3.2639 270)
			(unlocked yes)
			(layer "B.Fab")
			(hide yes)
			(effects
				(font
					(size 1.016 1.016)
					(thickness 0.1524)
				)
				(justify mirror)
			)
		)
		(duplicate_pad_numbers_are_jumpers no)
		(fp_rect
			(start 0.2794 0.6477)
			(end -0.2794 -0.6477)
			(stroke
				(width 0)
				(type default)
			)
			(fill no)
			(layer "B.CrtYd")
		)
		(fp_rect
			(start 0.2794 0.6477)
			(end -0.2794 -0.6477)
			(stroke
				(width 0)
				(type default)
			)
			(fill no)
			(layer "B.Fab")
		)
		(pad "1" smd custom
			(at 0 -0.2794 90)
			(size 0.0762 0.0762)
			(layers "B.Cu" "B.Mask" "B.Paste")
			(net "DUT_AVD_PCIE")
			(options
				(clearance outline)
				(anchor circle)
			)
			(primitives
				(gr_poly
					(pts
						(arc
							(start 0.1524 0.127)
							(mid 0.137521 0.162921)
							(end 0.1016 0.1778)
						)
						(arc
							(start -0.1016 0.1778)
							(mid -0.137521 0.162921)
							(end -0.1524 0.127)
						)
						(arc
							(start -0.1524 -0.127)
							(mid -0.137521 -0.162921)
							(end -0.1016 -0.1778)
						)
						(arc
							(start 0.1016 -0.1778)
							(mid 0.137521 -0.162921)
							(end 0.1524 -0.127)
						)
					)
					(width 0)
					(fill yes)
				)
			)
		)
		(pad "2" smd custom
			(at 0 0.2794 90)
			(size 0.0762 0.0762)
			(layers "B.Cu" "B.Mask" "B.Paste")
			(net "GND")
			(options
				(clearance outline)
				(anchor circle)
			)
			(primitives
				(gr_poly
					(pts
						(arc
							(start 0.1524 0.127)
							(mid 0.137521 0.162921)
							(end 0.1016 0.1778)
						)
						(arc
							(start -0.1016 0.1778)
							(mid -0.137521 0.162921)
							(end -0.1524 0.127)
						)
						(arc
							(start -0.1524 -0.127)
							(mid -0.137521 -0.162921)
							(end -0.1016 -0.1778)
						)
						(arc
							(start 0.1016 -0.1778)
							(mid 0.137521 -0.162921)
							(end 0.1524 -0.127)
						)
					)
					(width 0)
					(fill yes)
				)
			)
		)
	)
	(footprint ""
		(layer "B.Cu")
		(at 332.0796 -175.7426)
		(property "Reference" "C3214"
			(at 0 0 0)
			(layer "B.SilkS")
			(hide yes)
			(effects
				(font
					(size 1.27 1.27)
				)
				(justify mirror)
			)
		)
		(property "Value" "SCD1U25V2KX-2-GP"
			(at -1.1811 -2.7051 0)
			(unlocked yes)
			(layer "B.Fab")
			(hide yes)
			(effects
				(font
					(size 1.016 1.016)
					(thickness 0.1524)
				)
				(justify mirror)
			)
		)
		(property "Device Type" "C402H22"
			(at -1.1811 -4.2291 0)
			(unlocked yes)
			(layer "B.Fab")
			(hide yes)
			(effects
				(font
					(size 1.016 1.016)
					(thickness 0.1524)
				)
				(justify mirror)
			)
		)
		(duplicate_pad_numbers_are_jumpers no)
		(fp_rect
			(start 0.4318 0.9525)
			(end -0.4318 -0.9525)
			(stroke
				(width 0)
				(type default)
			)
			(fill no)
			(layer "B.CrtYd")
		)
		(fp_rect
			(start 0.4318 0.9525)
			(end -0.4318 -0.9525)
			(stroke
				(width 0)
				(type default)
			)
			(fill no)
			(layer "B.Fab")
		)
		(pad "1" smd custom
			(at 0 -0.4445 180)
			(size 0.1524 0.1524)
			(layers "B.Cu" "B.Mask" "B.Paste")
			(net "P3V3_STBY")
			(options
				(clearance outline)
				(anchor circle)
			)
			(primitives
				(gr_poly
					(pts
						(arc
							(start 0.3048 0.2032)
							(mid 0.275042 0.275042)
							(end 0.2032 0.3048)
						)
						(arc
							(start -0.2032 0.3048)
							(mid -0.275042 0.275042)
							(end -0.3048 0.2032)
						)
						(arc
							(start -0.3048 -0.2032)
							(mid -0.275042 -0.275042)
							(end -0.2032 -0.3048)
						)
						(arc
							(start 0.2032 -0.3048)
							(mid 0.275042 -0.275042)
							(end 0.3048 -0.2032)
						)
					)
					(width 0)
					(fill yes)
				)
			)
		)
		(pad "2" smd custom
			(at 0 0.4445 180)
			(size 0.1524 0.1524)
			(layers "B.Cu" "B.Mask" "B.Paste")
			(net "GND")
			(options
				(clearance outline)
				(anchor circle)
			)
			(primitives
				(gr_poly
					(pts
						(arc
							(start 0.3048 0.2032)
							(mid 0.275042 0.275042)
							(end 0.2032 0.3048)
						)
						(arc
							(start -0.2032 0.3048)
							(mid -0.275042 0.275042)
							(end -0.3048 0.2032)
						)
						(arc
							(start -0.3048 -0.2032)
							(mid -0.275042 -0.275042)
							(end -0.2032 -0.3048)
						)
						(arc
							(start 0.2032 -0.3048)
							(mid 0.275042 -0.275042)
							(end 0.3048 -0.2032)
						)
					)
					(width 0)
					(fill yes)
				)
			)
		)
	)
	(footprint ""
		(layer "B.Cu")
		(at 331.724 -181.61)
		(property "Reference" "C8093"
			(at 0 0 0)
			(layer "B.SilkS")
			(hide yes)
			(effects
				(font
					(size 1.27 1.27)
				)
				(justify mirror)
			)
		)
		(property "Value" "SCD047U25V2KX-GP"
			(at -1.1811 -2.7051 0)
			(unlocked yes)
			(layer "B.Fab")
			(hide yes)
			(effects
				(font
					(size 1.016 1.016)
					(thickness 0.1524)
				)
				(justify mirror)
			)
		)
		(property "Device Type" "C402H22"
			(at -1.1811 -4.2291 0)
			(unlocked yes)
			(layer "B.Fab")
			(hide yes)
			(effects
				(font
					(size 1.016 1.016)
					(thickness 0.1524)
				)
				(justify mirror)
			)
		)
		(duplicate_pad_numbers_are_jumpers no)
		(fp_rect
			(start 0.4318 0.9525)
			(end -0.4318 -0.9525)
			(stroke
				(width 0)
				(type default)
			)
			(fill no)
			(layer "B.CrtYd")
		)
		(fp_rect
			(start 0.4318 0.9525)
			(end -0.4318 -0.9525)
			(stroke
				(width 0)
				(type default)
			)
			(fill no)
			(layer "B.Fab")
		)
		(pad "1" smd custom
			(at 0 -0.4445 180)
			(size 0.1524 0.1524)
			(layers "B.Cu" "B.Mask" "B.Paste")
			(net "P3V3_STBY")
			(options
				(clearance outline)
				(anchor circle)
			)
			(primitives
				(gr_poly
					(pts
						(arc
							(start 0.3048 0.2032)
							(mid 0.275042 0.275042)
							(end 0.2032 0.3048)
						)
						(arc
							(start -0.2032 0.3048)
							(mid -0.275042 0.275042)
							(end -0.3048 0.2032)
						)
						(arc
							(start -0.3048 -0.2032)
							(mid -0.275042 -0.275042)
							(end -0.2032 -0.3048)
						)
						(arc
							(start 0.2032 -0.3048)
							(mid 0.275042 -0.275042)
							(end 0.3048 -0.2032)
						)
					)
					(width 0)
					(fill yes)
				)
			)
		)
		(pad "2" smd custom
			(at 0 0.4445 180)
			(size 0.1524 0.1524)
			(layers "B.Cu" "B.Mask" "B.Paste")
			(net "GND")
			(options
				(clearance outline)
				(anchor circle)
			)
			(primitives
				(gr_poly
					(pts
						(arc
							(start 0.3048 0.2032)
							(mid 0.275042 0.275042)
							(end 0.2032 0.3048)
						)
						(arc
							(start -0.2032 0.3048)
							(mid -0.275042 0.275042)
							(end -0.3048 0.2032)
						)
						(arc
							(start -0.3048 -0.2032)
							(mid -0.275042 -0.275042)
							(end -0.2032 -0.3048)
						)
						(arc
							(start 0.2032 -0.3048)
							(mid 0.275042 -0.275042)
							(end 0.3048 -0.2032)
						)
					)
					(width 0)
					(fill yes)
				)
			)
		)
	)
	(footprint ""
		(layer "B.Cu")
		(at 133.858 -196.3928)
		(property "Reference" "R4130"
			(at 0 0 0)
			(layer "B.SilkS")
			(hide yes)
			(effects
				(font
					(size 1.27 1.27)
				)
				(justify mirror)
			)
		)
		(property "Value" "4K7R2F-GP"
			(at -0.064008 -3.993896 0)
			(unlocked yes)
			(layer "B.Fab")
			(hide yes)
			(effects
				(font
					(size 1.016 1.016)
					(thickness 0.1524)
				)
				(justify mirror)
			)
		)
		(property "Device Type" "R402H16"
			(at -0.064008 -5.517896 0)
			(unlocked yes)
			(layer "B.Fab")
			(hide yes)
			(effects
				(font
					(size 1.016 1.016)
					(thickness 0.1524)
				)
				(justify mirror)
			)
		)
		(duplicate_pad_numbers_are_jumpers no)
		(fp_line
			(start -0.508 -0.9398)
			(end 0.508 -0.9398)
			(stroke
				(width 0.1524)
				(type default)
			)
			(layer "B.SilkS")
		)
		(fp_line
			(start 0.508 -0.9398)
			(end 0.508 0.9398)
			(stroke
				(width 0.1524)
				(type default)
			)
			(layer "B.SilkS")
		)
		(fp_rect
			(start 0.508 0.9398)
			(end -0.508 -0.9398)
			(stroke
				(width 0)
				(type default)
			)
			(fill no)
			(layer "B.CrtYd")
		)
		(fp_rect
			(start 0.508 0.9398)
			(end -0.508 -0.9398)
			(stroke
				(width 0)
				(type default)
			)
			(fill no)
			(layer "B.Fab")
		)
		(pad "1" smd custom
			(at 0 -0.4445 180)
			(size 0.1397 0.1397)
			(layers "B.Cu" "B.Mask" "B.Paste")
			(net "SSD_PERST#2")
			(options
				(clearance outline)
				(anchor circle)
			)
			(primitives
				(gr_poly
					(pts
						(arc
							(start -0.1778 0.2794)
							(mid -0.249642 0.249642)
							(end -0.2794 0.1778)
						)
						(arc
							(start -0.2794 -0.1778)
							(mid -0.249642 -0.249642)
							(end -0.1778 -0.2794)
						)
						(arc
							(start 0.1778 -0.2794)
							(mid 0.249642 -0.249642)
							(end 0.2794 -0.1778)
						)
						(arc
							(start 0.2794 0.1778)
							(mid 0.249642 0.249642)
							(end 0.1778 0.2794)
						)
					)
					(width 0)
					(fill yes)
				)
			)
		)
		(pad "2" smd custom
			(at 0 0.4445 180)
			(size 0.1397 0.1397)
			(layers "B.Cu" "B.Mask" "B.Paste")
			(net "P3V3_STBY")
			(options
				(clearance outline)
				(anchor circle)
			)
			(primitives
				(gr_poly
					(pts
						(arc
							(start -0.1778 0.2794)
							(mid -0.249642 0.249642)
							(end -0.2794 0.1778)
						)
						(arc
							(start -0.2794 -0.1778)
							(mid -0.249642 -0.249642)
							(end -0.1778 -0.2794)
						)
						(arc
							(start 0.1778 -0.2794)
							(mid 0.249642 -0.249642)
							(end 0.2794 -0.1778)
						)
						(arc
							(start 0.2794 0.1778)
							(mid 0.249642 0.249642)
							(end 0.1778 0.2794)
						)
					)
					(width 0)
					(fill yes)
				)
			)
		)
	)
	(footprint ""
		(layer "B.Cu")
		(at 253.5936 -38.002972 90)
		(property "Reference" "C592"
			(at 0 0 90)
			(layer "B.SilkS")
			(hide yes)
			(effects
				(font
					(size 1.27 1.27)
				)
				(justify mirror)
			)
		)
		(property "Value" "SCD1U16V1KX-1-GP"
			(at 2.8321 -1.7399 90)
			(unlocked yes)
			(layer "B.Fab")
			(hide yes)
			(effects
				(font
					(size 1.016 1.016)
					(thickness 0.1524)
				)
				(justify mirror)
			)
		)
		(property "Device Type" "C0201H13"
			(at 2.8321 -3.2639 90)
			(unlocked yes)
			(layer "B.Fab")
			(hide yes)
			(effects
				(font
					(size 1.016 1.016)
					(thickness 0.1524)
				)
				(justify mirror)
			)
		)
		(duplicate_pad_numbers_are_jumpers no)
		(fp_rect
			(start 0.2794 0.6477)
			(end -0.2794 -0.6477)
			(stroke
				(width 0)
				(type default)
			)
			(fill no)
			(layer "B.CrtYd")
		)
		(fp_rect
			(start 0.2794 0.6477)
			(end -0.2794 -0.6477)
			(stroke
				(width 0)
				(type default)
			)
			(fill no)
			(layer "B.Fab")
		)
		(pad "1" smd custom
			(at 0 -0.2794 270)
			(size 0.0762 0.0762)
			(layers "B.Cu" "B.Mask" "B.Paste")
			(net "DUT_AVD_PCIE")
			(options
				(clearance outline)
				(anchor circle)
			)
			(primitives
				(gr_poly
					(pts
						(arc
							(start 0.1524 0.127)
							(mid 0.137521 0.162921)
							(end 0.1016 0.1778)
						)
						(arc
							(start -0.1016 0.1778)
							(mid -0.137521 0.162921)
							(end -0.1524 0.127)
						)
						(arc
							(start -0.1524 -0.127)
							(mid -0.137521 -0.162921)
							(end -0.1016 -0.1778)
						)
						(arc
							(start 0.1016 -0.1778)
							(mid 0.137521 -0.162921)
							(end 0.1524 -0.127)
						)
					)
					(width 0)
					(fill yes)
				)
			)
		)
		(pad "2" smd custom
			(at 0 0.2794 270)
			(size 0.0762 0.0762)
			(layers "B.Cu" "B.Mask" "B.Paste")
			(net "GND")
			(options
				(clearance outline)
				(anchor circle)
			)
			(primitives
				(gr_poly
					(pts
						(arc
							(start 0.1524 0.127)
							(mid 0.137521 0.162921)
							(end 0.1016 0.1778)
						)
						(arc
							(start -0.1016 0.1778)
							(mid -0.137521 0.162921)
							(end -0.1524 0.127)
						)
						(arc
							(start -0.1524 -0.127)
							(mid -0.137521 -0.162921)
							(end -0.1016 -0.1778)
						)
						(arc
							(start 0.1016 -0.1778)
							(mid 0.137521 -0.162921)
							(end 0.1524 -0.127)
						)
					)
					(width 0)
					(fill yes)
				)
			)
		)
	)
	(footprint ""
		(layer "B.Cu")
		(at 126.976124 -196.443092)
		(property "Reference" "R4120"
			(at 0 0 0)
			(layer "B.SilkS")
			(hide yes)
			(effects
				(font
					(size 1.27 1.27)
				)
				(justify mirror)
			)
		)
		(property "Value" "4K7R2F-GP"
			(at -0.064008 -3.993896 0)
			(unlocked yes)
			(layer "B.Fab")
			(hide yes)
			(effects
				(font
					(size 1.016 1.016)
					(thickness 0.1524)
				)
				(justify mirror)
			)
		)
		(property "Device Type" "R402H16"
			(at -0.064008 -5.517896 0)
			(unlocked yes)
			(layer "B.Fab")
			(hide yes)
			(effects
				(font
					(size 1.016 1.016)
					(thickness 0.1524)
				)
				(justify mirror)
			)
		)
		(duplicate_pad_numbers_are_jumpers no)
		(fp_line
			(start -0.508 -0.9398)
			(end 0.508 -0.9398)
			(stroke
				(width 0.1524)
				(type default)
			)
			(layer "B.SilkS")
		)
		(fp_line
			(start 0.508 -0.9398)
			(end 0.508 0.9398)
			(stroke
				(width 0.1524)
				(type default)
			)
			(layer "B.SilkS")
		)
		(fp_rect
			(start 0.508 0.9398)
			(end -0.508 -0.9398)
			(stroke
				(width 0)
				(type default)
			)
			(fill no)
			(layer "B.CrtYd")
		)
		(fp_rect
			(start 0.508 0.9398)
			(end -0.508 -0.9398)
			(stroke
				(width 0)
				(type default)
			)
			(fill no)
			(layer "B.Fab")
		)
		(pad "1" smd custom
			(at 0 -0.4445 180)
			(size 0.1397 0.1397)
			(layers "B.Cu" "B.Mask" "B.Paste")
			(net "SSD_ATNLED#1")
			(options
				(clearance outline)
				(anchor circle)
			)
			(primitives
				(gr_poly
					(pts
						(arc
							(start -0.1778 0.2794)
							(mid -0.249642 0.249642)
							(end -0.2794 0.1778)
						)
						(arc
							(start -0.2794 -0.1778)
							(mid -0.249642 -0.249642)
							(end -0.1778 -0.2794)
						)
						(arc
							(start 0.1778 -0.2794)
							(mid 0.249642 -0.249642)
							(end 0.2794 -0.1778)
						)
						(arc
							(start 0.2794 0.1778)
							(mid 0.249642 0.249642)
							(end 0.1778 0.2794)
						)
					)
					(width 0)
					(fill yes)
				)
			)
		)
		(pad "2" smd custom
			(at 0 0.4445 180)
			(size 0.1397 0.1397)
			(layers "B.Cu" "B.Mask" "B.Paste")
			(net "P3V3_STBY")
			(options
				(clearance outline)
				(anchor circle)
			)
			(primitives
				(gr_poly
					(pts
						(arc
							(start -0.1778 0.2794)
							(mid -0.249642 0.249642)
							(end -0.2794 0.1778)
						)
						(arc
							(start -0.2794 -0.1778)
							(mid -0.249642 -0.249642)
							(end -0.1778 -0.2794)
						)
						(arc
							(start 0.1778 -0.2794)
							(mid 0.249642 -0.249642)
							(end 0.2794 -0.1778)
						)
						(arc
							(start 0.2794 0.1778)
							(mid 0.249642 0.249642)
							(end 0.1778 0.2794)
						)
					)
					(width 0)
					(fill yes)
				)
			)
		)
	)
	(footprint ""
		(layer "B.Cu")
		(at 340.7156 -175.7426)
		(property "Reference" "C3204"
			(at 0 0 0)
			(layer "B.SilkS")
			(hide yes)
			(effects
				(font
					(size 1.27 1.27)
				)
				(justify mirror)
			)
		)
		(property "Value" "SCD1U25V2KX-2-GP"
			(at -1.1811 -2.7051 0)
			(unlocked yes)
			(layer "B.Fab")
			(hide yes)
			(effects
				(font
					(size 1.016 1.016)
					(thickness 0.1524)
				)
				(justify mirror)
			)
		)
		(property "Device Type" "C402H22"
			(at -1.1811 -4.2291 0)
			(unlocked yes)
			(layer "B.Fab")
			(hide yes)
			(effects
				(font
					(size 1.016 1.016)
					(thickness 0.1524)
				)
				(justify mirror)
			)
		)
		(duplicate_pad_numbers_are_jumpers no)
		(fp_rect
			(start 0.4318 0.9525)
			(end -0.4318 -0.9525)
			(stroke
				(width 0)
				(type default)
			)
			(fill no)
			(layer "B.CrtYd")
		)
		(fp_rect
			(start 0.4318 0.9525)
			(end -0.4318 -0.9525)
			(stroke
				(width 0)
				(type default)
			)
			(fill no)
			(layer "B.Fab")
		)
		(pad "1" smd custom
			(at 0 -0.4445 180)
			(size 0.1524 0.1524)
			(layers "B.Cu" "B.Mask" "B.Paste")
			(net "P3V3_STBY")
			(options
				(clearance outline)
				(anchor circle)
			)
			(primitives
				(gr_poly
					(pts
						(arc
							(start 0.3048 0.2032)
							(mid 0.275042 0.275042)
							(end 0.2032 0.3048)
						)
						(arc
							(start -0.2032 0.3048)
							(mid -0.275042 0.275042)
							(end -0.3048 0.2032)
						)
						(arc
							(start -0.3048 -0.2032)
							(mid -0.275042 -0.275042)
							(end -0.2032 -0.3048)
						)
						(arc
							(start 0.2032 -0.3048)
							(mid 0.275042 -0.275042)
							(end 0.3048 -0.2032)
						)
					)
					(width 0)
					(fill yes)
				)
			)
		)
		(pad "2" smd custom
			(at 0 0.4445 180)
			(size 0.1524 0.1524)
			(layers "B.Cu" "B.Mask" "B.Paste")
			(net "GND")
			(options
				(clearance outline)
				(anchor circle)
			)
			(primitives
				(gr_poly
					(pts
						(arc
							(start 0.3048 0.2032)
							(mid 0.275042 0.275042)
							(end 0.2032 0.3048)
						)
						(arc
							(start -0.2032 0.3048)
							(mid -0.275042 0.275042)
							(end -0.3048 0.2032)
						)
						(arc
							(start -0.3048 -0.2032)
							(mid -0.275042 -0.275042)
							(end -0.2032 -0.3048)
						)
						(arc
							(start 0.2032 -0.3048)
							(mid 0.275042 -0.275042)
							(end 0.3048 -0.2032)
						)
					)
					(width 0)
					(fill yes)
				)
			)
		)
	)
	(footprint ""
		(layer "B.Cu")
		(at 271.4625 -4.7625 180)
		(property "Reference" "R389"
			(at 0 0 0)
			(layer "B.SilkS")
			(hide yes)
			(effects
				(font
					(size 1.27 1.27)
				)
				(justify mirror)
			)
		)
		(property "Value" "0R2J-2-GP"
			(at -0.064008 -3.993896 180)
			(unlocked yes)
			(layer "B.Fab")
			(hide yes)
			(effects
				(font
					(size 1.016 1.016)
					(thickness 0.1524)
				)
				(justify mirror)
			)
		)
		(property "Device Type" "R402H16"
			(at -0.064008 -5.517896 180)
			(unlocked yes)
			(layer "B.Fab")
			(hide yes)
			(effects
				(font
					(size 1.016 1.016)
					(thickness 0.1524)
				)
				(justify mirror)
			)
		)
		(duplicate_pad_numbers_are_jumpers no)
		(fp_line
			(start 0.508 -0.9398)
			(end 0.508 0.9398)
			(stroke
				(width 0.1524)
				(type default)
			)
			(layer "B.SilkS")
		)
		(fp_line
			(start -0.508 -0.9398)
			(end 0.508 -0.9398)
			(stroke
				(width 0.1524)
				(type default)
			)
			(layer "B.SilkS")
		)
		(fp_rect
			(start 0.508 0.9398)
			(end -0.508 -0.9398)
			(stroke
				(width 0)
				(type default)
			)
			(fill no)
			(layer "B.CrtYd")
		)
		(fp_rect
			(start 0.508 0.9398)
			(end -0.508 -0.9398)
			(stroke
				(width 0)
				(type default)
			)
			(fill no)
			(layer "B.Fab")
		)
		(pad "1" smd custom
			(at 0 -0.4445)
			(size 0.1397 0.1397)
			(layers "B.Cu" "B.Mask" "B.Paste")
			(net "MINISAS_CN16_C_I2C_INT#")
			(options
				(clearance outline)
				(anchor circle)
			)
			(primitives
				(gr_poly
					(pts
						(arc
							(start -0.1778 0.2794)
							(mid -0.249642 0.249642)
							(end -0.2794 0.1778)
						)
						(arc
							(start -0.2794 -0.1778)
							(mid -0.249642 -0.249642)
							(end -0.1778 -0.2794)
						)
						(arc
							(start 0.1778 -0.2794)
							(mid 0.249642 -0.249642)
							(end 0.2794 -0.1778)
						)
						(arc
							(start 0.2794 0.1778)
							(mid 0.249642 0.249642)
							(end 0.1778 0.2794)
						)
					)
					(width 0)
					(fill yes)
				)
			)
		)
		(pad "2" smd custom
			(at 0 0.4445)
			(size 0.1397 0.1397)
			(layers "B.Cu" "B.Mask" "B.Paste")
			(net "PCIE_REFCLK_H1_N_R")
			(options
				(clearance outline)
				(anchor circle)
			)
			(primitives
				(gr_poly
					(pts
						(arc
							(start -0.1778 0.2794)
							(mid -0.249642 0.249642)
							(end -0.2794 0.1778)
						)
						(arc
							(start -0.2794 -0.1778)
							(mid -0.249642 -0.249642)
							(end -0.1778 -0.2794)
						)
						(arc
							(start 0.1778 -0.2794)
							(mid 0.249642 -0.249642)
							(end 0.2794 -0.1778)
						)
						(arc
							(start 0.2794 0.1778)
							(mid 0.249642 0.249642)
							(end 0.1778 0.2794)
						)
					)
					(width 0)
					(fill yes)
				)
			)
		)
	)
	(footprint ""
		(layer "B.Cu")
		(at 247.1166 -41.995852 -90)
		(property "Reference" "C453"
			(at 0 0 90)
			(layer "B.SilkS")
			(hide yes)
			(effects
				(font
					(size 1.27 1.27)
				)
				(justify mirror)
			)
		)
		(property "Value" "SCD1U16V1KX-1-GP"
			(at 2.8321 -1.7399 270)
			(unlocked yes)
			(layer "B.Fab")
			(hide yes)
			(effects
				(font
					(size 1.016 1.016)
					(thickness 0.1524)
				)
				(justify mirror)
			)
		)
		(property "Device Type" "C0201H13"
			(at 2.8321 -3.2639 270)
			(unlocked yes)
			(layer "B.Fab")
			(hide yes)
			(effects
				(font
					(size 1.016 1.016)
					(thickness 0.1524)
				)
				(justify mirror)
			)
		)
		(duplicate_pad_numbers_are_jumpers no)
		(fp_rect
			(start 0.2794 0.6477)
			(end -0.2794 -0.6477)
			(stroke
				(width 0)
				(type default)
			)
			(fill no)
			(layer "B.CrtYd")
		)
		(fp_rect
			(start 0.2794 0.6477)
			(end -0.2794 -0.6477)
			(stroke
				(width 0)
				(type default)
			)
			(fill no)
			(layer "B.Fab")
		)
		(pad "1" smd custom
			(at 0 -0.2794 90)
			(size 0.0762 0.0762)
			(layers "B.Cu" "B.Mask" "B.Paste")
			(net "DUT_VDD")
			(options
				(clearance outline)
				(anchor circle)
			)
			(primitives
				(gr_poly
					(pts
						(arc
							(start 0.1524 0.127)
							(mid 0.137521 0.162921)
							(end 0.1016 0.1778)
						)
						(arc
							(start -0.1016 0.1778)
							(mid -0.137521 0.162921)
							(end -0.1524 0.127)
						)
						(arc
							(start -0.1524 -0.127)
							(mid -0.137521 -0.162921)
							(end -0.1016 -0.1778)
						)
						(arc
							(start 0.1016 -0.1778)
							(mid 0.137521 -0.162921)
							(end 0.1524 -0.127)
						)
					)
					(width 0)
					(fill yes)
				)
			)
		)
		(pad "2" smd custom
			(at 0 0.2794 90)
			(size 0.0762 0.0762)
			(layers "B.Cu" "B.Mask" "B.Paste")
			(net "GND")
			(options
				(clearance outline)
				(anchor circle)
			)
			(primitives
				(gr_poly
					(pts
						(arc
							(start 0.1524 0.127)
							(mid 0.137521 0.162921)
							(end 0.1016 0.1778)
						)
						(arc
							(start -0.1016 0.1778)
							(mid -0.137521 0.162921)
							(end -0.1524 0.127)
						)
						(arc
							(start -0.1524 -0.127)
							(mid -0.137521 -0.162921)
							(end -0.1016 -0.1778)
						)
						(arc
							(start 0.1016 -0.1778)
							(mid 0.137521 -0.162921)
							(end 0.1524 -0.127)
						)
					)
					(width 0)
					(fill yes)
				)
			)
		)
	)
	(footprint ""
		(layer "B.Cu")
		(at 13.50518 -76.661264 90)
		(property "Reference" "C621"
			(at 0 0 90)
			(layer "B.SilkS")
			(hide yes)
			(effects
				(font
					(size 1.27 1.27)
				)
				(justify mirror)
			)
		)
		(property "Value" "SCD1U16V2KX-3GP"
			(at -1.1811 -2.7051 90)
			(unlocked yes)
			(layer "B.Fab")
			(hide yes)
			(effects
				(font
					(size 1.016 1.016)
					(thickness 0.1524)
				)
				(justify mirror)
			)
		)
		(property "Device Type" "C402H22"
			(at -1.1811 -4.2291 90)
			(unlocked yes)
			(layer "B.Fab")
			(hide yes)
			(effects
				(font
					(size 1.016 1.016)
					(thickness 0.1524)
				)
				(justify mirror)
			)
		)
		(duplicate_pad_numbers_are_jumpers no)
		(fp_rect
			(start 0.4318 0.9525)
			(end -0.4318 -0.9525)
			(stroke
				(width 0)
				(type default)
			)
			(fill no)
			(layer "B.CrtYd")
		)
		(fp_rect
			(start 0.4318 0.9525)
			(end -0.4318 -0.9525)
			(stroke
				(width 0)
				(type default)
			)
			(fill no)
			(layer "B.Fab")
		)
		(pad "1" smd custom
			(at 0 -0.4445 270)
			(size 0.1524 0.1524)
			(layers "B.Cu" "B.Mask" "B.Paste")
			(net "P1V5_I210")
			(options
				(clearance outline)
				(anchor circle)
			)
			(primitives
				(gr_poly
					(pts
						(arc
							(start 0.3048 0.2032)
							(mid 0.275042 0.275042)
							(end 0.2032 0.3048)
						)
						(arc
							(start -0.2032 0.3048)
							(mid -0.275042 0.275042)
							(end -0.3048 0.2032)
						)
						(arc
							(start -0.3048 -0.2032)
							(mid -0.275042 -0.275042)
							(end -0.2032 -0.3048)
						)
						(arc
							(start 0.2032 -0.3048)
							(mid 0.275042 -0.275042)
							(end 0.3048 -0.2032)
						)
					)
					(width 0)
					(fill yes)
				)
			)
		)
		(pad "2" smd custom
			(at 0 0.4445 270)
			(size 0.1524 0.1524)
			(layers "B.Cu" "B.Mask" "B.Paste")
			(net "GND")
			(options
				(clearance outline)
				(anchor circle)
			)
			(primitives
				(gr_poly
					(pts
						(arc
							(start 0.3048 0.2032)
							(mid 0.275042 0.275042)
							(end 0.2032 0.3048)
						)
						(arc
							(start -0.2032 0.3048)
							(mid -0.275042 0.275042)
							(end -0.3048 0.2032)
						)
						(arc
							(start -0.3048 -0.2032)
							(mid -0.275042 -0.275042)
							(end -0.2032 -0.3048)
						)
						(arc
							(start 0.2032 -0.3048)
							(mid 0.275042 -0.275042)
							(end 0.3048 -0.2032)
						)
					)
					(width 0)
					(fill yes)
				)
			)
		)
	)
	(footprint ""
		(layer "B.Cu")
		(at 164.084 -33.528)
		(property "Reference" "R2921"
			(at 0 0 0)
			(layer "B.SilkS")
			(hide yes)
			(effects
				(font
					(size 1.27 1.27)
				)
				(justify mirror)
			)
		)
		(property "Value" "0R2J-2-GP"
			(at -0.064008 -3.993896 0)
			(unlocked yes)
			(layer "B.Fab")
			(hide yes)
			(effects
				(font
					(size 1.016 1.016)
					(thickness 0.1524)
				)
				(justify mirror)
			)
		)
		(property "Device Type" "R402H16"
			(at -0.064008 -5.517896 0)
			(unlocked yes)
			(layer "B.Fab")
			(hide yes)
			(effects
				(font
					(size 1.016 1.016)
					(thickness 0.1524)
				)
				(justify mirror)
			)
		)
		(duplicate_pad_numbers_are_jumpers no)
		(fp_line
			(start -0.508 -0.9398)
			(end 0.508 -0.9398)
			(stroke
				(width 0.1524)
				(type default)
			)
			(layer "B.SilkS")
		)
		(fp_line
			(start 0.508 -0.9398)
			(end 0.508 0.9398)
			(stroke
				(width 0.1524)
				(type default)
			)
			(layer "B.SilkS")
		)
		(fp_rect
			(start 0.508 0.9398)
			(end -0.508 -0.9398)
			(stroke
				(width 0)
				(type default)
			)
			(fill no)
			(layer "B.CrtYd")
		)
		(fp_rect
			(start 0.508 0.9398)
			(end -0.508 -0.9398)
			(stroke
				(width 0)
				(type default)
			)
			(fill no)
			(layer "B.Fab")
		)
		(pad "1" smd custom
			(at 0 -0.4445 180)
			(size 0.1397 0.1397)
			(layers "B.Cu" "B.Mask" "B.Paste")
			(net "BMC_I2C4_MINI4_SDA")
			(options
				(clearance outline)
				(anchor circle)
			)
			(primitives
				(gr_poly
					(pts
						(arc
							(start -0.1778 0.2794)
							(mid -0.249642 0.249642)
							(end -0.2794 0.1778)
						)
						(arc
							(start -0.2794 -0.1778)
							(mid -0.249642 -0.249642)
							(end -0.1778 -0.2794)
						)
						(arc
							(start 0.1778 -0.2794)
							(mid 0.249642 -0.249642)
							(end 0.2794 -0.1778)
						)
						(arc
							(start 0.2794 0.1778)
							(mid 0.249642 0.249642)
							(end 0.1778 0.2794)
						)
					)
					(width 0)
					(fill yes)
				)
			)
		)
		(pad "2" smd custom
			(at 0 0.4445 180)
			(size 0.1397 0.1397)
			(layers "B.Cu" "B.Mask" "B.Paste")
			(net "8644_SDA_R_4")
			(options
				(clearance outline)
				(anchor circle)
			)
			(primitives
				(gr_poly
					(pts
						(arc
							(start -0.1778 0.2794)
							(mid -0.249642 0.249642)
							(end -0.2794 0.1778)
						)
						(arc
							(start -0.2794 -0.1778)
							(mid -0.249642 -0.249642)
							(end -0.1778 -0.2794)
						)
						(arc
							(start 0.1778 -0.2794)
							(mid 0.249642 -0.249642)
							(end 0.2794 -0.1778)
						)
						(arc
							(start 0.2794 0.1778)
							(mid 0.249642 0.249642)
							(end 0.1778 0.2794)
						)
					)
					(width 0)
					(fill yes)
				)
			)
		)
	)
	(footprint ""
		(layer "B.Cu")
		(at 221.0816 -199.9996)
		(property "Reference" "R157"
			(at 0 0 0)
			(layer "B.SilkS")
			(hide yes)
			(effects
				(font
					(size 1.27 1.27)
				)
				(justify mirror)
			)
		)
		(property "Value" "4K7R2F-GP"
			(at -0.064008 -3.993896 0)
			(unlocked yes)
			(layer "B.Fab")
			(hide yes)
			(effects
				(font
					(size 1.016 1.016)
					(thickness 0.1524)
				)
				(justify mirror)
			)
		)
		(property "Device Type" "R402H16"
			(at -0.064008 -5.517896 0)
			(unlocked yes)
			(layer "B.Fab")
			(hide yes)
			(effects
				(font
					(size 1.016 1.016)
					(thickness 0.1524)
				)
				(justify mirror)
			)
		)
		(duplicate_pad_numbers_are_jumpers no)
		(fp_line
			(start -0.508 -0.9398)
			(end 0.508 -0.9398)
			(stroke
				(width 0.1524)
				(type default)
			)
			(layer "B.SilkS")
		)
		(fp_line
			(start 0.508 -0.9398)
			(end 0.508 0.9398)
			(stroke
				(width 0.1524)
				(type default)
			)
			(layer "B.SilkS")
		)
		(fp_rect
			(start 0.508 0.9398)
			(end -0.508 -0.9398)
			(stroke
				(width 0)
				(type default)
			)
			(fill no)
			(layer "B.CrtYd")
		)
		(fp_rect
			(start 0.508 0.9398)
			(end -0.508 -0.9398)
			(stroke
				(width 0)
				(type default)
			)
			(fill no)
			(layer "B.Fab")
		)
		(pad "1" smd custom
			(at 0 -0.4445 180)
			(size 0.1397 0.1397)
			(layers "B.Cu" "B.Mask" "B.Paste")
			(net "BMC_SSD_RST#0_A8")
			(options
				(clearance outline)
				(anchor circle)
			)
			(primitives
				(gr_poly
					(pts
						(arc
							(start -0.1778 0.2794)
							(mid -0.249642 0.249642)
							(end -0.2794 0.1778)
						)
						(arc
							(start -0.2794 -0.1778)
							(mid -0.249642 -0.249642)
							(end -0.1778 -0.2794)
						)
						(arc
							(start 0.1778 -0.2794)
							(mid 0.249642 -0.249642)
							(end 0.2794 -0.1778)
						)
						(arc
							(start 0.2794 0.1778)
							(mid 0.249642 0.249642)
							(end 0.1778 0.2794)
						)
					)
					(width 0)
					(fill yes)
				)
			)
		)
		(pad "2" smd custom
			(at 0 0.4445 180)
			(size 0.1397 0.1397)
			(layers "B.Cu" "B.Mask" "B.Paste")
			(net "P3V3_STBY")
			(options
				(clearance outline)
				(anchor circle)
			)
			(primitives
				(gr_poly
					(pts
						(arc
							(start -0.1778 0.2794)
							(mid -0.249642 0.249642)
							(end -0.2794 0.1778)
						)
						(arc
							(start -0.2794 -0.1778)
							(mid -0.249642 -0.249642)
							(end -0.1778 -0.2794)
						)
						(arc
							(start 0.1778 -0.2794)
							(mid 0.249642 -0.249642)
							(end 0.2794 -0.1778)
						)
						(arc
							(start 0.2794 0.1778)
							(mid 0.249642 0.249642)
							(end 0.1778 0.2794)
						)
					)
					(width 0)
					(fill yes)
				)
			)
		)
	)
	(footprint ""
		(layer "B.Cu")
		(at 297.591988 -35.059112 180)
		(property "Reference" "C256"
			(at 0 0 0)
			(layer "B.SilkS")
			(hide yes)
			(effects
				(font
					(size 1.27 1.27)
				)
				(justify mirror)
			)
		)
		(property "Value" "SCD1U10V2KX-5GP"
			(at -1.1811 -2.7051 180)
			(unlocked yes)
			(layer "B.Fab")
			(hide yes)
			(effects
				(font
					(size 1.016 1.016)
					(thickness 0.1524)
				)
				(justify mirror)
			)
		)
		(property "Device Type" "C402H22"
			(at -1.1811 -4.2291 180)
			(unlocked yes)
			(layer "B.Fab")
			(hide yes)
			(effects
				(font
					(size 1.016 1.016)
					(thickness 0.1524)
				)
				(justify mirror)
			)
		)
		(duplicate_pad_numbers_are_jumpers no)
		(fp_rect
			(start 0.4318 0.9525)
			(end -0.4318 -0.9525)
			(stroke
				(width 0)
				(type default)
			)
			(fill no)
			(layer "B.CrtYd")
		)
		(fp_rect
			(start 0.4318 0.9525)
			(end -0.4318 -0.9525)
			(stroke
				(width 0)
				(type default)
			)
			(fill no)
			(layer "B.Fab")
		)
		(pad "1" smd custom
			(at 0 -0.4445)
			(size 0.1524 0.1524)
			(layers "B.Cu" "B.Mask" "B.Paste")
			(net "GND")
			(options
				(clearance outline)
				(anchor circle)
			)
			(primitives
				(gr_poly
					(pts
						(arc
							(start 0.3048 0.2032)
							(mid 0.275042 0.275042)
							(end 0.2032 0.3048)
						)
						(arc
							(start -0.2032 0.3048)
							(mid -0.275042 0.275042)
							(end -0.3048 0.2032)
						)
						(arc
							(start -0.3048 -0.2032)
							(mid -0.275042 -0.275042)
							(end -0.2032 -0.3048)
						)
						(arc
							(start 0.2032 -0.3048)
							(mid 0.275042 -0.275042)
							(end 0.3048 -0.2032)
						)
					)
					(width 0)
					(fill yes)
				)
			)
		)
		(pad "2" smd custom
			(at 0 0.4445)
			(size 0.1524 0.1524)
			(layers "B.Cu" "B.Mask" "B.Paste")
			(net "P3V3_STBY")
			(options
				(clearance outline)
				(anchor circle)
			)
			(primitives
				(gr_poly
					(pts
						(arc
							(start 0.3048 0.2032)
							(mid 0.275042 0.275042)
							(end 0.2032 0.3048)
						)
						(arc
							(start -0.2032 0.3048)
							(mid -0.275042 0.275042)
							(end -0.3048 0.2032)
						)
						(arc
							(start -0.3048 -0.2032)
							(mid -0.275042 -0.275042)
							(end -0.2032 -0.3048)
						)
						(arc
							(start 0.2032 -0.3048)
							(mid 0.275042 -0.275042)
							(end 0.3048 -0.2032)
						)
					)
					(width 0)
					(fill yes)
				)
			)
		)
	)
	(footprint ""
		(layer "B.Cu")
		(at 51.470052 -110.70463)
		(property "Reference" "R325"
			(at 0 0 0)
			(layer "B.SilkS")
			(hide yes)
			(effects
				(font
					(size 1.27 1.27)
				)
				(justify mirror)
			)
		)
		(property "Value" "4K7R2F-GP"
			(at -0.064008 -3.993896 0)
			(unlocked yes)
			(layer "B.Fab")
			(hide yes)
			(effects
				(font
					(size 1.016 1.016)
					(thickness 0.1524)
				)
				(justify mirror)
			)
		)
		(property "Device Type" "R402H16"
			(at -0.064008 -5.517896 0)
			(unlocked yes)
			(layer "B.Fab")
			(hide yes)
			(effects
				(font
					(size 1.016 1.016)
					(thickness 0.1524)
				)
				(justify mirror)
			)
		)
		(duplicate_pad_numbers_are_jumpers no)
		(fp_line
			(start -0.508 -0.9398)
			(end 0.508 -0.9398)
			(stroke
				(width 0.1524)
				(type default)
			)
			(layer "B.SilkS")
		)
		(fp_line
			(start 0.508 -0.9398)
			(end 0.508 0.9398)
			(stroke
				(width 0.1524)
				(type default)
			)
			(layer "B.SilkS")
		)
		(fp_rect
			(start 0.508 0.9398)
			(end -0.508 -0.9398)
			(stroke
				(width 0)
				(type default)
			)
			(fill no)
			(layer "B.CrtYd")
		)
		(fp_rect
			(start 0.508 0.9398)
			(end -0.508 -0.9398)
			(stroke
				(width 0)
				(type default)
			)
			(fill no)
			(layer "B.Fab")
		)
		(pad "1" smd custom
			(at 0 -0.4445 180)
			(size 0.1397 0.1397)
			(layers "B.Cu" "B.Mask" "B.Paste")
			(net "P3V3_STBY")
			(options
				(clearance outline)
				(anchor circle)
			)
			(primitives
				(gr_poly
					(pts
						(arc
							(start -0.1778 0.2794)
							(mid -0.249642 0.249642)
							(end -0.2794 0.1778)
						)
						(arc
							(start -0.2794 -0.1778)
							(mid -0.249642 -0.249642)
							(end -0.1778 -0.2794)
						)
						(arc
							(start 0.1778 -0.2794)
							(mid 0.249642 -0.249642)
							(end 0.2794 -0.1778)
						)
						(arc
							(start 0.2794 0.1778)
							(mid 0.249642 0.249642)
							(end 0.1778 0.2794)
						)
					)
					(width 0)
					(fill yes)
				)
			)
		)
		(pad "2" smd custom
			(at 0 0.4445 180)
			(size 0.1397 0.1397)
			(layers "B.Cu" "B.Mask" "B.Paste")
			(net "I2C6_LS_G2")
			(options
				(clearance outline)
				(anchor circle)
			)
			(primitives
				(gr_poly
					(pts
						(arc
							(start -0.1778 0.2794)
							(mid -0.249642 0.249642)
							(end -0.2794 0.1778)
						)
						(arc
							(start -0.2794 -0.1778)
							(mid -0.249642 -0.249642)
							(end -0.1778 -0.2794)
						)
						(arc
							(start 0.1778 -0.2794)
							(mid 0.249642 -0.249642)
							(end 0.2794 -0.1778)
						)
						(arc
							(start 0.2794 0.1778)
							(mid 0.249642 0.249642)
							(end 0.1778 0.2794)
						)
					)
					(width 0)
					(fill yes)
				)
			)
		)
	)
	(footprint ""
		(layer "B.Cu")
		(at 266.486894 -2.567178 180)
		(property "Reference" "R188"
			(at 0 0 0)
			(layer "B.SilkS")
			(hide yes)
			(effects
				(font
					(size 1.27 1.27)
				)
				(justify mirror)
			)
		)
		(property "Value" "4K7R2F-GP"
			(at -0.064008 -3.993896 180)
			(unlocked yes)
			(layer "B.Fab")
			(hide yes)
			(effects
				(font
					(size 1.016 1.016)
					(thickness 0.1524)
				)
				(justify mirror)
			)
		)
		(property "Device Type" "R402H16"
			(at -0.064008 -5.517896 180)
			(unlocked yes)
			(layer "B.Fab")
			(hide yes)
			(effects
				(font
					(size 1.016 1.016)
					(thickness 0.1524)
				)
				(justify mirror)
			)
		)
		(duplicate_pad_numbers_are_jumpers no)
		(fp_line
			(start 0.508 -0.9398)
			(end 0.508 0.9398)
			(stroke
				(width 0.1524)
				(type default)
			)
			(layer "B.SilkS")
		)
		(fp_line
			(start -0.508 -0.9398)
			(end 0.508 -0.9398)
			(stroke
				(width 0.1524)
				(type default)
			)
			(layer "B.SilkS")
		)
		(fp_rect
			(start 0.508 0.9398)
			(end -0.508 -0.9398)
			(stroke
				(width 0)
				(type default)
			)
			(fill no)
			(layer "B.CrtYd")
		)
		(fp_rect
			(start 0.508 0.9398)
			(end -0.508 -0.9398)
			(stroke
				(width 0)
				(type default)
			)
			(fill no)
			(layer "B.Fab")
		)
		(pad "1" smd custom
			(at 0 -0.4445)
			(size 0.1397 0.1397)
			(layers "B.Cu" "B.Mask" "B.Paste")
			(net "P3V3_STBY")
			(options
				(clearance outline)
				(anchor circle)
			)
			(primitives
				(gr_poly
					(pts
						(arc
							(start -0.1778 0.2794)
							(mid -0.249642 0.249642)
							(end -0.2794 0.1778)
						)
						(arc
							(start -0.2794 -0.1778)
							(mid -0.249642 -0.249642)
							(end -0.1778 -0.2794)
						)
						(arc
							(start 0.1778 -0.2794)
							(mid 0.249642 -0.249642)
							(end 0.2794 -0.1778)
						)
						(arc
							(start 0.2794 0.1778)
							(mid 0.249642 0.249642)
							(end 0.1778 0.2794)
						)
					)
					(width 0)
					(fill yes)
				)
			)
		)
		(pad "2" smd custom
			(at 0 0.4445)
			(size 0.1397 0.1397)
			(layers "B.Cu" "B.Mask" "B.Paste")
			(net "TEMP_1_A0")
			(options
				(clearance outline)
				(anchor circle)
			)
			(primitives
				(gr_poly
					(pts
						(arc
							(start -0.1778 0.2794)
							(mid -0.249642 0.249642)
							(end -0.2794 0.1778)
						)
						(arc
							(start -0.2794 -0.1778)
							(mid -0.249642 -0.249642)
							(end -0.1778 -0.2794)
						)
						(arc
							(start 0.1778 -0.2794)
							(mid 0.249642 -0.249642)
							(end 0.2794 -0.1778)
						)
						(arc
							(start 0.2794 0.1778)
							(mid 0.249642 0.249642)
							(end 0.1778 0.2794)
						)
					)
					(width 0)
					(fill yes)
				)
			)
		)
	)
	(footprint ""
		(layer "B.Cu")
		(at 45.212 -138.938)
		(property "Reference" "TP228"
			(at 0 0 0)
			(layer "B.SilkS")
			(hide yes)
			(effects
				(font
					(size 1.27 1.27)
				)
				(justify mirror)
			)
		)
		(property "Value" "TPAD28-2-GP"
			(at 0.0127 -1.6637 0)
			(unlocked yes)
			(layer "B.Fab")
			(hide yes)
			(effects
				(font
					(size 1.016 1.016)
					(thickness 0.1524)
				)
				(justify mirror)
			)
		)
		(property "Device Type" "TPAD28"
			(at 0.0127 -3.1877 0)
			(unlocked yes)
			(layer "B.Fab")
			(hide yes)
			(effects
				(font
					(size 1.016 1.016)
					(thickness 0.1524)
				)
				(justify mirror)
			)
		)
		(duplicate_pad_numbers_are_jumpers no)
		(fp_poly
			(pts
				(arc
					(start 0.3556 0)
					(mid -0.3556 0)
					(end 0.3556 0)
				)
			)
			(stroke
				(width 0)
				(type default)
			)
			(fill no)
			(layer "B.CrtYd")
		)
		(fp_poly
			(pts
				(arc
					(start 0.6096 0)
					(mid -0.6096 0)
					(end 0.6096 0)
				)
			)
			(stroke
				(width 0)
				(type default)
			)
			(fill no)
			(layer "B.Fab")
		)
		(pad "1" smd circle
			(at 0 0 180)
			(size 0.7112 0.7112)
			(layers "B.Cu" "B.Mask" "B.Paste")
			(net "TP_GPION5")
		)
	)
	(footprint ""
		(layer "B.Cu")
		(at 247.0658 -54.006496 90)
		(property "Reference" "C37"
			(at 0 0 90)
			(layer "B.SilkS")
			(hide yes)
			(effects
				(font
					(size 1.27 1.27)
				)
				(justify mirror)
			)
		)
		(property "Value" "SCD1U16V1KX-1-GP"
			(at 2.8321 -1.7399 90)
			(unlocked yes)
			(layer "B.Fab")
			(hide yes)
			(effects
				(font
					(size 1.016 1.016)
					(thickness 0.1524)
				)
				(justify mirror)
			)
		)
		(property "Device Type" "C0201H13"
			(at 2.8321 -3.2639 90)
			(unlocked yes)
			(layer "B.Fab")
			(hide yes)
			(effects
				(font
					(size 1.016 1.016)
					(thickness 0.1524)
				)
				(justify mirror)
			)
		)
		(duplicate_pad_numbers_are_jumpers no)
		(fp_rect
			(start 0.2794 0.6477)
			(end -0.2794 -0.6477)
			(stroke
				(width 0)
				(type default)
			)
			(fill no)
			(layer "B.CrtYd")
		)
		(fp_rect
			(start 0.2794 0.6477)
			(end -0.2794 -0.6477)
			(stroke
				(width 0)
				(type default)
			)
			(fill no)
			(layer "B.Fab")
		)
		(pad "1" smd custom
			(at 0 -0.2794 270)
			(size 0.0762 0.0762)
			(layers "B.Cu" "B.Mask" "B.Paste")
			(net "DUT_VDD")
			(options
				(clearance outline)
				(anchor circle)
			)
			(primitives
				(gr_poly
					(pts
						(arc
							(start 0.1524 0.127)
							(mid 0.137521 0.162921)
							(end 0.1016 0.1778)
						)
						(arc
							(start -0.1016 0.1778)
							(mid -0.137521 0.162921)
							(end -0.1524 0.127)
						)
						(arc
							(start -0.1524 -0.127)
							(mid -0.137521 -0.162921)
							(end -0.1016 -0.1778)
						)
						(arc
							(start 0.1016 -0.1778)
							(mid 0.137521 -0.162921)
							(end 0.1524 -0.127)
						)
					)
					(width 0)
					(fill yes)
				)
			)
		)
		(pad "2" smd custom
			(at 0 0.2794 270)
			(size 0.0762 0.0762)
			(layers "B.Cu" "B.Mask" "B.Paste")
			(net "GND")
			(options
				(clearance outline)
				(anchor circle)
			)
			(primitives
				(gr_poly
					(pts
						(arc
							(start 0.1524 0.127)
							(mid 0.137521 0.162921)
							(end 0.1016 0.1778)
						)
						(arc
							(start -0.1016 0.1778)
							(mid -0.137521 0.162921)
							(end -0.1524 0.127)
						)
						(arc
							(start -0.1524 -0.127)
							(mid -0.137521 -0.162921)
							(end -0.1016 -0.1778)
						)
						(arc
							(start 0.1016 -0.1778)
							(mid 0.137521 -0.162921)
							(end 0.1524 -0.127)
						)
					)
					(width 0)
					(fill yes)
				)
			)
		)
	)
	(footprint ""
		(layer "B.Cu")
		(at 81.129124 -195.427092 180)
		(property "Reference" "R4110"
			(at 0 0 0)
			(layer "B.SilkS")
			(hide yes)
			(effects
				(font
					(size 1.27 1.27)
				)
				(justify mirror)
			)
		)
		(property "Value" "4K7R2F-GP"
			(at -0.064008 -3.993896 180)
			(unlocked yes)
			(layer "B.Fab")
			(hide yes)
			(effects
				(font
					(size 1.016 1.016)
					(thickness 0.1524)
				)
				(justify mirror)
			)
		)
		(property "Device Type" "R402H16"
			(at -0.064008 -5.517896 180)
			(unlocked yes)
			(layer "B.Fab")
			(hide yes)
			(effects
				(font
					(size 1.016 1.016)
					(thickness 0.1524)
				)
				(justify mirror)
			)
		)
		(duplicate_pad_numbers_are_jumpers no)
		(fp_line
			(start 0.508 -0.9398)
			(end 0.508 0.9398)
			(stroke
				(width 0.1524)
				(type default)
			)
			(layer "B.SilkS")
		)
		(fp_line
			(start -0.508 -0.9398)
			(end 0.508 -0.9398)
			(stroke
				(width 0.1524)
				(type default)
			)
			(layer "B.SilkS")
		)
		(fp_rect
			(start 0.508 0.9398)
			(end -0.508 -0.9398)
			(stroke
				(width 0)
				(type default)
			)
			(fill no)
			(layer "B.CrtYd")
		)
		(fp_rect
			(start 0.508 0.9398)
			(end -0.508 -0.9398)
			(stroke
				(width 0)
				(type default)
			)
			(fill no)
			(layer "B.Fab")
		)
		(pad "1" smd custom
			(at 0 -0.4445)
			(size 0.1397 0.1397)
			(layers "B.Cu" "B.Mask" "B.Paste")
			(net "SSD_ATNLED#10")
			(options
				(clearance outline)
				(anchor circle)
			)
			(primitives
				(gr_poly
					(pts
						(arc
							(start -0.1778 0.2794)
							(mid -0.249642 0.249642)
							(end -0.2794 0.1778)
						)
						(arc
							(start -0.2794 -0.1778)
							(mid -0.249642 -0.249642)
							(end -0.1778 -0.2794)
						)
						(arc
							(start 0.1778 -0.2794)
							(mid 0.249642 -0.249642)
							(end 0.2794 -0.1778)
						)
						(arc
							(start 0.2794 0.1778)
							(mid 0.249642 0.249642)
							(end 0.1778 0.2794)
						)
					)
					(width 0)
					(fill yes)
				)
			)
		)
		(pad "2" smd custom
			(at 0 0.4445)
			(size 0.1397 0.1397)
			(layers "B.Cu" "B.Mask" "B.Paste")
			(net "P3V3_STBY")
			(options
				(clearance outline)
				(anchor circle)
			)
			(primitives
				(gr_poly
					(pts
						(arc
							(start -0.1778 0.2794)
							(mid -0.249642 0.249642)
							(end -0.2794 0.1778)
						)
						(arc
							(start -0.2794 -0.1778)
							(mid -0.249642 -0.249642)
							(end -0.1778 -0.2794)
						)
						(arc
							(start 0.1778 -0.2794)
							(mid 0.249642 -0.249642)
							(end 0.2794 -0.1778)
						)
						(arc
							(start 0.2794 0.1778)
							(mid 0.249642 0.249642)
							(end 0.1778 0.2794)
						)
					)
					(width 0)
					(fill yes)
				)
			)
		)
	)
	(footprint ""
		(layer "B.Cu")
		(at 261.62 -13.6906 180)
		(property "Reference" "Q40"
			(at 0 0 0)
			(layer "B.SilkS")
			(hide yes)
			(effects
				(font
					(size 1.27 1.27)
				)
				(justify mirror)
			)
		)
		(property "Value" "2N7002K-1-GP"
			(at -0.127 -8.9662 180)
			(unlocked yes)
			(layer "B.Fab")
			(hide yes)
			(effects
				(font
					(size 1.016 1.016)
					(thickness 0.1524)
				)
				(justify mirror)
			)
		)
		(property "Device Type" "SOT23DGS2D4H44"
			(at -0.127 -10.4902 180)
			(unlocked yes)
			(layer "B.Fab")
			(hide yes)
			(effects
				(font
					(size 1.016 1.016)
					(thickness 0.1524)
				)
				(justify mirror)
			)
		)
		(duplicate_pad_numbers_are_jumpers no)
		(fp_line
			(start 1.651 1.778)
			(end -1.651 1.778)
			(stroke
				(width 0.1524)
				(type default)
			)
			(layer "B.SilkS")
		)
		(fp_line
			(start 1.651 -1.778)
			(end 1.651 1.778)
			(stroke
				(width 0.1524)
				(type default)
			)
			(layer "B.SilkS")
		)
		(fp_line
			(start -1.651 1.778)
			(end -1.651 -1.778)
			(stroke
				(width 0.1524)
				(type default)
			)
			(layer "B.SilkS")
		)
		(fp_line
			(start -1.651 -1.778)
			(end 1.651 -1.778)
			(stroke
				(width 0.1524)
				(type default)
			)
			(layer "B.SilkS")
		)
		(fp_poly
			(pts
				(xy 1.778 1.8796) (xy 1.778 -1.8796) (xy -1.778 -1.8796) (xy -1.778 1.8796)
			)
			(stroke
				(width 0)
				(type default)
			)
			(fill no)
			(layer "B.CrtYd")
		)
		(fp_poly
			(pts
				(xy 1.778 1.8796) (xy 1.778 -1.8796) (xy -1.778 -1.8796) (xy -1.778 1.8796)
			)
			(stroke
				(width 0)
				(type default)
			)
			(fill no)
			(layer "B.Fab")
		)
		(pad "D" smd custom
			(at 0 -0.9525)
			(size 0.1905 0.1905)
			(layers "B.Cu" "B.Mask" "B.Paste")
			(net "Q40_D")
			(options
				(clearance outline)
				(anchor circle)
			)
			(primitives
				(gr_poly
					(pts
						(arc
							(start -0.1778 -0.5715)
							(mid -0.321484 -0.511984)
							(end -0.381 -0.3683)
						)
						(arc
							(start -0.381 0.3683)
							(mid -0.321484 0.511984)
							(end -0.1778 0.5715)
						)
						(arc
							(start 0.1778 0.5715)
							(mid 0.321484 0.511984)
							(end 0.381 0.3683)
						)
						(arc
							(start 0.381 -0.3683)
							(mid 0.321484 -0.511984)
							(end 0.1778 -0.5715)
						)
					)
					(width 0)
					(fill yes)
				)
			)
		)
		(pad "G" smd custom
			(at 0.98425 0.9525)
			(size 0.1905 0.1905)
			(layers "B.Cu" "B.Mask" "B.Paste")
			(net "PWRGD_P1V8_STBY")
			(options
				(clearance outline)
				(anchor circle)
			)
			(primitives
				(gr_poly
					(pts
						(arc
							(start -0.1778 -0.5715)
							(mid -0.321484 -0.511984)
							(end -0.381 -0.3683)
						)
						(arc
							(start -0.381 0.3683)
							(mid -0.321484 0.511984)
							(end -0.1778 0.5715)
						)
						(arc
							(start 0.1778 0.5715)
							(mid 0.321484 0.511984)
							(end 0.381 0.3683)
						)
						(arc
							(start 0.381 -0.3683)
							(mid 0.321484 -0.511984)
							(end 0.1778 -0.5715)
						)
					)
					(width 0)
					(fill yes)
				)
			)
		)
		(pad "S" smd custom
			(at -0.98425 0.9525)
			(size 0.1905 0.1905)
			(layers "B.Cu" "B.Mask" "B.Paste")
			(net "GND")
			(options
				(clearance outline)
				(anchor circle)
			)
			(primitives
				(gr_poly
					(pts
						(arc
							(start -0.1778 -0.5715)
							(mid -0.321484 -0.511984)
							(end -0.381 -0.3683)
						)
						(arc
							(start -0.381 0.3683)
							(mid -0.321484 0.511984)
							(end -0.1778 0.5715)
						)
						(arc
							(start 0.1778 0.5715)
							(mid 0.321484 0.511984)
							(end 0.381 0.3683)
						)
						(arc
							(start 0.381 -0.3683)
							(mid 0.321484 -0.511984)
							(end 0.1778 -0.5715)
						)
					)
					(width 0)
					(fill yes)
				)
			)
		)
	)
	(footprint ""
		(layer "B.Cu")
		(at 128.696212 -205.849474)
		(property "Reference" "R3204"
			(at 0 0 0)
			(layer "B.SilkS")
			(hide yes)
			(effects
				(font
					(size 1.27 1.27)
				)
				(justify mirror)
			)
		)
		(property "Value" "0R2J-2-GP"
			(at -0.064008 -3.993896 0)
			(unlocked yes)
			(layer "B.Fab")
			(hide yes)
			(effects
				(font
					(size 1.016 1.016)
					(thickness 0.1524)
				)
				(justify mirror)
			)
		)
		(property "Device Type" "R402H16"
			(at -0.064008 -5.517896 0)
			(unlocked yes)
			(layer "B.Fab")
			(hide yes)
			(effects
				(font
					(size 1.016 1.016)
					(thickness 0.1524)
				)
				(justify mirror)
			)
		)
		(duplicate_pad_numbers_are_jumpers no)
		(fp_line
			(start -0.508 -0.9398)
			(end 0.508 -0.9398)
			(stroke
				(width 0.1524)
				(type default)
			)
			(layer "B.SilkS")
		)
		(fp_line
			(start 0.508 -0.9398)
			(end 0.508 0.9398)
			(stroke
				(width 0.1524)
				(type default)
			)
			(layer "B.SilkS")
		)
		(fp_rect
			(start 0.508 0.9398)
			(end -0.508 -0.9398)
			(stroke
				(width 0)
				(type default)
			)
			(fill no)
			(layer "B.CrtYd")
		)
		(fp_rect
			(start 0.508 0.9398)
			(end -0.508 -0.9398)
			(stroke
				(width 0)
				(type default)
			)
			(fill no)
			(layer "B.Fab")
		)
		(pad "1" smd custom
			(at 0 -0.4445 180)
			(size 0.1397 0.1397)
			(layers "B.Cu" "B.Mask" "B.Paste")
			(net "SSD_PERST#1")
			(options
				(clearance outline)
				(anchor circle)
			)
			(primitives
				(gr_poly
					(pts
						(arc
							(start -0.1778 0.2794)
							(mid -0.249642 0.249642)
							(end -0.2794 0.1778)
						)
						(arc
							(start -0.2794 -0.1778)
							(mid -0.249642 -0.249642)
							(end -0.1778 -0.2794)
						)
						(arc
							(start 0.1778 -0.2794)
							(mid 0.249642 -0.249642)
							(end 0.2794 -0.1778)
						)
						(arc
							(start 0.2794 0.1778)
							(mid 0.249642 0.249642)
							(end 0.1778 0.2794)
						)
					)
					(width 0)
					(fill yes)
				)
			)
		)
		(pad "2" smd custom
			(at 0 0.4445 180)
			(size 0.1397 0.1397)
			(layers "B.Cu" "B.Mask" "B.Paste")
			(net "SSD_PERST#0_B1")
			(options
				(clearance outline)
				(anchor circle)
			)
			(primitives
				(gr_poly
					(pts
						(arc
							(start -0.1778 0.2794)
							(mid -0.249642 0.249642)
							(end -0.2794 0.1778)
						)
						(arc
							(start -0.2794 -0.1778)
							(mid -0.249642 -0.249642)
							(end -0.1778 -0.2794)
						)
						(arc
							(start 0.1778 -0.2794)
							(mid 0.249642 -0.249642)
							(end 0.2794 -0.1778)
						)
						(arc
							(start 0.2794 0.1778)
							(mid 0.249642 0.249642)
							(end 0.1778 0.2794)
						)
					)
					(width 0)
					(fill yes)
				)
			)
		)
	)
	(footprint ""
		(layer "B.Cu")
		(at 255.831848 -9.123426 -90)
		(property "Reference" "C151"
			(at 0 0 90)
			(layer "B.SilkS")
			(hide yes)
			(effects
				(font
					(size 1.27 1.27)
				)
				(justify mirror)
			)
		)
		(property "Value" "SCD1U16V2KX-3GP"
			(at -1.1811 -2.7051 270)
			(unlocked yes)
			(layer "B.Fab")
			(hide yes)
			(effects
				(font
					(size 1.016 1.016)
					(thickness 0.1524)
				)
				(justify mirror)
			)
		)
		(property "Device Type" "C402H22"
			(at -1.1811 -4.2291 270)
			(unlocked yes)
			(layer "B.Fab")
			(hide yes)
			(effects
				(font
					(size 1.016 1.016)
					(thickness 0.1524)
				)
				(justify mirror)
			)
		)
		(duplicate_pad_numbers_are_jumpers no)
		(fp_rect
			(start 0.4318 0.9525)
			(end -0.4318 -0.9525)
			(stroke
				(width 0)
				(type default)
			)
			(fill no)
			(layer "B.CrtYd")
		)
		(fp_rect
			(start 0.4318 0.9525)
			(end -0.4318 -0.9525)
			(stroke
				(width 0)
				(type default)
			)
			(fill no)
			(layer "B.Fab")
		)
		(pad "1" smd custom
			(at 0 -0.4445 90)
			(size 0.1524 0.1524)
			(layers "B.Cu" "B.Mask" "B.Paste")
			(net "P3V3_STBY")
			(options
				(clearance outline)
				(anchor circle)
			)
			(primitives
				(gr_poly
					(pts
						(arc
							(start 0.3048 0.2032)
							(mid 0.275042 0.275042)
							(end 0.2032 0.3048)
						)
						(arc
							(start -0.2032 0.3048)
							(mid -0.275042 0.275042)
							(end -0.3048 0.2032)
						)
						(arc
							(start -0.3048 -0.2032)
							(mid -0.275042 -0.275042)
							(end -0.2032 -0.3048)
						)
						(arc
							(start 0.2032 -0.3048)
							(mid 0.275042 -0.275042)
							(end 0.3048 -0.2032)
						)
					)
					(width 0)
					(fill yes)
				)
			)
		)
		(pad "2" smd custom
			(at 0 0.4445 90)
			(size 0.1524 0.1524)
			(layers "B.Cu" "B.Mask" "B.Paste")
			(net "GND")
			(options
				(clearance outline)
				(anchor circle)
			)
			(primitives
				(gr_poly
					(pts
						(arc
							(start 0.3048 0.2032)
							(mid 0.275042 0.275042)
							(end 0.2032 0.3048)
						)
						(arc
							(start -0.2032 0.3048)
							(mid -0.275042 0.275042)
							(end -0.3048 0.2032)
						)
						(arc
							(start -0.3048 -0.2032)
							(mid -0.275042 -0.275042)
							(end -0.2032 -0.3048)
						)
						(arc
							(start 0.2032 -0.3048)
							(mid 0.275042 -0.275042)
							(end 0.3048 -0.2032)
						)
					)
					(width 0)
					(fill yes)
				)
			)
		)
	)
	(footprint ""
		(layer "B.Cu")
		(at 182.13578 -7.5438 -90)
		(property "Reference" "R2952"
			(at 0 0 90)
			(layer "B.SilkS")
			(hide yes)
			(effects
				(font
					(size 1.27 1.27)
				)
				(justify mirror)
			)
		)
		(property "Value" "0R2J-2-GP"
			(at -0.064008 -3.993896 270)
			(unlocked yes)
			(layer "B.Fab")
			(hide yes)
			(effects
				(font
					(size 1.016 1.016)
					(thickness 0.1524)
				)
				(justify mirror)
			)
		)
		(property "Device Type" "R402H16"
			(at -0.064008 -5.517896 270)
			(unlocked yes)
			(layer "B.Fab")
			(hide yes)
			(effects
				(font
					(size 1.016 1.016)
					(thickness 0.1524)
				)
				(justify mirror)
			)
		)
		(duplicate_pad_numbers_are_jumpers no)
		(fp_line
			(start -0.508 -0.9398)
			(end 0.508 -0.9398)
			(stroke
				(width 0.1524)
				(type default)
			)
			(layer "B.SilkS")
		)
		(fp_line
			(start 0.508 -0.9398)
			(end 0.508 0.9398)
			(stroke
				(width 0.1524)
				(type default)
			)
			(layer "B.SilkS")
		)
		(fp_rect
			(start 0.508 0.9398)
			(end -0.508 -0.9398)
			(stroke
				(width 0)
				(type default)
			)
			(fill no)
			(layer "B.CrtYd")
		)
		(fp_rect
			(start 0.508 0.9398)
			(end -0.508 -0.9398)
			(stroke
				(width 0)
				(type default)
			)
			(fill no)
			(layer "B.Fab")
		)
		(pad "1" smd custom
			(at 0 -0.4445 90)
			(size 0.1397 0.1397)
			(layers "B.Cu" "B.Mask" "B.Paste")
			(net "PCIE_REFCLK_H2_N")
			(options
				(clearance outline)
				(anchor circle)
			)
			(primitives
				(gr_poly
					(pts
						(arc
							(start -0.1778 0.2794)
							(mid -0.249642 0.249642)
							(end -0.2794 0.1778)
						)
						(arc
							(start -0.2794 -0.1778)
							(mid -0.249642 -0.249642)
							(end -0.1778 -0.2794)
						)
						(arc
							(start 0.1778 -0.2794)
							(mid 0.249642 -0.249642)
							(end 0.2794 -0.1778)
						)
						(arc
							(start 0.2794 0.1778)
							(mid 0.249642 0.249642)
							(end 0.1778 0.2794)
						)
					)
					(width 0)
					(fill yes)
				)
			)
		)
		(pad "2" smd custom
			(at 0 0.4445 90)
			(size 0.1397 0.1397)
			(layers "B.Cu" "B.Mask" "B.Paste")
			(net "PCIE_REFCLK_H2_N_R")
			(options
				(clearance outline)
				(anchor circle)
			)
			(primitives
				(gr_poly
					(pts
						(arc
							(start -0.1778 0.2794)
							(mid -0.249642 0.249642)
							(end -0.2794 0.1778)
						)
						(arc
							(start -0.2794 -0.1778)
							(mid -0.249642 -0.249642)
							(end -0.1778 -0.2794)
						)
						(arc
							(start 0.1778 -0.2794)
							(mid 0.249642 -0.249642)
							(end 0.2794 -0.1778)
						)
						(arc
							(start 0.2794 0.1778)
							(mid 0.249642 0.249642)
							(end 0.1778 0.2794)
						)
					)
					(width 0)
					(fill yes)
				)
			)
		)
	)
	(footprint ""
		(layer "B.Cu")
		(at 251.587 -42.0116 -90)
		(property "Reference" "C588"
			(at 0 0 90)
			(layer "B.SilkS")
			(hide yes)
			(effects
				(font
					(size 1.27 1.27)
				)
				(justify mirror)
			)
		)
		(property "Value" "SCD1U16V1KX-1-GP"
			(at 2.8321 -1.7399 270)
			(unlocked yes)
			(layer "B.Fab")
			(hide yes)
			(effects
				(font
					(size 1.016 1.016)
					(thickness 0.1524)
				)
				(justify mirror)
			)
		)
		(property "Device Type" "C0201H13"
			(at 2.8321 -3.2639 270)
			(unlocked yes)
			(layer "B.Fab")
			(hide yes)
			(effects
				(font
					(size 1.016 1.016)
					(thickness 0.1524)
				)
				(justify mirror)
			)
		)
		(duplicate_pad_numbers_are_jumpers no)
		(fp_rect
			(start 0.2794 0.6477)
			(end -0.2794 -0.6477)
			(stroke
				(width 0)
				(type default)
			)
			(fill no)
			(layer "B.CrtYd")
		)
		(fp_rect
			(start 0.2794 0.6477)
			(end -0.2794 -0.6477)
			(stroke
				(width 0)
				(type default)
			)
			(fill no)
			(layer "B.Fab")
		)
		(pad "1" smd custom
			(at 0 -0.2794 90)
			(size 0.0762 0.0762)
			(layers "B.Cu" "B.Mask" "B.Paste")
			(net "DUT_AVD_PCIE")
			(options
				(clearance outline)
				(anchor circle)
			)
			(primitives
				(gr_poly
					(pts
						(arc
							(start 0.1524 0.127)
							(mid 0.137521 0.162921)
							(end 0.1016 0.1778)
						)
						(arc
							(start -0.1016 0.1778)
							(mid -0.137521 0.162921)
							(end -0.1524 0.127)
						)
						(arc
							(start -0.1524 -0.127)
							(mid -0.137521 -0.162921)
							(end -0.1016 -0.1778)
						)
						(arc
							(start 0.1016 -0.1778)
							(mid 0.137521 -0.162921)
							(end 0.1524 -0.127)
						)
					)
					(width 0)
					(fill yes)
				)
			)
		)
		(pad "2" smd custom
			(at 0 0.2794 90)
			(size 0.0762 0.0762)
			(layers "B.Cu" "B.Mask" "B.Paste")
			(net "GND")
			(options
				(clearance outline)
				(anchor circle)
			)
			(primitives
				(gr_poly
					(pts
						(arc
							(start 0.1524 0.127)
							(mid 0.137521 0.162921)
							(end 0.1016 0.1778)
						)
						(arc
							(start -0.1016 0.1778)
							(mid -0.137521 0.162921)
							(end -0.1524 0.127)
						)
						(arc
							(start -0.1524 -0.127)
							(mid -0.137521 -0.162921)
							(end -0.1016 -0.1778)
						)
						(arc
							(start 0.1016 -0.1778)
							(mid 0.137521 -0.162921)
							(end 0.1524 -0.127)
						)
					)
					(width 0)
					(fill yes)
				)
			)
		)
	)
	(footprint ""
		(layer "B.Cu")
		(at 13.462 -78.0034 90)
		(property "Reference" "C635"
			(at 0 0 90)
			(layer "B.SilkS")
			(hide yes)
			(effects
				(font
					(size 1.27 1.27)
				)
				(justify mirror)
			)
		)
		(property "Value" "SCD1U16V2KX-3GP"
			(at -1.1811 -2.7051 90)
			(unlocked yes)
			(layer "B.Fab")
			(hide yes)
			(effects
				(font
					(size 1.016 1.016)
					(thickness 0.1524)
				)
				(justify mirror)
			)
		)
		(property "Device Type" "C402H22"
			(at -1.1811 -4.2291 90)
			(unlocked yes)
			(layer "B.Fab")
			(hide yes)
			(effects
				(font
					(size 1.016 1.016)
					(thickness 0.1524)
				)
				(justify mirror)
			)
		)
		(duplicate_pad_numbers_are_jumpers no)
		(fp_rect
			(start 0.4318 0.9525)
			(end -0.4318 -0.9525)
			(stroke
				(width 0)
				(type default)
			)
			(fill no)
			(layer "B.CrtYd")
		)
		(fp_rect
			(start 0.4318 0.9525)
			(end -0.4318 -0.9525)
			(stroke
				(width 0)
				(type default)
			)
			(fill no)
			(layer "B.Fab")
		)
		(pad "1" smd custom
			(at 0 -0.4445 270)
			(size 0.1524 0.1524)
			(layers "B.Cu" "B.Mask" "B.Paste")
			(net "P0V9_I210")
			(options
				(clearance outline)
				(anchor circle)
			)
			(primitives
				(gr_poly
					(pts
						(arc
							(start 0.3048 0.2032)
							(mid 0.275042 0.275042)
							(end 0.2032 0.3048)
						)
						(arc
							(start -0.2032 0.3048)
							(mid -0.275042 0.275042)
							(end -0.3048 0.2032)
						)
						(arc
							(start -0.3048 -0.2032)
							(mid -0.275042 -0.275042)
							(end -0.2032 -0.3048)
						)
						(arc
							(start 0.2032 -0.3048)
							(mid 0.275042 -0.275042)
							(end 0.3048 -0.2032)
						)
					)
					(width 0)
					(fill yes)
				)
			)
		)
		(pad "2" smd custom
			(at 0 0.4445 270)
			(size 0.1524 0.1524)
			(layers "B.Cu" "B.Mask" "B.Paste")
			(net "GND")
			(options
				(clearance outline)
				(anchor circle)
			)
			(primitives
				(gr_poly
					(pts
						(arc
							(start 0.3048 0.2032)
							(mid 0.275042 0.275042)
							(end 0.2032 0.3048)
						)
						(arc
							(start -0.2032 0.3048)
							(mid -0.275042 0.275042)
							(end -0.3048 0.2032)
						)
						(arc
							(start -0.3048 -0.2032)
							(mid -0.275042 -0.275042)
							(end -0.2032 -0.3048)
						)
						(arc
							(start 0.2032 -0.3048)
							(mid 0.275042 -0.275042)
							(end 0.3048 -0.2032)
						)
					)
					(width 0)
					(fill yes)
				)
			)
		)
	)
	(footprint ""
		(layer "B.Cu")
		(at 229.049072 -41.012872 90)
		(property "Reference" "C576"
			(at 0 0 90)
			(layer "B.SilkS")
			(hide yes)
			(effects
				(font
					(size 1.27 1.27)
				)
				(justify mirror)
			)
		)
		(property "Value" "SCD1U16V1KX-1-GP"
			(at 2.8321 -1.7399 90)
			(unlocked yes)
			(layer "B.Fab")
			(hide yes)
			(effects
				(font
					(size 1.016 1.016)
					(thickness 0.1524)
				)
				(justify mirror)
			)
		)
		(property "Device Type" "C0201H13"
			(at 2.8321 -3.2639 90)
			(unlocked yes)
			(layer "B.Fab")
			(hide yes)
			(effects
				(font
					(size 1.016 1.016)
					(thickness 0.1524)
				)
				(justify mirror)
			)
		)
		(duplicate_pad_numbers_are_jumpers no)
		(fp_rect
			(start 0.2794 0.6477)
			(end -0.2794 -0.6477)
			(stroke
				(width 0)
				(type default)
			)
			(fill no)
			(layer "B.CrtYd")
		)
		(fp_rect
			(start 0.2794 0.6477)
			(end -0.2794 -0.6477)
			(stroke
				(width 0)
				(type default)
			)
			(fill no)
			(layer "B.Fab")
		)
		(pad "1" smd custom
			(at 0 -0.2794 270)
			(size 0.0762 0.0762)
			(layers "B.Cu" "B.Mask" "B.Paste")
			(net "DUT_AVD_PCIE")
			(options
				(clearance outline)
				(anchor circle)
			)
			(primitives
				(gr_poly
					(pts
						(arc
							(start 0.1524 0.127)
							(mid 0.137521 0.162921)
							(end 0.1016 0.1778)
						)
						(arc
							(start -0.1016 0.1778)
							(mid -0.137521 0.162921)
							(end -0.1524 0.127)
						)
						(arc
							(start -0.1524 -0.127)
							(mid -0.137521 -0.162921)
							(end -0.1016 -0.1778)
						)
						(arc
							(start 0.1016 -0.1778)
							(mid 0.137521 -0.162921)
							(end 0.1524 -0.127)
						)
					)
					(width 0)
					(fill yes)
				)
			)
		)
		(pad "2" smd custom
			(at 0 0.2794 270)
			(size 0.0762 0.0762)
			(layers "B.Cu" "B.Mask" "B.Paste")
			(net "GND")
			(options
				(clearance outline)
				(anchor circle)
			)
			(primitives
				(gr_poly
					(pts
						(arc
							(start 0.1524 0.127)
							(mid 0.137521 0.162921)
							(end 0.1016 0.1778)
						)
						(arc
							(start -0.1016 0.1778)
							(mid -0.137521 0.162921)
							(end -0.1524 0.127)
						)
						(arc
							(start -0.1524 -0.127)
							(mid -0.137521 -0.162921)
							(end -0.1016 -0.1778)
						)
						(arc
							(start 0.1016 -0.1778)
							(mid 0.137521 -0.162921)
							(end 0.1524 -0.127)
						)
					)
					(width 0)
					(fill yes)
				)
			)
		)
	)
	(footprint ""
		(layer "B.Cu")
		(at 245.1354 -51.9938 90)
		(property "Reference" "C443"
			(at 0 0 90)
			(layer "B.SilkS")
			(hide yes)
			(effects
				(font
					(size 1.27 1.27)
				)
				(justify mirror)
			)
		)
		(property "Value" "SCD1U16V1KX-1-GP"
			(at 2.8321 -1.7399 90)
			(unlocked yes)
			(layer "B.Fab")
			(hide yes)
			(effects
				(font
					(size 1.016 1.016)
					(thickness 0.1524)
				)
				(justify mirror)
			)
		)
		(property "Device Type" "C0201H13"
			(at 2.8321 -3.2639 90)
			(unlocked yes)
			(layer "B.Fab")
			(hide yes)
			(effects
				(font
					(size 1.016 1.016)
					(thickness 0.1524)
				)
				(justify mirror)
			)
		)
		(duplicate_pad_numbers_are_jumpers no)
		(fp_rect
			(start 0.2794 0.6477)
			(end -0.2794 -0.6477)
			(stroke
				(width 0)
				(type default)
			)
			(fill no)
			(layer "B.CrtYd")
		)
		(fp_rect
			(start 0.2794 0.6477)
			(end -0.2794 -0.6477)
			(stroke
				(width 0)
				(type default)
			)
			(fill no)
			(layer "B.Fab")
		)
		(pad "1" smd custom
			(at 0 -0.2794 270)
			(size 0.0762 0.0762)
			(layers "B.Cu" "B.Mask" "B.Paste")
			(net "DUT_VDD")
			(options
				(clearance outline)
				(anchor circle)
			)
			(primitives
				(gr_poly
					(pts
						(arc
							(start 0.1524 0.127)
							(mid 0.137521 0.162921)
							(end 0.1016 0.1778)
						)
						(arc
							(start -0.1016 0.1778)
							(mid -0.137521 0.162921)
							(end -0.1524 0.127)
						)
						(arc
							(start -0.1524 -0.127)
							(mid -0.137521 -0.162921)
							(end -0.1016 -0.1778)
						)
						(arc
							(start 0.1016 -0.1778)
							(mid 0.137521 -0.162921)
							(end 0.1524 -0.127)
						)
					)
					(width 0)
					(fill yes)
				)
			)
		)
		(pad "2" smd custom
			(at 0 0.2794 270)
			(size 0.0762 0.0762)
			(layers "B.Cu" "B.Mask" "B.Paste")
			(net "GND")
			(options
				(clearance outline)
				(anchor circle)
			)
			(primitives
				(gr_poly
					(pts
						(arc
							(start 0.1524 0.127)
							(mid 0.137521 0.162921)
							(end 0.1016 0.1778)
						)
						(arc
							(start -0.1016 0.1778)
							(mid -0.137521 0.162921)
							(end -0.1524 0.127)
						)
						(arc
							(start -0.1524 -0.127)
							(mid -0.137521 -0.162921)
							(end -0.1016 -0.1778)
						)
						(arc
							(start 0.1016 -0.1778)
							(mid 0.137521 -0.162921)
							(end 0.1524 -0.127)
						)
					)
					(width 0)
					(fill yes)
				)
			)
		)
	)
	(footprint ""
		(layer "B.Cu")
		(at 61.341 -122.428 -90)
		(property "Reference" "R599"
			(at 0 0 90)
			(layer "B.SilkS")
			(hide yes)
			(effects
				(font
					(size 1.27 1.27)
				)
				(justify mirror)
			)
		)
		(property "Value" "4K7R2F-GP"
			(at -0.064008 -3.993896 270)
			(unlocked yes)
			(layer "B.Fab")
			(hide yes)
			(effects
				(font
					(size 1.016 1.016)
					(thickness 0.1524)
				)
				(justify mirror)
			)
		)
		(property "Device Type" "R402H16"
			(at -0.064008 -5.517896 270)
			(unlocked yes)
			(layer "B.Fab")
			(hide yes)
			(effects
				(font
					(size 1.016 1.016)
					(thickness 0.1524)
				)
				(justify mirror)
			)
		)
		(duplicate_pad_numbers_are_jumpers no)
		(fp_line
			(start -0.508 -0.9398)
			(end 0.508 -0.9398)
			(stroke
				(width 0.1524)
				(type default)
			)
			(layer "B.SilkS")
		)
		(fp_line
			(start 0.508 -0.9398)
			(end 0.508 0.9398)
			(stroke
				(width 0.1524)
				(type default)
			)
			(layer "B.SilkS")
		)
		(fp_rect
			(start 0.508 0.9398)
			(end -0.508 -0.9398)
			(stroke
				(width 0)
				(type default)
			)
			(fill no)
			(layer "B.CrtYd")
		)
		(fp_rect
			(start 0.508 0.9398)
			(end -0.508 -0.9398)
			(stroke
				(width 0)
				(type default)
			)
			(fill no)
			(layer "B.Fab")
		)
		(pad "1" smd custom
			(at 0 -0.4445 90)
			(size 0.1397 0.1397)
			(layers "B.Cu" "B.Mask" "B.Paste")
			(net "BMC_I2C4_MINI4_SDA_S")
			(options
				(clearance outline)
				(anchor circle)
			)
			(primitives
				(gr_poly
					(pts
						(arc
							(start -0.1778 0.2794)
							(mid -0.249642 0.249642)
							(end -0.2794 0.1778)
						)
						(arc
							(start -0.2794 -0.1778)
							(mid -0.249642 -0.249642)
							(end -0.1778 -0.2794)
						)
						(arc
							(start 0.1778 -0.2794)
							(mid 0.249642 -0.249642)
							(end 0.2794 -0.1778)
						)
						(arc
							(start 0.2794 0.1778)
							(mid 0.249642 0.249642)
							(end 0.1778 0.2794)
						)
					)
					(width 0)
					(fill yes)
				)
			)
		)
		(pad "2" smd custom
			(at 0 0.4445 90)
			(size 0.1397 0.1397)
			(layers "B.Cu" "B.Mask" "B.Paste")
			(net "P3V3_STBY")
			(options
				(clearance outline)
				(anchor circle)
			)
			(primitives
				(gr_poly
					(pts
						(arc
							(start -0.1778 0.2794)
							(mid -0.249642 0.249642)
							(end -0.2794 0.1778)
						)
						(arc
							(start -0.2794 -0.1778)
							(mid -0.249642 -0.249642)
							(end -0.1778 -0.2794)
						)
						(arc
							(start 0.1778 -0.2794)
							(mid 0.249642 -0.249642)
							(end 0.2794 -0.1778)
						)
						(arc
							(start 0.2794 0.1778)
							(mid 0.249642 0.249642)
							(end 0.1778 0.2794)
						)
					)
					(width 0)
					(fill yes)
				)
			)
		)
	)
	(footprint ""
		(layer "B.Cu")
		(at 75.102212 -186.545474)
		(property "Reference" "R3203"
			(at 0 0 0)
			(layer "B.SilkS")
			(hide yes)
			(effects
				(font
					(size 1.27 1.27)
				)
				(justify mirror)
			)
		)
		(property "Value" "0R2J-2-GP"
			(at -0.064008 -3.993896 0)
			(unlocked yes)
			(layer "B.Fab")
			(hide yes)
			(effects
				(font
					(size 1.016 1.016)
					(thickness 0.1524)
				)
				(justify mirror)
			)
		)
		(property "Device Type" "R402H16"
			(at -0.064008 -5.517896 0)
			(unlocked yes)
			(layer "B.Fab")
			(hide yes)
			(effects
				(font
					(size 1.016 1.016)
					(thickness 0.1524)
				)
				(justify mirror)
			)
		)
		(duplicate_pad_numbers_are_jumpers no)
		(fp_line
			(start -0.508 -0.9398)
			(end 0.508 -0.9398)
			(stroke
				(width 0.1524)
				(type default)
			)
			(layer "B.SilkS")
		)
		(fp_line
			(start 0.508 -0.9398)
			(end 0.508 0.9398)
			(stroke
				(width 0.1524)
				(type default)
			)
			(layer "B.SilkS")
		)
		(fp_rect
			(start 0.508 0.9398)
			(end -0.508 -0.9398)
			(stroke
				(width 0)
				(type default)
			)
			(fill no)
			(layer "B.CrtYd")
		)
		(fp_rect
			(start 0.508 0.9398)
			(end -0.508 -0.9398)
			(stroke
				(width 0)
				(type default)
			)
			(fill no)
			(layer "B.Fab")
		)
		(pad "1" smd custom
			(at 0 -0.4445 180)
			(size 0.1397 0.1397)
			(layers "B.Cu" "B.Mask" "B.Paste")
			(net "SSD_PERST_Y0")
			(options
				(clearance outline)
				(anchor circle)
			)
			(primitives
				(gr_poly
					(pts
						(arc
							(start -0.1778 0.2794)
							(mid -0.249642 0.249642)
							(end -0.2794 0.1778)
						)
						(arc
							(start -0.2794 -0.1778)
							(mid -0.249642 -0.249642)
							(end -0.1778 -0.2794)
						)
						(arc
							(start 0.1778 -0.2794)
							(mid 0.249642 -0.249642)
							(end 0.2794 -0.1778)
						)
						(arc
							(start 0.2794 0.1778)
							(mid 0.249642 0.249642)
							(end 0.1778 0.2794)
						)
					)
					(width 0)
					(fill yes)
				)
			)
		)
		(pad "2" smd custom
			(at 0 0.4445 180)
			(size 0.1397 0.1397)
			(layers "B.Cu" "B.Mask" "B.Paste")
			(net "SSD_PERST#0_R")
			(options
				(clearance outline)
				(anchor circle)
			)
			(primitives
				(gr_poly
					(pts
						(arc
							(start -0.1778 0.2794)
							(mid -0.249642 0.249642)
							(end -0.2794 0.1778)
						)
						(arc
							(start -0.2794 -0.1778)
							(mid -0.249642 -0.249642)
							(end -0.1778 -0.2794)
						)
						(arc
							(start 0.1778 -0.2794)
							(mid 0.249642 -0.249642)
							(end 0.2794 -0.1778)
						)
						(arc
							(start 0.2794 0.1778)
							(mid 0.249642 0.249642)
							(end 0.1778 0.2794)
						)
					)
					(width 0)
					(fill yes)
				)
			)
		)
	)
	(footprint ""
		(layer "B.Cu")
		(at 51.689 -195.58 180)
		(property "Reference" "R891"
			(at 0 0 0)
			(layer "B.SilkS")
			(hide yes)
			(effects
				(font
					(size 1.27 1.27)
				)
				(justify mirror)
			)
		)
		(property "Value" "0R2J-2-GP"
			(at -0.064008 -3.993896 180)
			(unlocked yes)
			(layer "B.Fab")
			(hide yes)
			(effects
				(font
					(size 1.016 1.016)
					(thickness 0.1524)
				)
				(justify mirror)
			)
		)
		(property "Device Type" "R402H16"
			(at -0.064008 -5.517896 180)
			(unlocked yes)
			(layer "B.Fab")
			(hide yes)
			(effects
				(font
					(size 1.016 1.016)
					(thickness 0.1524)
				)
				(justify mirror)
			)
		)
		(duplicate_pad_numbers_are_jumpers no)
		(fp_line
			(start 0.508 -0.9398)
			(end 0.508 0.9398)
			(stroke
				(width 0.1524)
				(type default)
			)
			(layer "B.SilkS")
		)
		(fp_line
			(start -0.508 -0.9398)
			(end 0.508 -0.9398)
			(stroke
				(width 0.1524)
				(type default)
			)
			(layer "B.SilkS")
		)
		(fp_rect
			(start 0.508 0.9398)
			(end -0.508 -0.9398)
			(stroke
				(width 0)
				(type default)
			)
			(fill no)
			(layer "B.CrtYd")
		)
		(fp_rect
			(start 0.508 0.9398)
			(end -0.508 -0.9398)
			(stroke
				(width 0)
				(type default)
			)
			(fill no)
			(layer "B.Fab")
		)
		(pad "1" smd custom
			(at 0 -0.4445)
			(size 0.1397 0.1397)
			(layers "B.Cu" "B.Mask" "B.Paste")
			(net "BMC_I2C7_B_DBP_SCL")
			(options
				(clearance outline)
				(anchor circle)
			)
			(primitives
				(gr_poly
					(pts
						(arc
							(start -0.1778 0.2794)
							(mid -0.249642 0.249642)
							(end -0.2794 0.1778)
						)
						(arc
							(start -0.2794 -0.1778)
							(mid -0.249642 -0.249642)
							(end -0.1778 -0.2794)
						)
						(arc
							(start 0.1778 -0.2794)
							(mid 0.249642 -0.249642)
							(end 0.2794 -0.1778)
						)
						(arc
							(start 0.2794 0.1778)
							(mid 0.249642 0.249642)
							(end 0.1778 0.2794)
						)
					)
					(width 0)
					(fill yes)
				)
			)
		)
		(pad "2" smd custom
			(at 0 0.4445)
			(size 0.1397 0.1397)
			(layers "B.Cu" "B.Mask" "B.Paste")
			(net "BUF_I2C7_B_DBP_SCL")
			(options
				(clearance outline)
				(anchor circle)
			)
			(primitives
				(gr_poly
					(pts
						(arc
							(start -0.1778 0.2794)
							(mid -0.249642 0.249642)
							(end -0.2794 0.1778)
						)
						(arc
							(start -0.2794 -0.1778)
							(mid -0.249642 -0.249642)
							(end -0.1778 -0.2794)
						)
						(arc
							(start 0.1778 -0.2794)
							(mid 0.249642 -0.249642)
							(end 0.2794 -0.1778)
						)
						(arc
							(start 0.2794 0.1778)
							(mid 0.249642 0.249642)
							(end 0.1778 0.2794)
						)
					)
					(width 0)
					(fill yes)
				)
			)
		)
	)
	(footprint ""
		(layer "B.Cu")
		(at 233.6038 -60.1218)
		(property "Reference" "C598"
			(at 0 0 0)
			(layer "B.SilkS")
			(hide yes)
			(effects
				(font
					(size 1.27 1.27)
				)
				(justify mirror)
			)
		)
		(property "Value" "SCD1U16V1KX-1-GP"
			(at 2.8321 -1.7399 0)
			(unlocked yes)
			(layer "B.Fab")
			(hide yes)
			(effects
				(font
					(size 1.016 1.016)
					(thickness 0.1524)
				)
				(justify mirror)
			)
		)
		(property "Device Type" "C0201H13"
			(at 2.8321 -3.2639 0)
			(unlocked yes)
			(layer "B.Fab")
			(hide yes)
			(effects
				(font
					(size 1.016 1.016)
					(thickness 0.1524)
				)
				(justify mirror)
			)
		)
		(duplicate_pad_numbers_are_jumpers no)
		(fp_rect
			(start 0.2794 0.6477)
			(end -0.2794 -0.6477)
			(stroke
				(width 0)
				(type default)
			)
			(fill no)
			(layer "B.CrtYd")
		)
		(fp_rect
			(start 0.2794 0.6477)
			(end -0.2794 -0.6477)
			(stroke
				(width 0)
				(type default)
			)
			(fill no)
			(layer "B.Fab")
		)
		(pad "1" smd custom
			(at 0 -0.2794 180)
			(size 0.0762 0.0762)
			(layers "B.Cu" "B.Mask" "B.Paste")
			(net "DUT_AVD_PCIE")
			(options
				(clearance outline)
				(anchor circle)
			)
			(primitives
				(gr_poly
					(pts
						(arc
							(start 0.1524 0.127)
							(mid 0.137521 0.162921)
							(end 0.1016 0.1778)
						)
						(arc
							(start -0.1016 0.1778)
							(mid -0.137521 0.162921)
							(end -0.1524 0.127)
						)
						(arc
							(start -0.1524 -0.127)
							(mid -0.137521 -0.162921)
							(end -0.1016 -0.1778)
						)
						(arc
							(start 0.1016 -0.1778)
							(mid 0.137521 -0.162921)
							(end 0.1524 -0.127)
						)
					)
					(width 0)
					(fill yes)
				)
			)
		)
		(pad "2" smd custom
			(at 0 0.2794 180)
			(size 0.0762 0.0762)
			(layers "B.Cu" "B.Mask" "B.Paste")
			(net "GND")
			(options
				(clearance outline)
				(anchor circle)
			)
			(primitives
				(gr_poly
					(pts
						(arc
							(start 0.1524 0.127)
							(mid 0.137521 0.162921)
							(end 0.1016 0.1778)
						)
						(arc
							(start -0.1016 0.1778)
							(mid -0.137521 0.162921)
							(end -0.1524 0.127)
						)
						(arc
							(start -0.1524 -0.127)
							(mid -0.137521 -0.162921)
							(end -0.1016 -0.1778)
						)
						(arc
							(start 0.1016 -0.1778)
							(mid 0.137521 -0.162921)
							(end 0.1524 -0.127)
						)
					)
					(width 0)
					(fill yes)
				)
			)
		)
	)
	(footprint ""
		(layer "B.Cu")
		(at 40.856154 -158.987744 180)
		(property "Reference" "C181"
			(at 0 0 0)
			(layer "B.SilkS")
			(hide yes)
			(effects
				(font
					(size 1.27 1.27)
				)
				(justify mirror)
			)
		)
		(property "Value" "SCD1U16V2KX-3GP"
			(at -1.1811 -2.7051 180)
			(unlocked yes)
			(layer "B.Fab")
			(hide yes)
			(effects
				(font
					(size 1.016 1.016)
					(thickness 0.1524)
				)
				(justify mirror)
			)
		)
		(property "Device Type" "C402H22"
			(at -1.1811 -4.2291 180)
			(unlocked yes)
			(layer "B.Fab")
			(hide yes)
			(effects
				(font
					(size 1.016 1.016)
					(thickness 0.1524)
				)
				(justify mirror)
			)
		)
		(duplicate_pad_numbers_are_jumpers no)
		(fp_rect
			(start 0.4318 0.9525)
			(end -0.4318 -0.9525)
			(stroke
				(width 0)
				(type default)
			)
			(fill no)
			(layer "B.CrtYd")
		)
		(fp_rect
			(start 0.4318 0.9525)
			(end -0.4318 -0.9525)
			(stroke
				(width 0)
				(type default)
			)
			(fill no)
			(layer "B.Fab")
		)
		(pad "1" smd custom
			(at 0 -0.4445)
			(size 0.1524 0.1524)
			(layers "B.Cu" "B.Mask" "B.Paste")
			(net "P1V53_STBY")
			(options
				(clearance outline)
				(anchor circle)
			)
			(primitives
				(gr_poly
					(pts
						(arc
							(start 0.3048 0.2032)
							(mid 0.275042 0.275042)
							(end 0.2032 0.3048)
						)
						(arc
							(start -0.2032 0.3048)
							(mid -0.275042 0.275042)
							(end -0.3048 0.2032)
						)
						(arc
							(start -0.3048 -0.2032)
							(mid -0.275042 -0.275042)
							(end -0.2032 -0.3048)
						)
						(arc
							(start 0.2032 -0.3048)
							(mid 0.275042 -0.275042)
							(end 0.3048 -0.2032)
						)
					)
					(width 0)
					(fill yes)
				)
			)
		)
		(pad "2" smd custom
			(at 0 0.4445)
			(size 0.1524 0.1524)
			(layers "B.Cu" "B.Mask" "B.Paste")
			(net "GND")
			(options
				(clearance outline)
				(anchor circle)
			)
			(primitives
				(gr_poly
					(pts
						(arc
							(start 0.3048 0.2032)
							(mid 0.275042 0.275042)
							(end 0.2032 0.3048)
						)
						(arc
							(start -0.2032 0.3048)
							(mid -0.275042 0.275042)
							(end -0.3048 0.2032)
						)
						(arc
							(start -0.3048 -0.2032)
							(mid -0.275042 -0.275042)
							(end -0.2032 -0.3048)
						)
						(arc
							(start 0.2032 -0.3048)
							(mid 0.275042 -0.275042)
							(end 0.3048 -0.2032)
						)
					)
					(width 0)
					(fill yes)
				)
			)
		)
	)
	(footprint ""
		(layer "B.Cu")
		(at 18.415 -132.715 90)
		(property "Reference" "R264"
			(at 0 0 90)
			(layer "B.SilkS")
			(hide yes)
			(effects
				(font
					(size 1.27 1.27)
				)
				(justify mirror)
			)
		)
		(property "Value" "2K2R2J-2-GP"
			(at -0.064008 -3.993896 90)
			(unlocked yes)
			(layer "B.Fab")
			(hide yes)
			(effects
				(font
					(size 1.016 1.016)
					(thickness 0.1524)
				)
				(justify mirror)
			)
		)
		(property "Device Type" "R402H16"
			(at -0.064008 -5.517896 90)
			(unlocked yes)
			(layer "B.Fab")
			(hide yes)
			(effects
				(font
					(size 1.016 1.016)
					(thickness 0.1524)
				)
				(justify mirror)
			)
		)
		(duplicate_pad_numbers_are_jumpers no)
		(fp_line
			(start 0.508 -0.9398)
			(end 0.508 0.9398)
			(stroke
				(width 0.1524)
				(type default)
			)
			(layer "B.SilkS")
		)
		(fp_line
			(start -0.508 -0.9398)
			(end 0.508 -0.9398)
			(stroke
				(width 0.1524)
				(type default)
			)
			(layer "B.SilkS")
		)
		(fp_rect
			(start 0.508 0.9398)
			(end -0.508 -0.9398)
			(stroke
				(width 0)
				(type default)
			)
			(fill no)
			(layer "B.CrtYd")
		)
		(fp_rect
			(start 0.508 0.9398)
			(end -0.508 -0.9398)
			(stroke
				(width 0)
				(type default)
			)
			(fill no)
			(layer "B.Fab")
		)
		(pad "1" smd custom
			(at 0 -0.4445 270)
			(size 0.1397 0.1397)
			(layers "B.Cu" "B.Mask" "B.Paste")
			(net "P3V3_STBY")
			(options
				(clearance outline)
				(anchor circle)
			)
			(primitives
				(gr_poly
					(pts
						(arc
							(start -0.1778 0.2794)
							(mid -0.249642 0.249642)
							(end -0.2794 0.1778)
						)
						(arc
							(start -0.2794 -0.1778)
							(mid -0.249642 -0.249642)
							(end -0.1778 -0.2794)
						)
						(arc
							(start 0.1778 -0.2794)
							(mid 0.249642 -0.249642)
							(end 0.2794 -0.1778)
						)
						(arc
							(start 0.2794 0.1778)
							(mid 0.249642 0.249642)
							(end 0.1778 0.2794)
						)
					)
					(width 0)
					(fill yes)
				)
			)
		)
		(pad "2" smd custom
			(at 0 0.4445 270)
			(size 0.1397 0.1397)
			(layers "B.Cu" "B.Mask" "B.Paste")
			(net "FLA_CS1_R")
			(options
				(clearance outline)
				(anchor circle)
			)
			(primitives
				(gr_poly
					(pts
						(arc
							(start -0.1778 0.2794)
							(mid -0.249642 0.249642)
							(end -0.2794 0.1778)
						)
						(arc
							(start -0.2794 -0.1778)
							(mid -0.249642 -0.249642)
							(end -0.1778 -0.2794)
						)
						(arc
							(start 0.1778 -0.2794)
							(mid 0.249642 -0.249642)
							(end 0.2794 -0.1778)
						)
						(arc
							(start 0.2794 0.1778)
							(mid 0.249642 0.249642)
							(end 0.1778 0.2794)
						)
					)
					(width 0)
					(fill yes)
				)
			)
		)
	)
	(footprint ""
		(layer "B.Cu")
		(at 127.103124 -208.889092 180)
		(property "Reference" "R4133"
			(at 0 0 0)
			(layer "B.SilkS")
			(hide yes)
			(effects
				(font
					(size 1.27 1.27)
				)
				(justify mirror)
			)
		)
		(property "Value" "4K7R2F-GP"
			(at -0.064008 -3.993896 180)
			(unlocked yes)
			(layer "B.Fab")
			(hide yes)
			(effects
				(font
					(size 1.016 1.016)
					(thickness 0.1524)
				)
				(justify mirror)
			)
		)
		(property "Device Type" "R402H16"
			(at -0.064008 -5.517896 180)
			(unlocked yes)
			(layer "B.Fab")
			(hide yes)
			(effects
				(font
					(size 1.016 1.016)
					(thickness 0.1524)
				)
				(justify mirror)
			)
		)
		(duplicate_pad_numbers_are_jumpers no)
		(fp_line
			(start 0.508 -0.9398)
			(end 0.508 0.9398)
			(stroke
				(width 0.1524)
				(type default)
			)
			(layer "B.SilkS")
		)
		(fp_line
			(start -0.508 -0.9398)
			(end 0.508 -0.9398)
			(stroke
				(width 0.1524)
				(type default)
			)
			(layer "B.SilkS")
		)
		(fp_rect
			(start 0.508 0.9398)
			(end -0.508 -0.9398)
			(stroke
				(width 0)
				(type default)
			)
			(fill no)
			(layer "B.CrtYd")
		)
		(fp_rect
			(start 0.508 0.9398)
			(end -0.508 -0.9398)
			(stroke
				(width 0)
				(type default)
			)
			(fill no)
			(layer "B.Fab")
		)
		(pad "1" smd custom
			(at 0 -0.4445)
			(size 0.1397 0.1397)
			(layers "B.Cu" "B.Mask" "B.Paste")
			(net "SSD_PERST#7")
			(options
				(clearance outline)
				(anchor circle)
			)
			(primitives
				(gr_poly
					(pts
						(arc
							(start -0.1778 0.2794)
							(mid -0.249642 0.249642)
							(end -0.2794 0.1778)
						)
						(arc
							(start -0.2794 -0.1778)
							(mid -0.249642 -0.249642)
							(end -0.1778 -0.2794)
						)
						(arc
							(start 0.1778 -0.2794)
							(mid 0.249642 -0.249642)
							(end 0.2794 -0.1778)
						)
						(arc
							(start 0.2794 0.1778)
							(mid 0.249642 0.249642)
							(end 0.1778 0.2794)
						)
					)
					(width 0)
					(fill yes)
				)
			)
		)
		(pad "2" smd custom
			(at 0 0.4445)
			(size 0.1397 0.1397)
			(layers "B.Cu" "B.Mask" "B.Paste")
			(net "P3V3_STBY")
			(options
				(clearance outline)
				(anchor circle)
			)
			(primitives
				(gr_poly
					(pts
						(arc
							(start -0.1778 0.2794)
							(mid -0.249642 0.249642)
							(end -0.2794 0.1778)
						)
						(arc
							(start -0.2794 -0.1778)
							(mid -0.249642 -0.249642)
							(end -0.1778 -0.2794)
						)
						(arc
							(start 0.1778 -0.2794)
							(mid 0.249642 -0.249642)
							(end 0.2794 -0.1778)
						)
						(arc
							(start 0.2794 0.1778)
							(mid 0.249642 0.249642)
							(end 0.1778 0.2794)
						)
					)
					(width 0)
					(fill yes)
				)
			)
		)
	)
	(footprint ""
		(layer "B.Cu")
		(at 322.537836 -36.991036 180)
		(property "Reference" "C237"
			(at 0 0 0)
			(layer "B.SilkS")
			(hide yes)
			(effects
				(font
					(size 1.27 1.27)
				)
				(justify mirror)
			)
		)
		(property "Value" "SCD1U10V2KX-5GP"
			(at -1.1811 -2.7051 180)
			(unlocked yes)
			(layer "B.Fab")
			(hide yes)
			(effects
				(font
					(size 1.016 1.016)
					(thickness 0.1524)
				)
				(justify mirror)
			)
		)
		(property "Device Type" "C402H22"
			(at -1.1811 -4.2291 180)
			(unlocked yes)
			(layer "B.Fab")
			(hide yes)
			(effects
				(font
					(size 1.016 1.016)
					(thickness 0.1524)
				)
				(justify mirror)
			)
		)
		(duplicate_pad_numbers_are_jumpers no)
		(fp_rect
			(start 0.4318 0.9525)
			(end -0.4318 -0.9525)
			(stroke
				(width 0)
				(type default)
			)
			(fill no)
			(layer "B.CrtYd")
		)
		(fp_rect
			(start 0.4318 0.9525)
			(end -0.4318 -0.9525)
			(stroke
				(width 0)
				(type default)
			)
			(fill no)
			(layer "B.Fab")
		)
		(pad "1" smd custom
			(at 0 -0.4445)
			(size 0.1524 0.1524)
			(layers "B.Cu" "B.Mask" "B.Paste")
			(net "GND")
			(options
				(clearance outline)
				(anchor circle)
			)
			(primitives
				(gr_poly
					(pts
						(arc
							(start 0.3048 0.2032)
							(mid 0.275042 0.275042)
							(end 0.2032 0.3048)
						)
						(arc
							(start -0.2032 0.3048)
							(mid -0.275042 0.275042)
							(end -0.3048 0.2032)
						)
						(arc
							(start -0.3048 -0.2032)
							(mid -0.275042 -0.275042)
							(end -0.2032 -0.3048)
						)
						(arc
							(start 0.2032 -0.3048)
							(mid 0.275042 -0.275042)
							(end 0.3048 -0.2032)
						)
					)
					(width 0)
					(fill yes)
				)
			)
		)
		(pad "2" smd custom
			(at 0 0.4445)
			(size 0.1524 0.1524)
			(layers "B.Cu" "B.Mask" "B.Paste")
			(net "P3V3_STBY")
			(options
				(clearance outline)
				(anchor circle)
			)
			(primitives
				(gr_poly
					(pts
						(arc
							(start 0.3048 0.2032)
							(mid 0.275042 0.275042)
							(end 0.2032 0.3048)
						)
						(arc
							(start -0.2032 0.3048)
							(mid -0.275042 0.275042)
							(end -0.3048 0.2032)
						)
						(arc
							(start -0.3048 -0.2032)
							(mid -0.275042 -0.275042)
							(end -0.2032 -0.3048)
						)
						(arc
							(start 0.2032 -0.3048)
							(mid 0.275042 -0.275042)
							(end 0.3048 -0.2032)
						)
					)
					(width 0)
					(fill yes)
				)
			)
		)
	)
	(footprint ""
		(layer "B.Cu")
		(at 76.848716 -183.238902)
		(property "Reference" "R4106"
			(at 0 0 0)
			(layer "B.SilkS")
			(hide yes)
			(effects
				(font
					(size 1.27 1.27)
				)
				(justify mirror)
			)
		)
		(property "Value" "4K7R2F-GP"
			(at -0.064008 -3.993896 0)
			(unlocked yes)
			(layer "B.Fab")
			(hide yes)
			(effects
				(font
					(size 1.016 1.016)
					(thickness 0.1524)
				)
				(justify mirror)
			)
		)
		(property "Device Type" "R402H16"
			(at -0.064008 -5.517896 0)
			(unlocked yes)
			(layer "B.Fab")
			(hide yes)
			(effects
				(font
					(size 1.016 1.016)
					(thickness 0.1524)
				)
				(justify mirror)
			)
		)
		(duplicate_pad_numbers_are_jumpers no)
		(fp_line
			(start -0.508 -0.9398)
			(end 0.508 -0.9398)
			(stroke
				(width 0.1524)
				(type default)
			)
			(layer "B.SilkS")
		)
		(fp_line
			(start 0.508 -0.9398)
			(end 0.508 0.9398)
			(stroke
				(width 0.1524)
				(type default)
			)
			(layer "B.SilkS")
		)
		(fp_rect
			(start 0.508 0.9398)
			(end -0.508 -0.9398)
			(stroke
				(width 0)
				(type default)
			)
			(fill no)
			(layer "B.CrtYd")
		)
		(fp_rect
			(start 0.508 0.9398)
			(end -0.508 -0.9398)
			(stroke
				(width 0)
				(type default)
			)
			(fill no)
			(layer "B.Fab")
		)
		(pad "1" smd custom
			(at 0 -0.4445 180)
			(size 0.1397 0.1397)
			(layers "B.Cu" "B.Mask" "B.Paste")
			(net "SSD_ATNLED#5")
			(options
				(clearance outline)
				(anchor circle)
			)
			(primitives
				(gr_poly
					(pts
						(arc
							(start -0.1778 0.2794)
							(mid -0.249642 0.249642)
							(end -0.2794 0.1778)
						)
						(arc
							(start -0.2794 -0.1778)
							(mid -0.249642 -0.249642)
							(end -0.1778 -0.2794)
						)
						(arc
							(start 0.1778 -0.2794)
							(mid 0.249642 -0.249642)
							(end 0.2794 -0.1778)
						)
						(arc
							(start 0.2794 0.1778)
							(mid 0.249642 0.249642)
							(end 0.1778 0.2794)
						)
					)
					(width 0)
					(fill yes)
				)
			)
		)
		(pad "2" smd custom
			(at 0 0.4445 180)
			(size 0.1397 0.1397)
			(layers "B.Cu" "B.Mask" "B.Paste")
			(net "P3V3_STBY")
			(options
				(clearance outline)
				(anchor circle)
			)
			(primitives
				(gr_poly
					(pts
						(arc
							(start -0.1778 0.2794)
							(mid -0.249642 0.249642)
							(end -0.2794 0.1778)
						)
						(arc
							(start -0.2794 -0.1778)
							(mid -0.249642 -0.249642)
							(end -0.1778 -0.2794)
						)
						(arc
							(start 0.1778 -0.2794)
							(mid 0.249642 -0.249642)
							(end 0.2794 -0.1778)
						)
						(arc
							(start 0.2794 0.1778)
							(mid 0.249642 0.249642)
							(end 0.1778 0.2794)
						)
					)
					(width 0)
					(fill yes)
				)
			)
		)
	)
	(footprint ""
		(layer "B.Cu")
		(at 158.512002 -59.209432 90)
		(property "Reference" "PC200"
			(at 0 0 90)
			(layer "B.SilkS")
			(hide yes)
			(effects
				(font
					(size 1.27 1.27)
				)
				(justify mirror)
			)
		)
		(property "Value" "SCD1U50V3KX-GP"
			(at 0 -2.8194 90)
			(unlocked yes)
			(layer "B.Fab")
			(hide yes)
			(effects
				(font
					(size 1.016 1.016)
					(thickness 0.1524)
				)
				(justify mirror)
			)
		)
		(property "Device Type" "C603H36"
			(at 0 -4.3434 90)
			(unlocked yes)
			(layer "B.Fab")
			(hide yes)
			(effects
				(font
					(size 1.016 1.016)
					(thickness 0.1524)
				)
				(justify mirror)
			)
		)
		(duplicate_pad_numbers_are_jumpers no)
		(fp_line
			(start -0.508 0)
			(end 0.508 0)
			(stroke
				(width 0.2032)
				(type default)
			)
			(layer "B.SilkS")
		)
		(fp_rect
			(start 0.5842 1.3335)
			(end -0.5842 -1.3335)
			(stroke
				(width 0)
				(type default)
			)
			(fill no)
			(layer "B.CrtYd")
		)
		(fp_rect
			(start 0.5842 1.3335)
			(end -0.5842 -1.3335)
			(stroke
				(width 0)
				(type default)
			)
			(fill no)
			(layer "B.Fab")
		)
		(pad "1" smd custom
			(at 0 -0.762 270)
			(size 0.2159 0.2159)
			(layers "B.Cu" "B.Mask" "B.Paste")
			(net "P0V9_VBST")
			(options
				(clearance outline)
				(anchor circle)
			)
			(primitives
				(gr_poly
					(pts
						(arc
							(start -0.3302 0.4318)
							(mid -0.402042 0.402042)
							(end -0.4318 0.3302)
						)
						(arc
							(start -0.4318 -0.3302)
							(mid -0.402042 -0.402042)
							(end -0.3302 -0.4318)
						)
						(arc
							(start 0.3302 -0.4318)
							(mid 0.402042 -0.402042)
							(end 0.4318 -0.3302)
						)
						(arc
							(start 0.4318 0.3302)
							(mid 0.402042 0.402042)
							(end 0.3302 0.4318)
						)
					)
					(width 0)
					(fill yes)
				)
			)
		)
		(pad "2" smd custom
			(at 0 0.762 270)
			(size 0.2159 0.2159)
			(layers "B.Cu" "B.Mask" "B.Paste")
			(net "P0V9_VBST_RC")
			(options
				(clearance outline)
				(anchor circle)
			)
			(primitives
				(gr_poly
					(pts
						(arc
							(start -0.3302 0.4318)
							(mid -0.402042 0.402042)
							(end -0.4318 0.3302)
						)
						(arc
							(start -0.4318 -0.3302)
							(mid -0.402042 -0.402042)
							(end -0.3302 -0.4318)
						)
						(arc
							(start 0.3302 -0.4318)
							(mid 0.402042 -0.402042)
							(end 0.4318 -0.3302)
						)
						(arc
							(start 0.4318 0.3302)
							(mid 0.402042 0.402042)
							(end 0.3302 0.4318)
						)
					)
					(width 0)
					(fill yes)
				)
			)
		)
	)
	(footprint ""
		(layer "B.Cu")
		(at 218.5416 -4.1148 90)
		(property "Reference" "Q3202"
			(at 0 0 90)
			(layer "B.SilkS")
			(hide yes)
			(effects
				(font
					(size 1.27 1.27)
				)
				(justify mirror)
			)
		)
		(property "Value" "2N7002K-1-GP"
			(at -0.127 -8.9662 90)
			(unlocked yes)
			(layer "B.Fab")
			(hide yes)
			(effects
				(font
					(size 1.016 1.016)
					(thickness 0.1524)
				)
				(justify mirror)
			)
		)
		(property "Device Type" "SOT23DGS2D4H44"
			(at -0.127 -10.4902 90)
			(unlocked yes)
			(layer "B.Fab")
			(hide yes)
			(effects
				(font
					(size 1.016 1.016)
					(thickness 0.1524)
				)
				(justify mirror)
			)
		)
		(duplicate_pad_numbers_are_jumpers no)
		(fp_line
			(start 1.651 -1.778)
			(end 1.651 1.778)
			(stroke
				(width 0.1524)
				(type default)
			)
			(layer "B.SilkS")
		)
		(fp_line
			(start -1.651 -1.778)
			(end 1.651 -1.778)
			(stroke
				(width 0.1524)
				(type default)
			)
			(layer "B.SilkS")
		)
		(fp_line
			(start 1.651 1.778)
			(end -1.651 1.778)
			(stroke
				(width 0.1524)
				(type default)
			)
			(layer "B.SilkS")
		)
		(fp_line
			(start -1.651 1.778)
			(end -1.651 -1.778)
			(stroke
				(width 0.1524)
				(type default)
			)
			(layer "B.SilkS")
		)
		(fp_poly
			(pts
				(xy 1.778 1.8796) (xy 1.778 -1.8796) (xy -1.778 -1.8796) (xy -1.778 1.8796)
			)
			(stroke
				(width 0)
				(type default)
			)
			(fill no)
			(layer "B.CrtYd")
		)
		(fp_poly
			(pts
				(xy 1.778 1.8796) (xy 1.778 -1.8796) (xy -1.778 -1.8796) (xy -1.778 1.8796)
			)
			(stroke
				(width 0)
				(type default)
			)
			(fill no)
			(layer "B.Fab")
		)
		(pad "D" smd custom
			(at 0 -0.9525 270)
			(size 0.1905 0.1905)
			(layers "B.Cu" "B.Mask" "B.Paste")
			(net "Q3202_D")
			(options
				(clearance outline)
				(anchor circle)
			)
			(primitives
				(gr_poly
					(pts
						(arc
							(start -0.1778 -0.5715)
							(mid -0.321484 -0.511984)
							(end -0.381 -0.3683)
						)
						(arc
							(start -0.381 0.3683)
							(mid -0.321484 0.511984)
							(end -0.1778 0.5715)
						)
						(arc
							(start 0.1778 0.5715)
							(mid 0.321484 0.511984)
							(end 0.381 0.3683)
						)
						(arc
							(start 0.381 -0.3683)
							(mid 0.321484 -0.511984)
							(end 0.1778 -0.5715)
						)
					)
					(width 0)
					(fill yes)
				)
			)
		)
		(pad "G" smd custom
			(at 0.98425 0.9525 270)
			(size 0.1905 0.1905)
			(layers "B.Cu" "B.Mask" "B.Paste")
			(net "P3V3_STBY")
			(options
				(clearance outline)
				(anchor circle)
			)
			(primitives
				(gr_poly
					(pts
						(arc
							(start -0.1778 -0.5715)
							(mid -0.321484 -0.511984)
							(end -0.381 -0.3683)
						)
						(arc
							(start -0.381 0.3683)
							(mid -0.321484 0.511984)
							(end -0.1778 0.5715)
						)
						(arc
							(start 0.1778 0.5715)
							(mid 0.321484 0.511984)
							(end 0.381 0.3683)
						)
						(arc
							(start 0.381 -0.3683)
							(mid 0.321484 -0.511984)
							(end 0.1778 -0.5715)
						)
					)
					(width 0)
					(fill yes)
				)
			)
		)
		(pad "S" smd custom
			(at -0.98425 0.9525 270)
			(size 0.1905 0.1905)
			(layers "B.Cu" "B.Mask" "B.Paste")
			(net "GND")
			(options
				(clearance outline)
				(anchor circle)
			)
			(primitives
				(gr_poly
					(pts
						(arc
							(start -0.1778 -0.5715)
							(mid -0.321484 -0.511984)
							(end -0.381 -0.3683)
						)
						(arc
							(start -0.381 0.3683)
							(mid -0.321484 0.511984)
							(end -0.1778 0.5715)
						)
						(arc
							(start 0.1778 0.5715)
							(mid 0.321484 0.511984)
							(end 0.381 0.3683)
						)
						(arc
							(start 0.381 -0.3683)
							(mid 0.321484 -0.511984)
							(end 0.1778 -0.5715)
						)
					)
					(width 0)
					(fill yes)
				)
			)
		)
	)
	(footprint ""
		(layer "B.Cu")
		(at 226.822 -23.241 180)
		(property "Reference" "R828"
			(at 0 0 0)
			(layer "B.SilkS")
			(hide yes)
			(effects
				(font
					(size 1.27 1.27)
				)
				(justify mirror)
			)
		)
		(property "Value" "0R2J-2-GP"
			(at -0.064008 -3.993896 180)
			(unlocked yes)
			(layer "B.Fab")
			(hide yes)
			(effects
				(font
					(size 1.016 1.016)
					(thickness 0.1524)
				)
				(justify mirror)
			)
		)
		(property "Device Type" "R402H16"
			(at -0.064008 -5.517896 180)
			(unlocked yes)
			(layer "B.Fab")
			(hide yes)
			(effects
				(font
					(size 1.016 1.016)
					(thickness 0.1524)
				)
				(justify mirror)
			)
		)
		(duplicate_pad_numbers_are_jumpers no)
		(fp_line
			(start 0.508 -0.9398)
			(end 0.508 0.9398)
			(stroke
				(width 0.1524)
				(type default)
			)
			(layer "B.SilkS")
		)
		(fp_line
			(start -0.508 -0.9398)
			(end 0.508 -0.9398)
			(stroke
				(width 0.1524)
				(type default)
			)
			(layer "B.SilkS")
		)
		(fp_rect
			(start 0.508 0.9398)
			(end -0.508 -0.9398)
			(stroke
				(width 0)
				(type default)
			)
			(fill no)
			(layer "B.CrtYd")
		)
		(fp_rect
			(start 0.508 0.9398)
			(end -0.508 -0.9398)
			(stroke
				(width 0)
				(type default)
			)
			(fill no)
			(layer "B.Fab")
		)
		(pad "1" smd custom
			(at 0 -0.4445)
			(size 0.1397 0.1397)
			(layers "B.Cu" "B.Mask" "B.Paste")
			(net "HOST4_RST_N_LS")
			(options
				(clearance outline)
				(anchor circle)
			)
			(primitives
				(gr_poly
					(pts
						(arc
							(start -0.1778 0.2794)
							(mid -0.249642 0.249642)
							(end -0.2794 0.1778)
						)
						(arc
							(start -0.2794 -0.1778)
							(mid -0.249642 -0.249642)
							(end -0.1778 -0.2794)
						)
						(arc
							(start 0.1778 -0.2794)
							(mid 0.249642 -0.249642)
							(end 0.2794 -0.1778)
						)
						(arc
							(start 0.2794 0.1778)
							(mid 0.249642 0.249642)
							(end 0.1778 0.2794)
						)
					)
					(width 0)
					(fill yes)
				)
			)
		)
		(pad "2" smd custom
			(at 0 0.4445)
			(size 0.1397 0.1397)
			(layers "B.Cu" "B.Mask" "B.Paste")
			(net "LBI_ADDR_3_R")
			(options
				(clearance outline)
				(anchor circle)
			)
			(primitives
				(gr_poly
					(pts
						(arc
							(start -0.1778 0.2794)
							(mid -0.249642 0.249642)
							(end -0.2794 0.1778)
						)
						(arc
							(start -0.2794 -0.1778)
							(mid -0.249642 -0.249642)
							(end -0.1778 -0.2794)
						)
						(arc
							(start 0.1778 -0.2794)
							(mid 0.249642 -0.249642)
							(end 0.2794 -0.1778)
						)
						(arc
							(start 0.2794 0.1778)
							(mid 0.249642 0.249642)
							(end 0.1778 0.2794)
						)
					)
					(width 0)
					(fill yes)
				)
			)
		)
	)
	(footprint ""
		(layer "B.Cu")
		(at 228.6254 -49.991772 90)
		(property "Reference" "C577"
			(at 0 0 90)
			(layer "B.SilkS")
			(hide yes)
			(effects
				(font
					(size 1.27 1.27)
				)
				(justify mirror)
			)
		)
		(property "Value" "SCD1U16V1KX-1-GP"
			(at 2.8321 -1.7399 90)
			(unlocked yes)
			(layer "B.Fab")
			(hide yes)
			(effects
				(font
					(size 1.016 1.016)
					(thickness 0.1524)
				)
				(justify mirror)
			)
		)
		(property "Device Type" "C0201H13"
			(at 2.8321 -3.2639 90)
			(unlocked yes)
			(layer "B.Fab")
			(hide yes)
			(effects
				(font
					(size 1.016 1.016)
					(thickness 0.1524)
				)
				(justify mirror)
			)
		)
		(duplicate_pad_numbers_are_jumpers no)
		(fp_rect
			(start 0.2794 0.6477)
			(end -0.2794 -0.6477)
			(stroke
				(width 0)
				(type default)
			)
			(fill no)
			(layer "B.CrtYd")
		)
		(fp_rect
			(start 0.2794 0.6477)
			(end -0.2794 -0.6477)
			(stroke
				(width 0)
				(type default)
			)
			(fill no)
			(layer "B.Fab")
		)
		(pad "1" smd custom
			(at 0 -0.2794 270)
			(size 0.0762 0.0762)
			(layers "B.Cu" "B.Mask" "B.Paste")
			(net "DUT_AVD_PCIE")
			(options
				(clearance outline)
				(anchor circle)
			)
			(primitives
				(gr_poly
					(pts
						(arc
							(start 0.1524 0.127)
							(mid 0.137521 0.162921)
							(end 0.1016 0.1778)
						)
						(arc
							(start -0.1016 0.1778)
							(mid -0.137521 0.162921)
							(end -0.1524 0.127)
						)
						(arc
							(start -0.1524 -0.127)
							(mid -0.137521 -0.162921)
							(end -0.1016 -0.1778)
						)
						(arc
							(start 0.1016 -0.1778)
							(mid 0.137521 -0.162921)
							(end 0.1524 -0.127)
						)
					)
					(width 0)
					(fill yes)
				)
			)
		)
		(pad "2" smd custom
			(at 0 0.2794 270)
			(size 0.0762 0.0762)
			(layers "B.Cu" "B.Mask" "B.Paste")
			(net "GND")
			(options
				(clearance outline)
				(anchor circle)
			)
			(primitives
				(gr_poly
					(pts
						(arc
							(start 0.1524 0.127)
							(mid 0.137521 0.162921)
							(end 0.1016 0.1778)
						)
						(arc
							(start -0.1016 0.1778)
							(mid -0.137521 0.162921)
							(end -0.1524 0.127)
						)
						(arc
							(start -0.1524 -0.127)
							(mid -0.137521 -0.162921)
							(end -0.1016 -0.1778)
						)
						(arc
							(start 0.1016 -0.1778)
							(mid 0.137521 -0.162921)
							(end 0.1524 -0.127)
						)
					)
					(width 0)
					(fill yes)
				)
			)
		)
	)
	(footprint ""
		(layer "B.Cu")
		(at 225.883724 -190.601092)
		(property "Reference" "R4143"
			(at 0 0 0)
			(layer "B.SilkS")
			(hide yes)
			(effects
				(font
					(size 1.27 1.27)
				)
				(justify mirror)
			)
		)
		(property "Value" "4K7R2F-GP"
			(at -0.064008 -3.993896 0)
			(unlocked yes)
			(layer "B.Fab")
			(hide yes)
			(effects
				(font
					(size 1.016 1.016)
					(thickness 0.1524)
				)
				(justify mirror)
			)
		)
		(property "Device Type" "R402H16"
			(at -0.064008 -5.517896 0)
			(unlocked yes)
			(layer "B.Fab")
			(hide yes)
			(effects
				(font
					(size 1.016 1.016)
					(thickness 0.1524)
				)
				(justify mirror)
			)
		)
		(duplicate_pad_numbers_are_jumpers no)
		(fp_line
			(start -0.508 -0.9398)
			(end 0.508 -0.9398)
			(stroke
				(width 0.1524)
				(type default)
			)
			(layer "B.SilkS")
		)
		(fp_line
			(start 0.508 -0.9398)
			(end 0.508 0.9398)
			(stroke
				(width 0.1524)
				(type default)
			)
			(layer "B.SilkS")
		)
		(fp_rect
			(start 0.508 0.9398)
			(end -0.508 -0.9398)
			(stroke
				(width 0)
				(type default)
			)
			(fill no)
			(layer "B.CrtYd")
		)
		(fp_rect
			(start 0.508 0.9398)
			(end -0.508 -0.9398)
			(stroke
				(width 0)
				(type default)
			)
			(fill no)
			(layer "B.Fab")
		)
		(pad "1" smd custom
			(at 0 -0.4445 180)
			(size 0.1397 0.1397)
			(layers "B.Cu" "B.Mask" "B.Paste")
			(net "SSD_ATNLED#8")
			(options
				(clearance outline)
				(anchor circle)
			)
			(primitives
				(gr_poly
					(pts
						(arc
							(start -0.1778 0.2794)
							(mid -0.249642 0.249642)
							(end -0.2794 0.1778)
						)
						(arc
							(start -0.2794 -0.1778)
							(mid -0.249642 -0.249642)
							(end -0.1778 -0.2794)
						)
						(arc
							(start 0.1778 -0.2794)
							(mid 0.249642 -0.249642)
							(end 0.2794 -0.1778)
						)
						(arc
							(start 0.2794 0.1778)
							(mid 0.249642 0.249642)
							(end 0.1778 0.2794)
						)
					)
					(width 0)
					(fill yes)
				)
			)
		)
		(pad "2" smd custom
			(at 0 0.4445 180)
			(size 0.1397 0.1397)
			(layers "B.Cu" "B.Mask" "B.Paste")
			(net "P3V3_STBY")
			(options
				(clearance outline)
				(anchor circle)
			)
			(primitives
				(gr_poly
					(pts
						(arc
							(start -0.1778 0.2794)
							(mid -0.249642 0.249642)
							(end -0.2794 0.1778)
						)
						(arc
							(start -0.2794 -0.1778)
							(mid -0.249642 -0.249642)
							(end -0.1778 -0.2794)
						)
						(arc
							(start 0.1778 -0.2794)
							(mid 0.249642 -0.249642)
							(end 0.2794 -0.1778)
						)
						(arc
							(start 0.2794 0.1778)
							(mid 0.249642 0.249642)
							(end 0.1778 0.2794)
						)
					)
					(width 0)
					(fill yes)
				)
			)
		)
	)
	(footprint ""
		(layer "B.Cu")
		(at 253.5936 -36.009072 90)
		(property "Reference" "C555"
			(at 0 0 90)
			(layer "B.SilkS")
			(hide yes)
			(effects
				(font
					(size 1.27 1.27)
				)
				(justify mirror)
			)
		)
		(property "Value" "SCD1U16V1KX-1-GP"
			(at 2.8321 -1.7399 90)
			(unlocked yes)
			(layer "B.Fab")
			(hide yes)
			(effects
				(font
					(size 1.016 1.016)
					(thickness 0.1524)
				)
				(justify mirror)
			)
		)
		(property "Device Type" "C0201H13"
			(at 2.8321 -3.2639 90)
			(unlocked yes)
			(layer "B.Fab")
			(hide yes)
			(effects
				(font
					(size 1.016 1.016)
					(thickness 0.1524)
				)
				(justify mirror)
			)
		)
		(duplicate_pad_numbers_are_jumpers no)
		(fp_rect
			(start 0.2794 0.6477)
			(end -0.2794 -0.6477)
			(stroke
				(width 0)
				(type default)
			)
			(fill no)
			(layer "B.CrtYd")
		)
		(fp_rect
			(start 0.2794 0.6477)
			(end -0.2794 -0.6477)
			(stroke
				(width 0)
				(type default)
			)
			(fill no)
			(layer "B.Fab")
		)
		(pad "1" smd custom
			(at 0 -0.2794 270)
			(size 0.0762 0.0762)
			(layers "B.Cu" "B.Mask" "B.Paste")
			(net "DUT_AVD_PCIE")
			(options
				(clearance outline)
				(anchor circle)
			)
			(primitives
				(gr_poly
					(pts
						(arc
							(start 0.1524 0.127)
							(mid 0.137521 0.162921)
							(end 0.1016 0.1778)
						)
						(arc
							(start -0.1016 0.1778)
							(mid -0.137521 0.162921)
							(end -0.1524 0.127)
						)
						(arc
							(start -0.1524 -0.127)
							(mid -0.137521 -0.162921)
							(end -0.1016 -0.1778)
						)
						(arc
							(start 0.1016 -0.1778)
							(mid 0.137521 -0.162921)
							(end 0.1524 -0.127)
						)
					)
					(width 0)
					(fill yes)
				)
			)
		)
		(pad "2" smd custom
			(at 0 0.2794 270)
			(size 0.0762 0.0762)
			(layers "B.Cu" "B.Mask" "B.Paste")
			(net "GND")
			(options
				(clearance outline)
				(anchor circle)
			)
			(primitives
				(gr_poly
					(pts
						(arc
							(start 0.1524 0.127)
							(mid 0.137521 0.162921)
							(end 0.1016 0.1778)
						)
						(arc
							(start -0.1016 0.1778)
							(mid -0.137521 0.162921)
							(end -0.1524 0.127)
						)
						(arc
							(start -0.1524 -0.127)
							(mid -0.137521 -0.162921)
							(end -0.1016 -0.1778)
						)
						(arc
							(start 0.1016 -0.1778)
							(mid 0.137521 -0.162921)
							(end 0.1524 -0.127)
						)
					)
					(width 0)
					(fill yes)
				)
			)
		)
	)
	(footprint ""
		(layer "B.Cu")
		(at 221.234 -20.447 180)
		(property "Reference" "R710"
			(at 0 0 0)
			(layer "B.SilkS")
			(hide yes)
			(effects
				(font
					(size 1.27 1.27)
				)
				(justify mirror)
			)
		)
		(property "Value" "1KR2F-3-GP"
			(at -0.064008 -3.993896 180)
			(unlocked yes)
			(layer "B.Fab")
			(hide yes)
			(effects
				(font
					(size 1.016 1.016)
					(thickness 0.1524)
				)
				(justify mirror)
			)
		)
		(property "Device Type" "R402H16"
			(at -0.064008 -5.517896 180)
			(unlocked yes)
			(layer "B.Fab")
			(hide yes)
			(effects
				(font
					(size 1.016 1.016)
					(thickness 0.1524)
				)
				(justify mirror)
			)
		)
		(duplicate_pad_numbers_are_jumpers no)
		(fp_line
			(start 0.508 -0.9398)
			(end 0.508 0.9398)
			(stroke
				(width 0.1524)
				(type default)
			)
			(layer "B.SilkS")
		)
		(fp_line
			(start -0.508 -0.9398)
			(end 0.508 -0.9398)
			(stroke
				(width 0.1524)
				(type default)
			)
			(layer "B.SilkS")
		)
		(fp_rect
			(start 0.508 0.9398)
			(end -0.508 -0.9398)
			(stroke
				(width 0)
				(type default)
			)
			(fill no)
			(layer "B.CrtYd")
		)
		(fp_rect
			(start 0.508 0.9398)
			(end -0.508 -0.9398)
			(stroke
				(width 0)
				(type default)
			)
			(fill no)
			(layer "B.Fab")
		)
		(pad "1" smd custom
			(at 0 -0.4445)
			(size 0.1397 0.1397)
			(layers "B.Cu" "B.Mask" "B.Paste")
			(net "DUT_VDDO")
			(options
				(clearance outline)
				(anchor circle)
			)
			(primitives
				(gr_poly
					(pts
						(arc
							(start -0.1778 0.2794)
							(mid -0.249642 0.249642)
							(end -0.2794 0.1778)
						)
						(arc
							(start -0.2794 -0.1778)
							(mid -0.249642 -0.249642)
							(end -0.1778 -0.2794)
						)
						(arc
							(start 0.1778 -0.2794)
							(mid 0.249642 -0.249642)
							(end 0.2794 -0.1778)
						)
						(arc
							(start 0.2794 0.1778)
							(mid 0.249642 0.249642)
							(end 0.1778 0.2794)
						)
					)
					(width 0)
					(fill yes)
				)
			)
		)
		(pad "2" smd custom
			(at 0 0.4445)
			(size 0.1397 0.1397)
			(layers "B.Cu" "B.Mask" "B.Paste")
			(net "MDIO")
			(options
				(clearance outline)
				(anchor circle)
			)
			(primitives
				(gr_poly
					(pts
						(arc
							(start -0.1778 0.2794)
							(mid -0.249642 0.249642)
							(end -0.2794 0.1778)
						)
						(arc
							(start -0.2794 -0.1778)
							(mid -0.249642 -0.249642)
							(end -0.1778 -0.2794)
						)
						(arc
							(start 0.1778 -0.2794)
							(mid 0.249642 -0.249642)
							(end 0.2794 -0.1778)
						)
						(arc
							(start 0.2794 0.1778)
							(mid 0.249642 0.249642)
							(end 0.1778 0.2794)
						)
					)
					(width 0)
					(fill yes)
				)
			)
		)
	)
	(footprint ""
		(layer "B.Cu")
		(at 160.147 -88.4174 180)
		(property "Reference" "C715"
			(at 0 0 0)
			(layer "B.SilkS")
			(hide yes)
			(effects
				(font
					(size 1.27 1.27)
				)
				(justify mirror)
			)
		)
		(property "Value" "SCD1U10V2KX-5GP"
			(at -1.1811 -2.7051 180)
			(unlocked yes)
			(layer "B.Fab")
			(hide yes)
			(effects
				(font
					(size 1.016 1.016)
					(thickness 0.1524)
				)
				(justify mirror)
			)
		)
		(property "Device Type" "C402H22"
			(at -1.1811 -4.2291 180)
			(unlocked yes)
			(layer "B.Fab")
			(hide yes)
			(effects
				(font
					(size 1.016 1.016)
					(thickness 0.1524)
				)
				(justify mirror)
			)
		)
		(duplicate_pad_numbers_are_jumpers no)
		(fp_rect
			(start 0.4318 0.9525)
			(end -0.4318 -0.9525)
			(stroke
				(width 0)
				(type default)
			)
			(fill no)
			(layer "B.CrtYd")
		)
		(fp_rect
			(start 0.4318 0.9525)
			(end -0.4318 -0.9525)
			(stroke
				(width 0)
				(type default)
			)
			(fill no)
			(layer "B.Fab")
		)
		(pad "1" smd custom
			(at 0 -0.4445)
			(size 0.1524 0.1524)
			(layers "B.Cu" "B.Mask" "B.Paste")
			(net "P1V8_CLKGEN")
			(options
				(clearance outline)
				(anchor circle)
			)
			(primitives
				(gr_poly
					(pts
						(arc
							(start 0.3048 0.2032)
							(mid 0.275042 0.275042)
							(end 0.2032 0.3048)
						)
						(arc
							(start -0.2032 0.3048)
							(mid -0.275042 0.275042)
							(end -0.3048 0.2032)
						)
						(arc
							(start -0.3048 -0.2032)
							(mid -0.275042 -0.275042)
							(end -0.2032 -0.3048)
						)
						(arc
							(start 0.2032 -0.3048)
							(mid 0.275042 -0.275042)
							(end 0.3048 -0.2032)
						)
					)
					(width 0)
					(fill yes)
				)
			)
		)
		(pad "2" smd custom
			(at 0 0.4445)
			(size 0.1524 0.1524)
			(layers "B.Cu" "B.Mask" "B.Paste")
			(net "GND")
			(options
				(clearance outline)
				(anchor circle)
			)
			(primitives
				(gr_poly
					(pts
						(arc
							(start 0.3048 0.2032)
							(mid 0.275042 0.275042)
							(end 0.2032 0.3048)
						)
						(arc
							(start -0.2032 0.3048)
							(mid -0.275042 0.275042)
							(end -0.3048 0.2032)
						)
						(arc
							(start -0.3048 -0.2032)
							(mid -0.275042 -0.275042)
							(end -0.2032 -0.3048)
						)
						(arc
							(start 0.2032 -0.3048)
							(mid 0.275042 -0.275042)
							(end 0.3048 -0.2032)
						)
					)
					(width 0)
					(fill yes)
				)
			)
		)
	)
	(footprint ""
		(layer "B.Cu")
		(at 182.0164 -61.595)
		(property "Reference" "C585"
			(at 0 0 0)
			(layer "B.SilkS")
			(hide yes)
			(effects
				(font
					(size 1.27 1.27)
				)
				(justify mirror)
			)
		)
		(property "Value" "SC4D7U16V5KX-1-GP"
			(at 0.0762 -6.1214 0)
			(unlocked yes)
			(layer "B.Fab")
			(hide yes)
			(effects
				(font
					(size 1.016 1.016)
					(thickness 0.1524)
				)
				(justify mirror)
			)
		)
		(property "Device Type" "C805H56"
			(at 0.0762 -8.1534 0)
			(unlocked yes)
			(layer "B.Fab")
			(hide yes)
			(effects
				(font
					(size 1.016 1.016)
					(thickness 0.1524)
				)
				(justify mirror)
			)
		)
		(duplicate_pad_numbers_are_jumpers no)
		(fp_line
			(start -0.635 0)
			(end 0.635 0)
			(stroke
				(width 0.508)
				(type default)
			)
			(layer "B.SilkS")
		)
		(fp_rect
			(start 0.9652 1.778)
			(end -0.9652 -1.778)
			(stroke
				(width 0)
				(type default)
			)
			(fill no)
			(layer "B.CrtYd")
		)
		(fp_poly
			(pts
				(xy 0.9652 -1.778) (xy -0.9652 -1.778) (xy -0.9652 1.778) (xy 0.9652 1.778)
			)
			(stroke
				(width 0)
				(type default)
			)
			(fill no)
			(layer "B.Fab")
		)
		(pad "1" smd rect
			(at 0 -0.9652 180)
			(size 1.397 1.143)
			(layers "B.Cu" "B.Mask" "B.Paste")
			(net "DUT_AVD_PCIE")
		)
		(pad "2" smd rect
			(at 0 0.9652 180)
			(size 1.397 1.143)
			(layers "B.Cu" "B.Mask" "B.Paste")
			(net "GND")
		)
	)
	(footprint ""
		(layer "B.Cu")
		(at 222.999046 -203.69784 180)
		(property "Reference" "R4142"
			(at 0 0 0)
			(layer "B.SilkS")
			(hide yes)
			(effects
				(font
					(size 1.27 1.27)
				)
				(justify mirror)
			)
		)
		(property "Value" "4K7R2F-GP"
			(at -0.064008 -3.993896 180)
			(unlocked yes)
			(layer "B.Fab")
			(hide yes)
			(effects
				(font
					(size 1.016 1.016)
					(thickness 0.1524)
				)
				(justify mirror)
			)
		)
		(property "Device Type" "R402H16"
			(at -0.064008 -5.517896 180)
			(unlocked yes)
			(layer "B.Fab")
			(hide yes)
			(effects
				(font
					(size 1.016 1.016)
					(thickness 0.1524)
				)
				(justify mirror)
			)
		)
		(duplicate_pad_numbers_are_jumpers no)
		(fp_line
			(start 0.508 -0.9398)
			(end 0.508 0.9398)
			(stroke
				(width 0.1524)
				(type default)
			)
			(layer "B.SilkS")
		)
		(fp_line
			(start -0.508 -0.9398)
			(end 0.508 -0.9398)
			(stroke
				(width 0.1524)
				(type default)
			)
			(layer "B.SilkS")
		)
		(fp_rect
			(start 0.508 0.9398)
			(end -0.508 -0.9398)
			(stroke
				(width 0)
				(type default)
			)
			(fill no)
			(layer "B.CrtYd")
		)
		(fp_rect
			(start 0.508 0.9398)
			(end -0.508 -0.9398)
			(stroke
				(width 0)
				(type default)
			)
			(fill no)
			(layer "B.Fab")
		)
		(pad "1" smd custom
			(at 0 -0.4445)
			(size 0.1397 0.1397)
			(layers "B.Cu" "B.Mask" "B.Paste")
			(net "SSD_ATNLED#13")
			(options
				(clearance outline)
				(anchor circle)
			)
			(primitives
				(gr_poly
					(pts
						(arc
							(start -0.1778 0.2794)
							(mid -0.249642 0.249642)
							(end -0.2794 0.1778)
						)
						(arc
							(start -0.2794 -0.1778)
							(mid -0.249642 -0.249642)
							(end -0.1778 -0.2794)
						)
						(arc
							(start 0.1778 -0.2794)
							(mid 0.249642 -0.249642)
							(end 0.2794 -0.1778)
						)
						(arc
							(start 0.2794 0.1778)
							(mid 0.249642 0.249642)
							(end 0.1778 0.2794)
						)
					)
					(width 0)
					(fill yes)
				)
			)
		)
		(pad "2" smd custom
			(at 0 0.4445)
			(size 0.1397 0.1397)
			(layers "B.Cu" "B.Mask" "B.Paste")
			(net "P3V3_STBY")
			(options
				(clearance outline)
				(anchor circle)
			)
			(primitives
				(gr_poly
					(pts
						(arc
							(start -0.1778 0.2794)
							(mid -0.249642 0.249642)
							(end -0.2794 0.1778)
						)
						(arc
							(start -0.2794 -0.1778)
							(mid -0.249642 -0.249642)
							(end -0.1778 -0.2794)
						)
						(arc
							(start 0.1778 -0.2794)
							(mid 0.249642 -0.249642)
							(end 0.2794 -0.1778)
						)
						(arc
							(start 0.2794 0.1778)
							(mid 0.249642 0.249642)
							(end 0.1778 0.2794)
						)
					)
					(width 0)
					(fill yes)
				)
			)
		)
	)
	(footprint ""
		(layer "B.Cu")
		(at 42.926 -116.332)
		(property "Reference" "TP298"
			(at 0 0 0)
			(layer "B.SilkS")
			(hide yes)
			(effects
				(font
					(size 1.27 1.27)
				)
				(justify mirror)
			)
		)
		(property "Value" "TPAD28-2-GP"
			(at 0.0127 -1.6637 0)
			(unlocked yes)
			(layer "B.Fab")
			(hide yes)
			(effects
				(font
					(size 1.016 1.016)
					(thickness 0.1524)
				)
				(justify mirror)
			)
		)
		(property "Device Type" "TPAD28"
			(at 0.0127 -3.1877 0)
			(unlocked yes)
			(layer "B.Fab")
			(hide yes)
			(effects
				(font
					(size 1.016 1.016)
					(thickness 0.1524)
				)
				(justify mirror)
			)
		)
		(duplicate_pad_numbers_are_jumpers no)
		(fp_poly
			(pts
				(arc
					(start 0.3556 0)
					(mid -0.3556 0)
					(end 0.3556 0)
				)
			)
			(stroke
				(width 0)
				(type default)
			)
			(fill no)
			(layer "B.CrtYd")
		)
		(fp_poly
			(pts
				(arc
					(start 0.6096 0)
					(mid -0.6096 0)
					(end 0.6096 0)
				)
			)
			(stroke
				(width 0)
				(type default)
			)
			(fill no)
			(layer "B.Fab")
		)
		(pad "1" smd circle
			(at 0 0 180)
			(size 0.7112 0.7112)
			(layers "B.Cu" "B.Mask" "B.Paste")
			(net "TP_GPIOV7")
		)
	)
	(footprint ""
		(layer "B.Cu")
		(at 258.786884 -14.629638 -90)
		(property "Reference" "R693"
			(at 0 0 90)
			(layer "B.SilkS")
			(hide yes)
			(effects
				(font
					(size 1.27 1.27)
				)
				(justify mirror)
			)
		)
		(property "Value" "4K7R2F-GP"
			(at -0.064008 -3.993896 270)
			(unlocked yes)
			(layer "B.Fab")
			(hide yes)
			(effects
				(font
					(size 1.016 1.016)
					(thickness 0.1524)
				)
				(justify mirror)
			)
		)
		(property "Device Type" "R402H16"
			(at -0.064008 -5.517896 270)
			(unlocked yes)
			(layer "B.Fab")
			(hide yes)
			(effects
				(font
					(size 1.016 1.016)
					(thickness 0.1524)
				)
				(justify mirror)
			)
		)
		(duplicate_pad_numbers_are_jumpers no)
		(fp_line
			(start -0.508 -0.9398)
			(end 0.508 -0.9398)
			(stroke
				(width 0.1524)
				(type default)
			)
			(layer "B.SilkS")
		)
		(fp_line
			(start 0.508 -0.9398)
			(end 0.508 0.9398)
			(stroke
				(width 0.1524)
				(type default)
			)
			(layer "B.SilkS")
		)
		(fp_rect
			(start 0.508 0.9398)
			(end -0.508 -0.9398)
			(stroke
				(width 0)
				(type default)
			)
			(fill no)
			(layer "B.CrtYd")
		)
		(fp_rect
			(start 0.508 0.9398)
			(end -0.508 -0.9398)
			(stroke
				(width 0)
				(type default)
			)
			(fill no)
			(layer "B.Fab")
		)
		(pad "1" smd custom
			(at 0 -0.4445 90)
			(size 0.1397 0.1397)
			(layers "B.Cu" "B.Mask" "B.Paste")
			(net "Q40_D")
			(options
				(clearance outline)
				(anchor circle)
			)
			(primitives
				(gr_poly
					(pts
						(arc
							(start -0.1778 0.2794)
							(mid -0.249642 0.249642)
							(end -0.2794 0.1778)
						)
						(arc
							(start -0.2794 -0.1778)
							(mid -0.249642 -0.249642)
							(end -0.1778 -0.2794)
						)
						(arc
							(start 0.1778 -0.2794)
							(mid 0.249642 -0.249642)
							(end 0.2794 -0.1778)
						)
						(arc
							(start 0.2794 0.1778)
							(mid 0.249642 0.249642)
							(end 0.1778 0.2794)
						)
					)
					(width 0)
					(fill yes)
				)
			)
		)
		(pad "2" smd custom
			(at 0 0.4445 90)
			(size 0.1397 0.1397)
			(layers "B.Cu" "B.Mask" "B.Paste")
			(net "P3V3_STBY")
			(options
				(clearance outline)
				(anchor circle)
			)
			(primitives
				(gr_poly
					(pts
						(arc
							(start -0.1778 0.2794)
							(mid -0.249642 0.249642)
							(end -0.2794 0.1778)
						)
						(arc
							(start -0.2794 -0.1778)
							(mid -0.249642 -0.249642)
							(end -0.1778 -0.2794)
						)
						(arc
							(start 0.1778 -0.2794)
							(mid 0.249642 -0.249642)
							(end 0.2794 -0.1778)
						)
						(arc
							(start 0.2794 0.1778)
							(mid 0.249642 0.249642)
							(end 0.1778 0.2794)
						)
					)
					(width 0)
					(fill yes)
				)
			)
		)
	)
	(footprint ""
		(layer "B.Cu")
		(at 218.670124 -190.601092 180)
		(property "Reference" "R553"
			(at 0 0 0)
			(layer "B.SilkS")
			(hide yes)
			(effects
				(font
					(size 1.27 1.27)
				)
				(justify mirror)
			)
		)
		(property "Value" "10KR2F-2-GP"
			(at -0.064008 -3.993896 180)
			(unlocked yes)
			(layer "B.Fab")
			(hide yes)
			(effects
				(font
					(size 1.016 1.016)
					(thickness 0.1524)
				)
				(justify mirror)
			)
		)
		(property "Device Type" "R402H16"
			(at -0.064008 -5.517896 180)
			(unlocked yes)
			(layer "B.Fab")
			(hide yes)
			(effects
				(font
					(size 1.016 1.016)
					(thickness 0.1524)
				)
				(justify mirror)
			)
		)
		(duplicate_pad_numbers_are_jumpers no)
		(fp_line
			(start 0.508 -0.9398)
			(end 0.508 0.9398)
			(stroke
				(width 0.1524)
				(type default)
			)
			(layer "B.SilkS")
		)
		(fp_line
			(start -0.508 -0.9398)
			(end 0.508 -0.9398)
			(stroke
				(width 0.1524)
				(type default)
			)
			(layer "B.SilkS")
		)
		(fp_rect
			(start 0.508 0.9398)
			(end -0.508 -0.9398)
			(stroke
				(width 0)
				(type default)
			)
			(fill no)
			(layer "B.CrtYd")
		)
		(fp_rect
			(start 0.508 0.9398)
			(end -0.508 -0.9398)
			(stroke
				(width 0)
				(type default)
			)
			(fill no)
			(layer "B.Fab")
		)
		(pad "1" smd custom
			(at 0 -0.4445)
			(size 0.1397 0.1397)
			(layers "B.Cu" "B.Mask" "B.Paste")
			(net "P3V3_STBY")
			(options
				(clearance outline)
				(anchor circle)
			)
			(primitives
				(gr_poly
					(pts
						(arc
							(start -0.1778 0.2794)
							(mid -0.249642 0.249642)
							(end -0.2794 0.1778)
						)
						(arc
							(start -0.2794 -0.1778)
							(mid -0.249642 -0.249642)
							(end -0.1778 -0.2794)
						)
						(arc
							(start 0.1778 -0.2794)
							(mid 0.249642 -0.249642)
							(end 0.2794 -0.1778)
						)
						(arc
							(start 0.2794 0.1778)
							(mid 0.249642 0.249642)
							(end 0.1778 0.2794)
						)
					)
					(width 0)
					(fill yes)
				)
			)
		)
		(pad "2" smd custom
			(at 0 0.4445)
			(size 0.1397 0.1397)
			(layers "B.Cu" "B.Mask" "B.Paste")
			(net "IOEXP3_AD2")
			(options
				(clearance outline)
				(anchor circle)
			)
			(primitives
				(gr_poly
					(pts
						(arc
							(start -0.1778 0.2794)
							(mid -0.249642 0.249642)
							(end -0.2794 0.1778)
						)
						(arc
							(start -0.2794 -0.1778)
							(mid -0.249642 -0.249642)
							(end -0.1778 -0.2794)
						)
						(arc
							(start 0.1778 -0.2794)
							(mid 0.249642 -0.249642)
							(end 0.2794 -0.1778)
						)
						(arc
							(start 0.2794 0.1778)
							(mid 0.249642 0.249642)
							(end 0.1778 0.2794)
						)
					)
					(width 0)
					(fill yes)
				)
			)
		)
	)
	(footprint ""
		(layer "B.Cu")
		(at 225.425 -198.882)
		(property "Reference" "R272"
			(at 0 0 0)
			(layer "B.SilkS")
			(hide yes)
			(effects
				(font
					(size 1.27 1.27)
				)
				(justify mirror)
			)
		)
		(property "Value" "4K7R2F-GP"
			(at -0.064008 -3.993896 0)
			(unlocked yes)
			(layer "B.Fab")
			(hide yes)
			(effects
				(font
					(size 1.016 1.016)
					(thickness 0.1524)
				)
				(justify mirror)
			)
		)
		(property "Device Type" "R402H16"
			(at -0.064008 -5.517896 0)
			(unlocked yes)
			(layer "B.Fab")
			(hide yes)
			(effects
				(font
					(size 1.016 1.016)
					(thickness 0.1524)
				)
				(justify mirror)
			)
		)
		(duplicate_pad_numbers_are_jumpers no)
		(fp_line
			(start -0.508 -0.9398)
			(end 0.508 -0.9398)
			(stroke
				(width 0.1524)
				(type default)
			)
			(layer "B.SilkS")
		)
		(fp_line
			(start 0.508 -0.9398)
			(end 0.508 0.9398)
			(stroke
				(width 0.1524)
				(type default)
			)
			(layer "B.SilkS")
		)
		(fp_rect
			(start 0.508 0.9398)
			(end -0.508 -0.9398)
			(stroke
				(width 0)
				(type default)
			)
			(fill no)
			(layer "B.CrtYd")
		)
		(fp_rect
			(start 0.508 0.9398)
			(end -0.508 -0.9398)
			(stroke
				(width 0)
				(type default)
			)
			(fill no)
			(layer "B.Fab")
		)
		(pad "1" smd custom
			(at 0 -0.4445 180)
			(size 0.1397 0.1397)
			(layers "B.Cu" "B.Mask" "B.Paste")
			(net "BMC_SSD_RST#0_A12")
			(options
				(clearance outline)
				(anchor circle)
			)
			(primitives
				(gr_poly
					(pts
						(arc
							(start -0.1778 0.2794)
							(mid -0.249642 0.249642)
							(end -0.2794 0.1778)
						)
						(arc
							(start -0.2794 -0.1778)
							(mid -0.249642 -0.249642)
							(end -0.1778 -0.2794)
						)
						(arc
							(start 0.1778 -0.2794)
							(mid 0.249642 -0.249642)
							(end 0.2794 -0.1778)
						)
						(arc
							(start 0.2794 0.1778)
							(mid 0.249642 0.249642)
							(end 0.1778 0.2794)
						)
					)
					(width 0)
					(fill yes)
				)
			)
		)
		(pad "2" smd custom
			(at 0 0.4445 180)
			(size 0.1397 0.1397)
			(layers "B.Cu" "B.Mask" "B.Paste")
			(net "P3V3_STBY")
			(options
				(clearance outline)
				(anchor circle)
			)
			(primitives
				(gr_poly
					(pts
						(arc
							(start -0.1778 0.2794)
							(mid -0.249642 0.249642)
							(end -0.2794 0.1778)
						)
						(arc
							(start -0.2794 -0.1778)
							(mid -0.249642 -0.249642)
							(end -0.1778 -0.2794)
						)
						(arc
							(start 0.1778 -0.2794)
							(mid 0.249642 -0.249642)
							(end 0.2794 -0.1778)
						)
						(arc
							(start 0.2794 0.1778)
							(mid 0.249642 0.249642)
							(end 0.1778 0.2794)
						)
					)
					(width 0)
					(fill yes)
				)
			)
		)
	)
	(footprint ""
		(layer "B.Cu")
		(at 47.117 -116.713)
		(property "Reference" "R223"
			(at 0 0 0)
			(layer "B.SilkS")
			(hide yes)
			(effects
				(font
					(size 1.27 1.27)
				)
				(justify mirror)
			)
		)
		(property "Value" "4K7R2F-GP"
			(at -0.064008 -3.993896 0)
			(unlocked yes)
			(layer "B.Fab")
			(hide yes)
			(effects
				(font
					(size 1.016 1.016)
					(thickness 0.1524)
				)
				(justify mirror)
			)
		)
		(property "Device Type" "R402H16"
			(at -0.064008 -5.517896 0)
			(unlocked yes)
			(layer "B.Fab")
			(hide yes)
			(effects
				(font
					(size 1.016 1.016)
					(thickness 0.1524)
				)
				(justify mirror)
			)
		)
		(duplicate_pad_numbers_are_jumpers no)
		(fp_line
			(start -0.508 -0.9398)
			(end 0.508 -0.9398)
			(stroke
				(width 0.1524)
				(type default)
			)
			(layer "B.SilkS")
		)
		(fp_line
			(start 0.508 -0.9398)
			(end 0.508 0.9398)
			(stroke
				(width 0.1524)
				(type default)
			)
			(layer "B.SilkS")
		)
		(fp_rect
			(start 0.508 0.9398)
			(end -0.508 -0.9398)
			(stroke
				(width 0)
				(type default)
			)
			(fill no)
			(layer "B.CrtYd")
		)
		(fp_rect
			(start 0.508 0.9398)
			(end -0.508 -0.9398)
			(stroke
				(width 0)
				(type default)
			)
			(fill no)
			(layer "B.Fab")
		)
		(pad "1" smd custom
			(at 0 -0.4445 180)
			(size 0.1397 0.1397)
			(layers "B.Cu" "B.Mask" "B.Paste")
			(net "PEER_TRAY_R")
			(options
				(clearance outline)
				(anchor circle)
			)
			(primitives
				(gr_poly
					(pts
						(arc
							(start -0.1778 0.2794)
							(mid -0.249642 0.249642)
							(end -0.2794 0.1778)
						)
						(arc
							(start -0.2794 -0.1778)
							(mid -0.249642 -0.249642)
							(end -0.1778 -0.2794)
						)
						(arc
							(start 0.1778 -0.2794)
							(mid 0.249642 -0.249642)
							(end 0.2794 -0.1778)
						)
						(arc
							(start 0.2794 0.1778)
							(mid 0.249642 0.249642)
							(end 0.1778 0.2794)
						)
					)
					(width 0)
					(fill yes)
				)
			)
		)
		(pad "2" smd custom
			(at 0 0.4445 180)
			(size 0.1397 0.1397)
			(layers "B.Cu" "B.Mask" "B.Paste")
			(net "P3V3_STBY")
			(options
				(clearance outline)
				(anchor circle)
			)
			(primitives
				(gr_poly
					(pts
						(arc
							(start -0.1778 0.2794)
							(mid -0.249642 0.249642)
							(end -0.2794 0.1778)
						)
						(arc
							(start -0.2794 -0.1778)
							(mid -0.249642 -0.249642)
							(end -0.1778 -0.2794)
						)
						(arc
							(start 0.1778 -0.2794)
							(mid 0.249642 -0.249642)
							(end 0.2794 -0.1778)
						)
						(arc
							(start 0.2794 0.1778)
							(mid 0.249642 0.249642)
							(end 0.1778 0.2794)
						)
					)
					(width 0)
					(fill yes)
				)
			)
		)
	)
	(footprint ""
		(layer "B.Cu")
		(at 68.834 -192.786 90)
		(property "Reference" "C8091"
			(at 0 0 90)
			(layer "B.SilkS")
			(hide yes)
			(effects
				(font
					(size 1.27 1.27)
				)
				(justify mirror)
			)
		)
		(property "Value" "SCD047U25V2KX-GP"
			(at -1.1811 -2.7051 90)
			(unlocked yes)
			(layer "B.Fab")
			(hide yes)
			(effects
				(font
					(size 1.016 1.016)
					(thickness 0.1524)
				)
				(justify mirror)
			)
		)
		(property "Device Type" "C402H22"
			(at -1.1811 -4.2291 90)
			(unlocked yes)
			(layer "B.Fab")
			(hide yes)
			(effects
				(font
					(size 1.016 1.016)
					(thickness 0.1524)
				)
				(justify mirror)
			)
		)
		(duplicate_pad_numbers_are_jumpers no)
		(fp_rect
			(start 0.4318 0.9525)
			(end -0.4318 -0.9525)
			(stroke
				(width 0)
				(type default)
			)
			(fill no)
			(layer "B.CrtYd")
		)
		(fp_rect
			(start 0.4318 0.9525)
			(end -0.4318 -0.9525)
			(stroke
				(width 0)
				(type default)
			)
			(fill no)
			(layer "B.Fab")
		)
		(pad "1" smd custom
			(at 0 -0.4445 270)
			(size 0.1524 0.1524)
			(layers "B.Cu" "B.Mask" "B.Paste")
			(net "P3V3_STBY")
			(options
				(clearance outline)
				(anchor circle)
			)
			(primitives
				(gr_poly
					(pts
						(arc
							(start 0.3048 0.2032)
							(mid 0.275042 0.275042)
							(end 0.2032 0.3048)
						)
						(arc
							(start -0.2032 0.3048)
							(mid -0.275042 0.275042)
							(end -0.3048 0.2032)
						)
						(arc
							(start -0.3048 -0.2032)
							(mid -0.275042 -0.275042)
							(end -0.2032 -0.3048)
						)
						(arc
							(start 0.2032 -0.3048)
							(mid 0.275042 -0.275042)
							(end 0.3048 -0.2032)
						)
					)
					(width 0)
					(fill yes)
				)
			)
		)
		(pad "2" smd custom
			(at 0 0.4445 270)
			(size 0.1524 0.1524)
			(layers "B.Cu" "B.Mask" "B.Paste")
			(net "GND")
			(options
				(clearance outline)
				(anchor circle)
			)
			(primitives
				(gr_poly
					(pts
						(arc
							(start 0.3048 0.2032)
							(mid 0.275042 0.275042)
							(end 0.2032 0.3048)
						)
						(arc
							(start -0.2032 0.3048)
							(mid -0.275042 0.275042)
							(end -0.3048 0.2032)
						)
						(arc
							(start -0.3048 -0.2032)
							(mid -0.275042 -0.275042)
							(end -0.2032 -0.3048)
						)
						(arc
							(start 0.2032 -0.3048)
							(mid 0.275042 -0.275042)
							(end 0.3048 -0.2032)
						)
					)
					(width 0)
					(fill yes)
				)
			)
		)
	)
	(footprint ""
		(layer "B.Cu")
		(at 219.837 -196.977)
		(property "Reference" "U67"
			(at 0 0 0)
			(layer "B.SilkS")
			(hide yes)
			(effects
				(font
					(size 1.27 1.27)
				)
				(justify mirror)
			)
		)
		(property "Value" "SN74LVC1G08DCKR-GP"
			(at 2.3368 -8.6868 0)
			(unlocked yes)
			(layer "B.Fab")
			(hide yes)
			(effects
				(font
					(size 1.016 1.016)
					(thickness 0.1524)
				)
				(justify mirror)
			)
		)
		(property "Device Type" "SC70-5H44"
			(at 2.3114 -10.414 0)
			(unlocked yes)
			(layer "B.Fab")
			(hide yes)
			(effects
				(font
					(size 1.016 1.016)
					(thickness 0.1524)
				)
				(justify mirror)
			)
		)
		(duplicate_pad_numbers_are_jumpers no)
		(fp_line
			(start -1.3843 -1.8034)
			(end -1.3843 -1.1176)
			(stroke
				(width 0.3302)
				(type default)
			)
			(layer "B.SilkS")
		)
		(fp_line
			(start -1.27 -1.7018)
			(end -1.27 1.7018)
			(stroke
				(width 0.1524)
				(type default)
			)
			(layer "B.SilkS")
		)
		(fp_line
			(start -1.27 1.7018)
			(end 1.27 1.7018)
			(stroke
				(width 0.1524)
				(type default)
			)
			(layer "B.SilkS")
		)
		(fp_line
			(start -0.6604 -1.8034)
			(end -1.3843 -1.8034)
			(stroke
				(width 0.3302)
				(type default)
			)
			(layer "B.SilkS")
		)
		(fp_line
			(start 1.27 -1.7018)
			(end -1.27 -1.7018)
			(stroke
				(width 0.1524)
				(type default)
			)
			(layer "B.SilkS")
		)
		(fp_line
			(start 1.27 1.7018)
			(end 1.27 -1.7018)
			(stroke
				(width 0.1524)
				(type default)
			)
			(layer "B.SilkS")
		)
		(fp_rect
			(start 1.524 1.9558)
			(end -1.524 -1.9558)
			(stroke
				(width 0)
				(type default)
			)
			(fill no)
			(layer "B.CrtYd")
		)
		(fp_poly
			(pts
				(xy 1.524 -1.9558) (xy -1.524 -1.9558) (xy -1.524 1.9558) (xy 1.524 1.9558)
			)
			(stroke
				(width 0)
				(type default)
			)
			(fill no)
			(layer "B.Fab")
		)
		(pad "1" smd rect
			(at -0.65024 -0.8255 180)
			(size 0.4064 1.2192)
			(layers "B.Cu" "B.Mask" "B.Paste")
			(net "BMC_SSD_RST#0_A3")
		)
		(pad "2" smd rect
			(at 0 -0.8255 180)
			(size 0.4064 1.2192)
			(layers "B.Cu" "B.Mask" "B.Paste")
			(net "SSD_PERST#0_B3")
		)
		(pad "3" smd rect
			(at 0.65024 -0.8255 180)
			(size 0.4064 1.2192)
			(layers "B.Cu" "B.Mask" "B.Paste")
			(net "GND")
		)
		(pad "4" smd rect
			(at 0.65024 0.8255 180)
			(size 0.4064 1.2192)
			(layers "B.Cu" "B.Mask" "B.Paste")
			(net "SSD_PERST_Y3")
		)
		(pad "5" smd rect
			(at -0.65024 0.8255 180)
			(size 0.4064 1.2192)
			(layers "B.Cu" "B.Mask" "B.Paste")
			(net "P3V3_STBY")
		)
	)
	(footprint ""
		(layer "B.Cu")
		(at 241.0968 -47.032672 90)
		(property "Reference" "C448"
			(at 0 0 90)
			(layer "B.SilkS")
			(hide yes)
			(effects
				(font
					(size 1.27 1.27)
				)
				(justify mirror)
			)
		)
		(property "Value" "SCD1U16V1KX-1-GP"
			(at 2.8321 -1.7399 90)
			(unlocked yes)
			(layer "B.Fab")
			(hide yes)
			(effects
				(font
					(size 1.016 1.016)
					(thickness 0.1524)
				)
				(justify mirror)
			)
		)
		(property "Device Type" "C0201H13"
			(at 2.8321 -3.2639 90)
			(unlocked yes)
			(layer "B.Fab")
			(hide yes)
			(effects
				(font
					(size 1.016 1.016)
					(thickness 0.1524)
				)
				(justify mirror)
			)
		)
		(duplicate_pad_numbers_are_jumpers no)
		(fp_rect
			(start 0.2794 0.6477)
			(end -0.2794 -0.6477)
			(stroke
				(width 0)
				(type default)
			)
			(fill no)
			(layer "B.CrtYd")
		)
		(fp_rect
			(start 0.2794 0.6477)
			(end -0.2794 -0.6477)
			(stroke
				(width 0)
				(type default)
			)
			(fill no)
			(layer "B.Fab")
		)
		(pad "1" smd custom
			(at 0 -0.2794 270)
			(size 0.0762 0.0762)
			(layers "B.Cu" "B.Mask" "B.Paste")
			(net "DUT_VDD")
			(options
				(clearance outline)
				(anchor circle)
			)
			(primitives
				(gr_poly
					(pts
						(arc
							(start 0.1524 0.127)
							(mid 0.137521 0.162921)
							(end 0.1016 0.1778)
						)
						(arc
							(start -0.1016 0.1778)
							(mid -0.137521 0.162921)
							(end -0.1524 0.127)
						)
						(arc
							(start -0.1524 -0.127)
							(mid -0.137521 -0.162921)
							(end -0.1016 -0.1778)
						)
						(arc
							(start 0.1016 -0.1778)
							(mid 0.137521 -0.162921)
							(end 0.1524 -0.127)
						)
					)
					(width 0)
					(fill yes)
				)
			)
		)
		(pad "2" smd custom
			(at 0 0.2794 270)
			(size 0.0762 0.0762)
			(layers "B.Cu" "B.Mask" "B.Paste")
			(net "GND")
			(options
				(clearance outline)
				(anchor circle)
			)
			(primitives
				(gr_poly
					(pts
						(arc
							(start 0.1524 0.127)
							(mid 0.137521 0.162921)
							(end 0.1016 0.1778)
						)
						(arc
							(start -0.1016 0.1778)
							(mid -0.137521 0.162921)
							(end -0.1524 0.127)
						)
						(arc
							(start -0.1524 -0.127)
							(mid -0.137521 -0.162921)
							(end -0.1016 -0.1778)
						)
						(arc
							(start 0.1016 -0.1778)
							(mid 0.137521 -0.162921)
							(end 0.1524 -0.127)
						)
					)
					(width 0)
					(fill yes)
				)
			)
		)
	)
	(footprint ""
		(layer "B.Cu")
		(at 171.999402 -62.714632)
		(property "Reference" "PC202"
			(at 0 0 0)
			(layer "B.SilkS")
			(hide yes)
			(effects
				(font
					(size 1.27 1.27)
				)
				(justify mirror)
			)
		)
		(property "Value" "SC22U6D3V5MX-5-GP"
			(at 0.0762 -6.1214 0)
			(unlocked yes)
			(layer "B.Fab")
			(hide yes)
			(effects
				(font
					(size 1.016 1.016)
					(thickness 0.1524)
				)
				(justify mirror)
			)
		)
		(property "Device Type" "C805H56"
			(at 0.0762 -8.1534 0)
			(unlocked yes)
			(layer "B.Fab")
			(hide yes)
			(effects
				(font
					(size 1.016 1.016)
					(thickness 0.1524)
				)
				(justify mirror)
			)
		)
		(duplicate_pad_numbers_are_jumpers no)
		(fp_line
			(start -0.635 0)
			(end 0.635 0)
			(stroke
				(width 0.508)
				(type default)
			)
			(layer "B.SilkS")
		)
		(fp_rect
			(start 0.9652 1.778)
			(end -0.9652 -1.778)
			(stroke
				(width 0)
				(type default)
			)
			(fill no)
			(layer "B.CrtYd")
		)
		(fp_poly
			(pts
				(xy 0.9652 -1.778) (xy -0.9652 -1.778) (xy -0.9652 1.778) (xy 0.9652 1.778)
			)
			(stroke
				(width 0)
				(type default)
			)
			(fill no)
			(layer "B.Fab")
		)
		(pad "1" smd rect
			(at 0 -0.9652 180)
			(size 1.397 1.143)
			(layers "B.Cu" "B.Mask" "B.Paste")
			(net "P0V9")
		)
		(pad "2" smd rect
			(at 0 0.9652 180)
			(size 1.397 1.143)
			(layers "B.Cu" "B.Mask" "B.Paste")
			(net "GND")
		)
	)
	(footprint ""
		(layer "B.Cu")
		(at 121.9708 -96.1898 180)
		(property "Reference" "R431"
			(at 0 0 0)
			(layer "B.SilkS")
			(hide yes)
			(effects
				(font
					(size 1.27 1.27)
				)
				(justify mirror)
			)
		)
		(property "Value" "0R2J-2-GP"
			(at -0.064008 -3.993896 180)
			(unlocked yes)
			(layer "B.Fab")
			(hide yes)
			(effects
				(font
					(size 1.016 1.016)
					(thickness 0.1524)
				)
				(justify mirror)
			)
		)
		(property "Device Type" "R402H16"
			(at -0.064008 -5.517896 180)
			(unlocked yes)
			(layer "B.Fab")
			(hide yes)
			(effects
				(font
					(size 1.016 1.016)
					(thickness 0.1524)
				)
				(justify mirror)
			)
		)
		(duplicate_pad_numbers_are_jumpers no)
		(fp_line
			(start 0.508 -0.9398)
			(end 0.508 0.9398)
			(stroke
				(width 0.1524)
				(type default)
			)
			(layer "B.SilkS")
		)
		(fp_line
			(start -0.508 -0.9398)
			(end 0.508 -0.9398)
			(stroke
				(width 0.1524)
				(type default)
			)
			(layer "B.SilkS")
		)
		(fp_rect
			(start 0.508 0.9398)
			(end -0.508 -0.9398)
			(stroke
				(width 0)
				(type default)
			)
			(fill no)
			(layer "B.CrtYd")
		)
		(fp_rect
			(start 0.508 0.9398)
			(end -0.508 -0.9398)
			(stroke
				(width 0)
				(type default)
			)
			(fill no)
			(layer "B.Fab")
		)
		(pad "1" smd custom
			(at 0 -0.4445)
			(size 0.1397 0.1397)
			(layers "B.Cu" "B.Mask" "B.Paste")
			(net "BMC_I2C10_8536_SCL")
			(options
				(clearance outline)
				(anchor circle)
			)
			(primitives
				(gr_poly
					(pts
						(arc
							(start -0.1778 0.2794)
							(mid -0.249642 0.249642)
							(end -0.2794 0.1778)
						)
						(arc
							(start -0.2794 -0.1778)
							(mid -0.249642 -0.249642)
							(end -0.1778 -0.2794)
						)
						(arc
							(start 0.1778 -0.2794)
							(mid 0.249642 -0.249642)
							(end 0.2794 -0.1778)
						)
						(arc
							(start 0.2794 0.1778)
							(mid 0.249642 0.249642)
							(end 0.1778 0.2794)
						)
					)
					(width 0)
					(fill yes)
				)
			)
		)
		(pad "2" smd custom
			(at 0 0.4445)
			(size 0.1397 0.1397)
			(layers "B.Cu" "B.Mask" "B.Paste")
			(net "TWI_SCL0")
			(options
				(clearance outline)
				(anchor circle)
			)
			(primitives
				(gr_poly
					(pts
						(arc
							(start -0.1778 0.2794)
							(mid -0.249642 0.249642)
							(end -0.2794 0.1778)
						)
						(arc
							(start -0.2794 -0.1778)
							(mid -0.249642 -0.249642)
							(end -0.1778 -0.2794)
						)
						(arc
							(start 0.1778 -0.2794)
							(mid 0.249642 -0.249642)
							(end 0.2794 -0.1778)
						)
						(arc
							(start 0.2794 0.1778)
							(mid 0.249642 0.249642)
							(end 0.1778 0.2794)
						)
					)
					(width 0)
					(fill yes)
				)
			)
		)
	)
	(footprint ""
		(layer "B.Cu")
		(at 75.987656 -195.730114 180)
		(property "Reference" "R4115"
			(at 0 0 0)
			(layer "B.SilkS")
			(hide yes)
			(effects
				(font
					(size 1.27 1.27)
				)
				(justify mirror)
			)
		)
		(property "Value" "4K7R2F-GP"
			(at -0.064008 -3.993896 180)
			(unlocked yes)
			(layer "B.Fab")
			(hide yes)
			(effects
				(font
					(size 1.016 1.016)
					(thickness 0.1524)
				)
				(justify mirror)
			)
		)
		(property "Device Type" "R402H16"
			(at -0.064008 -5.517896 180)
			(unlocked yes)
			(layer "B.Fab")
			(hide yes)
			(effects
				(font
					(size 1.016 1.016)
					(thickness 0.1524)
				)
				(justify mirror)
			)
		)
		(duplicate_pad_numbers_are_jumpers no)
		(fp_line
			(start 0.508 -0.9398)
			(end 0.508 0.9398)
			(stroke
				(width 0.1524)
				(type default)
			)
			(layer "B.SilkS")
		)
		(fp_line
			(start -0.508 -0.9398)
			(end 0.508 -0.9398)
			(stroke
				(width 0.1524)
				(type default)
			)
			(layer "B.SilkS")
		)
		(fp_rect
			(start 0.508 0.9398)
			(end -0.508 -0.9398)
			(stroke
				(width 0)
				(type default)
			)
			(fill no)
			(layer "B.CrtYd")
		)
		(fp_rect
			(start 0.508 0.9398)
			(end -0.508 -0.9398)
			(stroke
				(width 0)
				(type default)
			)
			(fill no)
			(layer "B.Fab")
		)
		(pad "1" smd custom
			(at 0 -0.4445)
			(size 0.1397 0.1397)
			(layers "B.Cu" "B.Mask" "B.Paste")
			(net "SSD_PRSNT#11")
			(options
				(clearance outline)
				(anchor circle)
			)
			(primitives
				(gr_poly
					(pts
						(arc
							(start -0.1778 0.2794)
							(mid -0.249642 0.249642)
							(end -0.2794 0.1778)
						)
						(arc
							(start -0.2794 -0.1778)
							(mid -0.249642 -0.249642)
							(end -0.1778 -0.2794)
						)
						(arc
							(start 0.1778 -0.2794)
							(mid 0.249642 -0.249642)
							(end 0.2794 -0.1778)
						)
						(arc
							(start 0.2794 0.1778)
							(mid 0.249642 0.249642)
							(end 0.1778 0.2794)
						)
					)
					(width 0)
					(fill yes)
				)
			)
		)
		(pad "2" smd custom
			(at 0 0.4445)
			(size 0.1397 0.1397)
			(layers "B.Cu" "B.Mask" "B.Paste")
			(net "P3V3_STBY")
			(options
				(clearance outline)
				(anchor circle)
			)
			(primitives
				(gr_poly
					(pts
						(arc
							(start -0.1778 0.2794)
							(mid -0.249642 0.249642)
							(end -0.2794 0.1778)
						)
						(arc
							(start -0.2794 -0.1778)
							(mid -0.249642 -0.249642)
							(end -0.1778 -0.2794)
						)
						(arc
							(start 0.1778 -0.2794)
							(mid 0.249642 -0.249642)
							(end 0.2794 -0.1778)
						)
						(arc
							(start 0.2794 0.1778)
							(mid 0.249642 0.249642)
							(end 0.1778 0.2794)
						)
					)
					(width 0)
					(fill yes)
				)
			)
		)
	)
	(footprint ""
		(layer "B.Cu")
		(at 71.724012 -195.689474)
		(property "Reference" "R519"
			(at 0 0 0)
			(layer "B.SilkS")
			(hide yes)
			(effects
				(font
					(size 1.27 1.27)
				)
				(justify mirror)
			)
		)
		(property "Value" "10KR2F-2-GP"
			(at -0.064008 -3.993896 0)
			(unlocked yes)
			(layer "B.Fab")
			(hide yes)
			(effects
				(font
					(size 1.016 1.016)
					(thickness 0.1524)
				)
				(justify mirror)
			)
		)
		(property "Device Type" "R402H16"
			(at -0.064008 -5.517896 0)
			(unlocked yes)
			(layer "B.Fab")
			(hide yes)
			(effects
				(font
					(size 1.016 1.016)
					(thickness 0.1524)
				)
				(justify mirror)
			)
		)
		(duplicate_pad_numbers_are_jumpers no)
		(fp_line
			(start -0.508 -0.9398)
			(end 0.508 -0.9398)
			(stroke
				(width 0.1524)
				(type default)
			)
			(layer "B.SilkS")
		)
		(fp_line
			(start 0.508 -0.9398)
			(end 0.508 0.9398)
			(stroke
				(width 0.1524)
				(type default)
			)
			(layer "B.SilkS")
		)
		(fp_rect
			(start 0.508 0.9398)
			(end -0.508 -0.9398)
			(stroke
				(width 0)
				(type default)
			)
			(fill no)
			(layer "B.CrtYd")
		)
		(fp_rect
			(start 0.508 0.9398)
			(end -0.508 -0.9398)
			(stroke
				(width 0)
				(type default)
			)
			(fill no)
			(layer "B.Fab")
		)
		(pad "1" smd custom
			(at 0 -0.4445 180)
			(size 0.1397 0.1397)
			(layers "B.Cu" "B.Mask" "B.Paste")
			(net "P3V3_STBY")
			(options
				(clearance outline)
				(anchor circle)
			)
			(primitives
				(gr_poly
					(pts
						(arc
							(start -0.1778 0.2794)
							(mid -0.249642 0.249642)
							(end -0.2794 0.1778)
						)
						(arc
							(start -0.2794 -0.1778)
							(mid -0.249642 -0.249642)
							(end -0.1778 -0.2794)
						)
						(arc
							(start 0.1778 -0.2794)
							(mid 0.249642 -0.249642)
							(end 0.2794 -0.1778)
						)
						(arc
							(start 0.2794 0.1778)
							(mid 0.249642 0.249642)
							(end 0.1778 0.2794)
						)
					)
					(width 0)
					(fill yes)
				)
			)
		)
		(pad "2" smd custom
			(at 0 0.4445 180)
			(size 0.1397 0.1397)
			(layers "B.Cu" "B.Mask" "B.Paste")
			(net "IOEXP1_AD0")
			(options
				(clearance outline)
				(anchor circle)
			)
			(primitives
				(gr_poly
					(pts
						(arc
							(start -0.1778 0.2794)
							(mid -0.249642 0.249642)
							(end -0.2794 0.1778)
						)
						(arc
							(start -0.2794 -0.1778)
							(mid -0.249642 -0.249642)
							(end -0.1778 -0.2794)
						)
						(arc
							(start 0.1778 -0.2794)
							(mid 0.249642 -0.249642)
							(end 0.2794 -0.1778)
						)
						(arc
							(start 0.2794 0.1778)
							(mid 0.249642 0.249642)
							(end 0.1778 0.2794)
						)
					)
					(width 0)
					(fill yes)
				)
			)
		)
	)
	(footprint ""
		(layer "B.Cu")
		(at 48.641 -148.082 180)
		(property "Reference" "R155"
			(at 0 0 0)
			(layer "B.SilkS")
			(hide yes)
			(effects
				(font
					(size 1.27 1.27)
				)
				(justify mirror)
			)
		)
		(property "Value" "4K7R2F-GP"
			(at -0.064008 -3.993896 180)
			(unlocked yes)
			(layer "B.Fab")
			(hide yes)
			(effects
				(font
					(size 1.016 1.016)
					(thickness 0.1524)
				)
				(justify mirror)
			)
		)
		(property "Device Type" "R402H16"
			(at -0.064008 -5.517896 180)
			(unlocked yes)
			(layer "B.Fab")
			(hide yes)
			(effects
				(font
					(size 1.016 1.016)
					(thickness 0.1524)
				)
				(justify mirror)
			)
		)
		(duplicate_pad_numbers_are_jumpers no)
		(fp_line
			(start 0.508 -0.9398)
			(end 0.508 0.9398)
			(stroke
				(width 0.1524)
				(type default)
			)
			(layer "B.SilkS")
		)
		(fp_line
			(start -0.508 -0.9398)
			(end 0.508 -0.9398)
			(stroke
				(width 0.1524)
				(type default)
			)
			(layer "B.SilkS")
		)
		(fp_rect
			(start 0.508 0.9398)
			(end -0.508 -0.9398)
			(stroke
				(width 0)
				(type default)
			)
			(fill no)
			(layer "B.CrtYd")
		)
		(fp_rect
			(start 0.508 0.9398)
			(end -0.508 -0.9398)
			(stroke
				(width 0)
				(type default)
			)
			(fill no)
			(layer "B.Fab")
		)
		(pad "1" smd custom
			(at 0 -0.4445)
			(size 0.1397 0.1397)
			(layers "B.Cu" "B.Mask" "B.Paste")
			(net "CBL_PRSNT_N_8")
			(options
				(clearance outline)
				(anchor circle)
			)
			(primitives
				(gr_poly
					(pts
						(arc
							(start -0.1778 0.2794)
							(mid -0.249642 0.249642)
							(end -0.2794 0.1778)
						)
						(arc
							(start -0.2794 -0.1778)
							(mid -0.249642 -0.249642)
							(end -0.1778 -0.2794)
						)
						(arc
							(start 0.1778 -0.2794)
							(mid 0.249642 -0.249642)
							(end 0.2794 -0.1778)
						)
						(arc
							(start 0.2794 0.1778)
							(mid 0.249642 0.249642)
							(end 0.1778 0.2794)
						)
					)
					(width 0)
					(fill yes)
				)
			)
		)
		(pad "2" smd custom
			(at 0 0.4445)
			(size 0.1397 0.1397)
			(layers "B.Cu" "B.Mask" "B.Paste")
			(net "P3V3_STBY")
			(options
				(clearance outline)
				(anchor circle)
			)
			(primitives
				(gr_poly
					(pts
						(arc
							(start -0.1778 0.2794)
							(mid -0.249642 0.249642)
							(end -0.2794 0.1778)
						)
						(arc
							(start -0.2794 -0.1778)
							(mid -0.249642 -0.249642)
							(end -0.1778 -0.2794)
						)
						(arc
							(start 0.1778 -0.2794)
							(mid 0.249642 -0.249642)
							(end 0.2794 -0.1778)
						)
						(arc
							(start 0.2794 0.1778)
							(mid 0.249642 0.249642)
							(end 0.1778 0.2794)
						)
					)
					(width 0)
					(fill yes)
				)
			)
		)
	)
	(footprint ""
		(layer "B.Cu")
		(at 180.72354 -3.09372 180)
		(property "Reference" "R213"
			(at 0 0 0)
			(layer "B.SilkS")
			(hide yes)
			(effects
				(font
					(size 1.27 1.27)
				)
				(justify mirror)
			)
		)
		(property "Value" "4K7R2F-GP"
			(at -0.064008 -3.993896 180)
			(unlocked yes)
			(layer "B.Fab")
			(hide yes)
			(effects
				(font
					(size 1.016 1.016)
					(thickness 0.1524)
				)
				(justify mirror)
			)
		)
		(property "Device Type" "R402H16"
			(at -0.064008 -5.517896 180)
			(unlocked yes)
			(layer "B.Fab")
			(hide yes)
			(effects
				(font
					(size 1.016 1.016)
					(thickness 0.1524)
				)
				(justify mirror)
			)
		)
		(duplicate_pad_numbers_are_jumpers no)
		(fp_line
			(start 0.508 -0.9398)
			(end 0.508 0.9398)
			(stroke
				(width 0.1524)
				(type default)
			)
			(layer "B.SilkS")
		)
		(fp_line
			(start -0.508 -0.9398)
			(end 0.508 -0.9398)
			(stroke
				(width 0.1524)
				(type default)
			)
			(layer "B.SilkS")
		)
		(fp_rect
			(start 0.508 0.9398)
			(end -0.508 -0.9398)
			(stroke
				(width 0)
				(type default)
			)
			(fill no)
			(layer "B.CrtYd")
		)
		(fp_rect
			(start 0.508 0.9398)
			(end -0.508 -0.9398)
			(stroke
				(width 0)
				(type default)
			)
			(fill no)
			(layer "B.Fab")
		)
		(pad "1" smd custom
			(at 0 -0.4445)
			(size 0.1397 0.1397)
			(layers "B.Cu" "B.Mask" "B.Paste")
			(net "P3V3_STBY")
			(options
				(clearance outline)
				(anchor circle)
			)
			(primitives
				(gr_poly
					(pts
						(arc
							(start -0.1778 0.2794)
							(mid -0.249642 0.249642)
							(end -0.2794 0.1778)
						)
						(arc
							(start -0.2794 -0.1778)
							(mid -0.249642 -0.249642)
							(end -0.1778 -0.2794)
						)
						(arc
							(start 0.1778 -0.2794)
							(mid 0.249642 -0.249642)
							(end 0.2794 -0.1778)
						)
						(arc
							(start 0.2794 0.1778)
							(mid 0.249642 0.249642)
							(end 0.1778 0.2794)
						)
					)
					(width 0)
					(fill yes)
				)
			)
		)
		(pad "2" smd custom
			(at 0 0.4445)
			(size 0.1397 0.1397)
			(layers "B.Cu" "B.Mask" "B.Paste")
			(net "CLK_P_1_R")
			(options
				(clearance outline)
				(anchor circle)
			)
			(primitives
				(gr_poly
					(pts
						(arc
							(start -0.1778 0.2794)
							(mid -0.249642 0.249642)
							(end -0.2794 0.1778)
						)
						(arc
							(start -0.2794 -0.1778)
							(mid -0.249642 -0.249642)
							(end -0.1778 -0.2794)
						)
						(arc
							(start 0.1778 -0.2794)
							(mid 0.249642 -0.249642)
							(end 0.2794 -0.1778)
						)
						(arc
							(start 0.2794 0.1778)
							(mid 0.249642 0.249642)
							(end 0.1778 0.2794)
						)
					)
					(width 0)
					(fill yes)
				)
			)
		)
	)
	(footprint ""
		(layer "B.Cu")
		(at 231.5972 -36.0045 90)
		(property "Reference" "TP205"
			(at 0 0 90)
			(layer "B.SilkS")
			(hide yes)
			(effects
				(font
					(size 1.27 1.27)
				)
				(justify mirror)
			)
		)
		(property "Value" "TPAD28-2-GP"
			(at 0.0127 -1.6637 90)
			(unlocked yes)
			(layer "B.Fab")
			(hide yes)
			(effects
				(font
					(size 1.016 1.016)
					(thickness 0.1524)
				)
				(justify mirror)
			)
		)
		(property "Device Type" "TPAD28"
			(at 0.0127 -3.1877 90)
			(unlocked yes)
			(layer "B.Fab")
			(hide yes)
			(effects
				(font
					(size 1.016 1.016)
					(thickness 0.1524)
				)
				(justify mirror)
			)
		)
		(duplicate_pad_numbers_are_jumpers no)
		(fp_poly
			(pts
				(arc
					(start 0 0.3556)
					(mid 0 -0.3556)
					(end 0 0.3556)
				)
			)
			(stroke
				(width 0)
				(type default)
			)
			(fill no)
			(layer "B.CrtYd")
		)
		(fp_poly
			(pts
				(arc
					(start 0 0.6096)
					(mid 0 -0.6096)
					(end 0 0.6096)
				)
			)
			(stroke
				(width 0)
				(type default)
			)
			(fill no)
			(layer "B.Fab")
		)
		(pad "1" smd circle
			(at 0 0 270)
			(size 0.7112 0.7112)
			(layers "B.Cu" "B.Mask" "B.Paste")
			(net "RMII_RX_ER")
		)
	)
	(footprint ""
		(layer "B.Cu")
		(at 235.6104 -36.5252 180)
		(property "Reference" "R9"
			(at 0 0 0)
			(layer "B.SilkS")
			(hide yes)
			(effects
				(font
					(size 1.27 1.27)
				)
				(justify mirror)
			)
		)
		(property "Value" "33R1J-GP"
			(at 3.3274 -1.3335 180)
			(unlocked yes)
			(layer "B.Fab")
			(hide yes)
			(effects
				(font
					(size 1.016 1.016)
					(thickness 0.1524)
				)
				(justify mirror)
			)
		)
		(property "Device Type" "R0201H12"
			(at 3.3274 -2.8575 180)
			(unlocked yes)
			(layer "B.Fab")
			(hide yes)
			(effects
				(font
					(size 1.016 1.016)
					(thickness 0.1524)
				)
				(justify mirror)
			)
		)
		(duplicate_pad_numbers_are_jumpers no)
		(fp_rect
			(start 0.2794 0.6477)
			(end -0.2794 -0.6477)
			(stroke
				(width 0)
				(type default)
			)
			(fill no)
			(layer "B.CrtYd")
		)
		(fp_rect
			(start 0.2794 0.6477)
			(end -0.2794 -0.6477)
			(stroke
				(width 0)
				(type default)
			)
			(fill no)
			(layer "B.Fab")
		)
		(pad "1" smd custom
			(at 0 -0.2794)
			(size 0.0762 0.0762)
			(layers "B.Cu" "B.Mask" "B.Paste")
			(net "PCIE_REFCLK_H3_N")
			(options
				(clearance outline)
				(anchor circle)
			)
			(primitives
				(gr_poly
					(pts
						(arc
							(start 0.1524 0.127)
							(mid 0.137521 0.162921)
							(end 0.1016 0.1778)
						)
						(arc
							(start -0.1016 0.1778)
							(mid -0.137521 0.162921)
							(end -0.1524 0.127)
						)
						(arc
							(start -0.1524 -0.127)
							(mid -0.137521 -0.162921)
							(end -0.1016 -0.1778)
						)
						(arc
							(start 0.1016 -0.1778)
							(mid 0.137521 -0.162921)
							(end 0.1524 -0.127)
						)
					)
					(width 0)
					(fill yes)
				)
			)
		)
		(pad "2" smd custom
			(at 0 0.2794)
			(size 0.0762 0.0762)
			(layers "B.Cu" "B.Mask" "B.Paste")
			(net "PCIE_REFCLK_H3_P")
			(options
				(clearance outline)
				(anchor circle)
			)
			(primitives
				(gr_poly
					(pts
						(arc
							(start 0.1524 0.127)
							(mid 0.137521 0.162921)
							(end 0.1016 0.1778)
						)
						(arc
							(start -0.1016 0.1778)
							(mid -0.137521 0.162921)
							(end -0.1524 0.127)
						)
						(arc
							(start -0.1524 -0.127)
							(mid -0.137521 -0.162921)
							(end -0.1016 -0.1778)
						)
						(arc
							(start 0.1016 -0.1778)
							(mid 0.137521 -0.162921)
							(end 0.1524 -0.127)
						)
					)
					(width 0)
					(fill yes)
				)
			)
		)
	)
	(footprint ""
		(layer "B.Cu")
		(at 235.1024 -41.995852 -90)
		(property "Reference" "C436"
			(at 0 0 90)
			(layer "B.SilkS")
			(hide yes)
			(effects
				(font
					(size 1.27 1.27)
				)
				(justify mirror)
			)
		)
		(property "Value" "SCD1U16V1KX-1-GP"
			(at 2.8321 -1.7399 270)
			(unlocked yes)
			(layer "B.Fab")
			(hide yes)
			(effects
				(font
					(size 1.016 1.016)
					(thickness 0.1524)
				)
				(justify mirror)
			)
		)
		(property "Device Type" "C0201H13"
			(at 2.8321 -3.2639 270)
			(unlocked yes)
			(layer "B.Fab")
			(hide yes)
			(effects
				(font
					(size 1.016 1.016)
					(thickness 0.1524)
				)
				(justify mirror)
			)
		)
		(duplicate_pad_numbers_are_jumpers no)
		(fp_rect
			(start 0.2794 0.6477)
			(end -0.2794 -0.6477)
			(stroke
				(width 0)
				(type default)
			)
			(fill no)
			(layer "B.CrtYd")
		)
		(fp_rect
			(start 0.2794 0.6477)
			(end -0.2794 -0.6477)
			(stroke
				(width 0)
				(type default)
			)
			(fill no)
			(layer "B.Fab")
		)
		(pad "1" smd custom
			(at 0 -0.2794 90)
			(size 0.0762 0.0762)
			(layers "B.Cu" "B.Mask" "B.Paste")
			(net "DUT_VDD")
			(options
				(clearance outline)
				(anchor circle)
			)
			(primitives
				(gr_poly
					(pts
						(arc
							(start 0.1524 0.127)
							(mid 0.137521 0.162921)
							(end 0.1016 0.1778)
						)
						(arc
							(start -0.1016 0.1778)
							(mid -0.137521 0.162921)
							(end -0.1524 0.127)
						)
						(arc
							(start -0.1524 -0.127)
							(mid -0.137521 -0.162921)
							(end -0.1016 -0.1778)
						)
						(arc
							(start 0.1016 -0.1778)
							(mid 0.137521 -0.162921)
							(end 0.1524 -0.127)
						)
					)
					(width 0)
					(fill yes)
				)
			)
		)
		(pad "2" smd custom
			(at 0 0.2794 90)
			(size 0.0762 0.0762)
			(layers "B.Cu" "B.Mask" "B.Paste")
			(net "GND")
			(options
				(clearance outline)
				(anchor circle)
			)
			(primitives
				(gr_poly
					(pts
						(arc
							(start 0.1524 0.127)
							(mid 0.137521 0.162921)
							(end 0.1016 0.1778)
						)
						(arc
							(start -0.1016 0.1778)
							(mid -0.137521 0.162921)
							(end -0.1524 0.127)
						)
						(arc
							(start -0.1524 -0.127)
							(mid -0.137521 -0.162921)
							(end -0.1016 -0.1778)
						)
						(arc
							(start 0.1016 -0.1778)
							(mid 0.137521 -0.162921)
							(end 0.1524 -0.127)
						)
					)
					(width 0)
					(fill yes)
				)
			)
		)
	)
	(footprint ""
		(layer "B.Cu")
		(at 182.1307 -4.55168 90)
		(property "Reference" "R205"
			(at 0 0 90)
			(layer "B.SilkS")
			(hide yes)
			(effects
				(font
					(size 1.27 1.27)
				)
				(justify mirror)
			)
		)
		(property "Value" "4K7R2F-GP"
			(at -0.064008 -3.993896 90)
			(unlocked yes)
			(layer "B.Fab")
			(hide yes)
			(effects
				(font
					(size 1.016 1.016)
					(thickness 0.1524)
				)
				(justify mirror)
			)
		)
		(property "Device Type" "R402H16"
			(at -0.064008 -5.517896 90)
			(unlocked yes)
			(layer "B.Fab")
			(hide yes)
			(effects
				(font
					(size 1.016 1.016)
					(thickness 0.1524)
				)
				(justify mirror)
			)
		)
		(duplicate_pad_numbers_are_jumpers no)
		(fp_line
			(start 0.508 -0.9398)
			(end 0.508 0.9398)
			(stroke
				(width 0.1524)
				(type default)
			)
			(layer "B.SilkS")
		)
		(fp_line
			(start -0.508 -0.9398)
			(end 0.508 -0.9398)
			(stroke
				(width 0.1524)
				(type default)
			)
			(layer "B.SilkS")
		)
		(fp_rect
			(start 0.508 0.9398)
			(end -0.508 -0.9398)
			(stroke
				(width 0)
				(type default)
			)
			(fill no)
			(layer "B.CrtYd")
		)
		(fp_rect
			(start 0.508 0.9398)
			(end -0.508 -0.9398)
			(stroke
				(width 0)
				(type default)
			)
			(fill no)
			(layer "B.Fab")
		)
		(pad "1" smd custom
			(at 0 -0.4445 270)
			(size 0.1397 0.1397)
			(layers "B.Cu" "B.Mask" "B.Paste")
			(net "CLK_P_1_R")
			(options
				(clearance outline)
				(anchor circle)
			)
			(primitives
				(gr_poly
					(pts
						(arc
							(start -0.1778 0.2794)
							(mid -0.249642 0.249642)
							(end -0.2794 0.1778)
						)
						(arc
							(start -0.2794 -0.1778)
							(mid -0.249642 -0.249642)
							(end -0.1778 -0.2794)
						)
						(arc
							(start 0.1778 -0.2794)
							(mid 0.249642 -0.249642)
							(end 0.2794 -0.1778)
						)
						(arc
							(start 0.2794 0.1778)
							(mid 0.249642 0.249642)
							(end 0.1778 0.2794)
						)
					)
					(width 0)
					(fill yes)
				)
			)
		)
		(pad "2" smd custom
			(at 0 0.4445 270)
			(size 0.1397 0.1397)
			(layers "B.Cu" "B.Mask" "B.Paste")
			(net "GND")
			(options
				(clearance outline)
				(anchor circle)
			)
			(primitives
				(gr_poly
					(pts
						(arc
							(start -0.1778 0.2794)
							(mid -0.249642 0.249642)
							(end -0.2794 0.1778)
						)
						(arc
							(start -0.2794 -0.1778)
							(mid -0.249642 -0.249642)
							(end -0.1778 -0.2794)
						)
						(arc
							(start 0.1778 -0.2794)
							(mid 0.249642 -0.249642)
							(end 0.2794 -0.1778)
						)
						(arc
							(start 0.2794 0.1778)
							(mid 0.249642 0.249642)
							(end 0.1778 0.2794)
						)
					)
					(width 0)
					(fill yes)
				)
			)
		)
	)
	(footprint ""
		(layer "B.Cu")
		(at 70.715124 -183.235092 180)
		(property "Reference" "R518"
			(at 0 0 0)
			(layer "B.SilkS")
			(hide yes)
			(effects
				(font
					(size 1.27 1.27)
				)
				(justify mirror)
			)
		)
		(property "Value" "10KR2F-2-GP"
			(at -0.064008 -3.993896 180)
			(unlocked yes)
			(layer "B.Fab")
			(hide yes)
			(effects
				(font
					(size 1.016 1.016)
					(thickness 0.1524)
				)
				(justify mirror)
			)
		)
		(property "Device Type" "R402H16"
			(at -0.064008 -5.517896 180)
			(unlocked yes)
			(layer "B.Fab")
			(hide yes)
			(effects
				(font
					(size 1.016 1.016)
					(thickness 0.1524)
				)
				(justify mirror)
			)
		)
		(duplicate_pad_numbers_are_jumpers no)
		(fp_line
			(start 0.508 -0.9398)
			(end 0.508 0.9398)
			(stroke
				(width 0.1524)
				(type default)
			)
			(layer "B.SilkS")
		)
		(fp_line
			(start -0.508 -0.9398)
			(end 0.508 -0.9398)
			(stroke
				(width 0.1524)
				(type default)
			)
			(layer "B.SilkS")
		)
		(fp_rect
			(start 0.508 0.9398)
			(end -0.508 -0.9398)
			(stroke
				(width 0)
				(type default)
			)
			(fill no)
			(layer "B.CrtYd")
		)
		(fp_rect
			(start 0.508 0.9398)
			(end -0.508 -0.9398)
			(stroke
				(width 0)
				(type default)
			)
			(fill no)
			(layer "B.Fab")
		)
		(pad "1" smd custom
			(at 0 -0.4445)
			(size 0.1397 0.1397)
			(layers "B.Cu" "B.Mask" "B.Paste")
			(net "P3V3_STBY")
			(options
				(clearance outline)
				(anchor circle)
			)
			(primitives
				(gr_poly
					(pts
						(arc
							(start -0.1778 0.2794)
							(mid -0.249642 0.249642)
							(end -0.2794 0.1778)
						)
						(arc
							(start -0.2794 -0.1778)
							(mid -0.249642 -0.249642)
							(end -0.1778 -0.2794)
						)
						(arc
							(start 0.1778 -0.2794)
							(mid 0.249642 -0.249642)
							(end 0.2794 -0.1778)
						)
						(arc
							(start 0.2794 0.1778)
							(mid 0.249642 0.249642)
							(end 0.1778 0.2794)
						)
					)
					(width 0)
					(fill yes)
				)
			)
		)
		(pad "2" smd custom
			(at 0 0.4445)
			(size 0.1397 0.1397)
			(layers "B.Cu" "B.Mask" "B.Paste")
			(net "IOEXP1_AD2")
			(options
				(clearance outline)
				(anchor circle)
			)
			(primitives
				(gr_poly
					(pts
						(arc
							(start -0.1778 0.2794)
							(mid -0.249642 0.249642)
							(end -0.2794 0.1778)
						)
						(arc
							(start -0.2794 -0.1778)
							(mid -0.249642 -0.249642)
							(end -0.1778 -0.2794)
						)
						(arc
							(start 0.1778 -0.2794)
							(mid 0.249642 -0.249642)
							(end 0.2794 -0.1778)
						)
						(arc
							(start 0.2794 0.1778)
							(mid 0.249642 0.249642)
							(end 0.1778 0.2794)
						)
					)
					(width 0)
					(fill yes)
				)
			)
		)
	)
	(footprint ""
		(layer "B.Cu")
		(at 249.428 -26.67 -90)
		(property "Reference" "TP286"
			(at 0 0 90)
			(layer "B.SilkS")
			(hide yes)
			(effects
				(font
					(size 1.27 1.27)
				)
				(justify mirror)
			)
		)
		(property "Value" "TPAD28-2-GP"
			(at 0.0127 -1.6637 270)
			(unlocked yes)
			(layer "B.Fab")
			(hide yes)
			(effects
				(font
					(size 1.016 1.016)
					(thickness 0.1524)
				)
				(justify mirror)
			)
		)
		(property "Device Type" "TPAD28"
			(at 0.0127 -3.1877 270)
			(unlocked yes)
			(layer "B.Fab")
			(hide yes)
			(effects
				(font
					(size 1.016 1.016)
					(thickness 0.1524)
				)
				(justify mirror)
			)
		)
		(duplicate_pad_numbers_are_jumpers no)
		(fp_poly
			(pts
				(arc
					(start 0 -0.3556)
					(mid 0 0.3556)
					(end 0 -0.3556)
				)
			)
			(stroke
				(width 0)
				(type default)
			)
			(fill no)
			(layer "B.CrtYd")
		)
		(fp_poly
			(pts
				(arc
					(start 0 -0.6096)
					(mid 0 0.6096)
					(end 0 -0.6096)
				)
			)
			(stroke
				(width 0)
				(type default)
			)
			(fill no)
			(layer "B.Fab")
		)
		(pad "1" smd circle
			(at 0 0 90)
			(size 0.7112 0.7112)
			(layers "B.Cu" "B.Mask" "B.Paste")
			(net "TWI_SCL5")
		)
	)
	(footprint ""
		(layer "B.Cu")
		(at 252.603 -40.9956 -90)
		(property "Reference" "C616"
			(at 0 0 90)
			(layer "B.SilkS")
			(hide yes)
			(effects
				(font
					(size 1.27 1.27)
				)
				(justify mirror)
			)
		)
		(property "Value" "SCD1U16V1KX-1-GP"
			(at 2.8321 -1.7399 270)
			(unlocked yes)
			(layer "B.Fab")
			(hide yes)
			(effects
				(font
					(size 1.016 1.016)
					(thickness 0.1524)
				)
				(justify mirror)
			)
		)
		(property "Device Type" "C0201H13"
			(at 2.8321 -3.2639 270)
			(unlocked yes)
			(layer "B.Fab")
			(hide yes)
			(effects
				(font
					(size 1.016 1.016)
					(thickness 0.1524)
				)
				(justify mirror)
			)
		)
		(duplicate_pad_numbers_are_jumpers no)
		(fp_rect
			(start 0.2794 0.6477)
			(end -0.2794 -0.6477)
			(stroke
				(width 0)
				(type default)
			)
			(fill no)
			(layer "B.CrtYd")
		)
		(fp_rect
			(start 0.2794 0.6477)
			(end -0.2794 -0.6477)
			(stroke
				(width 0)
				(type default)
			)
			(fill no)
			(layer "B.Fab")
		)
		(pad "1" smd custom
			(at 0 -0.2794 90)
			(size 0.0762 0.0762)
			(layers "B.Cu" "B.Mask" "B.Paste")
			(net "DUT_AVD_PCIE")
			(options
				(clearance outline)
				(anchor circle)
			)
			(primitives
				(gr_poly
					(pts
						(arc
							(start 0.1524 0.127)
							(mid 0.137521 0.162921)
							(end 0.1016 0.1778)
						)
						(arc
							(start -0.1016 0.1778)
							(mid -0.137521 0.162921)
							(end -0.1524 0.127)
						)
						(arc
							(start -0.1524 -0.127)
							(mid -0.137521 -0.162921)
							(end -0.1016 -0.1778)
						)
						(arc
							(start 0.1016 -0.1778)
							(mid 0.137521 -0.162921)
							(end 0.1524 -0.127)
						)
					)
					(width 0)
					(fill yes)
				)
			)
		)
		(pad "2" smd custom
			(at 0 0.2794 90)
			(size 0.0762 0.0762)
			(layers "B.Cu" "B.Mask" "B.Paste")
			(net "GND")
			(options
				(clearance outline)
				(anchor circle)
			)
			(primitives
				(gr_poly
					(pts
						(arc
							(start 0.1524 0.127)
							(mid 0.137521 0.162921)
							(end 0.1016 0.1778)
						)
						(arc
							(start -0.1016 0.1778)
							(mid -0.137521 0.162921)
							(end -0.1524 0.127)
						)
						(arc
							(start -0.1524 -0.127)
							(mid -0.137521 -0.162921)
							(end -0.1016 -0.1778)
						)
						(arc
							(start 0.1016 -0.1778)
							(mid 0.137521 -0.162921)
							(end 0.1524 -0.127)
						)
					)
					(width 0)
					(fill yes)
				)
			)
		)
	)
	(footprint ""
		(layer "B.Cu")
		(at 322.537836 -38.896798)
		(property "Reference" "C255"
			(at 0 0 0)
			(layer "B.SilkS")
			(hide yes)
			(effects
				(font
					(size 1.27 1.27)
				)
				(justify mirror)
			)
		)
		(property "Value" "SCD1U10V2KX-5GP"
			(at -1.1811 -2.7051 0)
			(unlocked yes)
			(layer "B.Fab")
			(hide yes)
			(effects
				(font
					(size 1.016 1.016)
					(thickness 0.1524)
				)
				(justify mirror)
			)
		)
		(property "Device Type" "C402H22"
			(at -1.1811 -4.2291 0)
			(unlocked yes)
			(layer "B.Fab")
			(hide yes)
			(effects
				(font
					(size 1.016 1.016)
					(thickness 0.1524)
				)
				(justify mirror)
			)
		)
		(duplicate_pad_numbers_are_jumpers no)
		(fp_rect
			(start 0.4318 0.9525)
			(end -0.4318 -0.9525)
			(stroke
				(width 0)
				(type default)
			)
			(fill no)
			(layer "B.CrtYd")
		)
		(fp_rect
			(start 0.4318 0.9525)
			(end -0.4318 -0.9525)
			(stroke
				(width 0)
				(type default)
			)
			(fill no)
			(layer "B.Fab")
		)
		(pad "1" smd custom
			(at 0 -0.4445 180)
			(size 0.1524 0.1524)
			(layers "B.Cu" "B.Mask" "B.Paste")
			(net "GND")
			(options
				(clearance outline)
				(anchor circle)
			)
			(primitives
				(gr_poly
					(pts
						(arc
							(start 0.3048 0.2032)
							(mid 0.275042 0.275042)
							(end 0.2032 0.3048)
						)
						(arc
							(start -0.2032 0.3048)
							(mid -0.275042 0.275042)
							(end -0.3048 0.2032)
						)
						(arc
							(start -0.3048 -0.2032)
							(mid -0.275042 -0.275042)
							(end -0.2032 -0.3048)
						)
						(arc
							(start 0.2032 -0.3048)
							(mid 0.275042 -0.275042)
							(end 0.3048 -0.2032)
						)
					)
					(width 0)
					(fill yes)
				)
			)
		)
		(pad "2" smd custom
			(at 0 0.4445 180)
			(size 0.1524 0.1524)
			(layers "B.Cu" "B.Mask" "B.Paste")
			(net "P3V3_STBY")
			(options
				(clearance outline)
				(anchor circle)
			)
			(primitives
				(gr_poly
					(pts
						(arc
							(start 0.3048 0.2032)
							(mid 0.275042 0.275042)
							(end 0.2032 0.3048)
						)
						(arc
							(start -0.2032 0.3048)
							(mid -0.275042 0.275042)
							(end -0.3048 0.2032)
						)
						(arc
							(start -0.3048 -0.2032)
							(mid -0.275042 -0.275042)
							(end -0.2032 -0.3048)
						)
						(arc
							(start 0.2032 -0.3048)
							(mid 0.275042 -0.275042)
							(end 0.3048 -0.2032)
						)
					)
					(width 0)
					(fill yes)
				)
			)
		)
	)
	(footprint ""
		(layer "B.Cu")
		(at 56.134 -133.985 180)
		(property "Reference" "C8088"
			(at 0 0 0)
			(layer "B.SilkS")
			(hide yes)
			(effects
				(font
					(size 1.27 1.27)
				)
				(justify mirror)
			)
		)
		(property "Value" "SCD1U25V2KX-2-GP"
			(at -1.1811 -2.7051 180)
			(unlocked yes)
			(layer "B.Fab")
			(hide yes)
			(effects
				(font
					(size 1.016 1.016)
					(thickness 0.1524)
				)
				(justify mirror)
			)
		)
		(property "Device Type" "C402H22"
			(at -1.1811 -4.2291 180)
			(unlocked yes)
			(layer "B.Fab")
			(hide yes)
			(effects
				(font
					(size 1.016 1.016)
					(thickness 0.1524)
				)
				(justify mirror)
			)
		)
		(duplicate_pad_numbers_are_jumpers no)
		(fp_rect
			(start 0.4318 0.9525)
			(end -0.4318 -0.9525)
			(stroke
				(width 0)
				(type default)
			)
			(fill no)
			(layer "B.CrtYd")
		)
		(fp_rect
			(start 0.4318 0.9525)
			(end -0.4318 -0.9525)
			(stroke
				(width 0)
				(type default)
			)
			(fill no)
			(layer "B.Fab")
		)
		(pad "1" smd custom
			(at 0 -0.4445)
			(size 0.1524 0.1524)
			(layers "B.Cu" "B.Mask" "B.Paste")
			(net "ADC_P5V_STBY")
			(options
				(clearance outline)
				(anchor circle)
			)
			(primitives
				(gr_poly
					(pts
						(arc
							(start 0.3048 0.2032)
							(mid 0.275042 0.275042)
							(end 0.2032 0.3048)
						)
						(arc
							(start -0.2032 0.3048)
							(mid -0.275042 0.275042)
							(end -0.3048 0.2032)
						)
						(arc
							(start -0.3048 -0.2032)
							(mid -0.275042 -0.275042)
							(end -0.2032 -0.3048)
						)
						(arc
							(start 0.2032 -0.3048)
							(mid 0.275042 -0.275042)
							(end 0.3048 -0.2032)
						)
					)
					(width 0)
					(fill yes)
				)
			)
		)
		(pad "2" smd custom
			(at 0 0.4445)
			(size 0.1524 0.1524)
			(layers "B.Cu" "B.Mask" "B.Paste")
			(net "GND")
			(options
				(clearance outline)
				(anchor circle)
			)
			(primitives
				(gr_poly
					(pts
						(arc
							(start 0.3048 0.2032)
							(mid 0.275042 0.275042)
							(end 0.2032 0.3048)
						)
						(arc
							(start -0.2032 0.3048)
							(mid -0.275042 0.275042)
							(end -0.3048 0.2032)
						)
						(arc
							(start -0.3048 -0.2032)
							(mid -0.275042 -0.275042)
							(end -0.2032 -0.3048)
						)
						(arc
							(start 0.2032 -0.3048)
							(mid 0.275042 -0.275042)
							(end 0.3048 -0.2032)
						)
					)
					(width 0)
					(fill yes)
				)
			)
		)
	)
	(footprint ""
		(layer "B.Cu")
		(at 73.787 -37.465)
		(property "Reference" "PR26"
			(at 0 0 0)
			(layer "B.SilkS")
			(hide yes)
			(effects
				(font
					(size 1.27 1.27)
				)
				(justify mirror)
			)
		)
		(property "Value" "2KR2F-3-GP"
			(at -0.064008 -3.993896 0)
			(unlocked yes)
			(layer "B.Fab")
			(hide yes)
			(effects
				(font
					(size 1.016 1.016)
					(thickness 0.1524)
				)
				(justify mirror)
			)
		)
		(property "Device Type" "R402H16"
			(at -0.064008 -5.517896 0)
			(unlocked yes)
			(layer "B.Fab")
			(hide yes)
			(effects
				(font
					(size 1.016 1.016)
					(thickness 0.1524)
				)
				(justify mirror)
			)
		)
		(duplicate_pad_numbers_are_jumpers no)
		(fp_line
			(start -0.508 -0.9398)
			(end 0.508 -0.9398)
			(stroke
				(width 0.1524)
				(type default)
			)
			(layer "B.SilkS")
		)
		(fp_line
			(start 0.508 -0.9398)
			(end 0.508 0.9398)
			(stroke
				(width 0.1524)
				(type default)
			)
			(layer "B.SilkS")
		)
		(fp_rect
			(start 0.508 0.9398)
			(end -0.508 -0.9398)
			(stroke
				(width 0)
				(type default)
			)
			(fill no)
			(layer "B.CrtYd")
		)
		(fp_rect
			(start 0.508 0.9398)
			(end -0.508 -0.9398)
			(stroke
				(width 0)
				(type default)
			)
			(fill no)
			(layer "B.Fab")
		)
		(pad "1" smd custom
			(at 0 -0.4445 180)
			(size 0.1397 0.1397)
			(layers "B.Cu" "B.Mask" "B.Paste")
			(net "P3V3_STBY_LL")
			(options
				(clearance outline)
				(anchor circle)
			)
			(primitives
				(gr_poly
					(pts
						(arc
							(start -0.1778 0.2794)
							(mid -0.249642 0.249642)
							(end -0.2794 0.1778)
						)
						(arc
							(start -0.2794 -0.1778)
							(mid -0.249642 -0.249642)
							(end -0.1778 -0.2794)
						)
						(arc
							(start 0.1778 -0.2794)
							(mid 0.249642 -0.249642)
							(end 0.2794 -0.1778)
						)
						(arc
							(start 0.2794 0.1778)
							(mid 0.249642 0.249642)
							(end 0.1778 0.2794)
						)
					)
					(width 0)
					(fill yes)
				)
			)
		)
		(pad "2" smd custom
			(at 0 0.4445 180)
			(size 0.1397 0.1397)
			(layers "B.Cu" "B.Mask" "B.Paste")
			(net "P3V3_STBY_LL_R")
			(options
				(clearance outline)
				(anchor circle)
			)
			(primitives
				(gr_poly
					(pts
						(arc
							(start -0.1778 0.2794)
							(mid -0.249642 0.249642)
							(end -0.2794 0.1778)
						)
						(arc
							(start -0.2794 -0.1778)
							(mid -0.249642 -0.249642)
							(end -0.1778 -0.2794)
						)
						(arc
							(start 0.1778 -0.2794)
							(mid 0.249642 -0.249642)
							(end 0.2794 -0.1778)
						)
						(arc
							(start 0.2794 0.1778)
							(mid 0.249642 0.249642)
							(end 0.1778 0.2794)
						)
					)
					(width 0)
					(fill yes)
				)
			)
		)
	)
	(footprint ""
		(layer "B.Cu")
		(at 182.8546 -71.628 180)
		(property "Reference" "C619"
			(at 0 0 0)
			(layer "B.SilkS")
			(hide yes)
			(effects
				(font
					(size 1.27 1.27)
				)
				(justify mirror)
			)
		)
		(property "Value" "SC4D7U16V5KX-1-GP"
			(at 0.0762 -6.1214 180)
			(unlocked yes)
			(layer "B.Fab")
			(hide yes)
			(effects
				(font
					(size 1.016 1.016)
					(thickness 0.1524)
				)
				(justify mirror)
			)
		)
		(property "Device Type" "C805H56"
			(at 0.0762 -8.1534 180)
			(unlocked yes)
			(layer "B.Fab")
			(hide yes)
			(effects
				(font
					(size 1.016 1.016)
					(thickness 0.1524)
				)
				(justify mirror)
			)
		)
		(duplicate_pad_numbers_are_jumpers no)
		(fp_line
			(start -0.635 0)
			(end 0.635 0)
			(stroke
				(width 0.508)
				(type default)
			)
			(layer "B.SilkS")
		)
		(fp_rect
			(start 0.9652 1.778)
			(end -0.9652 -1.778)
			(stroke
				(width 0)
				(type default)
			)
			(fill no)
			(layer "B.CrtYd")
		)
		(fp_poly
			(pts
				(xy 0.9652 -1.778) (xy -0.9652 -1.778) (xy -0.9652 1.778) (xy 0.9652 1.778)
			)
			(stroke
				(width 0)
				(type default)
			)
			(fill no)
			(layer "B.Fab")
		)
		(pad "1" smd rect
			(at 0 -0.9652)
			(size 1.397 1.143)
			(layers "B.Cu" "B.Mask" "B.Paste")
			(net "DUT_AVD_PCIE")
		)
		(pad "2" smd rect
			(at 0 0.9652)
			(size 1.397 1.143)
			(layers "B.Cu" "B.Mask" "B.Paste")
			(net "GND")
		)
	)
	(footprint ""
		(layer "B.Cu")
		(at 12.9032 -85.979 180)
		(property "Reference" "C627"
			(at 0 0 0)
			(layer "B.SilkS")
			(hide yes)
			(effects
				(font
					(size 1.27 1.27)
				)
				(justify mirror)
			)
		)
		(property "Value" "SC10U6D3V5KX-4GP"
			(at 0.0762 -6.1214 180)
			(unlocked yes)
			(layer "B.Fab")
			(hide yes)
			(effects
				(font
					(size 1.016 1.016)
					(thickness 0.1524)
				)
				(justify mirror)
			)
		)
		(property "Device Type" "C805H58"
			(at 0.0762 -8.1534 180)
			(unlocked yes)
			(layer "B.Fab")
			(hide yes)
			(effects
				(font
					(size 1.016 1.016)
					(thickness 0.1524)
				)
				(justify mirror)
			)
		)
		(duplicate_pad_numbers_are_jumpers no)
		(fp_line
			(start -0.635 0)
			(end 0.635 0)
			(stroke
				(width 0.508)
				(type default)
			)
			(layer "B.SilkS")
		)
		(fp_rect
			(start 0.9652 1.778)
			(end -0.9652 -1.778)
			(stroke
				(width 0)
				(type default)
			)
			(fill no)
			(layer "B.CrtYd")
		)
		(fp_poly
			(pts
				(xy 0.9652 -1.778) (xy -0.9652 -1.778) (xy -0.9652 1.778) (xy 0.9652 1.778)
			)
			(stroke
				(width 0)
				(type default)
			)
			(fill no)
			(layer "B.Fab")
		)
		(pad "1" smd rect
			(at 0 -0.9652)
			(size 1.397 1.143)
			(layers "B.Cu" "B.Mask" "B.Paste")
			(net "P3V3_STBY")
		)
		(pad "2" smd rect
			(at 0 0.9652)
			(size 1.397 1.143)
			(layers "B.Cu" "B.Mask" "B.Paste")
			(net "GND")
		)
	)
	(footprint ""
		(layer "B.Cu")
		(at 239.8522 -25.019 90)
		(property "Reference" "TP194"
			(at 0 0 90)
			(layer "B.SilkS")
			(hide yes)
			(effects
				(font
					(size 1.27 1.27)
				)
				(justify mirror)
			)
		)
		(property "Value" "TPAD28-2-GP"
			(at 0.0127 -1.6637 90)
			(unlocked yes)
			(layer "B.Fab")
			(hide yes)
			(effects
				(font
					(size 1.016 1.016)
					(thickness 0.1524)
				)
				(justify mirror)
			)
		)
		(property "Device Type" "TPAD28"
			(at 0.0127 -3.1877 90)
			(unlocked yes)
			(layer "B.Fab")
			(hide yes)
			(effects
				(font
					(size 1.016 1.016)
					(thickness 0.1524)
				)
				(justify mirror)
			)
		)
		(duplicate_pad_numbers_are_jumpers no)
		(fp_poly
			(pts
				(arc
					(start 0 0.3556)
					(mid 0 -0.3556)
					(end 0 0.3556)
				)
			)
			(stroke
				(width 0)
				(type default)
			)
			(fill no)
			(layer "B.CrtYd")
		)
		(fp_poly
			(pts
				(arc
					(start 0 0.6096)
					(mid 0 -0.6096)
					(end 0 0.6096)
				)
			)
			(stroke
				(width 0)
				(type default)
			)
			(fill no)
			(layer "B.Fab")
		)
		(pad "1" smd circle
			(at 0 0 270)
			(size 0.7112 0.7112)
			(layers "B.Cu" "B.Mask" "B.Paste")
			(net "LBI_CE#0")
		)
	)
	(footprint ""
		(layer "B.Cu")
		(at 53.721 -138.811 90)
		(property "Reference" "R149"
			(at 0 0 90)
			(layer "B.SilkS")
			(hide yes)
			(effects
				(font
					(size 1.27 1.27)
				)
				(justify mirror)
			)
		)
		(property "Value" "4K7R2F-GP"
			(at -0.064008 -3.993896 90)
			(unlocked yes)
			(layer "B.Fab")
			(hide yes)
			(effects
				(font
					(size 1.016 1.016)
					(thickness 0.1524)
				)
				(justify mirror)
			)
		)
		(property "Device Type" "R402H16"
			(at -0.064008 -5.517896 90)
			(unlocked yes)
			(layer "B.Fab")
			(hide yes)
			(effects
				(font
					(size 1.016 1.016)
					(thickness 0.1524)
				)
				(justify mirror)
			)
		)
		(duplicate_pad_numbers_are_jumpers no)
		(fp_line
			(start 0.508 -0.9398)
			(end 0.508 0.9398)
			(stroke
				(width 0.1524)
				(type default)
			)
			(layer "B.SilkS")
		)
		(fp_line
			(start -0.508 -0.9398)
			(end 0.508 -0.9398)
			(stroke
				(width 0.1524)
				(type default)
			)
			(layer "B.SilkS")
		)
		(fp_rect
			(start 0.508 0.9398)
			(end -0.508 -0.9398)
			(stroke
				(width 0)
				(type default)
			)
			(fill no)
			(layer "B.CrtYd")
		)
		(fp_rect
			(start 0.508 0.9398)
			(end -0.508 -0.9398)
			(stroke
				(width 0)
				(type default)
			)
			(fill no)
			(layer "B.Fab")
		)
		(pad "1" smd custom
			(at 0 -0.4445 270)
			(size 0.1397 0.1397)
			(layers "B.Cu" "B.Mask" "B.Paste")
			(net "CBL_PRSNT_N_5")
			(options
				(clearance outline)
				(anchor circle)
			)
			(primitives
				(gr_poly
					(pts
						(arc
							(start -0.1778 0.2794)
							(mid -0.249642 0.249642)
							(end -0.2794 0.1778)
						)
						(arc
							(start -0.2794 -0.1778)
							(mid -0.249642 -0.249642)
							(end -0.1778 -0.2794)
						)
						(arc
							(start 0.1778 -0.2794)
							(mid 0.249642 -0.249642)
							(end 0.2794 -0.1778)
						)
						(arc
							(start 0.2794 0.1778)
							(mid 0.249642 0.249642)
							(end 0.1778 0.2794)
						)
					)
					(width 0)
					(fill yes)
				)
			)
		)
		(pad "2" smd custom
			(at 0 0.4445 270)
			(size 0.1397 0.1397)
			(layers "B.Cu" "B.Mask" "B.Paste")
			(net "P3V3_STBY")
			(options
				(clearance outline)
				(anchor circle)
			)
			(primitives
				(gr_poly
					(pts
						(arc
							(start -0.1778 0.2794)
							(mid -0.249642 0.249642)
							(end -0.2794 0.1778)
						)
						(arc
							(start -0.2794 -0.1778)
							(mid -0.249642 -0.249642)
							(end -0.1778 -0.2794)
						)
						(arc
							(start 0.1778 -0.2794)
							(mid 0.249642 -0.249642)
							(end 0.2794 -0.1778)
						)
						(arc
							(start 0.2794 0.1778)
							(mid 0.249642 0.249642)
							(end 0.1778 0.2794)
						)
					)
					(width 0)
					(fill yes)
				)
			)
		)
	)
	(footprint ""
		(layer "B.Cu")
		(at 226.925124 -190.601092)
		(property "Reference" "R4145"
			(at 0 0 0)
			(layer "B.SilkS")
			(hide yes)
			(effects
				(font
					(size 1.27 1.27)
				)
				(justify mirror)
			)
		)
		(property "Value" "4K7R2F-GP"
			(at -0.064008 -3.993896 0)
			(unlocked yes)
			(layer "B.Fab")
			(hide yes)
			(effects
				(font
					(size 1.016 1.016)
					(thickness 0.1524)
				)
				(justify mirror)
			)
		)
		(property "Device Type" "R402H16"
			(at -0.064008 -5.517896 0)
			(unlocked yes)
			(layer "B.Fab")
			(hide yes)
			(effects
				(font
					(size 1.016 1.016)
					(thickness 0.1524)
				)
				(justify mirror)
			)
		)
		(duplicate_pad_numbers_are_jumpers no)
		(fp_line
			(start -0.508 -0.9398)
			(end 0.508 -0.9398)
			(stroke
				(width 0.1524)
				(type default)
			)
			(layer "B.SilkS")
		)
		(fp_line
			(start 0.508 -0.9398)
			(end 0.508 0.9398)
			(stroke
				(width 0.1524)
				(type default)
			)
			(layer "B.SilkS")
		)
		(fp_rect
			(start 0.508 0.9398)
			(end -0.508 -0.9398)
			(stroke
				(width 0)
				(type default)
			)
			(fill no)
			(layer "B.CrtYd")
		)
		(fp_rect
			(start 0.508 0.9398)
			(end -0.508 -0.9398)
			(stroke
				(width 0)
				(type default)
			)
			(fill no)
			(layer "B.Fab")
		)
		(pad "1" smd custom
			(at 0 -0.4445 180)
			(size 0.1397 0.1397)
			(layers "B.Cu" "B.Mask" "B.Paste")
			(net "SSD_PERST#8")
			(options
				(clearance outline)
				(anchor circle)
			)
			(primitives
				(gr_poly
					(pts
						(arc
							(start -0.1778 0.2794)
							(mid -0.249642 0.249642)
							(end -0.2794 0.1778)
						)
						(arc
							(start -0.2794 -0.1778)
							(mid -0.249642 -0.249642)
							(end -0.1778 -0.2794)
						)
						(arc
							(start 0.1778 -0.2794)
							(mid 0.249642 -0.249642)
							(end 0.2794 -0.1778)
						)
						(arc
							(start 0.2794 0.1778)
							(mid 0.249642 0.249642)
							(end 0.1778 0.2794)
						)
					)
					(width 0)
					(fill yes)
				)
			)
		)
		(pad "2" smd custom
			(at 0 0.4445 180)
			(size 0.1397 0.1397)
			(layers "B.Cu" "B.Mask" "B.Paste")
			(net "P3V3_STBY")
			(options
				(clearance outline)
				(anchor circle)
			)
			(primitives
				(gr_poly
					(pts
						(arc
							(start -0.1778 0.2794)
							(mid -0.249642 0.249642)
							(end -0.2794 0.1778)
						)
						(arc
							(start -0.2794 -0.1778)
							(mid -0.249642 -0.249642)
							(end -0.1778 -0.2794)
						)
						(arc
							(start 0.1778 -0.2794)
							(mid 0.249642 -0.249642)
							(end 0.2794 -0.1778)
						)
						(arc
							(start 0.2794 0.1778)
							(mid 0.249642 0.249642)
							(end 0.1778 0.2794)
						)
					)
					(width 0)
					(fill yes)
				)
			)
		)
	)
	(footprint ""
		(layer "B.Cu")
		(at 80.518 -189.611)
		(property "Reference" "R158"
			(at 0 0 0)
			(layer "B.SilkS")
			(hide yes)
			(effects
				(font
					(size 1.27 1.27)
				)
				(justify mirror)
			)
		)
		(property "Value" "4K7R2F-GP"
			(at -0.064008 -3.993896 0)
			(unlocked yes)
			(layer "B.Fab")
			(hide yes)
			(effects
				(font
					(size 1.016 1.016)
					(thickness 0.1524)
				)
				(justify mirror)
			)
		)
		(property "Device Type" "R402H16"
			(at -0.064008 -5.517896 0)
			(unlocked yes)
			(layer "B.Fab")
			(hide yes)
			(effects
				(font
					(size 1.016 1.016)
					(thickness 0.1524)
				)
				(justify mirror)
			)
		)
		(duplicate_pad_numbers_are_jumpers no)
		(fp_line
			(start -0.508 -0.9398)
			(end 0.508 -0.9398)
			(stroke
				(width 0.1524)
				(type default)
			)
			(layer "B.SilkS")
		)
		(fp_line
			(start 0.508 -0.9398)
			(end 0.508 0.9398)
			(stroke
				(width 0.1524)
				(type default)
			)
			(layer "B.SilkS")
		)
		(fp_rect
			(start 0.508 0.9398)
			(end -0.508 -0.9398)
			(stroke
				(width 0)
				(type default)
			)
			(fill no)
			(layer "B.CrtYd")
		)
		(fp_rect
			(start 0.508 0.9398)
			(end -0.508 -0.9398)
			(stroke
				(width 0)
				(type default)
			)
			(fill no)
			(layer "B.Fab")
		)
		(pad "1" smd custom
			(at 0 -0.4445 180)
			(size 0.1397 0.1397)
			(layers "B.Cu" "B.Mask" "B.Paste")
			(net "BMC_SSD_RST#0_A10")
			(options
				(clearance outline)
				(anchor circle)
			)
			(primitives
				(gr_poly
					(pts
						(arc
							(start -0.1778 0.2794)
							(mid -0.249642 0.249642)
							(end -0.2794 0.1778)
						)
						(arc
							(start -0.2794 -0.1778)
							(mid -0.249642 -0.249642)
							(end -0.1778 -0.2794)
						)
						(arc
							(start 0.1778 -0.2794)
							(mid 0.249642 -0.249642)
							(end 0.2794 -0.1778)
						)
						(arc
							(start 0.2794 0.1778)
							(mid 0.249642 0.249642)
							(end 0.1778 0.2794)
						)
					)
					(width 0)
					(fill yes)
				)
			)
		)
		(pad "2" smd custom
			(at 0 0.4445 180)
			(size 0.1397 0.1397)
			(layers "B.Cu" "B.Mask" "B.Paste")
			(net "P3V3_STBY")
			(options
				(clearance outline)
				(anchor circle)
			)
			(primitives
				(gr_poly
					(pts
						(arc
							(start -0.1778 0.2794)
							(mid -0.249642 0.249642)
							(end -0.2794 0.1778)
						)
						(arc
							(start -0.2794 -0.1778)
							(mid -0.249642 -0.249642)
							(end -0.1778 -0.2794)
						)
						(arc
							(start 0.1778 -0.2794)
							(mid 0.249642 -0.249642)
							(end 0.2794 -0.1778)
						)
						(arc
							(start 0.2794 0.1778)
							(mid 0.249642 0.249642)
							(end 0.1778 0.2794)
						)
					)
					(width 0)
					(fill yes)
				)
			)
		)
	)
	(footprint ""
		(layer "B.Cu")
		(at 58.565034 -118.876318 180)
		(property "Reference" "R520"
			(at 0 0 0)
			(layer "B.SilkS")
			(hide yes)
			(effects
				(font
					(size 1.27 1.27)
				)
				(justify mirror)
			)
		)
		(property "Value" "4K7R2F-GP"
			(at -0.064008 -3.993896 180)
			(unlocked yes)
			(layer "B.Fab")
			(hide yes)
			(effects
				(font
					(size 1.016 1.016)
					(thickness 0.1524)
				)
				(justify mirror)
			)
		)
		(property "Device Type" "R402H16"
			(at -0.064008 -5.517896 180)
			(unlocked yes)
			(layer "B.Fab")
			(hide yes)
			(effects
				(font
					(size 1.016 1.016)
					(thickness 0.1524)
				)
				(justify mirror)
			)
		)
		(duplicate_pad_numbers_are_jumpers no)
		(fp_line
			(start 0.508 -0.9398)
			(end 0.508 0.9398)
			(stroke
				(width 0.1524)
				(type default)
			)
			(layer "B.SilkS")
		)
		(fp_line
			(start -0.508 -0.9398)
			(end 0.508 -0.9398)
			(stroke
				(width 0.1524)
				(type default)
			)
			(layer "B.SilkS")
		)
		(fp_rect
			(start 0.508 0.9398)
			(end -0.508 -0.9398)
			(stroke
				(width 0)
				(type default)
			)
			(fill no)
			(layer "B.CrtYd")
		)
		(fp_rect
			(start 0.508 0.9398)
			(end -0.508 -0.9398)
			(stroke
				(width 0)
				(type default)
			)
			(fill no)
			(layer "B.Fab")
		)
		(pad "1" smd custom
			(at 0 -0.4445)
			(size 0.1397 0.1397)
			(layers "B.Cu" "B.Mask" "B.Paste")
			(net "BMC_I2C3_MINI3_SDA_S")
			(options
				(clearance outline)
				(anchor circle)
			)
			(primitives
				(gr_poly
					(pts
						(arc
							(start -0.1778 0.2794)
							(mid -0.249642 0.249642)
							(end -0.2794 0.1778)
						)
						(arc
							(start -0.2794 -0.1778)
							(mid -0.249642 -0.249642)
							(end -0.1778 -0.2794)
						)
						(arc
							(start 0.1778 -0.2794)
							(mid 0.249642 -0.249642)
							(end 0.2794 -0.1778)
						)
						(arc
							(start 0.2794 0.1778)
							(mid 0.249642 0.249642)
							(end 0.1778 0.2794)
						)
					)
					(width 0)
					(fill yes)
				)
			)
		)
		(pad "2" smd custom
			(at 0 0.4445)
			(size 0.1397 0.1397)
			(layers "B.Cu" "B.Mask" "B.Paste")
			(net "P3V3_STBY")
			(options
				(clearance outline)
				(anchor circle)
			)
			(primitives
				(gr_poly
					(pts
						(arc
							(start -0.1778 0.2794)
							(mid -0.249642 0.249642)
							(end -0.2794 0.1778)
						)
						(arc
							(start -0.2794 -0.1778)
							(mid -0.249642 -0.249642)
							(end -0.1778 -0.2794)
						)
						(arc
							(start 0.1778 -0.2794)
							(mid 0.249642 -0.249642)
							(end 0.2794 -0.1778)
						)
						(arc
							(start 0.2794 0.1778)
							(mid 0.249642 0.249642)
							(end 0.1778 0.2794)
						)
					)
					(width 0)
					(fill yes)
				)
			)
		)
	)
	(footprint ""
		(layer "B.Cu")
		(at 157.492192 -33.589976)
		(property "Reference" "R2932"
			(at 0 0 0)
			(layer "B.SilkS")
			(hide yes)
			(effects
				(font
					(size 1.27 1.27)
				)
				(justify mirror)
			)
		)
		(property "Value" "0R2J-2-GP"
			(at -0.064008 -3.993896 0)
			(unlocked yes)
			(layer "B.Fab")
			(hide yes)
			(effects
				(font
					(size 1.016 1.016)
					(thickness 0.1524)
				)
				(justify mirror)
			)
		)
		(property "Device Type" "R402H16"
			(at -0.064008 -5.517896 0)
			(unlocked yes)
			(layer "B.Fab")
			(hide yes)
			(effects
				(font
					(size 1.016 1.016)
					(thickness 0.1524)
				)
				(justify mirror)
			)
		)
		(duplicate_pad_numbers_are_jumpers no)
		(fp_line
			(start -0.508 -0.9398)
			(end 0.508 -0.9398)
			(stroke
				(width 0.1524)
				(type default)
			)
			(layer "B.SilkS")
		)
		(fp_line
			(start 0.508 -0.9398)
			(end 0.508 0.9398)
			(stroke
				(width 0.1524)
				(type default)
			)
			(layer "B.SilkS")
		)
		(fp_rect
			(start 0.508 0.9398)
			(end -0.508 -0.9398)
			(stroke
				(width 0)
				(type default)
			)
			(fill no)
			(layer "B.CrtYd")
		)
		(fp_rect
			(start 0.508 0.9398)
			(end -0.508 -0.9398)
			(stroke
				(width 0)
				(type default)
			)
			(fill no)
			(layer "B.Fab")
		)
		(pad "1" smd custom
			(at 0 -0.4445 180)
			(size 0.1397 0.1397)
			(layers "B.Cu" "B.Mask" "B.Paste")
			(net "BMC_I2C3_MINI3_SDA")
			(options
				(clearance outline)
				(anchor circle)
			)
			(primitives
				(gr_poly
					(pts
						(arc
							(start -0.1778 0.2794)
							(mid -0.249642 0.249642)
							(end -0.2794 0.1778)
						)
						(arc
							(start -0.2794 -0.1778)
							(mid -0.249642 -0.249642)
							(end -0.1778 -0.2794)
						)
						(arc
							(start 0.1778 -0.2794)
							(mid 0.249642 -0.249642)
							(end 0.2794 -0.1778)
						)
						(arc
							(start 0.2794 0.1778)
							(mid 0.249642 0.249642)
							(end 0.1778 0.2794)
						)
					)
					(width 0)
					(fill yes)
				)
			)
		)
		(pad "2" smd custom
			(at 0 0.4445 180)
			(size 0.1397 0.1397)
			(layers "B.Cu" "B.Mask" "B.Paste")
			(net "8644_CBL_PRSNT_R_3")
			(options
				(clearance outline)
				(anchor circle)
			)
			(primitives
				(gr_poly
					(pts
						(arc
							(start -0.1778 0.2794)
							(mid -0.249642 0.249642)
							(end -0.2794 0.1778)
						)
						(arc
							(start -0.2794 -0.1778)
							(mid -0.249642 -0.249642)
							(end -0.1778 -0.2794)
						)
						(arc
							(start 0.1778 -0.2794)
							(mid 0.249642 -0.249642)
							(end 0.2794 -0.1778)
						)
						(arc
							(start 0.2794 0.1778)
							(mid 0.249642 0.249642)
							(end 0.1778 0.2794)
						)
					)
					(width 0)
					(fill yes)
				)
			)
		)
	)
	(footprint ""
		(layer "B.Cu")
		(at 237.1598 -48.9966 90)
		(property "Reference" "C31"
			(at 0 0 90)
			(layer "B.SilkS")
			(hide yes)
			(effects
				(font
					(size 1.27 1.27)
				)
				(justify mirror)
			)
		)
		(property "Value" "SCD1U16V1KX-1-GP"
			(at 2.8321 -1.7399 90)
			(unlocked yes)
			(layer "B.Fab")
			(hide yes)
			(effects
				(font
					(size 1.016 1.016)
					(thickness 0.1524)
				)
				(justify mirror)
			)
		)
		(property "Device Type" "C0201H13"
			(at 2.8321 -3.2639 90)
			(unlocked yes)
			(layer "B.Fab")
			(hide yes)
			(effects
				(font
					(size 1.016 1.016)
					(thickness 0.1524)
				)
				(justify mirror)
			)
		)
		(duplicate_pad_numbers_are_jumpers no)
		(fp_rect
			(start 0.2794 0.6477)
			(end -0.2794 -0.6477)
			(stroke
				(width 0)
				(type default)
			)
			(fill no)
			(layer "B.CrtYd")
		)
		(fp_rect
			(start 0.2794 0.6477)
			(end -0.2794 -0.6477)
			(stroke
				(width 0)
				(type default)
			)
			(fill no)
			(layer "B.Fab")
		)
		(pad "1" smd custom
			(at 0 -0.2794 270)
			(size 0.0762 0.0762)
			(layers "B.Cu" "B.Mask" "B.Paste")
			(net "DUT_VDD")
			(options
				(clearance outline)
				(anchor circle)
			)
			(primitives
				(gr_poly
					(pts
						(arc
							(start 0.1524 0.127)
							(mid 0.137521 0.162921)
							(end 0.1016 0.1778)
						)
						(arc
							(start -0.1016 0.1778)
							(mid -0.137521 0.162921)
							(end -0.1524 0.127)
						)
						(arc
							(start -0.1524 -0.127)
							(mid -0.137521 -0.162921)
							(end -0.1016 -0.1778)
						)
						(arc
							(start 0.1016 -0.1778)
							(mid 0.137521 -0.162921)
							(end 0.1524 -0.127)
						)
					)
					(width 0)
					(fill yes)
				)
			)
		)
		(pad "2" smd custom
			(at 0 0.2794 270)
			(size 0.0762 0.0762)
			(layers "B.Cu" "B.Mask" "B.Paste")
			(net "GND")
			(options
				(clearance outline)
				(anchor circle)
			)
			(primitives
				(gr_poly
					(pts
						(arc
							(start 0.1524 0.127)
							(mid 0.137521 0.162921)
							(end 0.1016 0.1778)
						)
						(arc
							(start -0.1016 0.1778)
							(mid -0.137521 0.162921)
							(end -0.1524 0.127)
						)
						(arc
							(start -0.1524 -0.127)
							(mid -0.137521 -0.162921)
							(end -0.1016 -0.1778)
						)
						(arc
							(start 0.1016 -0.1778)
							(mid 0.137521 -0.162921)
							(end 0.1524 -0.127)
						)
					)
					(width 0)
					(fill yes)
				)
			)
		)
	)
	(footprint ""
		(layer "B.Cu")
		(at 251.599954 -33.999932 -90)
		(property "Reference" "TP279"
			(at 0 0 90)
			(layer "B.SilkS")
			(hide yes)
			(effects
				(font
					(size 1.27 1.27)
				)
				(justify mirror)
			)
		)
		(property "Value" "TPAD28-2-GP"
			(at 0.0127 -1.6637 270)
			(unlocked yes)
			(layer "B.Fab")
			(hide yes)
			(effects
				(font
					(size 1.016 1.016)
					(thickness 0.1524)
				)
				(justify mirror)
			)
		)
		(property "Device Type" "TPAD28"
			(at 0.0127 -3.1877 270)
			(unlocked yes)
			(layer "B.Fab")
			(hide yes)
			(effects
				(font
					(size 1.016 1.016)
					(thickness 0.1524)
				)
				(justify mirror)
			)
		)
		(duplicate_pad_numbers_are_jumpers no)
		(fp_poly
			(pts
				(arc
					(start 0 -0.3556)
					(mid 0 0.3556)
					(end 0 -0.3556)
				)
			)
			(stroke
				(width 0)
				(type default)
			)
			(fill no)
			(layer "B.CrtYd")
		)
		(fp_poly
			(pts
				(arc
					(start 0 -0.6096)
					(mid 0 0.6096)
					(end 0 -0.6096)
				)
			)
			(stroke
				(width 0)
				(type default)
			)
			(fill no)
			(layer "B.Fab")
		)
		(pad "1" smd circle
			(at 0 0 90)
			(size 0.7112 0.7112)
			(layers "B.Cu" "B.Mask" "B.Paste")
			(net "TWI_SRST#0")
		)
	)
	(footprint ""
		(layer "B.Cu")
		(at 15.4686 -80.0354 90)
		(property "Reference" "C633"
			(at 0 0 90)
			(layer "B.SilkS")
			(hide yes)
			(effects
				(font
					(size 1.27 1.27)
				)
				(justify mirror)
			)
		)
		(property "Value" "SC47U4V5MX-2-GP"
			(at 0.0762 -6.1214 90)
			(unlocked yes)
			(layer "B.Fab")
			(hide yes)
			(effects
				(font
					(size 1.016 1.016)
					(thickness 0.1524)
				)
				(justify mirror)
			)
		)
		(property "Device Type" "C805H58"
			(at 0.0762 -8.1534 90)
			(unlocked yes)
			(layer "B.Fab")
			(hide yes)
			(effects
				(font
					(size 1.016 1.016)
					(thickness 0.1524)
				)
				(justify mirror)
			)
		)
		(duplicate_pad_numbers_are_jumpers no)
		(fp_line
			(start -0.635 0)
			(end 0.635 0)
			(stroke
				(width 0.508)
				(type default)
			)
			(layer "B.SilkS")
		)
		(fp_rect
			(start 0.9652 1.778)
			(end -0.9652 -1.778)
			(stroke
				(width 0)
				(type default)
			)
			(fill no)
			(layer "B.CrtYd")
		)
		(fp_poly
			(pts
				(xy 0.9652 -1.778) (xy -0.9652 -1.778) (xy -0.9652 1.778) (xy 0.9652 1.778)
			)
			(stroke
				(width 0)
				(type default)
			)
			(fill no)
			(layer "B.Fab")
		)
		(pad "1" smd rect
			(at 0 -0.9652 270)
			(size 1.397 1.143)
			(layers "B.Cu" "B.Mask" "B.Paste")
			(net "P0V9_I210")
		)
		(pad "2" smd rect
			(at 0 0.9652 270)
			(size 1.397 1.143)
			(layers "B.Cu" "B.Mask" "B.Paste")
			(net "GND")
		)
	)
	(footprint ""
		(layer "B.Cu")
		(at 59.218322 -121.368566 90)
		(property "Reference" "R492"
			(at 0 0 90)
			(layer "B.SilkS")
			(hide yes)
			(effects
				(font
					(size 1.27 1.27)
				)
				(justify mirror)
			)
		)
		(property "Value" "2K2R2J-2-GP"
			(at -0.064008 -3.993896 90)
			(unlocked yes)
			(layer "B.Fab")
			(hide yes)
			(effects
				(font
					(size 1.016 1.016)
					(thickness 0.1524)
				)
				(justify mirror)
			)
		)
		(property "Device Type" "R402H16"
			(at -0.064008 -5.517896 90)
			(unlocked yes)
			(layer "B.Fab")
			(hide yes)
			(effects
				(font
					(size 1.016 1.016)
					(thickness 0.1524)
				)
				(justify mirror)
			)
		)
		(duplicate_pad_numbers_are_jumpers no)
		(fp_line
			(start 0.508 -0.9398)
			(end 0.508 0.9398)
			(stroke
				(width 0.1524)
				(type default)
			)
			(layer "B.SilkS")
		)
		(fp_line
			(start -0.508 -0.9398)
			(end 0.508 -0.9398)
			(stroke
				(width 0.1524)
				(type default)
			)
			(layer "B.SilkS")
		)
		(fp_rect
			(start 0.508 0.9398)
			(end -0.508 -0.9398)
			(stroke
				(width 0)
				(type default)
			)
			(fill no)
			(layer "B.CrtYd")
		)
		(fp_rect
			(start 0.508 0.9398)
			(end -0.508 -0.9398)
			(stroke
				(width 0)
				(type default)
			)
			(fill no)
			(layer "B.Fab")
		)
		(pad "1" smd custom
			(at 0 -0.4445 270)
			(size 0.1397 0.1397)
			(layers "B.Cu" "B.Mask" "B.Paste")
			(net "BMC_I2C5_D_PEB_DEVICE_SCL")
			(options
				(clearance outline)
				(anchor circle)
			)
			(primitives
				(gr_poly
					(pts
						(arc
							(start -0.1778 0.2794)
							(mid -0.249642 0.249642)
							(end -0.2794 0.1778)
						)
						(arc
							(start -0.2794 -0.1778)
							(mid -0.249642 -0.249642)
							(end -0.1778 -0.2794)
						)
						(arc
							(start 0.1778 -0.2794)
							(mid 0.249642 -0.249642)
							(end 0.2794 -0.1778)
						)
						(arc
							(start 0.2794 0.1778)
							(mid 0.249642 0.249642)
							(end 0.1778 0.2794)
						)
					)
					(width 0)
					(fill yes)
				)
			)
		)
		(pad "2" smd custom
			(at 0 0.4445 270)
			(size 0.1397 0.1397)
			(layers "B.Cu" "B.Mask" "B.Paste")
			(net "P3V3_STBY")
			(options
				(clearance outline)
				(anchor circle)
			)
			(primitives
				(gr_poly
					(pts
						(arc
							(start -0.1778 0.2794)
							(mid -0.249642 0.249642)
							(end -0.2794 0.1778)
						)
						(arc
							(start -0.2794 -0.1778)
							(mid -0.249642 -0.249642)
							(end -0.1778 -0.2794)
						)
						(arc
							(start 0.1778 -0.2794)
							(mid 0.249642 -0.249642)
							(end 0.2794 -0.1778)
						)
						(arc
							(start 0.2794 0.1778)
							(mid 0.249642 0.249642)
							(end 0.1778 0.2794)
						)
					)
					(width 0)
					(fill yes)
				)
			)
		)
	)
	(footprint ""
		(layer "B.Cu")
		(at 79.039212 -192.641474)
		(property "Reference" "R3216"
			(at 0 0 0)
			(layer "B.SilkS")
			(hide yes)
			(effects
				(font
					(size 1.27 1.27)
				)
				(justify mirror)
			)
		)
		(property "Value" "0R2J-2-GP"
			(at -0.064008 -3.993896 0)
			(unlocked yes)
			(layer "B.Fab")
			(hide yes)
			(effects
				(font
					(size 1.016 1.016)
					(thickness 0.1524)
				)
				(justify mirror)
			)
		)
		(property "Device Type" "R402H16"
			(at -0.064008 -5.517896 0)
			(unlocked yes)
			(layer "B.Fab")
			(hide yes)
			(effects
				(font
					(size 1.016 1.016)
					(thickness 0.1524)
				)
				(justify mirror)
			)
		)
		(duplicate_pad_numbers_are_jumpers no)
		(fp_line
			(start -0.508 -0.9398)
			(end 0.508 -0.9398)
			(stroke
				(width 0.1524)
				(type default)
			)
			(layer "B.SilkS")
		)
		(fp_line
			(start 0.508 -0.9398)
			(end 0.508 0.9398)
			(stroke
				(width 0.1524)
				(type default)
			)
			(layer "B.SilkS")
		)
		(fp_rect
			(start 0.508 0.9398)
			(end -0.508 -0.9398)
			(stroke
				(width 0)
				(type default)
			)
			(fill no)
			(layer "B.CrtYd")
		)
		(fp_rect
			(start 0.508 0.9398)
			(end -0.508 -0.9398)
			(stroke
				(width 0)
				(type default)
			)
			(fill no)
			(layer "B.Fab")
		)
		(pad "1" smd custom
			(at 0 -0.4445 180)
			(size 0.1397 0.1397)
			(layers "B.Cu" "B.Mask" "B.Paste")
			(net "SSD_PERST#5")
			(options
				(clearance outline)
				(anchor circle)
			)
			(primitives
				(gr_poly
					(pts
						(arc
							(start -0.1778 0.2794)
							(mid -0.249642 0.249642)
							(end -0.2794 0.1778)
						)
						(arc
							(start -0.2794 -0.1778)
							(mid -0.249642 -0.249642)
							(end -0.1778 -0.2794)
						)
						(arc
							(start 0.1778 -0.2794)
							(mid 0.249642 -0.249642)
							(end 0.2794 -0.1778)
						)
						(arc
							(start 0.2794 0.1778)
							(mid 0.249642 0.249642)
							(end 0.1778 0.2794)
						)
					)
					(width 0)
					(fill yes)
				)
			)
		)
		(pad "2" smd custom
			(at 0 0.4445 180)
			(size 0.1397 0.1397)
			(layers "B.Cu" "B.Mask" "B.Paste")
			(net "SSD_PERST#0_B5")
			(options
				(clearance outline)
				(anchor circle)
			)
			(primitives
				(gr_poly
					(pts
						(arc
							(start -0.1778 0.2794)
							(mid -0.249642 0.249642)
							(end -0.2794 0.1778)
						)
						(arc
							(start -0.2794 -0.1778)
							(mid -0.249642 -0.249642)
							(end -0.1778 -0.2794)
						)
						(arc
							(start 0.1778 -0.2794)
							(mid 0.249642 -0.249642)
							(end 0.2794 -0.1778)
						)
						(arc
							(start 0.2794 0.1778)
							(mid 0.249642 0.249642)
							(end 0.1778 0.2794)
						)
					)
					(width 0)
					(fill yes)
				)
			)
		)
	)
	(footprint ""
		(layer "B.Cu")
		(at 241.681 -20.447)
		(property "Reference" "R811"
			(at 0 0 0)
			(layer "B.SilkS")
			(hide yes)
			(effects
				(font
					(size 1.27 1.27)
				)
				(justify mirror)
			)
		)
		(property "Value" "4K7R2F-GP"
			(at -0.064008 -3.993896 0)
			(unlocked yes)
			(layer "B.Fab")
			(hide yes)
			(effects
				(font
					(size 1.016 1.016)
					(thickness 0.1524)
				)
				(justify mirror)
			)
		)
		(property "Device Type" "R402H16"
			(at -0.064008 -5.517896 0)
			(unlocked yes)
			(layer "B.Fab")
			(hide yes)
			(effects
				(font
					(size 1.016 1.016)
					(thickness 0.1524)
				)
				(justify mirror)
			)
		)
		(duplicate_pad_numbers_are_jumpers no)
		(fp_line
			(start -0.508 -0.9398)
			(end 0.508 -0.9398)
			(stroke
				(width 0.1524)
				(type default)
			)
			(layer "B.SilkS")
		)
		(fp_line
			(start 0.508 -0.9398)
			(end 0.508 0.9398)
			(stroke
				(width 0.1524)
				(type default)
			)
			(layer "B.SilkS")
		)
		(fp_rect
			(start 0.508 0.9398)
			(end -0.508 -0.9398)
			(stroke
				(width 0)
				(type default)
			)
			(fill no)
			(layer "B.CrtYd")
		)
		(fp_rect
			(start 0.508 0.9398)
			(end -0.508 -0.9398)
			(stroke
				(width 0)
				(type default)
			)
			(fill no)
			(layer "B.Fab")
		)
		(pad "1" smd custom
			(at 0 -0.4445 180)
			(size 0.1397 0.1397)
			(layers "B.Cu" "B.Mask" "B.Paste")
			(net "BOOTSTRAP5")
			(options
				(clearance outline)
				(anchor circle)
			)
			(primitives
				(gr_poly
					(pts
						(arc
							(start -0.1778 0.2794)
							(mid -0.249642 0.249642)
							(end -0.2794 0.1778)
						)
						(arc
							(start -0.2794 -0.1778)
							(mid -0.249642 -0.249642)
							(end -0.1778 -0.2794)
						)
						(arc
							(start 0.1778 -0.2794)
							(mid 0.249642 -0.249642)
							(end 0.2794 -0.1778)
						)
						(arc
							(start 0.2794 0.1778)
							(mid 0.249642 0.249642)
							(end 0.1778 0.2794)
						)
					)
					(width 0)
					(fill yes)
				)
			)
		)
		(pad "2" smd custom
			(at 0 0.4445 180)
			(size 0.1397 0.1397)
			(layers "B.Cu" "B.Mask" "B.Paste")
			(net "DUT_VDDO")
			(options
				(clearance outline)
				(anchor circle)
			)
			(primitives
				(gr_poly
					(pts
						(arc
							(start -0.1778 0.2794)
							(mid -0.249642 0.249642)
							(end -0.2794 0.1778)
						)
						(arc
							(start -0.2794 -0.1778)
							(mid -0.249642 -0.249642)
							(end -0.1778 -0.2794)
						)
						(arc
							(start 0.1778 -0.2794)
							(mid 0.249642 -0.249642)
							(end 0.2794 -0.1778)
						)
						(arc
							(start 0.2794 0.1778)
							(mid 0.249642 0.249642)
							(end 0.1778 0.2794)
						)
					)
					(width 0)
					(fill yes)
				)
			)
		)
	)
	(footprint ""
		(layer "B.Cu")
		(at 57.023 -139.827 -90)
		(property "Reference" "R310"
			(at 0 0 90)
			(layer "B.SilkS")
			(hide yes)
			(effects
				(font
					(size 1.27 1.27)
				)
				(justify mirror)
			)
		)
		(property "Value" "0R2J-2-GP"
			(at -0.064008 -3.993896 270)
			(unlocked yes)
			(layer "B.Fab")
			(hide yes)
			(effects
				(font
					(size 1.016 1.016)
					(thickness 0.1524)
				)
				(justify mirror)
			)
		)
		(property "Device Type" "R402H16"
			(at -0.064008 -5.517896 270)
			(unlocked yes)
			(layer "B.Fab")
			(hide yes)
			(effects
				(font
					(size 1.016 1.016)
					(thickness 0.1524)
				)
				(justify mirror)
			)
		)
		(duplicate_pad_numbers_are_jumpers no)
		(fp_line
			(start -0.508 -0.9398)
			(end 0.508 -0.9398)
			(stroke
				(width 0.1524)
				(type default)
			)
			(layer "B.SilkS")
		)
		(fp_line
			(start 0.508 -0.9398)
			(end 0.508 0.9398)
			(stroke
				(width 0.1524)
				(type default)
			)
			(layer "B.SilkS")
		)
		(fp_rect
			(start 0.508 0.9398)
			(end -0.508 -0.9398)
			(stroke
				(width 0)
				(type default)
			)
			(fill no)
			(layer "B.CrtYd")
		)
		(fp_rect
			(start 0.508 0.9398)
			(end -0.508 -0.9398)
			(stroke
				(width 0)
				(type default)
			)
			(fill no)
			(layer "B.Fab")
		)
		(pad "1" smd custom
			(at 0 -0.4445 90)
			(size 0.1397 0.1397)
			(layers "B.Cu" "B.Mask" "B.Paste")
			(net "BMC_SELF_TRAY")
			(options
				(clearance outline)
				(anchor circle)
			)
			(primitives
				(gr_poly
					(pts
						(arc
							(start -0.1778 0.2794)
							(mid -0.249642 0.249642)
							(end -0.2794 0.1778)
						)
						(arc
							(start -0.2794 -0.1778)
							(mid -0.249642 -0.249642)
							(end -0.1778 -0.2794)
						)
						(arc
							(start 0.1778 -0.2794)
							(mid 0.249642 -0.249642)
							(end 0.2794 -0.1778)
						)
						(arc
							(start 0.2794 0.1778)
							(mid 0.249642 0.249642)
							(end 0.1778 0.2794)
						)
					)
					(width 0)
					(fill yes)
				)
			)
		)
		(pad "2" smd custom
			(at 0 0.4445 90)
			(size 0.1397 0.1397)
			(layers "B.Cu" "B.Mask" "B.Paste")
			(net "BMC_SELF_TRAY_R")
			(options
				(clearance outline)
				(anchor circle)
			)
			(primitives
				(gr_poly
					(pts
						(arc
							(start -0.1778 0.2794)
							(mid -0.249642 0.249642)
							(end -0.2794 0.1778)
						)
						(arc
							(start -0.2794 -0.1778)
							(mid -0.249642 -0.249642)
							(end -0.1778 -0.2794)
						)
						(arc
							(start 0.1778 -0.2794)
							(mid 0.249642 -0.249642)
							(end 0.2794 -0.1778)
						)
						(arc
							(start 0.2794 0.1778)
							(mid 0.249642 0.249642)
							(end 0.1778 0.2794)
						)
					)
					(width 0)
					(fill yes)
				)
			)
		)
	)
	(footprint ""
		(layer "B.Cu")
		(at 236.5629 -40.005 90)
		(property "Reference" "C547"
			(at 0 0 90)
			(layer "B.SilkS")
			(hide yes)
			(effects
				(font
					(size 1.27 1.27)
				)
				(justify mirror)
			)
		)
		(property "Value" "SCD1U16V1KX-1-GP"
			(at 2.8321 -1.7399 90)
			(unlocked yes)
			(layer "B.Fab")
			(hide yes)
			(effects
				(font
					(size 1.016 1.016)
					(thickness 0.1524)
				)
				(justify mirror)
			)
		)
		(property "Device Type" "C0201H13"
			(at 2.8321 -3.2639 90)
			(unlocked yes)
			(layer "B.Fab")
			(hide yes)
			(effects
				(font
					(size 1.016 1.016)
					(thickness 0.1524)
				)
				(justify mirror)
			)
		)
		(duplicate_pad_numbers_are_jumpers no)
		(fp_rect
			(start 0.2794 0.6477)
			(end -0.2794 -0.6477)
			(stroke
				(width 0)
				(type default)
			)
			(fill no)
			(layer "B.CrtYd")
		)
		(fp_rect
			(start 0.2794 0.6477)
			(end -0.2794 -0.6477)
			(stroke
				(width 0)
				(type default)
			)
			(fill no)
			(layer "B.Fab")
		)
		(pad "1" smd custom
			(at 0 -0.2794 270)
			(size 0.0762 0.0762)
			(layers "B.Cu" "B.Mask" "B.Paste")
			(net "DUT_AVD_PCIE")
			(options
				(clearance outline)
				(anchor circle)
			)
			(primitives
				(gr_poly
					(pts
						(arc
							(start 0.1524 0.127)
							(mid 0.137521 0.162921)
							(end 0.1016 0.1778)
						)
						(arc
							(start -0.1016 0.1778)
							(mid -0.137521 0.162921)
							(end -0.1524 0.127)
						)
						(arc
							(start -0.1524 -0.127)
							(mid -0.137521 -0.162921)
							(end -0.1016 -0.1778)
						)
						(arc
							(start 0.1016 -0.1778)
							(mid 0.137521 -0.162921)
							(end 0.1524 -0.127)
						)
					)
					(width 0)
					(fill yes)
				)
			)
		)
		(pad "2" smd custom
			(at 0 0.2794 270)
			(size 0.0762 0.0762)
			(layers "B.Cu" "B.Mask" "B.Paste")
			(net "GND")
			(options
				(clearance outline)
				(anchor circle)
			)
			(primitives
				(gr_poly
					(pts
						(arc
							(start 0.1524 0.127)
							(mid 0.137521 0.162921)
							(end 0.1016 0.1778)
						)
						(arc
							(start -0.1016 0.1778)
							(mid -0.137521 0.162921)
							(end -0.1524 0.127)
						)
						(arc
							(start -0.1524 -0.127)
							(mid -0.137521 -0.162921)
							(end -0.1016 -0.1778)
						)
						(arc
							(start 0.1016 -0.1778)
							(mid 0.137521 -0.162921)
							(end 0.1524 -0.127)
						)
					)
					(width 0)
					(fill yes)
				)
			)
		)
	)
	(footprint ""
		(layer "B.Cu")
		(at 249.588528 -39.99992 -90)
		(property "Reference" "TP209"
			(at 0 0 90)
			(layer "B.SilkS")
			(hide yes)
			(effects
				(font
					(size 1.27 1.27)
				)
				(justify mirror)
			)
		)
		(property "Value" "TPAD28-2-GP"
			(at 0.0127 -1.6637 270)
			(unlocked yes)
			(layer "B.Fab")
			(hide yes)
			(effects
				(font
					(size 1.016 1.016)
					(thickness 0.1524)
				)
				(justify mirror)
			)
		)
		(property "Device Type" "TPAD28"
			(at 0.0127 -3.1877 270)
			(unlocked yes)
			(layer "B.Fab")
			(hide yes)
			(effects
				(font
					(size 1.016 1.016)
					(thickness 0.1524)
				)
				(justify mirror)
			)
		)
		(duplicate_pad_numbers_are_jumpers no)
		(fp_poly
			(pts
				(arc
					(start 0 -0.3556)
					(mid 0 0.3556)
					(end 0 -0.3556)
				)
			)
			(stroke
				(width 0)
				(type default)
			)
			(fill no)
			(layer "B.CrtYd")
		)
		(fp_poly
			(pts
				(arc
					(start 0 -0.6096)
					(mid 0 0.6096)
					(end 0 -0.6096)
				)
			)
			(stroke
				(width 0)
				(type default)
			)
			(fill no)
			(layer "B.Fab")
		)
		(pad "1" smd circle
			(at 0 0 90)
			(size 0.7112 0.7112)
			(layers "B.Cu" "B.Mask" "B.Paste")
			(net "GPIO108_R")
		)
	)
	(footprint ""
		(layer "B.Cu")
		(at 246.888 -37.9984 90)
		(property "Reference" "C483"
			(at 0 0 90)
			(layer "B.SilkS")
			(hide yes)
			(effects
				(font
					(size 1.27 1.27)
				)
				(justify mirror)
			)
		)
		(property "Value" "SCD1U16V1KX-1-GP"
			(at 2.8321 -1.7399 90)
			(unlocked yes)
			(layer "B.Fab")
			(hide yes)
			(effects
				(font
					(size 1.016 1.016)
					(thickness 0.1524)
				)
				(justify mirror)
			)
		)
		(property "Device Type" "C0201H13"
			(at 2.8321 -3.2639 90)
			(unlocked yes)
			(layer "B.Fab")
			(hide yes)
			(effects
				(font
					(size 1.016 1.016)
					(thickness 0.1524)
				)
				(justify mirror)
			)
		)
		(duplicate_pad_numbers_are_jumpers no)
		(fp_rect
			(start 0.2794 0.6477)
			(end -0.2794 -0.6477)
			(stroke
				(width 0)
				(type default)
			)
			(fill no)
			(layer "B.CrtYd")
		)
		(fp_rect
			(start 0.2794 0.6477)
			(end -0.2794 -0.6477)
			(stroke
				(width 0)
				(type default)
			)
			(fill no)
			(layer "B.Fab")
		)
		(pad "1" smd custom
			(at 0 -0.2794 270)
			(size 0.0762 0.0762)
			(layers "B.Cu" "B.Mask" "B.Paste")
			(net "DUT_VDDO")
			(options
				(clearance outline)
				(anchor circle)
			)
			(primitives
				(gr_poly
					(pts
						(arc
							(start 0.1524 0.127)
							(mid 0.137521 0.162921)
							(end 0.1016 0.1778)
						)
						(arc
							(start -0.1016 0.1778)
							(mid -0.137521 0.162921)
							(end -0.1524 0.127)
						)
						(arc
							(start -0.1524 -0.127)
							(mid -0.137521 -0.162921)
							(end -0.1016 -0.1778)
						)
						(arc
							(start 0.1016 -0.1778)
							(mid 0.137521 -0.162921)
							(end 0.1524 -0.127)
						)
					)
					(width 0)
					(fill yes)
				)
			)
		)
		(pad "2" smd custom
			(at 0 0.2794 270)
			(size 0.0762 0.0762)
			(layers "B.Cu" "B.Mask" "B.Paste")
			(net "GND")
			(options
				(clearance outline)
				(anchor circle)
			)
			(primitives
				(gr_poly
					(pts
						(arc
							(start 0.1524 0.127)
							(mid 0.137521 0.162921)
							(end 0.1016 0.1778)
						)
						(arc
							(start -0.1016 0.1778)
							(mid -0.137521 0.162921)
							(end -0.1524 0.127)
						)
						(arc
							(start -0.1524 -0.127)
							(mid -0.137521 -0.162921)
							(end -0.1016 -0.1778)
						)
						(arc
							(start 0.1016 -0.1778)
							(mid 0.137521 -0.162921)
							(end 0.1524 -0.127)
						)
					)
					(width 0)
					(fill yes)
				)
			)
		)
	)
	(footprint ""
		(layer "B.Cu")
		(at 132.54228 -33.54578)
		(property "Reference" "R2926"
			(at 0 0 0)
			(layer "B.SilkS")
			(hide yes)
			(effects
				(font
					(size 1.27 1.27)
				)
				(justify mirror)
			)
		)
		(property "Value" "0R2J-2-GP"
			(at -0.064008 -3.993896 0)
			(unlocked yes)
			(layer "B.Fab")
			(hide yes)
			(effects
				(font
					(size 1.016 1.016)
					(thickness 0.1524)
				)
				(justify mirror)
			)
		)
		(property "Device Type" "R402H16"
			(at -0.064008 -5.517896 0)
			(unlocked yes)
			(layer "B.Fab")
			(hide yes)
			(effects
				(font
					(size 1.016 1.016)
					(thickness 0.1524)
				)
				(justify mirror)
			)
		)
		(duplicate_pad_numbers_are_jumpers no)
		(fp_line
			(start -0.508 -0.9398)
			(end 0.508 -0.9398)
			(stroke
				(width 0.1524)
				(type default)
			)
			(layer "B.SilkS")
		)
		(fp_line
			(start 0.508 -0.9398)
			(end 0.508 0.9398)
			(stroke
				(width 0.1524)
				(type default)
			)
			(layer "B.SilkS")
		)
		(fp_rect
			(start 0.508 0.9398)
			(end -0.508 -0.9398)
			(stroke
				(width 0)
				(type default)
			)
			(fill no)
			(layer "B.CrtYd")
		)
		(fp_rect
			(start 0.508 0.9398)
			(end -0.508 -0.9398)
			(stroke
				(width 0)
				(type default)
			)
			(fill no)
			(layer "B.Fab")
		)
		(pad "1" smd custom
			(at 0 -0.4445 180)
			(size 0.1397 0.1397)
			(layers "B.Cu" "B.Mask" "B.Paste")
			(net "BMC_I2C1_MINI1_SDA")
			(options
				(clearance outline)
				(anchor circle)
			)
			(primitives
				(gr_poly
					(pts
						(arc
							(start -0.1778 0.2794)
							(mid -0.249642 0.249642)
							(end -0.2794 0.1778)
						)
						(arc
							(start -0.2794 -0.1778)
							(mid -0.249642 -0.249642)
							(end -0.1778 -0.2794)
						)
						(arc
							(start 0.1778 -0.2794)
							(mid 0.249642 -0.249642)
							(end 0.2794 -0.1778)
						)
						(arc
							(start 0.2794 0.1778)
							(mid 0.249642 0.249642)
							(end 0.1778 0.2794)
						)
					)
					(width 0)
					(fill yes)
				)
			)
		)
		(pad "2" smd custom
			(at 0 0.4445 180)
			(size 0.1397 0.1397)
			(layers "B.Cu" "B.Mask" "B.Paste")
			(net "8644_CBL_PRSNT_R_1")
			(options
				(clearance outline)
				(anchor circle)
			)
			(primitives
				(gr_poly
					(pts
						(arc
							(start -0.1778 0.2794)
							(mid -0.249642 0.249642)
							(end -0.2794 0.1778)
						)
						(arc
							(start -0.2794 -0.1778)
							(mid -0.249642 -0.249642)
							(end -0.1778 -0.2794)
						)
						(arc
							(start 0.1778 -0.2794)
							(mid 0.249642 -0.249642)
							(end 0.2794 -0.1778)
						)
						(arc
							(start 0.2794 0.1778)
							(mid 0.249642 0.249642)
							(end 0.1778 0.2794)
						)
					)
					(width 0)
					(fill yes)
				)
			)
		)
	)
	(footprint ""
		(layer "B.Cu")
		(at 245.1354 -47.032672 -90)
		(property "Reference" "C461"
			(at 0 0 90)
			(layer "B.SilkS")
			(hide yes)
			(effects
				(font
					(size 1.27 1.27)
				)
				(justify mirror)
			)
		)
		(property "Value" "SCD1U16V1KX-1-GP"
			(at 2.8321 -1.7399 270)
			(unlocked yes)
			(layer "B.Fab")
			(hide yes)
			(effects
				(font
					(size 1.016 1.016)
					(thickness 0.1524)
				)
				(justify mirror)
			)
		)
		(property "Device Type" "C0201H13"
			(at 2.8321 -3.2639 270)
			(unlocked yes)
			(layer "B.Fab")
			(hide yes)
			(effects
				(font
					(size 1.016 1.016)
					(thickness 0.1524)
				)
				(justify mirror)
			)
		)
		(duplicate_pad_numbers_are_jumpers no)
		(fp_rect
			(start 0.2794 0.6477)
			(end -0.2794 -0.6477)
			(stroke
				(width 0)
				(type default)
			)
			(fill no)
			(layer "B.CrtYd")
		)
		(fp_rect
			(start 0.2794 0.6477)
			(end -0.2794 -0.6477)
			(stroke
				(width 0)
				(type default)
			)
			(fill no)
			(layer "B.Fab")
		)
		(pad "1" smd custom
			(at 0 -0.2794 90)
			(size 0.0762 0.0762)
			(layers "B.Cu" "B.Mask" "B.Paste")
			(net "DUT_VDD")
			(options
				(clearance outline)
				(anchor circle)
			)
			(primitives
				(gr_poly
					(pts
						(arc
							(start 0.1524 0.127)
							(mid 0.137521 0.162921)
							(end 0.1016 0.1778)
						)
						(arc
							(start -0.1016 0.1778)
							(mid -0.137521 0.162921)
							(end -0.1524 0.127)
						)
						(arc
							(start -0.1524 -0.127)
							(mid -0.137521 -0.162921)
							(end -0.1016 -0.1778)
						)
						(arc
							(start 0.1016 -0.1778)
							(mid 0.137521 -0.162921)
							(end 0.1524 -0.127)
						)
					)
					(width 0)
					(fill yes)
				)
			)
		)
		(pad "2" smd custom
			(at 0 0.2794 90)
			(size 0.0762 0.0762)
			(layers "B.Cu" "B.Mask" "B.Paste")
			(net "GND")
			(options
				(clearance outline)
				(anchor circle)
			)
			(primitives
				(gr_poly
					(pts
						(arc
							(start 0.1524 0.127)
							(mid 0.137521 0.162921)
							(end 0.1016 0.1778)
						)
						(arc
							(start -0.1016 0.1778)
							(mid -0.137521 0.162921)
							(end -0.1524 0.127)
						)
						(arc
							(start -0.1524 -0.127)
							(mid -0.137521 -0.162921)
							(end -0.1016 -0.1778)
						)
						(arc
							(start 0.1016 -0.1778)
							(mid 0.137521 -0.162921)
							(end 0.1524 -0.127)
						)
					)
					(width 0)
					(fill yes)
				)
			)
		)
	)
	(footprint ""
		(layer "B.Cu")
		(at 181.70906 -7.97052)
		(property "Reference" "R268"
			(at 0 0 0)
			(layer "B.SilkS")
			(hide yes)
			(effects
				(font
					(size 1.27 1.27)
				)
				(justify mirror)
			)
		)
		(property "Value" "0R2J-2-GP"
			(at -0.064008 -3.993896 0)
			(unlocked yes)
			(layer "B.Fab")
			(hide yes)
			(effects
				(font
					(size 1.016 1.016)
					(thickness 0.1524)
				)
				(justify mirror)
			)
		)
		(property "Device Type" "R402H16"
			(at -0.064008 -5.517896 0)
			(unlocked yes)
			(layer "B.Fab")
			(hide yes)
			(effects
				(font
					(size 1.016 1.016)
					(thickness 0.1524)
				)
				(justify mirror)
			)
		)
		(duplicate_pad_numbers_are_jumpers no)
		(fp_line
			(start -0.508 -0.9398)
			(end 0.508 -0.9398)
			(stroke
				(width 0.1524)
				(type default)
			)
			(layer "B.SilkS")
		)
		(fp_line
			(start 0.508 -0.9398)
			(end 0.508 0.9398)
			(stroke
				(width 0.1524)
				(type default)
			)
			(layer "B.SilkS")
		)
		(fp_rect
			(start 0.508 0.9398)
			(end -0.508 -0.9398)
			(stroke
				(width 0)
				(type default)
			)
			(fill no)
			(layer "B.CrtYd")
		)
		(fp_rect
			(start 0.508 0.9398)
			(end -0.508 -0.9398)
			(stroke
				(width 0)
				(type default)
			)
			(fill no)
			(layer "B.Fab")
		)
		(pad "1" smd custom
			(at 0 -0.4445 180)
			(size 0.1397 0.1397)
			(layers "B.Cu" "B.Mask" "B.Paste")
			(net "MINISAS_CN15_A_I2C_INT#")
			(options
				(clearance outline)
				(anchor circle)
			)
			(primitives
				(gr_poly
					(pts
						(arc
							(start -0.1778 0.2794)
							(mid -0.249642 0.249642)
							(end -0.2794 0.1778)
						)
						(arc
							(start -0.2794 -0.1778)
							(mid -0.249642 -0.249642)
							(end -0.1778 -0.2794)
						)
						(arc
							(start 0.1778 -0.2794)
							(mid 0.249642 -0.249642)
							(end 0.2794 -0.1778)
						)
						(arc
							(start 0.2794 0.1778)
							(mid 0.249642 0.249642)
							(end 0.1778 0.2794)
						)
					)
					(width 0)
					(fill yes)
				)
			)
		)
		(pad "2" smd custom
			(at 0 0.4445 180)
			(size 0.1397 0.1397)
			(layers "B.Cu" "B.Mask" "B.Paste")
			(net "PCIE_REFCLK_H2_N_R")
			(options
				(clearance outline)
				(anchor circle)
			)
			(primitives
				(gr_poly
					(pts
						(arc
							(start -0.1778 0.2794)
							(mid -0.249642 0.249642)
							(end -0.2794 0.1778)
						)
						(arc
							(start -0.2794 -0.1778)
							(mid -0.249642 -0.249642)
							(end -0.1778 -0.2794)
						)
						(arc
							(start 0.1778 -0.2794)
							(mid 0.249642 -0.249642)
							(end 0.2794 -0.1778)
						)
						(arc
							(start 0.2794 0.1778)
							(mid 0.249642 0.249642)
							(end 0.1778 0.2794)
						)
					)
					(width 0)
					(fill yes)
				)
			)
		)
	)
	(footprint ""
		(layer "B.Cu")
		(at 321.673728 -36.991036 180)
		(property "Reference" "C242"
			(at 0 0 0)
			(layer "B.SilkS")
			(hide yes)
			(effects
				(font
					(size 1.27 1.27)
				)
				(justify mirror)
			)
		)
		(property "Value" "SCD1U10V2KX-5GP"
			(at -1.1811 -2.7051 180)
			(unlocked yes)
			(layer "B.Fab")
			(hide yes)
			(effects
				(font
					(size 1.016 1.016)
					(thickness 0.1524)
				)
				(justify mirror)
			)
		)
		(property "Device Type" "C402H22"
			(at -1.1811 -4.2291 180)
			(unlocked yes)
			(layer "B.Fab")
			(hide yes)
			(effects
				(font
					(size 1.016 1.016)
					(thickness 0.1524)
				)
				(justify mirror)
			)
		)
		(duplicate_pad_numbers_are_jumpers no)
		(fp_rect
			(start 0.4318 0.9525)
			(end -0.4318 -0.9525)
			(stroke
				(width 0)
				(type default)
			)
			(fill no)
			(layer "B.CrtYd")
		)
		(fp_rect
			(start 0.4318 0.9525)
			(end -0.4318 -0.9525)
			(stroke
				(width 0)
				(type default)
			)
			(fill no)
			(layer "B.Fab")
		)
		(pad "1" smd custom
			(at 0 -0.4445)
			(size 0.1524 0.1524)
			(layers "B.Cu" "B.Mask" "B.Paste")
			(net "GND")
			(options
				(clearance outline)
				(anchor circle)
			)
			(primitives
				(gr_poly
					(pts
						(arc
							(start 0.3048 0.2032)
							(mid 0.275042 0.275042)
							(end 0.2032 0.3048)
						)
						(arc
							(start -0.2032 0.3048)
							(mid -0.275042 0.275042)
							(end -0.3048 0.2032)
						)
						(arc
							(start -0.3048 -0.2032)
							(mid -0.275042 -0.275042)
							(end -0.2032 -0.3048)
						)
						(arc
							(start 0.2032 -0.3048)
							(mid 0.275042 -0.275042)
							(end 0.3048 -0.2032)
						)
					)
					(width 0)
					(fill yes)
				)
			)
		)
		(pad "2" smd custom
			(at 0 0.4445)
			(size 0.1524 0.1524)
			(layers "B.Cu" "B.Mask" "B.Paste")
			(net "P3V3_STBY")
			(options
				(clearance outline)
				(anchor circle)
			)
			(primitives
				(gr_poly
					(pts
						(arc
							(start 0.3048 0.2032)
							(mid 0.275042 0.275042)
							(end 0.2032 0.3048)
						)
						(arc
							(start -0.2032 0.3048)
							(mid -0.275042 0.275042)
							(end -0.3048 0.2032)
						)
						(arc
							(start -0.3048 -0.2032)
							(mid -0.275042 -0.275042)
							(end -0.2032 -0.3048)
						)
						(arc
							(start 0.2032 -0.3048)
							(mid 0.275042 -0.275042)
							(end 0.3048 -0.2032)
						)
					)
					(width 0)
					(fill yes)
				)
			)
		)
	)
	(footprint ""
		(layer "B.Cu")
		(at 64.135 -44.958 90)
		(property "Reference" "PC23"
			(at 0 0 90)
			(layer "B.SilkS")
			(hide yes)
			(effects
				(font
					(size 1.27 1.27)
				)
				(justify mirror)
			)
		)
		(property "Value" "SC10U25V5KX-GP"
			(at 0.0762 -6.1214 90)
			(unlocked yes)
			(layer "B.Fab")
			(hide yes)
			(effects
				(font
					(size 1.016 1.016)
					(thickness 0.1524)
				)
				(justify mirror)
			)
		)
		(property "Device Type" "C805H56"
			(at 0.0762 -8.1534 90)
			(unlocked yes)
			(layer "B.Fab")
			(hide yes)
			(effects
				(font
					(size 1.016 1.016)
					(thickness 0.1524)
				)
				(justify mirror)
			)
		)
		(duplicate_pad_numbers_are_jumpers no)
		(fp_line
			(start -0.635 0)
			(end 0.635 0)
			(stroke
				(width 0.508)
				(type default)
			)
			(layer "B.SilkS")
		)
		(fp_rect
			(start 0.9652 1.778)
			(end -0.9652 -1.778)
			(stroke
				(width 0)
				(type default)
			)
			(fill no)
			(layer "B.CrtYd")
		)
		(fp_poly
			(pts
				(xy 0.9652 -1.778) (xy -0.9652 -1.778) (xy -0.9652 1.778) (xy 0.9652 1.778)
			)
			(stroke
				(width 0)
				(type default)
			)
			(fill no)
			(layer "B.Fab")
		)
		(pad "1" smd rect
			(at 0 -0.9652 270)
			(size 1.397 1.143)
			(layers "B.Cu" "B.Mask" "B.Paste")
			(net "P3V3_STBY_VIN")
		)
		(pad "2" smd rect
			(at 0 0.9652 270)
			(size 1.397 1.143)
			(layers "B.Cu" "B.Mask" "B.Paste")
			(net "GND")
		)
	)
	(footprint ""
		(layer "B.Cu")
		(at 64.135 -121.285 90)
		(property "Reference" "R244"
			(at 0 0 90)
			(layer "B.SilkS")
			(hide yes)
			(effects
				(font
					(size 1.27 1.27)
				)
				(justify mirror)
			)
		)
		(property "Value" "0R2J-2-GP"
			(at -0.064008 -3.993896 90)
			(unlocked yes)
			(layer "B.Fab")
			(hide yes)
			(effects
				(font
					(size 1.016 1.016)
					(thickness 0.1524)
				)
				(justify mirror)
			)
		)
		(property "Device Type" "R402H16"
			(at -0.064008 -5.517896 90)
			(unlocked yes)
			(layer "B.Fab")
			(hide yes)
			(effects
				(font
					(size 1.016 1.016)
					(thickness 0.1524)
				)
				(justify mirror)
			)
		)
		(duplicate_pad_numbers_are_jumpers no)
		(fp_line
			(start 0.508 -0.9398)
			(end 0.508 0.9398)
			(stroke
				(width 0.1524)
				(type default)
			)
			(layer "B.SilkS")
		)
		(fp_line
			(start -0.508 -0.9398)
			(end 0.508 -0.9398)
			(stroke
				(width 0.1524)
				(type default)
			)
			(layer "B.SilkS")
		)
		(fp_rect
			(start 0.508 0.9398)
			(end -0.508 -0.9398)
			(stroke
				(width 0)
				(type default)
			)
			(fill no)
			(layer "B.CrtYd")
		)
		(fp_rect
			(start 0.508 0.9398)
			(end -0.508 -0.9398)
			(stroke
				(width 0)
				(type default)
			)
			(fill no)
			(layer "B.Fab")
		)
		(pad "1" smd custom
			(at 0 -0.4445 270)
			(size 0.1397 0.1397)
			(layers "B.Cu" "B.Mask" "B.Paste")
			(net "BMC_I2C4_MINI4_SCL_S")
			(options
				(clearance outline)
				(anchor circle)
			)
			(primitives
				(gr_poly
					(pts
						(arc
							(start -0.1778 0.2794)
							(mid -0.249642 0.249642)
							(end -0.2794 0.1778)
						)
						(arc
							(start -0.2794 -0.1778)
							(mid -0.249642 -0.249642)
							(end -0.1778 -0.2794)
						)
						(arc
							(start 0.1778 -0.2794)
							(mid 0.249642 -0.249642)
							(end 0.2794 -0.1778)
						)
						(arc
							(start 0.2794 0.1778)
							(mid 0.249642 0.249642)
							(end 0.1778 0.2794)
						)
					)
					(width 0)
					(fill yes)
				)
			)
		)
		(pad "2" smd custom
			(at 0 0.4445 270)
			(size 0.1397 0.1397)
			(layers "B.Cu" "B.Mask" "B.Paste")
			(net "BMC0_SMB4_CLK")
			(options
				(clearance outline)
				(anchor circle)
			)
			(primitives
				(gr_poly
					(pts
						(arc
							(start -0.1778 0.2794)
							(mid -0.249642 0.249642)
							(end -0.2794 0.1778)
						)
						(arc
							(start -0.2794 -0.1778)
							(mid -0.249642 -0.249642)
							(end -0.1778 -0.2794)
						)
						(arc
							(start 0.1778 -0.2794)
							(mid 0.249642 -0.249642)
							(end 0.2794 -0.1778)
						)
						(arc
							(start 0.2794 0.1778)
							(mid 0.249642 0.249642)
							(end 0.1778 0.2794)
						)
					)
					(width 0)
					(fill yes)
				)
			)
		)
	)
	(footprint ""
		(layer "B.Cu")
		(at 169.967402 -62.714632)
		(property "Reference" "PC209"
			(at 0 0 0)
			(layer "B.SilkS")
			(hide yes)
			(effects
				(font
					(size 1.27 1.27)
				)
				(justify mirror)
			)
		)
		(property "Value" "SC22U6D3V5MX-5-GP"
			(at 0.0762 -6.1214 0)
			(unlocked yes)
			(layer "B.Fab")
			(hide yes)
			(effects
				(font
					(size 1.016 1.016)
					(thickness 0.1524)
				)
				(justify mirror)
			)
		)
		(property "Device Type" "C805H56"
			(at 0.0762 -8.1534 0)
			(unlocked yes)
			(layer "B.Fab")
			(hide yes)
			(effects
				(font
					(size 1.016 1.016)
					(thickness 0.1524)
				)
				(justify mirror)
			)
		)
		(duplicate_pad_numbers_are_jumpers no)
		(fp_line
			(start -0.635 0)
			(end 0.635 0)
			(stroke
				(width 0.508)
				(type default)
			)
			(layer "B.SilkS")
		)
		(fp_rect
			(start 0.9652 1.778)
			(end -0.9652 -1.778)
			(stroke
				(width 0)
				(type default)
			)
			(fill no)
			(layer "B.CrtYd")
		)
		(fp_poly
			(pts
				(xy 0.9652 -1.778) (xy -0.9652 -1.778) (xy -0.9652 1.778) (xy 0.9652 1.778)
			)
			(stroke
				(width 0)
				(type default)
			)
			(fill no)
			(layer "B.Fab")
		)
		(pad "1" smd rect
			(at 0 -0.9652 180)
			(size 1.397 1.143)
			(layers "B.Cu" "B.Mask" "B.Paste")
			(net "P0V9")
		)
		(pad "2" smd rect
			(at 0 0.9652 180)
			(size 1.397 1.143)
			(layers "B.Cu" "B.Mask" "B.Paste")
			(net "GND")
		)
	)
	(footprint ""
		(layer "B.Cu")
		(at 178.0794 -66.929)
		(property "Reference" "PG24"
			(at 0 0 0)
			(layer "B.SilkS")
			(hide yes)
			(effects
				(font
					(size 1.27 1.27)
				)
				(justify mirror)
			)
		)
		(property "Value" "GAP-CLOSE-PWR-3-GP"
			(at -0.0254 -6.5786 0)
			(unlocked yes)
			(layer "B.Fab")
			(hide yes)
			(effects
				(font
					(size 1.016 1.016)
					(thickness 0.1524)
				)
				(justify mirror)
			)
		)
		(property "Device Type" "GAP-CLOSE-PWR-3"
			(at -0.0254 -8.255 0)
			(unlocked yes)
			(layer "B.Fab")
			(hide yes)
			(effects
				(font
					(size 1.016 1.016)
					(thickness 0.1524)
				)
				(justify mirror)
			)
		)
		(duplicate_pad_numbers_are_jumpers no)
		(fp_rect
			(start 0.7112 0.4572)
			(end -0.7112 -0.4572)
			(stroke
				(width 0)
				(type default)
			)
			(fill no)
			(layer "B.CrtYd")
		)
		(fp_poly
			(pts
				(xy 0.7112 -0.4572) (xy -0.7112 -0.4572) (xy -0.7112 0.4572) (xy 0.7112 0.4572)
			)
			(stroke
				(width 0)
				(type default)
			)
			(fill no)
			(layer "B.Fab")
		)
		(pad "1" smd rect
			(at 0.3048 0 180)
			(size 0.6604 0.762)
			(layers "B.Cu" "B.Mask" "B.Paste")
			(net "DUT_AVD_PCIE")
		)
		(pad "2" smd rect
			(at -0.3048 0 180)
			(size 0.6604 0.762)
			(layers "B.Cu" "B.Mask" "B.Paste")
			(net "P0V9")
		)
	)
	(footprint ""
		(layer "B.Cu")
		(at 123.928124 -196.443092 180)
		(property "Reference" "R536"
			(at 0 0 0)
			(layer "B.SilkS")
			(hide yes)
			(effects
				(font
					(size 1.27 1.27)
				)
				(justify mirror)
			)
		)
		(property "Value" "10KR2F-2-GP"
			(at -0.064008 -3.993896 180)
			(unlocked yes)
			(layer "B.Fab")
			(hide yes)
			(effects
				(font
					(size 1.016 1.016)
					(thickness 0.1524)
				)
				(justify mirror)
			)
		)
		(property "Device Type" "R402H16"
			(at -0.064008 -5.517896 180)
			(unlocked yes)
			(layer "B.Fab")
			(hide yes)
			(effects
				(font
					(size 1.016 1.016)
					(thickness 0.1524)
				)
				(justify mirror)
			)
		)
		(duplicate_pad_numbers_are_jumpers no)
		(fp_line
			(start 0.508 -0.9398)
			(end 0.508 0.9398)
			(stroke
				(width 0.1524)
				(type default)
			)
			(layer "B.SilkS")
		)
		(fp_line
			(start -0.508 -0.9398)
			(end 0.508 -0.9398)
			(stroke
				(width 0.1524)
				(type default)
			)
			(layer "B.SilkS")
		)
		(fp_rect
			(start 0.508 0.9398)
			(end -0.508 -0.9398)
			(stroke
				(width 0)
				(type default)
			)
			(fill no)
			(layer "B.CrtYd")
		)
		(fp_rect
			(start 0.508 0.9398)
			(end -0.508 -0.9398)
			(stroke
				(width 0)
				(type default)
			)
			(fill no)
			(layer "B.Fab")
		)
		(pad "1" smd custom
			(at 0 -0.4445)
			(size 0.1397 0.1397)
			(layers "B.Cu" "B.Mask" "B.Paste")
			(net "P3V3_STBY")
			(options
				(clearance outline)
				(anchor circle)
			)
			(primitives
				(gr_poly
					(pts
						(arc
							(start -0.1778 0.2794)
							(mid -0.249642 0.249642)
							(end -0.2794 0.1778)
						)
						(arc
							(start -0.2794 -0.1778)
							(mid -0.249642 -0.249642)
							(end -0.1778 -0.2794)
						)
						(arc
							(start 0.1778 -0.2794)
							(mid 0.249642 -0.249642)
							(end 0.2794 -0.1778)
						)
						(arc
							(start 0.2794 0.1778)
							(mid 0.249642 0.249642)
							(end 0.1778 0.2794)
						)
					)
					(width 0)
					(fill yes)
				)
			)
		)
		(pad "2" smd custom
			(at 0 0.4445)
			(size 0.1397 0.1397)
			(layers "B.Cu" "B.Mask" "B.Paste")
			(net "IOEXP2_AD1")
			(options
				(clearance outline)
				(anchor circle)
			)
			(primitives
				(gr_poly
					(pts
						(arc
							(start -0.1778 0.2794)
							(mid -0.249642 0.249642)
							(end -0.2794 0.1778)
						)
						(arc
							(start -0.2794 -0.1778)
							(mid -0.249642 -0.249642)
							(end -0.1778 -0.2794)
						)
						(arc
							(start 0.1778 -0.2794)
							(mid 0.249642 -0.249642)
							(end 0.2794 -0.1778)
						)
						(arc
							(start 0.2794 0.1778)
							(mid 0.249642 0.249642)
							(end 0.1778 0.2794)
						)
					)
					(width 0)
					(fill yes)
				)
			)
		)
	)
	(footprint ""
		(layer "B.Cu")
		(at 28.702 -116.967)
		(property "Reference" "R705"
			(at 0 0 0)
			(layer "B.SilkS")
			(hide yes)
			(effects
				(font
					(size 1.27 1.27)
				)
				(justify mirror)
			)
		)
		(property "Value" "0R2J-2-GP"
			(at -0.064008 -3.993896 0)
			(unlocked yes)
			(layer "B.Fab")
			(hide yes)
			(effects
				(font
					(size 1.016 1.016)
					(thickness 0.1524)
				)
				(justify mirror)
			)
		)
		(property "Device Type" "R402H16"
			(at -0.064008 -5.517896 0)
			(unlocked yes)
			(layer "B.Fab")
			(hide yes)
			(effects
				(font
					(size 1.016 1.016)
					(thickness 0.1524)
				)
				(justify mirror)
			)
		)
		(duplicate_pad_numbers_are_jumpers no)
		(fp_line
			(start -0.508 -0.9398)
			(end 0.508 -0.9398)
			(stroke
				(width 0.1524)
				(type default)
			)
			(layer "B.SilkS")
		)
		(fp_line
			(start 0.508 -0.9398)
			(end 0.508 0.9398)
			(stroke
				(width 0.1524)
				(type default)
			)
			(layer "B.SilkS")
		)
		(fp_rect
			(start 0.508 0.9398)
			(end -0.508 -0.9398)
			(stroke
				(width 0)
				(type default)
			)
			(fill no)
			(layer "B.CrtYd")
		)
		(fp_rect
			(start 0.508 0.9398)
			(end -0.508 -0.9398)
			(stroke
				(width 0)
				(type default)
			)
			(fill no)
			(layer "B.Fab")
		)
		(pad "1" smd custom
			(at 0 -0.4445 180)
			(size 0.1397 0.1397)
			(layers "B.Cu" "B.Mask" "B.Paste")
			(net "SPIDO_R")
			(options
				(clearance outline)
				(anchor circle)
			)
			(primitives
				(gr_poly
					(pts
						(arc
							(start -0.1778 0.2794)
							(mid -0.249642 0.249642)
							(end -0.2794 0.1778)
						)
						(arc
							(start -0.2794 -0.1778)
							(mid -0.249642 -0.249642)
							(end -0.1778 -0.2794)
						)
						(arc
							(start 0.1778 -0.2794)
							(mid 0.249642 -0.249642)
							(end 0.2794 -0.1778)
						)
						(arc
							(start 0.2794 0.1778)
							(mid 0.249642 0.249642)
							(end 0.1778 0.2794)
						)
					)
					(width 0)
					(fill yes)
				)
			)
		)
		(pad "2" smd custom
			(at 0 0.4445 180)
			(size 0.1397 0.1397)
			(layers "B.Cu" "B.Mask" "B.Paste")
			(net "SPIDO")
			(options
				(clearance outline)
				(anchor circle)
			)
			(primitives
				(gr_poly
					(pts
						(arc
							(start -0.1778 0.2794)
							(mid -0.249642 0.249642)
							(end -0.2794 0.1778)
						)
						(arc
							(start -0.2794 -0.1778)
							(mid -0.249642 -0.249642)
							(end -0.1778 -0.2794)
						)
						(arc
							(start 0.1778 -0.2794)
							(mid 0.249642 -0.249642)
							(end 0.2794 -0.1778)
						)
						(arc
							(start 0.2794 0.1778)
							(mid 0.249642 0.249642)
							(end 0.1778 0.2794)
						)
					)
					(width 0)
					(fill yes)
				)
			)
		)
	)
	(footprint ""
		(layer "B.Cu")
		(at 249.599958 -33.999932 -90)
		(property "Reference" "TP208"
			(at 0 0 90)
			(layer "B.SilkS")
			(hide yes)
			(effects
				(font
					(size 1.27 1.27)
				)
				(justify mirror)
			)
		)
		(property "Value" "TPAD28-2-GP"
			(at 0.0127 -1.6637 270)
			(unlocked yes)
			(layer "B.Fab")
			(hide yes)
			(effects
				(font
					(size 1.016 1.016)
					(thickness 0.1524)
				)
				(justify mirror)
			)
		)
		(property "Device Type" "TPAD28"
			(at 0.0127 -3.1877 270)
			(unlocked yes)
			(layer "B.Fab")
			(hide yes)
			(effects
				(font
					(size 1.016 1.016)
					(thickness 0.1524)
				)
				(justify mirror)
			)
		)
		(duplicate_pad_numbers_are_jumpers no)
		(fp_poly
			(pts
				(arc
					(start 0 -0.3556)
					(mid 0 0.3556)
					(end 0 -0.3556)
				)
			)
			(stroke
				(width 0)
				(type default)
			)
			(fill no)
			(layer "B.CrtYd")
		)
		(fp_poly
			(pts
				(arc
					(start 0 -0.6096)
					(mid 0 0.6096)
					(end 0 -0.6096)
				)
			)
			(stroke
				(width 0)
				(type default)
			)
			(fill no)
			(layer "B.Fab")
		)
		(pad "1" smd circle
			(at 0 0 90)
			(size 0.7112 0.7112)
			(layers "B.Cu" "B.Mask" "B.Paste")
			(net "GPIO109_R")
		)
	)
	(footprint ""
		(layer "B.Cu")
		(at 310.007 -59.309 180)
		(property "Reference" "PG41"
			(at 0 0 0)
			(layer "B.SilkS")
			(hide yes)
			(effects
				(font
					(size 1.27 1.27)
				)
				(justify mirror)
			)
		)
		(property "Value" "GAP-CLOSE-PWR-3-GP"
			(at -0.0254 -6.5786 180)
			(unlocked yes)
			(layer "B.Fab")
			(hide yes)
			(effects
				(font
					(size 1.016 1.016)
					(thickness 0.1524)
				)
				(justify mirror)
			)
		)
		(property "Device Type" "GAP-CLOSE-PWR-3"
			(at -0.0254 -8.255 180)
			(unlocked yes)
			(layer "B.Fab")
			(hide yes)
			(effects
				(font
					(size 1.016 1.016)
					(thickness 0.1524)
				)
				(justify mirror)
			)
		)
		(duplicate_pad_numbers_are_jumpers no)
		(fp_rect
			(start 0.7112 0.4572)
			(end -0.7112 -0.4572)
			(stroke
				(width 0)
				(type default)
			)
			(fill no)
			(layer "B.CrtYd")
		)
		(fp_poly
			(pts
				(xy 0.7112 -0.4572) (xy -0.7112 -0.4572) (xy -0.7112 0.4572) (xy 0.7112 0.4572)
			)
			(stroke
				(width 0)
				(type default)
			)
			(fill no)
			(layer "B.Fab")
		)
		(pad "1" smd rect
			(at 0.3048 0)
			(size 0.6604 0.762)
			(layers "B.Cu" "B.Mask" "B.Paste")
			(net "DUT_VDD")
		)
		(pad "2" smd rect
			(at -0.3048 0)
			(size 0.6604 0.762)
			(layers "B.Cu" "B.Mask" "B.Paste")
			(net "P0V9_E")
		)
	)
	(footprint ""
		(layer "B.Cu")
		(at 125.953012 -208.897474)
		(property "Reference" "R535"
			(at 0 0 0)
			(layer "B.SilkS")
			(hide yes)
			(effects
				(font
					(size 1.27 1.27)
				)
				(justify mirror)
			)
		)
		(property "Value" "10KR2F-2-GP"
			(at -0.064008 -3.993896 0)
			(unlocked yes)
			(layer "B.Fab")
			(hide yes)
			(effects
				(font
					(size 1.016 1.016)
					(thickness 0.1524)
				)
				(justify mirror)
			)
		)
		(property "Device Type" "R402H16"
			(at -0.064008 -5.517896 0)
			(unlocked yes)
			(layer "B.Fab")
			(hide yes)
			(effects
				(font
					(size 1.016 1.016)
					(thickness 0.1524)
				)
				(justify mirror)
			)
		)
		(duplicate_pad_numbers_are_jumpers no)
		(fp_line
			(start -0.508 -0.9398)
			(end 0.508 -0.9398)
			(stroke
				(width 0.1524)
				(type default)
			)
			(layer "B.SilkS")
		)
		(fp_line
			(start 0.508 -0.9398)
			(end 0.508 0.9398)
			(stroke
				(width 0.1524)
				(type default)
			)
			(layer "B.SilkS")
		)
		(fp_rect
			(start 0.508 0.9398)
			(end -0.508 -0.9398)
			(stroke
				(width 0)
				(type default)
			)
			(fill no)
			(layer "B.CrtYd")
		)
		(fp_rect
			(start 0.508 0.9398)
			(end -0.508 -0.9398)
			(stroke
				(width 0)
				(type default)
			)
			(fill no)
			(layer "B.Fab")
		)
		(pad "1" smd custom
			(at 0 -0.4445 180)
			(size 0.1397 0.1397)
			(layers "B.Cu" "B.Mask" "B.Paste")
			(net "P3V3_STBY")
			(options
				(clearance outline)
				(anchor circle)
			)
			(primitives
				(gr_poly
					(pts
						(arc
							(start -0.1778 0.2794)
							(mid -0.249642 0.249642)
							(end -0.2794 0.1778)
						)
						(arc
							(start -0.2794 -0.1778)
							(mid -0.249642 -0.249642)
							(end -0.1778 -0.2794)
						)
						(arc
							(start 0.1778 -0.2794)
							(mid 0.249642 -0.249642)
							(end 0.2794 -0.1778)
						)
						(arc
							(start 0.2794 0.1778)
							(mid 0.249642 0.249642)
							(end 0.1778 0.2794)
						)
					)
					(width 0)
					(fill yes)
				)
			)
		)
		(pad "2" smd custom
			(at 0 0.4445 180)
			(size 0.1397 0.1397)
			(layers "B.Cu" "B.Mask" "B.Paste")
			(net "IOEXP2_AD0")
			(options
				(clearance outline)
				(anchor circle)
			)
			(primitives
				(gr_poly
					(pts
						(arc
							(start -0.1778 0.2794)
							(mid -0.249642 0.249642)
							(end -0.2794 0.1778)
						)
						(arc
							(start -0.2794 -0.1778)
							(mid -0.249642 -0.249642)
							(end -0.1778 -0.2794)
						)
						(arc
							(start 0.1778 -0.2794)
							(mid 0.249642 -0.249642)
							(end 0.2794 -0.1778)
						)
						(arc
							(start 0.2794 0.1778)
							(mid 0.249642 0.249642)
							(end 0.1778 0.2794)
						)
					)
					(width 0)
					(fill yes)
				)
			)
		)
	)
	(footprint ""
		(layer "B.Cu")
		(at 243.59997 -40.999918 90)
		(property "Reference" "TP264"
			(at 0 0 90)
			(layer "B.SilkS")
			(hide yes)
			(effects
				(font
					(size 1.27 1.27)
				)
				(justify mirror)
			)
		)
		(property "Value" "TPAD28-2-GP"
			(at 0.0127 -1.6637 90)
			(unlocked yes)
			(layer "B.Fab")
			(hide yes)
			(effects
				(font
					(size 1.016 1.016)
					(thickness 0.1524)
				)
				(justify mirror)
			)
		)
		(property "Device Type" "TPAD28"
			(at 0.0127 -3.1877 90)
			(unlocked yes)
			(layer "B.Fab")
			(hide yes)
			(effects
				(font
					(size 1.016 1.016)
					(thickness 0.1524)
				)
				(justify mirror)
			)
		)
		(duplicate_pad_numbers_are_jumpers no)
		(fp_poly
			(pts
				(arc
					(start 0 0.3556)
					(mid 0 -0.3556)
					(end 0 0.3556)
				)
			)
			(stroke
				(width 0)
				(type default)
			)
			(fill no)
			(layer "B.CrtYd")
		)
		(fp_poly
			(pts
				(arc
					(start 0 0.6096)
					(mid 0 -0.6096)
					(end 0 0.6096)
				)
			)
			(stroke
				(width 0)
				(type default)
			)
			(fill no)
			(layer "B.Fab")
		)
		(pad "1" smd circle
			(at 0 0 270)
			(size 0.7112 0.7112)
			(layers "B.Cu" "B.Mask" "B.Paste")
			(net "LBI_DATA_7")
		)
	)
	(footprint ""
		(layer "B.Cu")
		(at 20.1168 -121.5644 -90)
		(property "Reference" "R225"
			(at 0 0 90)
			(layer "B.SilkS")
			(hide yes)
			(effects
				(font
					(size 1.27 1.27)
				)
				(justify mirror)
			)
		)
		(property "Value" "4K7R2F-GP"
			(at -0.064008 -3.993896 270)
			(unlocked yes)
			(layer "B.Fab")
			(hide yes)
			(effects
				(font
					(size 1.016 1.016)
					(thickness 0.1524)
				)
				(justify mirror)
			)
		)
		(property "Device Type" "R402H16"
			(at -0.064008 -5.517896 270)
			(unlocked yes)
			(layer "B.Fab")
			(hide yes)
			(effects
				(font
					(size 1.016 1.016)
					(thickness 0.1524)
				)
				(justify mirror)
			)
		)
		(duplicate_pad_numbers_are_jumpers no)
		(fp_line
			(start -0.508 -0.9398)
			(end 0.508 -0.9398)
			(stroke
				(width 0.1524)
				(type default)
			)
			(layer "B.SilkS")
		)
		(fp_line
			(start 0.508 -0.9398)
			(end 0.508 0.9398)
			(stroke
				(width 0.1524)
				(type default)
			)
			(layer "B.SilkS")
		)
		(fp_rect
			(start 0.508 0.9398)
			(end -0.508 -0.9398)
			(stroke
				(width 0)
				(type default)
			)
			(fill no)
			(layer "B.CrtYd")
		)
		(fp_rect
			(start 0.508 0.9398)
			(end -0.508 -0.9398)
			(stroke
				(width 0)
				(type default)
			)
			(fill no)
			(layer "B.Fab")
		)
		(pad "1" smd custom
			(at 0 -0.4445 90)
			(size 0.1397 0.1397)
			(layers "B.Cu" "B.Mask" "B.Paste")
			(net "DPB_HW_REVISION")
			(options
				(clearance outline)
				(anchor circle)
			)
			(primitives
				(gr_poly
					(pts
						(arc
							(start -0.1778 0.2794)
							(mid -0.249642 0.249642)
							(end -0.2794 0.1778)
						)
						(arc
							(start -0.2794 -0.1778)
							(mid -0.249642 -0.249642)
							(end -0.1778 -0.2794)
						)
						(arc
							(start 0.1778 -0.2794)
							(mid 0.249642 -0.249642)
							(end 0.2794 -0.1778)
						)
						(arc
							(start 0.2794 0.1778)
							(mid 0.249642 0.249642)
							(end 0.1778 0.2794)
						)
					)
					(width 0)
					(fill yes)
				)
			)
		)
		(pad "2" smd custom
			(at 0 0.4445 90)
			(size 0.1397 0.1397)
			(layers "B.Cu" "B.Mask" "B.Paste")
			(net "P3V3_STBY")
			(options
				(clearance outline)
				(anchor circle)
			)
			(primitives
				(gr_poly
					(pts
						(arc
							(start -0.1778 0.2794)
							(mid -0.249642 0.249642)
							(end -0.2794 0.1778)
						)
						(arc
							(start -0.2794 -0.1778)
							(mid -0.249642 -0.249642)
							(end -0.1778 -0.2794)
						)
						(arc
							(start 0.1778 -0.2794)
							(mid 0.249642 -0.249642)
							(end 0.2794 -0.1778)
						)
						(arc
							(start 0.2794 0.1778)
							(mid 0.249642 0.249642)
							(end 0.1778 0.2794)
						)
					)
					(width 0)
					(fill yes)
				)
			)
		)
	)
	(footprint ""
		(layer "B.Cu")
		(at 135.935212 -199.753474)
		(property "Reference" "C3207"
			(at 0 0 0)
			(layer "B.SilkS")
			(hide yes)
			(effects
				(font
					(size 1.27 1.27)
				)
				(justify mirror)
			)
		)
		(property "Value" "SCD1U25V2KX-2-GP"
			(at -1.1811 -2.7051 0)
			(unlocked yes)
			(layer "B.Fab")
			(hide yes)
			(effects
				(font
					(size 1.016 1.016)
					(thickness 0.1524)
				)
				(justify mirror)
			)
		)
		(property "Device Type" "C402H22"
			(at -1.1811 -4.2291 0)
			(unlocked yes)
			(layer "B.Fab")
			(hide yes)
			(effects
				(font
					(size 1.016 1.016)
					(thickness 0.1524)
				)
				(justify mirror)
			)
		)
		(duplicate_pad_numbers_are_jumpers no)
		(fp_rect
			(start 0.4318 0.9525)
			(end -0.4318 -0.9525)
			(stroke
				(width 0)
				(type default)
			)
			(fill no)
			(layer "B.CrtYd")
		)
		(fp_rect
			(start 0.4318 0.9525)
			(end -0.4318 -0.9525)
			(stroke
				(width 0)
				(type default)
			)
			(fill no)
			(layer "B.Fab")
		)
		(pad "1" smd custom
			(at 0 -0.4445 180)
			(size 0.1524 0.1524)
			(layers "B.Cu" "B.Mask" "B.Paste")
			(net "P3V3_STBY")
			(options
				(clearance outline)
				(anchor circle)
			)
			(primitives
				(gr_poly
					(pts
						(arc
							(start 0.3048 0.2032)
							(mid 0.275042 0.275042)
							(end 0.2032 0.3048)
						)
						(arc
							(start -0.2032 0.3048)
							(mid -0.275042 0.275042)
							(end -0.3048 0.2032)
						)
						(arc
							(start -0.3048 -0.2032)
							(mid -0.275042 -0.275042)
							(end -0.2032 -0.3048)
						)
						(arc
							(start 0.2032 -0.3048)
							(mid 0.275042 -0.275042)
							(end 0.3048 -0.2032)
						)
					)
					(width 0)
					(fill yes)
				)
			)
		)
		(pad "2" smd custom
			(at 0 0.4445 180)
			(size 0.1524 0.1524)
			(layers "B.Cu" "B.Mask" "B.Paste")
			(net "GND")
			(options
				(clearance outline)
				(anchor circle)
			)
			(primitives
				(gr_poly
					(pts
						(arc
							(start 0.3048 0.2032)
							(mid 0.275042 0.275042)
							(end 0.2032 0.3048)
						)
						(arc
							(start -0.2032 0.3048)
							(mid -0.275042 0.275042)
							(end -0.3048 0.2032)
						)
						(arc
							(start -0.3048 -0.2032)
							(mid -0.275042 -0.275042)
							(end -0.2032 -0.3048)
						)
						(arc
							(start 0.2032 -0.3048)
							(mid 0.275042 -0.275042)
							(end 0.3048 -0.2032)
						)
					)
					(width 0)
					(fill yes)
				)
			)
		)
	)
	(footprint ""
		(layer "B.Cu")
		(at 60.1472 -25.4508)
		(property "Reference" "R571"
			(at 0 0 0)
			(layer "B.SilkS")
			(hide yes)
			(effects
				(font
					(size 1.27 1.27)
				)
				(justify mirror)
			)
		)
		(property "Value" "10KR2F-2-GP"
			(at -0.064008 -3.993896 0)
			(unlocked yes)
			(layer "B.Fab")
			(hide yes)
			(effects
				(font
					(size 1.016 1.016)
					(thickness 0.1524)
				)
				(justify mirror)
			)
		)
		(property "Device Type" "R402H16"
			(at -0.064008 -5.517896 0)
			(unlocked yes)
			(layer "B.Fab")
			(hide yes)
			(effects
				(font
					(size 1.016 1.016)
					(thickness 0.1524)
				)
				(justify mirror)
			)
		)
		(duplicate_pad_numbers_are_jumpers no)
		(fp_line
			(start -0.508 -0.9398)
			(end 0.508 -0.9398)
			(stroke
				(width 0.1524)
				(type default)
			)
			(layer "B.SilkS")
		)
		(fp_line
			(start 0.508 -0.9398)
			(end 0.508 0.9398)
			(stroke
				(width 0.1524)
				(type default)
			)
			(layer "B.SilkS")
		)
		(fp_rect
			(start 0.508 0.9398)
			(end -0.508 -0.9398)
			(stroke
				(width 0)
				(type default)
			)
			(fill no)
			(layer "B.CrtYd")
		)
		(fp_rect
			(start 0.508 0.9398)
			(end -0.508 -0.9398)
			(stroke
				(width 0)
				(type default)
			)
			(fill no)
			(layer "B.Fab")
		)
		(pad "1" smd custom
			(at 0 -0.4445 180)
			(size 0.1397 0.1397)
			(layers "B.Cu" "B.Mask" "B.Paste")
			(net "P3V3_STBY")
			(options
				(clearance outline)
				(anchor circle)
			)
			(primitives
				(gr_poly
					(pts
						(arc
							(start -0.1778 0.2794)
							(mid -0.249642 0.249642)
							(end -0.2794 0.1778)
						)
						(arc
							(start -0.2794 -0.1778)
							(mid -0.249642 -0.249642)
							(end -0.1778 -0.2794)
						)
						(arc
							(start 0.1778 -0.2794)
							(mid 0.249642 -0.249642)
							(end 0.2794 -0.1778)
						)
						(arc
							(start 0.2794 0.1778)
							(mid 0.249642 0.249642)
							(end 0.1778 0.2794)
						)
					)
					(width 0)
					(fill yes)
				)
			)
		)
		(pad "2" smd custom
			(at 0 0.4445 180)
			(size 0.1397 0.1397)
			(layers "B.Cu" "B.Mask" "B.Paste")
			(net "BMC_INT_N")
			(options
				(clearance outline)
				(anchor circle)
			)
			(primitives
				(gr_poly
					(pts
						(arc
							(start -0.1778 0.2794)
							(mid -0.249642 0.249642)
							(end -0.2794 0.1778)
						)
						(arc
							(start -0.2794 -0.1778)
							(mid -0.249642 -0.249642)
							(end -0.1778 -0.2794)
						)
						(arc
							(start 0.1778 -0.2794)
							(mid 0.249642 -0.249642)
							(end 0.2794 -0.1778)
						)
						(arc
							(start 0.2794 0.1778)
							(mid 0.249642 0.249642)
							(end 0.1778 0.2794)
						)
					)
					(width 0)
					(fill yes)
				)
			)
		)
	)
	(footprint ""
		(layer "B.Cu")
		(at 314.071 -68.58 180)
		(property "Reference" "PC182"
			(at 0 0 0)
			(layer "B.SilkS")
			(hide yes)
			(effects
				(font
					(size 1.27 1.27)
				)
				(justify mirror)
			)
		)
		(property "Value" "SC22U6D3V5MX-5-GP"
			(at 0.0762 -6.1214 180)
			(unlocked yes)
			(layer "B.Fab")
			(hide yes)
			(effects
				(font
					(size 1.016 1.016)
					(thickness 0.1524)
				)
				(justify mirror)
			)
		)
		(property "Device Type" "C805H56"
			(at 0.0762 -8.1534 180)
			(unlocked yes)
			(layer "B.Fab")
			(hide yes)
			(effects
				(font
					(size 1.016 1.016)
					(thickness 0.1524)
				)
				(justify mirror)
			)
		)
		(duplicate_pad_numbers_are_jumpers no)
		(fp_line
			(start -0.635 0)
			(end 0.635 0)
			(stroke
				(width 0.508)
				(type default)
			)
			(layer "B.SilkS")
		)
		(fp_rect
			(start 0.9652 1.778)
			(end -0.9652 -1.778)
			(stroke
				(width 0)
				(type default)
			)
			(fill no)
			(layer "B.CrtYd")
		)
		(fp_poly
			(pts
				(xy 0.9652 -1.778) (xy -0.9652 -1.778) (xy -0.9652 1.778) (xy 0.9652 1.778)
			)
			(stroke
				(width 0)
				(type default)
			)
			(fill no)
			(layer "B.Fab")
		)
		(pad "1" smd rect
			(at 0 -0.9652)
			(size 1.397 1.143)
			(layers "B.Cu" "B.Mask" "B.Paste")
			(net "P0V9_E")
		)
		(pad "2" smd rect
			(at 0 0.9652)
			(size 1.397 1.143)
			(layers "B.Cu" "B.Mask" "B.Paste")
			(net "GND")
		)
	)
	(footprint ""
		(layer "B.Cu")
		(at 42.418 -138.557)
		(property "Reference" "TP231"
			(at 0 0 0)
			(layer "B.SilkS")
			(hide yes)
			(effects
				(font
					(size 1.27 1.27)
				)
				(justify mirror)
			)
		)
		(property "Value" "TPAD28-2-GP"
			(at 0.0127 -1.6637 0)
			(unlocked yes)
			(layer "B.Fab")
			(hide yes)
			(effects
				(font
					(size 1.016 1.016)
					(thickness 0.1524)
				)
				(justify mirror)
			)
		)
		(property "Device Type" "TPAD28"
			(at 0.0127 -3.1877 0)
			(unlocked yes)
			(layer "B.Fab")
			(hide yes)
			(effects
				(font
					(size 1.016 1.016)
					(thickness 0.1524)
				)
				(justify mirror)
			)
		)
		(duplicate_pad_numbers_are_jumpers no)
		(fp_poly
			(pts
				(arc
					(start 0.3556 0)
					(mid -0.3556 0)
					(end 0.3556 0)
				)
			)
			(stroke
				(width 0)
				(type default)
			)
			(fill no)
			(layer "B.CrtYd")
		)
		(fp_poly
			(pts
				(arc
					(start 0.6096 0)
					(mid -0.6096 0)
					(end 0.6096 0)
				)
			)
			(stroke
				(width 0)
				(type default)
			)
			(fill no)
			(layer "B.Fab")
		)
		(pad "1" smd circle
			(at 0 0 180)
			(size 0.7112 0.7112)
			(layers "B.Cu" "B.Mask" "B.Paste")
			(net "TP_GPIOP2")
		)
	)
	(footprint ""
		(layer "B.Cu")
		(at 228.6254 -45.991272 90)
		(property "Reference" "C490"
			(at 0 0 90)
			(layer "B.SilkS")
			(hide yes)
			(effects
				(font
					(size 1.27 1.27)
				)
				(justify mirror)
			)
		)
		(property "Value" "SCD1U16V1KX-1-GP"
			(at 2.8321 -1.7399 90)
			(unlocked yes)
			(layer "B.Fab")
			(hide yes)
			(effects
				(font
					(size 1.016 1.016)
					(thickness 0.1524)
				)
				(justify mirror)
			)
		)
		(property "Device Type" "C0201H13"
			(at 2.8321 -3.2639 90)
			(unlocked yes)
			(layer "B.Fab")
			(hide yes)
			(effects
				(font
					(size 1.016 1.016)
					(thickness 0.1524)
				)
				(justify mirror)
			)
		)
		(duplicate_pad_numbers_are_jumpers no)
		(fp_rect
			(start 0.2794 0.6477)
			(end -0.2794 -0.6477)
			(stroke
				(width 0)
				(type default)
			)
			(fill no)
			(layer "B.CrtYd")
		)
		(fp_rect
			(start 0.2794 0.6477)
			(end -0.2794 -0.6477)
			(stroke
				(width 0)
				(type default)
			)
			(fill no)
			(layer "B.Fab")
		)
		(pad "1" smd custom
			(at 0 -0.2794 270)
			(size 0.0762 0.0762)
			(layers "B.Cu" "B.Mask" "B.Paste")
			(net "DUT_AVD_PCIE")
			(options
				(clearance outline)
				(anchor circle)
			)
			(primitives
				(gr_poly
					(pts
						(arc
							(start 0.1524 0.127)
							(mid 0.137521 0.162921)
							(end 0.1016 0.1778)
						)
						(arc
							(start -0.1016 0.1778)
							(mid -0.137521 0.162921)
							(end -0.1524 0.127)
						)
						(arc
							(start -0.1524 -0.127)
							(mid -0.137521 -0.162921)
							(end -0.1016 -0.1778)
						)
						(arc
							(start 0.1016 -0.1778)
							(mid 0.137521 -0.162921)
							(end 0.1524 -0.127)
						)
					)
					(width 0)
					(fill yes)
				)
			)
		)
		(pad "2" smd custom
			(at 0 0.2794 270)
			(size 0.0762 0.0762)
			(layers "B.Cu" "B.Mask" "B.Paste")
			(net "GND")
			(options
				(clearance outline)
				(anchor circle)
			)
			(primitives
				(gr_poly
					(pts
						(arc
							(start 0.1524 0.127)
							(mid 0.137521 0.162921)
							(end 0.1016 0.1778)
						)
						(arc
							(start -0.1016 0.1778)
							(mid -0.137521 0.162921)
							(end -0.1524 0.127)
						)
						(arc
							(start -0.1524 -0.127)
							(mid -0.137521 -0.162921)
							(end -0.1016 -0.1778)
						)
						(arc
							(start 0.1016 -0.1778)
							(mid 0.137521 -0.162921)
							(end 0.1524 -0.127)
						)
					)
					(width 0)
					(fill yes)
				)
			)
		)
	)
	(footprint ""
		(layer "B.Cu")
		(at 228.6254 -51.998372 90)
		(property "Reference" "C561"
			(at 0 0 90)
			(layer "B.SilkS")
			(hide yes)
			(effects
				(font
					(size 1.27 1.27)
				)
				(justify mirror)
			)
		)
		(property "Value" "SCD1U16V1KX-1-GP"
			(at 2.8321 -1.7399 90)
			(unlocked yes)
			(layer "B.Fab")
			(hide yes)
			(effects
				(font
					(size 1.016 1.016)
					(thickness 0.1524)
				)
				(justify mirror)
			)
		)
		(property "Device Type" "C0201H13"
			(at 2.8321 -3.2639 90)
			(unlocked yes)
			(layer "B.Fab")
			(hide yes)
			(effects
				(font
					(size 1.016 1.016)
					(thickness 0.1524)
				)
				(justify mirror)
			)
		)
		(duplicate_pad_numbers_are_jumpers no)
		(fp_rect
			(start 0.2794 0.6477)
			(end -0.2794 -0.6477)
			(stroke
				(width 0)
				(type default)
			)
			(fill no)
			(layer "B.CrtYd")
		)
		(fp_rect
			(start 0.2794 0.6477)
			(end -0.2794 -0.6477)
			(stroke
				(width 0)
				(type default)
			)
			(fill no)
			(layer "B.Fab")
		)
		(pad "1" smd custom
			(at 0 -0.2794 270)
			(size 0.0762 0.0762)
			(layers "B.Cu" "B.Mask" "B.Paste")
			(net "DUT_AVD_PCIE")
			(options
				(clearance outline)
				(anchor circle)
			)
			(primitives
				(gr_poly
					(pts
						(arc
							(start 0.1524 0.127)
							(mid 0.137521 0.162921)
							(end 0.1016 0.1778)
						)
						(arc
							(start -0.1016 0.1778)
							(mid -0.137521 0.162921)
							(end -0.1524 0.127)
						)
						(arc
							(start -0.1524 -0.127)
							(mid -0.137521 -0.162921)
							(end -0.1016 -0.1778)
						)
						(arc
							(start 0.1016 -0.1778)
							(mid 0.137521 -0.162921)
							(end 0.1524 -0.127)
						)
					)
					(width 0)
					(fill yes)
				)
			)
		)
		(pad "2" smd custom
			(at 0 0.2794 270)
			(size 0.0762 0.0762)
			(layers "B.Cu" "B.Mask" "B.Paste")
			(net "GND")
			(options
				(clearance outline)
				(anchor circle)
			)
			(primitives
				(gr_poly
					(pts
						(arc
							(start 0.1524 0.127)
							(mid 0.137521 0.162921)
							(end 0.1016 0.1778)
						)
						(arc
							(start -0.1016 0.1778)
							(mid -0.137521 0.162921)
							(end -0.1524 0.127)
						)
						(arc
							(start -0.1524 -0.127)
							(mid -0.137521 -0.162921)
							(end -0.1016 -0.1778)
						)
						(arc
							(start 0.1016 -0.1778)
							(mid 0.137521 -0.162921)
							(end 0.1524 -0.127)
						)
					)
					(width 0)
					(fill yes)
				)
			)
		)
	)
	(footprint ""
		(layer "B.Cu")
		(at 182.07482 -13.5128 -90)
		(property "Reference" "R2953"
			(at 0 0 90)
			(layer "B.SilkS")
			(hide yes)
			(effects
				(font
					(size 1.27 1.27)
				)
				(justify mirror)
			)
		)
		(property "Value" "0R2J-2-GP"
			(at -0.064008 -3.993896 270)
			(unlocked yes)
			(layer "B.Fab")
			(hide yes)
			(effects
				(font
					(size 1.016 1.016)
					(thickness 0.1524)
				)
				(justify mirror)
			)
		)
		(property "Device Type" "R402H16"
			(at -0.064008 -5.517896 270)
			(unlocked yes)
			(layer "B.Fab")
			(hide yes)
			(effects
				(font
					(size 1.016 1.016)
					(thickness 0.1524)
				)
				(justify mirror)
			)
		)
		(duplicate_pad_numbers_are_jumpers no)
		(fp_line
			(start -0.508 -0.9398)
			(end 0.508 -0.9398)
			(stroke
				(width 0.1524)
				(type default)
			)
			(layer "B.SilkS")
		)
		(fp_line
			(start 0.508 -0.9398)
			(end 0.508 0.9398)
			(stroke
				(width 0.1524)
				(type default)
			)
			(layer "B.SilkS")
		)
		(fp_rect
			(start 0.508 0.9398)
			(end -0.508 -0.9398)
			(stroke
				(width 0)
				(type default)
			)
			(fill no)
			(layer "B.CrtYd")
		)
		(fp_rect
			(start 0.508 0.9398)
			(end -0.508 -0.9398)
			(stroke
				(width 0)
				(type default)
			)
			(fill no)
			(layer "B.Fab")
		)
		(pad "1" smd custom
			(at 0 -0.4445 90)
			(size 0.1397 0.1397)
			(layers "B.Cu" "B.Mask" "B.Paste")
			(net "PCIE_REFCLK_H3_N")
			(options
				(clearance outline)
				(anchor circle)
			)
			(primitives
				(gr_poly
					(pts
						(arc
							(start -0.1778 0.2794)
							(mid -0.249642 0.249642)
							(end -0.2794 0.1778)
						)
						(arc
							(start -0.2794 -0.1778)
							(mid -0.249642 -0.249642)
							(end -0.1778 -0.2794)
						)
						(arc
							(start 0.1778 -0.2794)
							(mid 0.249642 -0.249642)
							(end 0.2794 -0.1778)
						)
						(arc
							(start 0.2794 0.1778)
							(mid 0.249642 0.249642)
							(end 0.1778 0.2794)
						)
					)
					(width 0)
					(fill yes)
				)
			)
		)
		(pad "2" smd custom
			(at 0 0.4445 90)
			(size 0.1397 0.1397)
			(layers "B.Cu" "B.Mask" "B.Paste")
			(net "PCIE_REFCLK_H3_N_R")
			(options
				(clearance outline)
				(anchor circle)
			)
			(primitives
				(gr_poly
					(pts
						(arc
							(start -0.1778 0.2794)
							(mid -0.249642 0.249642)
							(end -0.2794 0.1778)
						)
						(arc
							(start -0.2794 -0.1778)
							(mid -0.249642 -0.249642)
							(end -0.1778 -0.2794)
						)
						(arc
							(start 0.1778 -0.2794)
							(mid 0.249642 -0.249642)
							(end 0.2794 -0.1778)
						)
						(arc
							(start 0.2794 0.1778)
							(mid 0.249642 0.249642)
							(end 0.1778 0.2794)
						)
					)
					(width 0)
					(fill yes)
				)
			)
		)
	)
	(footprint ""
		(layer "B.Cu")
		(at 232.611422 -31.9786)
		(property "Reference" "C478"
			(at 0 0 0)
			(layer "B.SilkS")
			(hide yes)
			(effects
				(font
					(size 1.27 1.27)
				)
				(justify mirror)
			)
		)
		(property "Value" "SCD1U16V1KX-1-GP"
			(at 2.8321 -1.7399 0)
			(unlocked yes)
			(layer "B.Fab")
			(hide yes)
			(effects
				(font
					(size 1.016 1.016)
					(thickness 0.1524)
				)
				(justify mirror)
			)
		)
		(property "Device Type" "C0201H13"
			(at 2.8321 -3.2639 0)
			(unlocked yes)
			(layer "B.Fab")
			(hide yes)
			(effects
				(font
					(size 1.016 1.016)
					(thickness 0.1524)
				)
				(justify mirror)
			)
		)
		(duplicate_pad_numbers_are_jumpers no)
		(fp_rect
			(start 0.2794 0.6477)
			(end -0.2794 -0.6477)
			(stroke
				(width 0)
				(type default)
			)
			(fill no)
			(layer "B.CrtYd")
		)
		(fp_rect
			(start 0.2794 0.6477)
			(end -0.2794 -0.6477)
			(stroke
				(width 0)
				(type default)
			)
			(fill no)
			(layer "B.Fab")
		)
		(pad "1" smd custom
			(at 0 -0.2794 180)
			(size 0.0762 0.0762)
			(layers "B.Cu" "B.Mask" "B.Paste")
			(net "DUT_VDDO")
			(options
				(clearance outline)
				(anchor circle)
			)
			(primitives
				(gr_poly
					(pts
						(arc
							(start 0.1524 0.127)
							(mid 0.137521 0.162921)
							(end 0.1016 0.1778)
						)
						(arc
							(start -0.1016 0.1778)
							(mid -0.137521 0.162921)
							(end -0.1524 0.127)
						)
						(arc
							(start -0.1524 -0.127)
							(mid -0.137521 -0.162921)
							(end -0.1016 -0.1778)
						)
						(arc
							(start 0.1016 -0.1778)
							(mid 0.137521 -0.162921)
							(end 0.1524 -0.127)
						)
					)
					(width 0)
					(fill yes)
				)
			)
		)
		(pad "2" smd custom
			(at 0 0.2794 180)
			(size 0.0762 0.0762)
			(layers "B.Cu" "B.Mask" "B.Paste")
			(net "GND")
			(options
				(clearance outline)
				(anchor circle)
			)
			(primitives
				(gr_poly
					(pts
						(arc
							(start 0.1524 0.127)
							(mid 0.137521 0.162921)
							(end 0.1016 0.1778)
						)
						(arc
							(start -0.1016 0.1778)
							(mid -0.137521 0.162921)
							(end -0.1524 0.127)
						)
						(arc
							(start -0.1524 -0.127)
							(mid -0.137521 -0.162921)
							(end -0.1016 -0.1778)
						)
						(arc
							(start 0.1016 -0.1778)
							(mid 0.137521 -0.162921)
							(end 0.1524 -0.127)
						)
					)
					(width 0)
					(fill yes)
				)
			)
		)
	)
	(footprint ""
		(layer "B.Cu")
		(at 55.118 -136.271 180)
		(property "Reference" "C8081"
			(at 0 0 0)
			(layer "B.SilkS")
			(hide yes)
			(effects
				(font
					(size 1.27 1.27)
				)
				(justify mirror)
			)
		)
		(property "Value" "SCD1U25V2KX-2-GP"
			(at -1.1811 -2.7051 180)
			(unlocked yes)
			(layer "B.Fab")
			(hide yes)
			(effects
				(font
					(size 1.016 1.016)
					(thickness 0.1524)
				)
				(justify mirror)
			)
		)
		(property "Device Type" "C402H22"
			(at -1.1811 -4.2291 180)
			(unlocked yes)
			(layer "B.Fab")
			(hide yes)
			(effects
				(font
					(size 1.016 1.016)
					(thickness 0.1524)
				)
				(justify mirror)
			)
		)
		(duplicate_pad_numbers_are_jumpers no)
		(fp_rect
			(start 0.4318 0.9525)
			(end -0.4318 -0.9525)
			(stroke
				(width 0)
				(type default)
			)
			(fill no)
			(layer "B.CrtYd")
		)
		(fp_rect
			(start 0.4318 0.9525)
			(end -0.4318 -0.9525)
			(stroke
				(width 0)
				(type default)
			)
			(fill no)
			(layer "B.Fab")
		)
		(pad "1" smd custom
			(at 0 -0.4445)
			(size 0.1524 0.1524)
			(layers "B.Cu" "B.Mask" "B.Paste")
			(net "ADC_P0V9_E")
			(options
				(clearance outline)
				(anchor circle)
			)
			(primitives
				(gr_poly
					(pts
						(arc
							(start 0.3048 0.2032)
							(mid 0.275042 0.275042)
							(end 0.2032 0.3048)
						)
						(arc
							(start -0.2032 0.3048)
							(mid -0.275042 0.275042)
							(end -0.3048 0.2032)
						)
						(arc
							(start -0.3048 -0.2032)
							(mid -0.275042 -0.275042)
							(end -0.2032 -0.3048)
						)
						(arc
							(start 0.2032 -0.3048)
							(mid 0.275042 -0.275042)
							(end 0.3048 -0.2032)
						)
					)
					(width 0)
					(fill yes)
				)
			)
		)
		(pad "2" smd custom
			(at 0 0.4445)
			(size 0.1524 0.1524)
			(layers "B.Cu" "B.Mask" "B.Paste")
			(net "GND")
			(options
				(clearance outline)
				(anchor circle)
			)
			(primitives
				(gr_poly
					(pts
						(arc
							(start 0.3048 0.2032)
							(mid 0.275042 0.275042)
							(end 0.2032 0.3048)
						)
						(arc
							(start -0.2032 0.3048)
							(mid -0.275042 0.275042)
							(end -0.3048 0.2032)
						)
						(arc
							(start -0.3048 -0.2032)
							(mid -0.275042 -0.275042)
							(end -0.2032 -0.3048)
						)
						(arc
							(start 0.2032 -0.3048)
							(mid 0.275042 -0.275042)
							(end 0.3048 -0.2032)
						)
					)
					(width 0)
					(fill yes)
				)
			)
		)
	)
	(footprint ""
		(layer "B.Cu")
		(at 242.824 -20.447)
		(property "Reference" "R792"
			(at 0 0 0)
			(layer "B.SilkS")
			(hide yes)
			(effects
				(font
					(size 1.27 1.27)
				)
				(justify mirror)
			)
		)
		(property "Value" "4K7R2F-GP"
			(at -0.064008 -3.993896 0)
			(unlocked yes)
			(layer "B.Fab")
			(hide yes)
			(effects
				(font
					(size 1.016 1.016)
					(thickness 0.1524)
				)
				(justify mirror)
			)
		)
		(property "Device Type" "R402H16"
			(at -0.064008 -5.517896 0)
			(unlocked yes)
			(layer "B.Fab")
			(hide yes)
			(effects
				(font
					(size 1.016 1.016)
					(thickness 0.1524)
				)
				(justify mirror)
			)
		)
		(duplicate_pad_numbers_are_jumpers no)
		(fp_line
			(start -0.508 -0.9398)
			(end 0.508 -0.9398)
			(stroke
				(width 0.1524)
				(type default)
			)
			(layer "B.SilkS")
		)
		(fp_line
			(start 0.508 -0.9398)
			(end 0.508 0.9398)
			(stroke
				(width 0.1524)
				(type default)
			)
			(layer "B.SilkS")
		)
		(fp_rect
			(start 0.508 0.9398)
			(end -0.508 -0.9398)
			(stroke
				(width 0)
				(type default)
			)
			(fill no)
			(layer "B.CrtYd")
		)
		(fp_rect
			(start 0.508 0.9398)
			(end -0.508 -0.9398)
			(stroke
				(width 0)
				(type default)
			)
			(fill no)
			(layer "B.Fab")
		)
		(pad "1" smd custom
			(at 0 -0.4445 180)
			(size 0.1397 0.1397)
			(layers "B.Cu" "B.Mask" "B.Paste")
			(net "BOOTSTRAP0")
			(options
				(clearance outline)
				(anchor circle)
			)
			(primitives
				(gr_poly
					(pts
						(arc
							(start -0.1778 0.2794)
							(mid -0.249642 0.249642)
							(end -0.2794 0.1778)
						)
						(arc
							(start -0.2794 -0.1778)
							(mid -0.249642 -0.249642)
							(end -0.1778 -0.2794)
						)
						(arc
							(start 0.1778 -0.2794)
							(mid 0.249642 -0.249642)
							(end 0.2794 -0.1778)
						)
						(arc
							(start 0.2794 0.1778)
							(mid 0.249642 0.249642)
							(end 0.1778 0.2794)
						)
					)
					(width 0)
					(fill yes)
				)
			)
		)
		(pad "2" smd custom
			(at 0 0.4445 180)
			(size 0.1397 0.1397)
			(layers "B.Cu" "B.Mask" "B.Paste")
			(net "DUT_VDDO")
			(options
				(clearance outline)
				(anchor circle)
			)
			(primitives
				(gr_poly
					(pts
						(arc
							(start -0.1778 0.2794)
							(mid -0.249642 0.249642)
							(end -0.2794 0.1778)
						)
						(arc
							(start -0.2794 -0.1778)
							(mid -0.249642 -0.249642)
							(end -0.1778 -0.2794)
						)
						(arc
							(start 0.1778 -0.2794)
							(mid 0.249642 -0.249642)
							(end 0.2794 -0.1778)
						)
						(arc
							(start 0.2794 0.1778)
							(mid 0.249642 0.249642)
							(end 0.1778 0.2794)
						)
					)
					(width 0)
					(fill yes)
				)
			)
		)
	)
	(footprint ""
		(layer "B.Cu")
		(at 241.0968 -41.995852 -90)
		(property "Reference" "C437"
			(at 0 0 90)
			(layer "B.SilkS")
			(hide yes)
			(effects
				(font
					(size 1.27 1.27)
				)
				(justify mirror)
			)
		)
		(property "Value" "SCD1U16V1KX-1-GP"
			(at 2.8321 -1.7399 270)
			(unlocked yes)
			(layer "B.Fab")
			(hide yes)
			(effects
				(font
					(size 1.016 1.016)
					(thickness 0.1524)
				)
				(justify mirror)
			)
		)
		(property "Device Type" "C0201H13"
			(at 2.8321 -3.2639 270)
			(unlocked yes)
			(layer "B.Fab")
			(hide yes)
			(effects
				(font
					(size 1.016 1.016)
					(thickness 0.1524)
				)
				(justify mirror)
			)
		)
		(duplicate_pad_numbers_are_jumpers no)
		(fp_rect
			(start 0.2794 0.6477)
			(end -0.2794 -0.6477)
			(stroke
				(width 0)
				(type default)
			)
			(fill no)
			(layer "B.CrtYd")
		)
		(fp_rect
			(start 0.2794 0.6477)
			(end -0.2794 -0.6477)
			(stroke
				(width 0)
				(type default)
			)
			(fill no)
			(layer "B.Fab")
		)
		(pad "1" smd custom
			(at 0 -0.2794 90)
			(size 0.0762 0.0762)
			(layers "B.Cu" "B.Mask" "B.Paste")
			(net "DUT_VDD")
			(options
				(clearance outline)
				(anchor circle)
			)
			(primitives
				(gr_poly
					(pts
						(arc
							(start 0.1524 0.127)
							(mid 0.137521 0.162921)
							(end 0.1016 0.1778)
						)
						(arc
							(start -0.1016 0.1778)
							(mid -0.137521 0.162921)
							(end -0.1524 0.127)
						)
						(arc
							(start -0.1524 -0.127)
							(mid -0.137521 -0.162921)
							(end -0.1016 -0.1778)
						)
						(arc
							(start 0.1016 -0.1778)
							(mid 0.137521 -0.162921)
							(end 0.1524 -0.127)
						)
					)
					(width 0)
					(fill yes)
				)
			)
		)
		(pad "2" smd custom
			(at 0 0.2794 90)
			(size 0.0762 0.0762)
			(layers "B.Cu" "B.Mask" "B.Paste")
			(net "GND")
			(options
				(clearance outline)
				(anchor circle)
			)
			(primitives
				(gr_poly
					(pts
						(arc
							(start 0.1524 0.127)
							(mid 0.137521 0.162921)
							(end 0.1016 0.1778)
						)
						(arc
							(start -0.1016 0.1778)
							(mid -0.137521 0.162921)
							(end -0.1524 0.127)
						)
						(arc
							(start -0.1524 -0.127)
							(mid -0.137521 -0.162921)
							(end -0.1016 -0.1778)
						)
						(arc
							(start 0.1016 -0.1778)
							(mid 0.137521 -0.162921)
							(end 0.1524 -0.127)
						)
					)
					(width 0)
					(fill yes)
				)
			)
		)
	)
	(footprint ""
		(layer "B.Cu")
		(at 222.8088 -190.5762)
		(property "Reference" "R9032"
			(at 0 0 0)
			(layer "B.SilkS")
			(hide yes)
			(effects
				(font
					(size 1.27 1.27)
				)
				(justify mirror)
			)
		)
		(property "Value" "4K7R2F-GP"
			(at -0.064008 -3.993896 0)
			(unlocked yes)
			(layer "B.Fab")
			(hide yes)
			(effects
				(font
					(size 1.016 1.016)
					(thickness 0.1524)
				)
				(justify mirror)
			)
		)
		(property "Device Type" "R402H16"
			(at -0.064008 -5.517896 0)
			(unlocked yes)
			(layer "B.Fab")
			(hide yes)
			(effects
				(font
					(size 1.016 1.016)
					(thickness 0.1524)
				)
				(justify mirror)
			)
		)
		(duplicate_pad_numbers_are_jumpers no)
		(fp_line
			(start -0.508 -0.9398)
			(end 0.508 -0.9398)
			(stroke
				(width 0.1524)
				(type default)
			)
			(layer "B.SilkS")
		)
		(fp_line
			(start 0.508 -0.9398)
			(end 0.508 0.9398)
			(stroke
				(width 0.1524)
				(type default)
			)
			(layer "B.SilkS")
		)
		(fp_rect
			(start 0.508 0.9398)
			(end -0.508 -0.9398)
			(stroke
				(width 0)
				(type default)
			)
			(fill no)
			(layer "B.CrtYd")
		)
		(fp_rect
			(start 0.508 0.9398)
			(end -0.508 -0.9398)
			(stroke
				(width 0)
				(type default)
			)
			(fill no)
			(layer "B.Fab")
		)
		(pad "1" smd custom
			(at 0 -0.4445 180)
			(size 0.1397 0.1397)
			(layers "B.Cu" "B.Mask" "B.Paste")
			(net "SSD_PERST#3")
			(options
				(clearance outline)
				(anchor circle)
			)
			(primitives
				(gr_poly
					(pts
						(arc
							(start -0.1778 0.2794)
							(mid -0.249642 0.249642)
							(end -0.2794 0.1778)
						)
						(arc
							(start -0.2794 -0.1778)
							(mid -0.249642 -0.249642)
							(end -0.1778 -0.2794)
						)
						(arc
							(start 0.1778 -0.2794)
							(mid 0.249642 -0.249642)
							(end 0.2794 -0.1778)
						)
						(arc
							(start 0.2794 0.1778)
							(mid 0.249642 0.249642)
							(end 0.1778 0.2794)
						)
					)
					(width 0)
					(fill yes)
				)
			)
		)
		(pad "2" smd custom
			(at 0 0.4445 180)
			(size 0.1397 0.1397)
			(layers "B.Cu" "B.Mask" "B.Paste")
			(net "GND")
			(options
				(clearance outline)
				(anchor circle)
			)
			(primitives
				(gr_poly
					(pts
						(arc
							(start -0.1778 0.2794)
							(mid -0.249642 0.249642)
							(end -0.2794 0.1778)
						)
						(arc
							(start -0.2794 -0.1778)
							(mid -0.249642 -0.249642)
							(end -0.1778 -0.2794)
						)
						(arc
							(start 0.1778 -0.2794)
							(mid 0.249642 -0.249642)
							(end 0.2794 -0.1778)
						)
						(arc
							(start 0.2794 0.1778)
							(mid 0.249642 0.249642)
							(end 0.1778 0.2794)
						)
					)
					(width 0)
					(fill yes)
				)
			)
		)
	)
	(footprint ""
		(layer "B.Cu")
		(at 61.341 -124.46 -90)
		(property "Reference" "R578"
			(at 0 0 90)
			(layer "B.SilkS")
			(hide yes)
			(effects
				(font
					(size 1.27 1.27)
				)
				(justify mirror)
			)
		)
		(property "Value" "4K7R2F-GP"
			(at -0.064008 -3.993896 270)
			(unlocked yes)
			(layer "B.Fab")
			(hide yes)
			(effects
				(font
					(size 1.016 1.016)
					(thickness 0.1524)
				)
				(justify mirror)
			)
		)
		(property "Device Type" "R402H16"
			(at -0.064008 -5.517896 270)
			(unlocked yes)
			(layer "B.Fab")
			(hide yes)
			(effects
				(font
					(size 1.016 1.016)
					(thickness 0.1524)
				)
				(justify mirror)
			)
		)
		(duplicate_pad_numbers_are_jumpers no)
		(fp_line
			(start -0.508 -0.9398)
			(end 0.508 -0.9398)
			(stroke
				(width 0.1524)
				(type default)
			)
			(layer "B.SilkS")
		)
		(fp_line
			(start 0.508 -0.9398)
			(end 0.508 0.9398)
			(stroke
				(width 0.1524)
				(type default)
			)
			(layer "B.SilkS")
		)
		(fp_rect
			(start 0.508 0.9398)
			(end -0.508 -0.9398)
			(stroke
				(width 0)
				(type default)
			)
			(fill no)
			(layer "B.CrtYd")
		)
		(fp_rect
			(start 0.508 0.9398)
			(end -0.508 -0.9398)
			(stroke
				(width 0)
				(type default)
			)
			(fill no)
			(layer "B.Fab")
		)
		(pad "1" smd custom
			(at 0 -0.4445 90)
			(size 0.1397 0.1397)
			(layers "B.Cu" "B.Mask" "B.Paste")
			(net "BMC_I2C6_C_FCB_SDA")
			(options
				(clearance outline)
				(anchor circle)
			)
			(primitives
				(gr_poly
					(pts
						(arc
							(start -0.1778 0.2794)
							(mid -0.249642 0.249642)
							(end -0.2794 0.1778)
						)
						(arc
							(start -0.2794 -0.1778)
							(mid -0.249642 -0.249642)
							(end -0.1778 -0.2794)
						)
						(arc
							(start 0.1778 -0.2794)
							(mid 0.249642 -0.249642)
							(end 0.2794 -0.1778)
						)
						(arc
							(start 0.2794 0.1778)
							(mid 0.249642 0.249642)
							(end 0.1778 0.2794)
						)
					)
					(width 0)
					(fill yes)
				)
			)
		)
		(pad "2" smd custom
			(at 0 0.4445 90)
			(size 0.1397 0.1397)
			(layers "B.Cu" "B.Mask" "B.Paste")
			(net "P3V3_STBY")
			(options
				(clearance outline)
				(anchor circle)
			)
			(primitives
				(gr_poly
					(pts
						(arc
							(start -0.1778 0.2794)
							(mid -0.249642 0.249642)
							(end -0.2794 0.1778)
						)
						(arc
							(start -0.2794 -0.1778)
							(mid -0.249642 -0.249642)
							(end -0.1778 -0.2794)
						)
						(arc
							(start 0.1778 -0.2794)
							(mid 0.249642 -0.249642)
							(end 0.2794 -0.1778)
						)
						(arc
							(start 0.2794 0.1778)
							(mid 0.249642 0.249642)
							(end 0.1778 0.2794)
						)
					)
					(width 0)
					(fill yes)
				)
			)
		)
	)
	(footprint ""
		(layer "B.Cu")
		(at 46.609 -112.5982 -90)
		(property "Reference" "C219"
			(at 0 0 90)
			(layer "B.SilkS")
			(hide yes)
			(effects
				(font
					(size 1.27 1.27)
				)
				(justify mirror)
			)
		)
		(property "Value" "SC1U10V2KX-4-GP"
			(at -1.1811 -2.7051 270)
			(unlocked yes)
			(layer "B.Fab")
			(hide yes)
			(effects
				(font
					(size 1.016 1.016)
					(thickness 0.1524)
				)
				(justify mirror)
			)
		)
		(property "Device Type" "C402H22"
			(at -1.1811 -4.2291 270)
			(unlocked yes)
			(layer "B.Fab")
			(hide yes)
			(effects
				(font
					(size 1.016 1.016)
					(thickness 0.1524)
				)
				(justify mirror)
			)
		)
		(duplicate_pad_numbers_are_jumpers no)
		(fp_rect
			(start 0.4318 0.9525)
			(end -0.4318 -0.9525)
			(stroke
				(width 0)
				(type default)
			)
			(fill no)
			(layer "B.CrtYd")
		)
		(fp_rect
			(start 0.4318 0.9525)
			(end -0.4318 -0.9525)
			(stroke
				(width 0)
				(type default)
			)
			(fill no)
			(layer "B.Fab")
		)
		(pad "1" smd custom
			(at 0 -0.4445 90)
			(size 0.1524 0.1524)
			(layers "B.Cu" "B.Mask" "B.Paste")
			(net "P3V3_STBY")
			(options
				(clearance outline)
				(anchor circle)
			)
			(primitives
				(gr_poly
					(pts
						(arc
							(start 0.3048 0.2032)
							(mid 0.275042 0.275042)
							(end 0.2032 0.3048)
						)
						(arc
							(start -0.2032 0.3048)
							(mid -0.275042 0.275042)
							(end -0.3048 0.2032)
						)
						(arc
							(start -0.3048 -0.2032)
							(mid -0.275042 -0.275042)
							(end -0.2032 -0.3048)
						)
						(arc
							(start 0.2032 -0.3048)
							(mid 0.275042 -0.275042)
							(end 0.3048 -0.2032)
						)
					)
					(width 0)
					(fill yes)
				)
			)
		)
		(pad "2" smd custom
			(at 0 0.4445 90)
			(size 0.1524 0.1524)
			(layers "B.Cu" "B.Mask" "B.Paste")
			(net "GND")
			(options
				(clearance outline)
				(anchor circle)
			)
			(primitives
				(gr_poly
					(pts
						(arc
							(start 0.3048 0.2032)
							(mid 0.275042 0.275042)
							(end 0.2032 0.3048)
						)
						(arc
							(start -0.2032 0.3048)
							(mid -0.275042 0.275042)
							(end -0.3048 0.2032)
						)
						(arc
							(start -0.3048 -0.2032)
							(mid -0.275042 -0.275042)
							(end -0.2032 -0.3048)
						)
						(arc
							(start 0.2032 -0.3048)
							(mid 0.275042 -0.275042)
							(end 0.3048 -0.2032)
						)
					)
					(width 0)
					(fill yes)
				)
			)
		)
	)
	(footprint ""
		(layer "B.Cu")
		(at 158.623 -90.0684 90)
		(property "Reference" "C716"
			(at 0 0 90)
			(layer "B.SilkS")
			(hide yes)
			(effects
				(font
					(size 1.27 1.27)
				)
				(justify mirror)
			)
		)
		(property "Value" "SCD1U10V2KX-5GP"
			(at -1.1811 -2.7051 90)
			(unlocked yes)
			(layer "B.Fab")
			(hide yes)
			(effects
				(font
					(size 1.016 1.016)
					(thickness 0.1524)
				)
				(justify mirror)
			)
		)
		(property "Device Type" "C402H22"
			(at -1.1811 -4.2291 90)
			(unlocked yes)
			(layer "B.Fab")
			(hide yes)
			(effects
				(font
					(size 1.016 1.016)
					(thickness 0.1524)
				)
				(justify mirror)
			)
		)
		(duplicate_pad_numbers_are_jumpers no)
		(fp_rect
			(start 0.4318 0.9525)
			(end -0.4318 -0.9525)
			(stroke
				(width 0)
				(type default)
			)
			(fill no)
			(layer "B.CrtYd")
		)
		(fp_rect
			(start 0.4318 0.9525)
			(end -0.4318 -0.9525)
			(stroke
				(width 0)
				(type default)
			)
			(fill no)
			(layer "B.Fab")
		)
		(pad "1" smd custom
			(at 0 -0.4445 270)
			(size 0.1524 0.1524)
			(layers "B.Cu" "B.Mask" "B.Paste")
			(net "P1V8_CLKGEN")
			(options
				(clearance outline)
				(anchor circle)
			)
			(primitives
				(gr_poly
					(pts
						(arc
							(start 0.3048 0.2032)
							(mid 0.275042 0.275042)
							(end 0.2032 0.3048)
						)
						(arc
							(start -0.2032 0.3048)
							(mid -0.275042 0.275042)
							(end -0.3048 0.2032)
						)
						(arc
							(start -0.3048 -0.2032)
							(mid -0.275042 -0.275042)
							(end -0.2032 -0.3048)
						)
						(arc
							(start 0.2032 -0.3048)
							(mid 0.275042 -0.275042)
							(end 0.3048 -0.2032)
						)
					)
					(width 0)
					(fill yes)
				)
			)
		)
		(pad "2" smd custom
			(at 0 0.4445 270)
			(size 0.1524 0.1524)
			(layers "B.Cu" "B.Mask" "B.Paste")
			(net "GND")
			(options
				(clearance outline)
				(anchor circle)
			)
			(primitives
				(gr_poly
					(pts
						(arc
							(start 0.3048 0.2032)
							(mid 0.275042 0.275042)
							(end 0.2032 0.3048)
						)
						(arc
							(start -0.2032 0.3048)
							(mid -0.275042 0.275042)
							(end -0.3048 0.2032)
						)
						(arc
							(start -0.3048 -0.2032)
							(mid -0.275042 -0.275042)
							(end -0.2032 -0.3048)
						)
						(arc
							(start 0.2032 -0.3048)
							(mid 0.275042 -0.275042)
							(end 0.3048 -0.2032)
						)
					)
					(width 0)
					(fill yes)
				)
			)
		)
	)
	(footprint ""
		(layer "B.Cu")
		(at 233.5276 -55.0037 90)
		(property "Reference" "C545"
			(at 0 0 90)
			(layer "B.SilkS")
			(hide yes)
			(effects
				(font
					(size 1.27 1.27)
				)
				(justify mirror)
			)
		)
		(property "Value" "SCD1U16V1KX-1-GP"
			(at 2.8321 -1.7399 90)
			(unlocked yes)
			(layer "B.Fab")
			(hide yes)
			(effects
				(font
					(size 1.016 1.016)
					(thickness 0.1524)
				)
				(justify mirror)
			)
		)
		(property "Device Type" "C0201H13"
			(at 2.8321 -3.2639 90)
			(unlocked yes)
			(layer "B.Fab")
			(hide yes)
			(effects
				(font
					(size 1.016 1.016)
					(thickness 0.1524)
				)
				(justify mirror)
			)
		)
		(duplicate_pad_numbers_are_jumpers no)
		(fp_rect
			(start 0.2794 0.6477)
			(end -0.2794 -0.6477)
			(stroke
				(width 0)
				(type default)
			)
			(fill no)
			(layer "B.CrtYd")
		)
		(fp_rect
			(start 0.2794 0.6477)
			(end -0.2794 -0.6477)
			(stroke
				(width 0)
				(type default)
			)
			(fill no)
			(layer "B.Fab")
		)
		(pad "1" smd custom
			(at 0 -0.2794 270)
			(size 0.0762 0.0762)
			(layers "B.Cu" "B.Mask" "B.Paste")
			(net "DUT_AVD_PCIE")
			(options
				(clearance outline)
				(anchor circle)
			)
			(primitives
				(gr_poly
					(pts
						(arc
							(start 0.1524 0.127)
							(mid 0.137521 0.162921)
							(end 0.1016 0.1778)
						)
						(arc
							(start -0.1016 0.1778)
							(mid -0.137521 0.162921)
							(end -0.1524 0.127)
						)
						(arc
							(start -0.1524 -0.127)
							(mid -0.137521 -0.162921)
							(end -0.1016 -0.1778)
						)
						(arc
							(start 0.1016 -0.1778)
							(mid 0.137521 -0.162921)
							(end 0.1524 -0.127)
						)
					)
					(width 0)
					(fill yes)
				)
			)
		)
		(pad "2" smd custom
			(at 0 0.2794 270)
			(size 0.0762 0.0762)
			(layers "B.Cu" "B.Mask" "B.Paste")
			(net "GND")
			(options
				(clearance outline)
				(anchor circle)
			)
			(primitives
				(gr_poly
					(pts
						(arc
							(start 0.1524 0.127)
							(mid 0.137521 0.162921)
							(end 0.1016 0.1778)
						)
						(arc
							(start -0.1016 0.1778)
							(mid -0.137521 0.162921)
							(end -0.1524 0.127)
						)
						(arc
							(start -0.1524 -0.127)
							(mid -0.137521 -0.162921)
							(end -0.1016 -0.1778)
						)
						(arc
							(start 0.1016 -0.1778)
							(mid 0.137521 -0.162921)
							(end 0.1524 -0.127)
						)
					)
					(width 0)
					(fill yes)
				)
			)
		)
	)
	(footprint ""
		(layer "B.Cu")
		(at 333.915512 -184.878218 180)
		(property "Reference" "R4165"
			(at 0 0 0)
			(layer "B.SilkS")
			(hide yes)
			(effects
				(font
					(size 1.27 1.27)
				)
				(justify mirror)
			)
		)
		(property "Value" "4K7R2F-GP"
			(at -0.064008 -3.993896 180)
			(unlocked yes)
			(layer "B.Fab")
			(hide yes)
			(effects
				(font
					(size 1.016 1.016)
					(thickness 0.1524)
				)
				(justify mirror)
			)
		)
		(property "Device Type" "R402H16"
			(at -0.064008 -5.517896 180)
			(unlocked yes)
			(layer "B.Fab")
			(hide yes)
			(effects
				(font
					(size 1.016 1.016)
					(thickness 0.1524)
				)
				(justify mirror)
			)
		)
		(duplicate_pad_numbers_are_jumpers no)
		(fp_line
			(start 0.508 -0.9398)
			(end 0.508 0.9398)
			(stroke
				(width 0.1524)
				(type default)
			)
			(layer "B.SilkS")
		)
		(fp_line
			(start -0.508 -0.9398)
			(end 0.508 -0.9398)
			(stroke
				(width 0.1524)
				(type default)
			)
			(layer "B.SilkS")
		)
		(fp_rect
			(start 0.508 0.9398)
			(end -0.508 -0.9398)
			(stroke
				(width 0)
				(type default)
			)
			(fill no)
			(layer "B.CrtYd")
		)
		(fp_rect
			(start 0.508 0.9398)
			(end -0.508 -0.9398)
			(stroke
				(width 0)
				(type default)
			)
			(fill no)
			(layer "B.Fab")
		)
		(pad "1" smd custom
			(at 0 -0.4445)
			(size 0.1397 0.1397)
			(layers "B.Cu" "B.Mask" "B.Paste")
			(net "BMC_PERST#15")
			(options
				(clearance outline)
				(anchor circle)
			)
			(primitives
				(gr_poly
					(pts
						(arc
							(start -0.1778 0.2794)
							(mid -0.249642 0.249642)
							(end -0.2794 0.1778)
						)
						(arc
							(start -0.2794 -0.1778)
							(mid -0.249642 -0.249642)
							(end -0.1778 -0.2794)
						)
						(arc
							(start 0.1778 -0.2794)
							(mid 0.249642 -0.249642)
							(end 0.2794 -0.1778)
						)
						(arc
							(start 0.2794 0.1778)
							(mid 0.249642 0.249642)
							(end 0.1778 0.2794)
						)
					)
					(width 0)
					(fill yes)
				)
			)
		)
		(pad "2" smd custom
			(at 0 0.4445)
			(size 0.1397 0.1397)
			(layers "B.Cu" "B.Mask" "B.Paste")
			(net "P3V3_STBY")
			(options
				(clearance outline)
				(anchor circle)
			)
			(primitives
				(gr_poly
					(pts
						(arc
							(start -0.1778 0.2794)
							(mid -0.249642 0.249642)
							(end -0.2794 0.1778)
						)
						(arc
							(start -0.2794 -0.1778)
							(mid -0.249642 -0.249642)
							(end -0.1778 -0.2794)
						)
						(arc
							(start 0.1778 -0.2794)
							(mid 0.249642 -0.249642)
							(end 0.2794 -0.1778)
						)
						(arc
							(start 0.2794 0.1778)
							(mid 0.249642 0.249642)
							(end 0.1778 0.2794)
						)
					)
					(width 0)
					(fill yes)
				)
			)
		)
	)
	(footprint ""
		(layer "B.Cu")
		(at 53.975508 -121.823226 -90)
		(property "Reference" "R246"
			(at 0 0 90)
			(layer "B.SilkS")
			(hide yes)
			(effects
				(font
					(size 1.27 1.27)
				)
				(justify mirror)
			)
		)
		(property "Value" "0R2J-2-GP"
			(at -0.064008 -3.993896 270)
			(unlocked yes)
			(layer "B.Fab")
			(hide yes)
			(effects
				(font
					(size 1.016 1.016)
					(thickness 0.1524)
				)
				(justify mirror)
			)
		)
		(property "Device Type" "R402H16"
			(at -0.064008 -5.517896 270)
			(unlocked yes)
			(layer "B.Fab")
			(hide yes)
			(effects
				(font
					(size 1.016 1.016)
					(thickness 0.1524)
				)
				(justify mirror)
			)
		)
		(duplicate_pad_numbers_are_jumpers no)
		(fp_line
			(start -0.508 -0.9398)
			(end 0.508 -0.9398)
			(stroke
				(width 0.1524)
				(type default)
			)
			(layer "B.SilkS")
		)
		(fp_line
			(start 0.508 -0.9398)
			(end 0.508 0.9398)
			(stroke
				(width 0.1524)
				(type default)
			)
			(layer "B.SilkS")
		)
		(fp_rect
			(start 0.508 0.9398)
			(end -0.508 -0.9398)
			(stroke
				(width 0)
				(type default)
			)
			(fill no)
			(layer "B.CrtYd")
		)
		(fp_rect
			(start 0.508 0.9398)
			(end -0.508 -0.9398)
			(stroke
				(width 0)
				(type default)
			)
			(fill no)
			(layer "B.Fab")
		)
		(pad "1" smd custom
			(at 0 -0.4445 90)
			(size 0.1397 0.1397)
			(layers "B.Cu" "B.Mask" "B.Paste")
			(net "BMC_I2C5_D_PEB_DEVICE_SCL")
			(options
				(clearance outline)
				(anchor circle)
			)
			(primitives
				(gr_poly
					(pts
						(arc
							(start -0.1778 0.2794)
							(mid -0.249642 0.249642)
							(end -0.2794 0.1778)
						)
						(arc
							(start -0.2794 -0.1778)
							(mid -0.249642 -0.249642)
							(end -0.1778 -0.2794)
						)
						(arc
							(start 0.1778 -0.2794)
							(mid 0.249642 -0.249642)
							(end 0.2794 -0.1778)
						)
						(arc
							(start 0.2794 0.1778)
							(mid 0.249642 0.249642)
							(end 0.1778 0.2794)
						)
					)
					(width 0)
					(fill yes)
				)
			)
		)
		(pad "2" smd custom
			(at 0 0.4445 90)
			(size 0.1397 0.1397)
			(layers "B.Cu" "B.Mask" "B.Paste")
			(net "BMC0_SMB5_CLK")
			(options
				(clearance outline)
				(anchor circle)
			)
			(primitives
				(gr_poly
					(pts
						(arc
							(start -0.1778 0.2794)
							(mid -0.249642 0.249642)
							(end -0.2794 0.1778)
						)
						(arc
							(start -0.2794 -0.1778)
							(mid -0.249642 -0.249642)
							(end -0.1778 -0.2794)
						)
						(arc
							(start 0.1778 -0.2794)
							(mid 0.249642 -0.249642)
							(end 0.2794 -0.1778)
						)
						(arc
							(start 0.2794 0.1778)
							(mid 0.249642 0.249642)
							(end 0.1778 0.2794)
						)
					)
					(width 0)
					(fill yes)
				)
			)
		)
	)
	(footprint ""
		(layer "B.Cu")
		(at 234.5944 -31.9786)
		(property "Reference" "C476"
			(at 0 0 0)
			(layer "B.SilkS")
			(hide yes)
			(effects
				(font
					(size 1.27 1.27)
				)
				(justify mirror)
			)
		)
		(property "Value" "SCD1U16V1KX-1-GP"
			(at 2.8321 -1.7399 0)
			(unlocked yes)
			(layer "B.Fab")
			(hide yes)
			(effects
				(font
					(size 1.016 1.016)
					(thickness 0.1524)
				)
				(justify mirror)
			)
		)
		(property "Device Type" "C0201H13"
			(at 2.8321 -3.2639 0)
			(unlocked yes)
			(layer "B.Fab")
			(hide yes)
			(effects
				(font
					(size 1.016 1.016)
					(thickness 0.1524)
				)
				(justify mirror)
			)
		)
		(duplicate_pad_numbers_are_jumpers no)
		(fp_rect
			(start 0.2794 0.6477)
			(end -0.2794 -0.6477)
			(stroke
				(width 0)
				(type default)
			)
			(fill no)
			(layer "B.CrtYd")
		)
		(fp_rect
			(start 0.2794 0.6477)
			(end -0.2794 -0.6477)
			(stroke
				(width 0)
				(type default)
			)
			(fill no)
			(layer "B.Fab")
		)
		(pad "1" smd custom
			(at 0 -0.2794 180)
			(size 0.0762 0.0762)
			(layers "B.Cu" "B.Mask" "B.Paste")
			(net "DUT_VDDO")
			(options
				(clearance outline)
				(anchor circle)
			)
			(primitives
				(gr_poly
					(pts
						(arc
							(start 0.1524 0.127)
							(mid 0.137521 0.162921)
							(end 0.1016 0.1778)
						)
						(arc
							(start -0.1016 0.1778)
							(mid -0.137521 0.162921)
							(end -0.1524 0.127)
						)
						(arc
							(start -0.1524 -0.127)
							(mid -0.137521 -0.162921)
							(end -0.1016 -0.1778)
						)
						(arc
							(start 0.1016 -0.1778)
							(mid 0.137521 -0.162921)
							(end 0.1524 -0.127)
						)
					)
					(width 0)
					(fill yes)
				)
			)
		)
		(pad "2" smd custom
			(at 0 0.2794 180)
			(size 0.0762 0.0762)
			(layers "B.Cu" "B.Mask" "B.Paste")
			(net "GND")
			(options
				(clearance outline)
				(anchor circle)
			)
			(primitives
				(gr_poly
					(pts
						(arc
							(start 0.1524 0.127)
							(mid 0.137521 0.162921)
							(end 0.1016 0.1778)
						)
						(arc
							(start -0.1016 0.1778)
							(mid -0.137521 0.162921)
							(end -0.1524 0.127)
						)
						(arc
							(start -0.1524 -0.127)
							(mid -0.137521 -0.162921)
							(end -0.1016 -0.1778)
						)
						(arc
							(start 0.1016 -0.1778)
							(mid 0.137521 -0.162921)
							(end 0.1524 -0.127)
						)
					)
					(width 0)
					(fill yes)
				)
			)
		)
	)
	(footprint ""
		(layer "B.Cu")
		(at 296.064178 -209.04454 90)
		(property "Reference" "C4152"
			(at 0 0 90)
			(layer "B.SilkS")
			(hide yes)
			(effects
				(font
					(size 1.27 1.27)
				)
				(justify mirror)
			)
		)
		(property "Value" "SCD1U25V3KX-GP"
			(at 0 -2.8194 90)
			(unlocked yes)
			(layer "B.Fab")
			(hide yes)
			(effects
				(font
					(size 1.016 1.016)
					(thickness 0.1524)
				)
				(justify mirror)
			)
		)
		(property "Device Type" "C603H36"
			(at 0 -4.3434 90)
			(unlocked yes)
			(layer "B.Fab")
			(hide yes)
			(effects
				(font
					(size 1.016 1.016)
					(thickness 0.1524)
				)
				(justify mirror)
			)
		)
		(duplicate_pad_numbers_are_jumpers no)
		(fp_line
			(start -0.508 0)
			(end 0.508 0)
			(stroke
				(width 0.2032)
				(type default)
			)
			(layer "B.SilkS")
		)
		(fp_rect
			(start 0.5842 1.3335)
			(end -0.5842 -1.3335)
			(stroke
				(width 0)
				(type default)
			)
			(fill no)
			(layer "B.CrtYd")
		)
		(fp_rect
			(start 0.5842 1.3335)
			(end -0.5842 -1.3335)
			(stroke
				(width 0)
				(type default)
			)
			(fill no)
			(layer "B.Fab")
		)
		(pad "1" smd custom
			(at 0 -0.762 270)
			(size 0.2159 0.2159)
			(layers "B.Cu" "B.Mask" "B.Paste")
			(net "GND")
			(options
				(clearance outline)
				(anchor circle)
			)
			(primitives
				(gr_poly
					(pts
						(arc
							(start -0.3302 0.4318)
							(mid -0.402042 0.402042)
							(end -0.4318 0.3302)
						)
						(arc
							(start -0.4318 -0.3302)
							(mid -0.402042 -0.402042)
							(end -0.3302 -0.4318)
						)
						(arc
							(start 0.3302 -0.4318)
							(mid 0.402042 -0.402042)
							(end 0.4318 -0.3302)
						)
						(arc
							(start 0.4318 0.3302)
							(mid 0.402042 0.402042)
							(end 0.3302 0.4318)
						)
					)
					(width 0)
					(fill yes)
				)
			)
		)
		(pad "2" smd custom
			(at 0 0.762 270)
			(size 0.2159 0.2159)
			(layers "B.Cu" "B.Mask" "B.Paste")
			(net "SSD_PWREN4_R")
			(options
				(clearance outline)
				(anchor circle)
			)
			(primitives
				(gr_poly
					(pts
						(arc
							(start -0.3302 0.4318)
							(mid -0.402042 0.402042)
							(end -0.4318 0.3302)
						)
						(arc
							(start -0.4318 -0.3302)
							(mid -0.402042 -0.402042)
							(end -0.3302 -0.4318)
						)
						(arc
							(start 0.3302 -0.4318)
							(mid 0.402042 -0.402042)
							(end 0.4318 -0.3302)
						)
						(arc
							(start 0.4318 0.3302)
							(mid 0.402042 0.402042)
							(end 0.3302 0.4318)
						)
					)
					(width 0)
					(fill yes)
				)
			)
		)
	)
	(footprint ""
		(layer "B.Cu")
		(at 162.941 -90.3224 -90)
		(property "Reference" "C721"
			(at 0 0 90)
			(layer "B.SilkS")
			(hide yes)
			(effects
				(font
					(size 1.27 1.27)
				)
				(justify mirror)
			)
		)
		(property "Value" "SCD1U10V2KX-5GP"
			(at -1.1811 -2.7051 270)
			(unlocked yes)
			(layer "B.Fab")
			(hide yes)
			(effects
				(font
					(size 1.016 1.016)
					(thickness 0.1524)
				)
				(justify mirror)
			)
		)
		(property "Device Type" "C402H22"
			(at -1.1811 -4.2291 270)
			(unlocked yes)
			(layer "B.Fab")
			(hide yes)
			(effects
				(font
					(size 1.016 1.016)
					(thickness 0.1524)
				)
				(justify mirror)
			)
		)
		(duplicate_pad_numbers_are_jumpers no)
		(fp_rect
			(start 0.4318 0.9525)
			(end -0.4318 -0.9525)
			(stroke
				(width 0)
				(type default)
			)
			(fill no)
			(layer "B.CrtYd")
		)
		(fp_rect
			(start 0.4318 0.9525)
			(end -0.4318 -0.9525)
			(stroke
				(width 0)
				(type default)
			)
			(fill no)
			(layer "B.Fab")
		)
		(pad "1" smd custom
			(at 0 -0.4445 90)
			(size 0.1524 0.1524)
			(layers "B.Cu" "B.Mask" "B.Paste")
			(net "P1V8_CLKGEN_A")
			(options
				(clearance outline)
				(anchor circle)
			)
			(primitives
				(gr_poly
					(pts
						(arc
							(start 0.3048 0.2032)
							(mid 0.275042 0.275042)
							(end 0.2032 0.3048)
						)
						(arc
							(start -0.2032 0.3048)
							(mid -0.275042 0.275042)
							(end -0.3048 0.2032)
						)
						(arc
							(start -0.3048 -0.2032)
							(mid -0.275042 -0.275042)
							(end -0.2032 -0.3048)
						)
						(arc
							(start 0.2032 -0.3048)
							(mid 0.275042 -0.275042)
							(end 0.3048 -0.2032)
						)
					)
					(width 0)
					(fill yes)
				)
			)
		)
		(pad "2" smd custom
			(at 0 0.4445 90)
			(size 0.1524 0.1524)
			(layers "B.Cu" "B.Mask" "B.Paste")
			(net "GND")
			(options
				(clearance outline)
				(anchor circle)
			)
			(primitives
				(gr_poly
					(pts
						(arc
							(start 0.3048 0.2032)
							(mid 0.275042 0.275042)
							(end 0.2032 0.3048)
						)
						(arc
							(start -0.2032 0.3048)
							(mid -0.275042 0.275042)
							(end -0.3048 0.2032)
						)
						(arc
							(start -0.3048 -0.2032)
							(mid -0.275042 -0.275042)
							(end -0.2032 -0.3048)
						)
						(arc
							(start 0.2032 -0.3048)
							(mid 0.275042 -0.275042)
							(end 0.3048 -0.2032)
						)
					)
					(width 0)
					(fill yes)
				)
			)
		)
	)
	(footprint ""
		(layer "B.Cu")
		(at 247.6373 -54.99354 -90)
		(property "Reference" "C594"
			(at 0 0 90)
			(layer "B.SilkS")
			(hide yes)
			(effects
				(font
					(size 1.27 1.27)
				)
				(justify mirror)
			)
		)
		(property "Value" "SCD1U16V1KX-1-GP"
			(at 2.8321 -1.7399 270)
			(unlocked yes)
			(layer "B.Fab")
			(hide yes)
			(effects
				(font
					(size 1.016 1.016)
					(thickness 0.1524)
				)
				(justify mirror)
			)
		)
		(property "Device Type" "C0201H13"
			(at 2.8321 -3.2639 270)
			(unlocked yes)
			(layer "B.Fab")
			(hide yes)
			(effects
				(font
					(size 1.016 1.016)
					(thickness 0.1524)
				)
				(justify mirror)
			)
		)
		(duplicate_pad_numbers_are_jumpers no)
		(fp_rect
			(start 0.2794 0.6477)
			(end -0.2794 -0.6477)
			(stroke
				(width 0)
				(type default)
			)
			(fill no)
			(layer "B.CrtYd")
		)
		(fp_rect
			(start 0.2794 0.6477)
			(end -0.2794 -0.6477)
			(stroke
				(width 0)
				(type default)
			)
			(fill no)
			(layer "B.Fab")
		)
		(pad "1" smd custom
			(at 0 -0.2794 90)
			(size 0.0762 0.0762)
			(layers "B.Cu" "B.Mask" "B.Paste")
			(net "DUT_AVD_PCIE")
			(options
				(clearance outline)
				(anchor circle)
			)
			(primitives
				(gr_poly
					(pts
						(arc
							(start 0.1524 0.127)
							(mid 0.137521 0.162921)
							(end 0.1016 0.1778)
						)
						(arc
							(start -0.1016 0.1778)
							(mid -0.137521 0.162921)
							(end -0.1524 0.127)
						)
						(arc
							(start -0.1524 -0.127)
							(mid -0.137521 -0.162921)
							(end -0.1016 -0.1778)
						)
						(arc
							(start 0.1016 -0.1778)
							(mid 0.137521 -0.162921)
							(end 0.1524 -0.127)
						)
					)
					(width 0)
					(fill yes)
				)
			)
		)
		(pad "2" smd custom
			(at 0 0.2794 90)
			(size 0.0762 0.0762)
			(layers "B.Cu" "B.Mask" "B.Paste")
			(net "GND")
			(options
				(clearance outline)
				(anchor circle)
			)
			(primitives
				(gr_poly
					(pts
						(arc
							(start 0.1524 0.127)
							(mid 0.137521 0.162921)
							(end 0.1016 0.1778)
						)
						(arc
							(start -0.1016 0.1778)
							(mid -0.137521 0.162921)
							(end -0.1524 0.127)
						)
						(arc
							(start -0.1524 -0.127)
							(mid -0.137521 -0.162921)
							(end -0.1016 -0.1778)
						)
						(arc
							(start 0.1016 -0.1778)
							(mid 0.137521 -0.162921)
							(end 0.1524 -0.127)
						)
					)
					(width 0)
					(fill yes)
				)
			)
		)
	)
	(footprint ""
		(layer "B.Cu")
		(at 38.1381 -114.55146 180)
		(property "Reference" "R442"
			(at 0 0 0)
			(layer "B.SilkS")
			(hide yes)
			(effects
				(font
					(size 1.27 1.27)
				)
				(justify mirror)
			)
		)
		(property "Value" "0R2J-2-GP"
			(at -0.064008 -3.993896 180)
			(unlocked yes)
			(layer "B.Fab")
			(hide yes)
			(effects
				(font
					(size 1.016 1.016)
					(thickness 0.1524)
				)
				(justify mirror)
			)
		)
		(property "Device Type" "R402H16"
			(at -0.064008 -5.517896 180)
			(unlocked yes)
			(layer "B.Fab")
			(hide yes)
			(effects
				(font
					(size 1.016 1.016)
					(thickness 0.1524)
				)
				(justify mirror)
			)
		)
		(duplicate_pad_numbers_are_jumpers no)
		(fp_line
			(start 0.508 -0.9398)
			(end 0.508 0.9398)
			(stroke
				(width 0.1524)
				(type default)
			)
			(layer "B.SilkS")
		)
		(fp_line
			(start -0.508 -0.9398)
			(end 0.508 -0.9398)
			(stroke
				(width 0.1524)
				(type default)
			)
			(layer "B.SilkS")
		)
		(fp_rect
			(start 0.508 0.9398)
			(end -0.508 -0.9398)
			(stroke
				(width 0)
				(type default)
			)
			(fill no)
			(layer "B.CrtYd")
		)
		(fp_rect
			(start 0.508 0.9398)
			(end -0.508 -0.9398)
			(stroke
				(width 0)
				(type default)
			)
			(fill no)
			(layer "B.Fab")
		)
		(pad "1" smd custom
			(at 0 -0.4445)
			(size 0.1397 0.1397)
			(layers "B.Cu" "B.Mask" "B.Paste")
			(net "GND")
			(options
				(clearance outline)
				(anchor circle)
			)
			(primitives
				(gr_poly
					(pts
						(arc
							(start -0.1778 0.2794)
							(mid -0.249642 0.249642)
							(end -0.2794 0.1778)
						)
						(arc
							(start -0.2794 -0.1778)
							(mid -0.249642 -0.249642)
							(end -0.1778 -0.2794)
						)
						(arc
							(start 0.1778 -0.2794)
							(mid 0.249642 -0.249642)
							(end 0.2794 -0.1778)
						)
						(arc
							(start 0.2794 0.1778)
							(mid 0.249642 0.249642)
							(end 0.1778 0.2794)
						)
					)
					(width 0)
					(fill yes)
				)
			)
		)
		(pad "2" smd custom
			(at 0 0.4445)
			(size 0.1397 0.1397)
			(layers "B.Cu" "B.Mask" "B.Paste")
			(net "RMII_PHY_BMC_RXD0")
			(options
				(clearance outline)
				(anchor circle)
			)
			(primitives
				(gr_poly
					(pts
						(arc
							(start -0.1778 0.2794)
							(mid -0.249642 0.249642)
							(end -0.2794 0.1778)
						)
						(arc
							(start -0.2794 -0.1778)
							(mid -0.249642 -0.249642)
							(end -0.1778 -0.2794)
						)
						(arc
							(start 0.1778 -0.2794)
							(mid 0.249642 -0.249642)
							(end 0.2794 -0.1778)
						)
						(arc
							(start 0.2794 0.1778)
							(mid 0.249642 0.249642)
							(end 0.1778 0.2794)
						)
					)
					(width 0)
					(fill yes)
				)
			)
		)
	)
	(footprint ""
		(layer "B.Cu")
		(at 59.218322 -120.352566 90)
		(property "Reference" "R472"
			(at 0 0 90)
			(layer "B.SilkS")
			(hide yes)
			(effects
				(font
					(size 1.27 1.27)
				)
				(justify mirror)
			)
		)
		(property "Value" "2K2R2J-2-GP"
			(at -0.064008 -3.993896 90)
			(unlocked yes)
			(layer "B.Fab")
			(hide yes)
			(effects
				(font
					(size 1.016 1.016)
					(thickness 0.1524)
				)
				(justify mirror)
			)
		)
		(property "Device Type" "R402H16"
			(at -0.064008 -5.517896 90)
			(unlocked yes)
			(layer "B.Fab")
			(hide yes)
			(effects
				(font
					(size 1.016 1.016)
					(thickness 0.1524)
				)
				(justify mirror)
			)
		)
		(duplicate_pad_numbers_are_jumpers no)
		(fp_line
			(start 0.508 -0.9398)
			(end 0.508 0.9398)
			(stroke
				(width 0.1524)
				(type default)
			)
			(layer "B.SilkS")
		)
		(fp_line
			(start -0.508 -0.9398)
			(end 0.508 -0.9398)
			(stroke
				(width 0.1524)
				(type default)
			)
			(layer "B.SilkS")
		)
		(fp_rect
			(start 0.508 0.9398)
			(end -0.508 -0.9398)
			(stroke
				(width 0)
				(type default)
			)
			(fill no)
			(layer "B.CrtYd")
		)
		(fp_rect
			(start 0.508 0.9398)
			(end -0.508 -0.9398)
			(stroke
				(width 0)
				(type default)
			)
			(fill no)
			(layer "B.Fab")
		)
		(pad "1" smd custom
			(at 0 -0.4445 270)
			(size 0.1397 0.1397)
			(layers "B.Cu" "B.Mask" "B.Paste")
			(net "BMC_I2C5_D_PEB_DEVICE_SDA")
			(options
				(clearance outline)
				(anchor circle)
			)
			(primitives
				(gr_poly
					(pts
						(arc
							(start -0.1778 0.2794)
							(mid -0.249642 0.249642)
							(end -0.2794 0.1778)
						)
						(arc
							(start -0.2794 -0.1778)
							(mid -0.249642 -0.249642)
							(end -0.1778 -0.2794)
						)
						(arc
							(start 0.1778 -0.2794)
							(mid 0.249642 -0.249642)
							(end 0.2794 -0.1778)
						)
						(arc
							(start 0.2794 0.1778)
							(mid 0.249642 0.249642)
							(end 0.1778 0.2794)
						)
					)
					(width 0)
					(fill yes)
				)
			)
		)
		(pad "2" smd custom
			(at 0 0.4445 270)
			(size 0.1397 0.1397)
			(layers "B.Cu" "B.Mask" "B.Paste")
			(net "P3V3_STBY")
			(options
				(clearance outline)
				(anchor circle)
			)
			(primitives
				(gr_poly
					(pts
						(arc
							(start -0.1778 0.2794)
							(mid -0.249642 0.249642)
							(end -0.2794 0.1778)
						)
						(arc
							(start -0.2794 -0.1778)
							(mid -0.249642 -0.249642)
							(end -0.1778 -0.2794)
						)
						(arc
							(start 0.1778 -0.2794)
							(mid 0.249642 -0.249642)
							(end 0.2794 -0.1778)
						)
						(arc
							(start 0.2794 0.1778)
							(mid 0.249642 0.249642)
							(end 0.1778 0.2794)
						)
					)
					(width 0)
					(fill yes)
				)
			)
		)
	)
	(footprint ""
		(layer "B.Cu")
		(at 134.342124 -208.889092 180)
		(property "Reference" "R4118"
			(at 0 0 0)
			(layer "B.SilkS")
			(hide yes)
			(effects
				(font
					(size 1.27 1.27)
				)
				(justify mirror)
			)
		)
		(property "Value" "4K7R2F-GP"
			(at -0.064008 -3.993896 180)
			(unlocked yes)
			(layer "B.Fab")
			(hide yes)
			(effects
				(font
					(size 1.016 1.016)
					(thickness 0.1524)
				)
				(justify mirror)
			)
		)
		(property "Device Type" "R402H16"
			(at -0.064008 -5.517896 180)
			(unlocked yes)
			(layer "B.Fab")
			(hide yes)
			(effects
				(font
					(size 1.016 1.016)
					(thickness 0.1524)
				)
				(justify mirror)
			)
		)
		(duplicate_pad_numbers_are_jumpers no)
		(fp_line
			(start 0.508 -0.9398)
			(end 0.508 0.9398)
			(stroke
				(width 0.1524)
				(type default)
			)
			(layer "B.SilkS")
		)
		(fp_line
			(start -0.508 -0.9398)
			(end 0.508 -0.9398)
			(stroke
				(width 0.1524)
				(type default)
			)
			(layer "B.SilkS")
		)
		(fp_rect
			(start 0.508 0.9398)
			(end -0.508 -0.9398)
			(stroke
				(width 0)
				(type default)
			)
			(fill no)
			(layer "B.CrtYd")
		)
		(fp_rect
			(start 0.508 0.9398)
			(end -0.508 -0.9398)
			(stroke
				(width 0)
				(type default)
			)
			(fill no)
			(layer "B.Fab")
		)
		(pad "1" smd custom
			(at 0 -0.4445)
			(size 0.1397 0.1397)
			(layers "B.Cu" "B.Mask" "B.Paste")
			(net "SSD_PRSNT#6")
			(options
				(clearance outline)
				(anchor circle)
			)
			(primitives
				(gr_poly
					(pts
						(arc
							(start -0.1778 0.2794)
							(mid -0.249642 0.249642)
							(end -0.2794 0.1778)
						)
						(arc
							(start -0.2794 -0.1778)
							(mid -0.249642 -0.249642)
							(end -0.1778 -0.2794)
						)
						(arc
							(start 0.1778 -0.2794)
							(mid 0.249642 -0.249642)
							(end 0.2794 -0.1778)
						)
						(arc
							(start 0.2794 0.1778)
							(mid 0.249642 0.249642)
							(end 0.1778 0.2794)
						)
					)
					(width 0)
					(fill yes)
				)
			)
		)
		(pad "2" smd custom
			(at 0 0.4445)
			(size 0.1397 0.1397)
			(layers "B.Cu" "B.Mask" "B.Paste")
			(net "P3V3_STBY")
			(options
				(clearance outline)
				(anchor circle)
			)
			(primitives
				(gr_poly
					(pts
						(arc
							(start -0.1778 0.2794)
							(mid -0.249642 0.249642)
							(end -0.2794 0.1778)
						)
						(arc
							(start -0.2794 -0.1778)
							(mid -0.249642 -0.249642)
							(end -0.1778 -0.2794)
						)
						(arc
							(start 0.1778 -0.2794)
							(mid 0.249642 -0.249642)
							(end 0.2794 -0.1778)
						)
						(arc
							(start 0.2794 0.1778)
							(mid 0.249642 0.249642)
							(end 0.1778 0.2794)
						)
					)
					(width 0)
					(fill yes)
				)
			)
		)
	)
	(footprint ""
		(layer "B.Cu")
		(at 78.843124 -183.235092)
		(property "Reference" "R4108"
			(at 0 0 0)
			(layer "B.SilkS")
			(hide yes)
			(effects
				(font
					(size 1.27 1.27)
				)
				(justify mirror)
			)
		)
		(property "Value" "4K7R2F-GP"
			(at -0.064008 -3.993896 0)
			(unlocked yes)
			(layer "B.Fab")
			(hide yes)
			(effects
				(font
					(size 1.016 1.016)
					(thickness 0.1524)
				)
				(justify mirror)
			)
		)
		(property "Device Type" "R402H16"
			(at -0.064008 -5.517896 0)
			(unlocked yes)
			(layer "B.Fab")
			(hide yes)
			(effects
				(font
					(size 1.016 1.016)
					(thickness 0.1524)
				)
				(justify mirror)
			)
		)
		(duplicate_pad_numbers_are_jumpers no)
		(fp_line
			(start -0.508 -0.9398)
			(end 0.508 -0.9398)
			(stroke
				(width 0.1524)
				(type default)
			)
			(layer "B.SilkS")
		)
		(fp_line
			(start 0.508 -0.9398)
			(end 0.508 0.9398)
			(stroke
				(width 0.1524)
				(type default)
			)
			(layer "B.SilkS")
		)
		(fp_rect
			(start 0.508 0.9398)
			(end -0.508 -0.9398)
			(stroke
				(width 0)
				(type default)
			)
			(fill no)
			(layer "B.CrtYd")
		)
		(fp_rect
			(start 0.508 0.9398)
			(end -0.508 -0.9398)
			(stroke
				(width 0)
				(type default)
			)
			(fill no)
			(layer "B.Fab")
		)
		(pad "1" smd custom
			(at 0 -0.4445 180)
			(size 0.1397 0.1397)
			(layers "B.Cu" "B.Mask" "B.Paste")
			(net "SSD_PERST#5")
			(options
				(clearance outline)
				(anchor circle)
			)
			(primitives
				(gr_poly
					(pts
						(arc
							(start -0.1778 0.2794)
							(mid -0.249642 0.249642)
							(end -0.2794 0.1778)
						)
						(arc
							(start -0.2794 -0.1778)
							(mid -0.249642 -0.249642)
							(end -0.1778 -0.2794)
						)
						(arc
							(start 0.1778 -0.2794)
							(mid 0.249642 -0.249642)
							(end 0.2794 -0.1778)
						)
						(arc
							(start 0.2794 0.1778)
							(mid 0.249642 0.249642)
							(end 0.1778 0.2794)
						)
					)
					(width 0)
					(fill yes)
				)
			)
		)
		(pad "2" smd custom
			(at 0 0.4445 180)
			(size 0.1397 0.1397)
			(layers "B.Cu" "B.Mask" "B.Paste")
			(net "P3V3_STBY")
			(options
				(clearance outline)
				(anchor circle)
			)
			(primitives
				(gr_poly
					(pts
						(arc
							(start -0.1778 0.2794)
							(mid -0.249642 0.249642)
							(end -0.2794 0.1778)
						)
						(arc
							(start -0.2794 -0.1778)
							(mid -0.249642 -0.249642)
							(end -0.1778 -0.2794)
						)
						(arc
							(start 0.1778 -0.2794)
							(mid 0.249642 -0.249642)
							(end 0.2794 -0.1778)
						)
						(arc
							(start 0.2794 0.1778)
							(mid 0.249642 0.249642)
							(end 0.1778 0.2794)
						)
					)
					(width 0)
					(fill yes)
				)
			)
		)
	)
	(footprint ""
		(layer "B.Cu")
		(at 77.343 -198.1454 90)
		(property "Reference" "C4112"
			(at 0 0 90)
			(layer "B.SilkS")
			(hide yes)
			(effects
				(font
					(size 1.27 1.27)
				)
				(justify mirror)
			)
		)
		(property "Value" "SCD1U25V3KX-GP"
			(at 0 -2.8194 90)
			(unlocked yes)
			(layer "B.Fab")
			(hide yes)
			(effects
				(font
					(size 1.016 1.016)
					(thickness 0.1524)
				)
				(justify mirror)
			)
		)
		(property "Device Type" "C603H36"
			(at 0 -4.3434 90)
			(unlocked yes)
			(layer "B.Fab")
			(hide yes)
			(effects
				(font
					(size 1.016 1.016)
					(thickness 0.1524)
				)
				(justify mirror)
			)
		)
		(duplicate_pad_numbers_are_jumpers no)
		(fp_line
			(start -0.508 0)
			(end 0.508 0)
			(stroke
				(width 0.2032)
				(type default)
			)
			(layer "B.SilkS")
		)
		(fp_rect
			(start 0.5842 1.3335)
			(end -0.5842 -1.3335)
			(stroke
				(width 0)
				(type default)
			)
			(fill no)
			(layer "B.CrtYd")
		)
		(fp_rect
			(start 0.5842 1.3335)
			(end -0.5842 -1.3335)
			(stroke
				(width 0)
				(type default)
			)
			(fill no)
			(layer "B.Fab")
		)
		(pad "1" smd custom
			(at 0 -0.762 270)
			(size 0.2159 0.2159)
			(layers "B.Cu" "B.Mask" "B.Paste")
			(net "GND")
			(options
				(clearance outline)
				(anchor circle)
			)
			(primitives
				(gr_poly
					(pts
						(arc
							(start -0.3302 0.4318)
							(mid -0.402042 0.402042)
							(end -0.4318 0.3302)
						)
						(arc
							(start -0.4318 -0.3302)
							(mid -0.402042 -0.402042)
							(end -0.3302 -0.4318)
						)
						(arc
							(start 0.3302 -0.4318)
							(mid 0.402042 -0.402042)
							(end 0.4318 -0.3302)
						)
						(arc
							(start 0.4318 0.3302)
							(mid 0.402042 0.402042)
							(end 0.3302 0.4318)
						)
					)
					(width 0)
					(fill yes)
				)
			)
		)
		(pad "2" smd custom
			(at 0 0.762 270)
			(size 0.2159 0.2159)
			(layers "B.Cu" "B.Mask" "B.Paste")
			(net "SSD_PWREN10_R")
			(options
				(clearance outline)
				(anchor circle)
			)
			(primitives
				(gr_poly
					(pts
						(arc
							(start -0.3302 0.4318)
							(mid -0.402042 0.402042)
							(end -0.4318 0.3302)
						)
						(arc
							(start -0.4318 -0.3302)
							(mid -0.402042 -0.402042)
							(end -0.3302 -0.4318)
						)
						(arc
							(start 0.3302 -0.4318)
							(mid 0.402042 -0.402042)
							(end 0.4318 -0.3302)
						)
						(arc
							(start 0.4318 0.3302)
							(mid 0.402042 0.402042)
							(end 0.3302 0.4318)
						)
					)
					(width 0)
					(fill yes)
				)
			)
		)
	)
	(footprint ""
		(layer "B.Cu")
		(at 41.656 -128.397 -90)
		(property "Reference" "C215"
			(at 0 0 90)
			(layer "B.SilkS")
			(hide yes)
			(effects
				(font
					(size 1.27 1.27)
				)
				(justify mirror)
			)
		)
		(property "Value" "SC1U10V2KX-4-GP"
			(at -1.1811 -2.7051 270)
			(unlocked yes)
			(layer "B.Fab")
			(hide yes)
			(effects
				(font
					(size 1.016 1.016)
					(thickness 0.1524)
				)
				(justify mirror)
			)
		)
		(property "Device Type" "C402H22"
			(at -1.1811 -4.2291 270)
			(unlocked yes)
			(layer "B.Fab")
			(hide yes)
			(effects
				(font
					(size 1.016 1.016)
					(thickness 0.1524)
				)
				(justify mirror)
			)
		)
		(duplicate_pad_numbers_are_jumpers no)
		(fp_rect
			(start 0.4318 0.9525)
			(end -0.4318 -0.9525)
			(stroke
				(width 0)
				(type default)
			)
			(fill no)
			(layer "B.CrtYd")
		)
		(fp_rect
			(start 0.4318 0.9525)
			(end -0.4318 -0.9525)
			(stroke
				(width 0)
				(type default)
			)
			(fill no)
			(layer "B.Fab")
		)
		(pad "1" smd custom
			(at 0 -0.4445 90)
			(size 0.1524 0.1524)
			(layers "B.Cu" "B.Mask" "B.Paste")
			(net "P3V3_STBY")
			(options
				(clearance outline)
				(anchor circle)
			)
			(primitives
				(gr_poly
					(pts
						(arc
							(start 0.3048 0.2032)
							(mid 0.275042 0.275042)
							(end 0.2032 0.3048)
						)
						(arc
							(start -0.2032 0.3048)
							(mid -0.275042 0.275042)
							(end -0.3048 0.2032)
						)
						(arc
							(start -0.3048 -0.2032)
							(mid -0.275042 -0.275042)
							(end -0.2032 -0.3048)
						)
						(arc
							(start 0.2032 -0.3048)
							(mid 0.275042 -0.275042)
							(end 0.3048 -0.2032)
						)
					)
					(width 0)
					(fill yes)
				)
			)
		)
		(pad "2" smd custom
			(at 0 0.4445 90)
			(size 0.1524 0.1524)
			(layers "B.Cu" "B.Mask" "B.Paste")
			(net "GND")
			(options
				(clearance outline)
				(anchor circle)
			)
			(primitives
				(gr_poly
					(pts
						(arc
							(start 0.3048 0.2032)
							(mid 0.275042 0.275042)
							(end 0.2032 0.3048)
						)
						(arc
							(start -0.2032 0.3048)
							(mid -0.275042 0.275042)
							(end -0.3048 0.2032)
						)
						(arc
							(start -0.3048 -0.2032)
							(mid -0.275042 -0.275042)
							(end -0.2032 -0.3048)
						)
						(arc
							(start 0.2032 -0.3048)
							(mid 0.275042 -0.275042)
							(end 0.3048 -0.2032)
						)
					)
					(width 0)
					(fill yes)
				)
			)
		)
	)
	(footprint ""
		(layer "B.Cu")
		(at 42.824146 -133.914134)
		(property "Reference" "TP159"
			(at 0 0 0)
			(layer "B.SilkS")
			(hide yes)
			(effects
				(font
					(size 1.27 1.27)
				)
				(justify mirror)
			)
		)
		(property "Value" "TPAD28-2-GP"
			(at 0.0127 -1.6637 0)
			(unlocked yes)
			(layer "B.Fab")
			(hide yes)
			(effects
				(font
					(size 1.016 1.016)
					(thickness 0.1524)
				)
				(justify mirror)
			)
		)
		(property "Device Type" "TPAD28"
			(at 0.0127 -3.1877 0)
			(unlocked yes)
			(layer "B.Fab")
			(hide yes)
			(effects
				(font
					(size 1.016 1.016)
					(thickness 0.1524)
				)
				(justify mirror)
			)
		)
		(duplicate_pad_numbers_are_jumpers no)
		(fp_poly
			(pts
				(arc
					(start 0.3556 0)
					(mid -0.3556 0)
					(end 0.3556 0)
				)
			)
			(stroke
				(width 0)
				(type default)
			)
			(fill no)
			(layer "B.CrtYd")
		)
		(fp_poly
			(pts
				(arc
					(start 0.6096 0)
					(mid -0.6096 0)
					(end 0.6096 0)
				)
			)
			(stroke
				(width 0)
				(type default)
			)
			(fill no)
			(layer "B.Fab")
		)
		(pad "1" smd circle
			(at 0 0 180)
			(size 0.7112 0.7112)
			(layers "B.Cu" "B.Mask" "B.Paste")
			(net "TP_BMC_GPIOJ4")
		)
	)
	(footprint ""
		(layer "B.Cu")
		(at 345.186 -71.501 180)
		(property "Reference" "PR163"
			(at 0 0 0)
			(layer "B.SilkS")
			(hide yes)
			(effects
				(font
					(size 1.27 1.27)
				)
				(justify mirror)
			)
		)
		(property "Value" "100KR2F-L1-GP"
			(at -0.064008 -3.993896 180)
			(unlocked yes)
			(layer "B.Fab")
			(hide yes)
			(effects
				(font
					(size 1.016 1.016)
					(thickness 0.1524)
				)
				(justify mirror)
			)
		)
		(property "Device Type" "R402H16"
			(at -0.064008 -5.517896 180)
			(unlocked yes)
			(layer "B.Fab")
			(hide yes)
			(effects
				(font
					(size 1.016 1.016)
					(thickness 0.1524)
				)
				(justify mirror)
			)
		)
		(duplicate_pad_numbers_are_jumpers no)
		(fp_line
			(start 0.508 -0.9398)
			(end 0.508 0.9398)
			(stroke
				(width 0.1524)
				(type default)
			)
			(layer "B.SilkS")
		)
		(fp_line
			(start -0.508 -0.9398)
			(end 0.508 -0.9398)
			(stroke
				(width 0.1524)
				(type default)
			)
			(layer "B.SilkS")
		)
		(fp_rect
			(start 0.508 0.9398)
			(end -0.508 -0.9398)
			(stroke
				(width 0)
				(type default)
			)
			(fill no)
			(layer "B.CrtYd")
		)
		(fp_rect
			(start 0.508 0.9398)
			(end -0.508 -0.9398)
			(stroke
				(width 0)
				(type default)
			)
			(fill no)
			(layer "B.Fab")
		)
		(pad "1" smd custom
			(at 0 -0.4445)
			(size 0.1397 0.1397)
			(layers "B.Cu" "B.Mask" "B.Paste")
			(net "P0V9_E_MODE")
			(options
				(clearance outline)
				(anchor circle)
			)
			(primitives
				(gr_poly
					(pts
						(arc
							(start -0.1778 0.2794)
							(mid -0.249642 0.249642)
							(end -0.2794 0.1778)
						)
						(arc
							(start -0.2794 -0.1778)
							(mid -0.249642 -0.249642)
							(end -0.1778 -0.2794)
						)
						(arc
							(start 0.1778 -0.2794)
							(mid 0.249642 -0.249642)
							(end 0.2794 -0.1778)
						)
						(arc
							(start 0.2794 0.1778)
							(mid 0.249642 0.249642)
							(end 0.1778 0.2794)
						)
					)
					(width 0)
					(fill yes)
				)
			)
		)
		(pad "2" smd custom
			(at 0 0.4445)
			(size 0.1397 0.1397)
			(layers "B.Cu" "B.Mask" "B.Paste")
			(net "AGND_P0V9_E")
			(options
				(clearance outline)
				(anchor circle)
			)
			(primitives
				(gr_poly
					(pts
						(arc
							(start -0.1778 0.2794)
							(mid -0.249642 0.249642)
							(end -0.2794 0.1778)
						)
						(arc
							(start -0.2794 -0.1778)
							(mid -0.249642 -0.249642)
							(end -0.1778 -0.2794)
						)
						(arc
							(start 0.1778 -0.2794)
							(mid 0.249642 -0.249642)
							(end 0.2794 -0.1778)
						)
						(arc
							(start 0.2794 0.1778)
							(mid 0.249642 0.249642)
							(end 0.1778 0.2794)
						)
					)
					(width 0)
					(fill yes)
				)
			)
		)
	)
	(footprint ""
		(layer "B.Cu")
		(at 23.796498 -127.021336 90)
		(property "Reference" "R360"
			(at 0 0 90)
			(layer "B.SilkS")
			(hide yes)
			(effects
				(font
					(size 1.27 1.27)
				)
				(justify mirror)
			)
		)
		(property "Value" "3K3R2F-2-GP"
			(at -0.064008 -3.993896 90)
			(unlocked yes)
			(layer "B.Fab")
			(hide yes)
			(effects
				(font
					(size 1.016 1.016)
					(thickness 0.1524)
				)
				(justify mirror)
			)
		)
		(property "Device Type" "R402H16"
			(at -0.064008 -5.517896 90)
			(unlocked yes)
			(layer "B.Fab")
			(hide yes)
			(effects
				(font
					(size 1.016 1.016)
					(thickness 0.1524)
				)
				(justify mirror)
			)
		)
		(duplicate_pad_numbers_are_jumpers no)
		(fp_line
			(start 0.508 -0.9398)
			(end 0.508 0.9398)
			(stroke
				(width 0.1524)
				(type default)
			)
			(layer "B.SilkS")
		)
		(fp_line
			(start -0.508 -0.9398)
			(end 0.508 -0.9398)
			(stroke
				(width 0.1524)
				(type default)
			)
			(layer "B.SilkS")
		)
		(fp_rect
			(start 0.508 0.9398)
			(end -0.508 -0.9398)
			(stroke
				(width 0)
				(type default)
			)
			(fill no)
			(layer "B.CrtYd")
		)
		(fp_rect
			(start 0.508 0.9398)
			(end -0.508 -0.9398)
			(stroke
				(width 0)
				(type default)
			)
			(fill no)
			(layer "B.Fab")
		)
		(pad "1" smd custom
			(at 0 -0.4445 270)
			(size 0.1397 0.1397)
			(layers "B.Cu" "B.Mask" "B.Paste")
			(net "P3V3_STBY")
			(options
				(clearance outline)
				(anchor circle)
			)
			(primitives
				(gr_poly
					(pts
						(arc
							(start -0.1778 0.2794)
							(mid -0.249642 0.249642)
							(end -0.2794 0.1778)
						)
						(arc
							(start -0.2794 -0.1778)
							(mid -0.249642 -0.249642)
							(end -0.1778 -0.2794)
						)
						(arc
							(start 0.1778 -0.2794)
							(mid 0.249642 -0.249642)
							(end 0.2794 -0.1778)
						)
						(arc
							(start 0.2794 0.1778)
							(mid 0.249642 0.249642)
							(end 0.1778 0.2794)
						)
					)
					(width 0)
					(fill yes)
				)
			)
		)
		(pad "2" smd custom
			(at 0 0.4445 270)
			(size 0.1397 0.1397)
			(layers "B.Cu" "B.Mask" "B.Paste")
			(net "ROMA13")
			(options
				(clearance outline)
				(anchor circle)
			)
			(primitives
				(gr_poly
					(pts
						(arc
							(start -0.1778 0.2794)
							(mid -0.249642 0.249642)
							(end -0.2794 0.1778)
						)
						(arc
							(start -0.2794 -0.1778)
							(mid -0.249642 -0.249642)
							(end -0.1778 -0.2794)
						)
						(arc
							(start 0.1778 -0.2794)
							(mid 0.249642 -0.249642)
							(end 0.2794 -0.1778)
						)
						(arc
							(start 0.2794 0.1778)
							(mid 0.249642 0.249642)
							(end 0.1778 0.2794)
						)
					)
					(width 0)
					(fill yes)
				)
			)
		)
	)
	(footprint ""
		(layer "B.Cu")
		(at 140.58392 -34.934652 90)
		(property "Reference" "C227"
			(at 0 0 90)
			(layer "B.SilkS")
			(hide yes)
			(effects
				(font
					(size 1.27 1.27)
				)
				(justify mirror)
			)
		)
		(property "Value" "SCD1U10V2KX-5GP"
			(at -1.1811 -2.7051 90)
			(unlocked yes)
			(layer "B.Fab")
			(hide yes)
			(effects
				(font
					(size 1.016 1.016)
					(thickness 0.1524)
				)
				(justify mirror)
			)
		)
		(property "Device Type" "C402H22"
			(at -1.1811 -4.2291 90)
			(unlocked yes)
			(layer "B.Fab")
			(hide yes)
			(effects
				(font
					(size 1.016 1.016)
					(thickness 0.1524)
				)
				(justify mirror)
			)
		)
		(duplicate_pad_numbers_are_jumpers no)
		(fp_rect
			(start 0.4318 0.9525)
			(end -0.4318 -0.9525)
			(stroke
				(width 0)
				(type default)
			)
			(fill no)
			(layer "B.CrtYd")
		)
		(fp_rect
			(start 0.4318 0.9525)
			(end -0.4318 -0.9525)
			(stroke
				(width 0)
				(type default)
			)
			(fill no)
			(layer "B.Fab")
		)
		(pad "1" smd custom
			(at 0 -0.4445 270)
			(size 0.1524 0.1524)
			(layers "B.Cu" "B.Mask" "B.Paste")
			(net "GND")
			(options
				(clearance outline)
				(anchor circle)
			)
			(primitives
				(gr_poly
					(pts
						(arc
							(start 0.3048 0.2032)
							(mid 0.275042 0.275042)
							(end 0.2032 0.3048)
						)
						(arc
							(start -0.2032 0.3048)
							(mid -0.275042 0.275042)
							(end -0.3048 0.2032)
						)
						(arc
							(start -0.3048 -0.2032)
							(mid -0.275042 -0.275042)
							(end -0.2032 -0.3048)
						)
						(arc
							(start 0.2032 -0.3048)
							(mid 0.275042 -0.275042)
							(end 0.3048 -0.2032)
						)
					)
					(width 0)
					(fill yes)
				)
			)
		)
		(pad "2" smd custom
			(at 0 0.4445 270)
			(size 0.1524 0.1524)
			(layers "B.Cu" "B.Mask" "B.Paste")
			(net "P3V3_STBY")
			(options
				(clearance outline)
				(anchor circle)
			)
			(primitives
				(gr_poly
					(pts
						(arc
							(start 0.3048 0.2032)
							(mid 0.275042 0.275042)
							(end 0.2032 0.3048)
						)
						(arc
							(start -0.2032 0.3048)
							(mid -0.275042 0.275042)
							(end -0.3048 0.2032)
						)
						(arc
							(start -0.3048 -0.2032)
							(mid -0.275042 -0.275042)
							(end -0.2032 -0.3048)
						)
						(arc
							(start 0.2032 -0.3048)
							(mid 0.275042 -0.275042)
							(end 0.3048 -0.2032)
						)
					)
					(width 0)
					(fill yes)
				)
			)
		)
	)
	(footprint ""
		(layer "B.Cu")
		(at 9.1186 -70.739 -90)
		(property "Reference" "C624"
			(at 0 0 90)
			(layer "B.SilkS")
			(hide yes)
			(effects
				(font
					(size 1.27 1.27)
				)
				(justify mirror)
			)
		)
		(property "Value" "SC10U6D3V5KX-4GP"
			(at 0.0762 -6.1214 270)
			(unlocked yes)
			(layer "B.Fab")
			(hide yes)
			(effects
				(font
					(size 1.016 1.016)
					(thickness 0.1524)
				)
				(justify mirror)
			)
		)
		(property "Device Type" "C805H58"
			(at 0.0762 -8.1534 270)
			(unlocked yes)
			(layer "B.Fab")
			(hide yes)
			(effects
				(font
					(size 1.016 1.016)
					(thickness 0.1524)
				)
				(justify mirror)
			)
		)
		(duplicate_pad_numbers_are_jumpers no)
		(fp_line
			(start -0.635 0)
			(end 0.635 0)
			(stroke
				(width 0.508)
				(type default)
			)
			(layer "B.SilkS")
		)
		(fp_rect
			(start 0.9652 1.778)
			(end -0.9652 -1.778)
			(stroke
				(width 0)
				(type default)
			)
			(fill no)
			(layer "B.CrtYd")
		)
		(fp_poly
			(pts
				(xy 0.9652 -1.778) (xy -0.9652 -1.778) (xy -0.9652 1.778) (xy 0.9652 1.778)
			)
			(stroke
				(width 0)
				(type default)
			)
			(fill no)
			(layer "B.Fab")
		)
		(pad "1" smd rect
			(at 0 -0.9652 90)
			(size 1.397 1.143)
			(layers "B.Cu" "B.Mask" "B.Paste")
			(net "P1V5_I210")
		)
		(pad "2" smd rect
			(at 0 0.9652 90)
			(size 1.397 1.143)
			(layers "B.Cu" "B.Mask" "B.Paste")
			(net "GND")
		)
	)
	(footprint ""
		(layer "B.Cu")
		(at 247.599962 -39.99992)
		(property "Reference" "TP289"
			(at 0 0 0)
			(layer "B.SilkS")
			(hide yes)
			(effects
				(font
					(size 1.27 1.27)
				)
				(justify mirror)
			)
		)
		(property "Value" "TPAD28-2-GP"
			(at 0.0127 -1.6637 0)
			(unlocked yes)
			(layer "B.Fab")
			(hide yes)
			(effects
				(font
					(size 1.016 1.016)
					(thickness 0.1524)
				)
				(justify mirror)
			)
		)
		(property "Device Type" "TPAD28"
			(at 0.0127 -3.1877 0)
			(unlocked yes)
			(layer "B.Fab")
			(hide yes)
			(effects
				(font
					(size 1.016 1.016)
					(thickness 0.1524)
				)
				(justify mirror)
			)
		)
		(duplicate_pad_numbers_are_jumpers no)
		(fp_poly
			(pts
				(arc
					(start 0.3556 0)
					(mid -0.3556 0)
					(end 0.3556 0)
				)
			)
			(stroke
				(width 0)
				(type default)
			)
			(fill no)
			(layer "B.CrtYd")
		)
		(fp_poly
			(pts
				(arc
					(start 0.6096 0)
					(mid -0.6096 0)
					(end 0.6096 0)
				)
			)
			(stroke
				(width 0)
				(type default)
			)
			(fill no)
			(layer "B.Fab")
		)
		(pad "1" smd circle
			(at 0 0 180)
			(size 0.7112 0.7112)
			(layers "B.Cu" "B.Mask" "B.Paste")
			(net "TWI_SCL6")
		)
	)
	(footprint ""
		(layer "B.Cu")
		(at 245.599966 -33.999932)
		(property "Reference" "TP283"
			(at 0 0 0)
			(layer "B.SilkS")
			(hide yes)
			(effects
				(font
					(size 1.27 1.27)
				)
				(justify mirror)
			)
		)
		(property "Value" "TPAD28-2-GP"
			(at 0.0127 -1.6637 0)
			(unlocked yes)
			(layer "B.Fab")
			(hide yes)
			(effects
				(font
					(size 1.016 1.016)
					(thickness 0.1524)
				)
				(justify mirror)
			)
		)
		(property "Device Type" "TPAD28"
			(at 0.0127 -3.1877 0)
			(unlocked yes)
			(layer "B.Fab")
			(hide yes)
			(effects
				(font
					(size 1.016 1.016)
					(thickness 0.1524)
				)
				(justify mirror)
			)
		)
		(duplicate_pad_numbers_are_jumpers no)
		(fp_poly
			(pts
				(arc
					(start 0.3556 0)
					(mid -0.3556 0)
					(end 0.3556 0)
				)
			)
			(stroke
				(width 0)
				(type default)
			)
			(fill no)
			(layer "B.CrtYd")
		)
		(fp_poly
			(pts
				(arc
					(start 0.6096 0)
					(mid -0.6096 0)
					(end 0.6096 0)
				)
			)
			(stroke
				(width 0)
				(type default)
			)
			(fill no)
			(layer "B.Fab")
		)
		(pad "1" smd circle
			(at 0 0 180)
			(size 0.7112 0.7112)
			(layers "B.Cu" "B.Mask" "B.Paste")
			(net "TWI_SRST#4")
		)
	)
	(footprint ""
		(layer "B.Cu")
		(at 122.1232 -203.835)
		(property "Reference" "R147"
			(at 0 0 0)
			(layer "B.SilkS")
			(hide yes)
			(effects
				(font
					(size 1.27 1.27)
				)
				(justify mirror)
			)
		)
		(property "Value" "4K7R2F-GP"
			(at -0.064008 -3.993896 0)
			(unlocked yes)
			(layer "B.Fab")
			(hide yes)
			(effects
				(font
					(size 1.016 1.016)
					(thickness 0.1524)
				)
				(justify mirror)
			)
		)
		(property "Device Type" "R402H16"
			(at -0.064008 -5.517896 0)
			(unlocked yes)
			(layer "B.Fab")
			(hide yes)
			(effects
				(font
					(size 1.016 1.016)
					(thickness 0.1524)
				)
				(justify mirror)
			)
		)
		(duplicate_pad_numbers_are_jumpers no)
		(fp_line
			(start -0.508 -0.9398)
			(end 0.508 -0.9398)
			(stroke
				(width 0.1524)
				(type default)
			)
			(layer "B.SilkS")
		)
		(fp_line
			(start 0.508 -0.9398)
			(end 0.508 0.9398)
			(stroke
				(width 0.1524)
				(type default)
			)
			(layer "B.SilkS")
		)
		(fp_rect
			(start 0.508 0.9398)
			(end -0.508 -0.9398)
			(stroke
				(width 0)
				(type default)
			)
			(fill no)
			(layer "B.CrtYd")
		)
		(fp_rect
			(start 0.508 0.9398)
			(end -0.508 -0.9398)
			(stroke
				(width 0)
				(type default)
			)
			(fill no)
			(layer "B.Fab")
		)
		(pad "1" smd custom
			(at 0 -0.4445 180)
			(size 0.1397 0.1397)
			(layers "B.Cu" "B.Mask" "B.Paste")
			(net "BMC_SSD_RST#0_A7")
			(options
				(clearance outline)
				(anchor circle)
			)
			(primitives
				(gr_poly
					(pts
						(arc
							(start -0.1778 0.2794)
							(mid -0.249642 0.249642)
							(end -0.2794 0.1778)
						)
						(arc
							(start -0.2794 -0.1778)
							(mid -0.249642 -0.249642)
							(end -0.1778 -0.2794)
						)
						(arc
							(start 0.1778 -0.2794)
							(mid 0.249642 -0.249642)
							(end 0.2794 -0.1778)
						)
						(arc
							(start 0.2794 0.1778)
							(mid 0.249642 0.249642)
							(end 0.1778 0.2794)
						)
					)
					(width 0)
					(fill yes)
				)
			)
		)
		(pad "2" smd custom
			(at 0 0.4445 180)
			(size 0.1397 0.1397)
			(layers "B.Cu" "B.Mask" "B.Paste")
			(net "P3V3_STBY")
			(options
				(clearance outline)
				(anchor circle)
			)
			(primitives
				(gr_poly
					(pts
						(arc
							(start -0.1778 0.2794)
							(mid -0.249642 0.249642)
							(end -0.2794 0.1778)
						)
						(arc
							(start -0.2794 -0.1778)
							(mid -0.249642 -0.249642)
							(end -0.1778 -0.2794)
						)
						(arc
							(start 0.1778 -0.2794)
							(mid 0.249642 -0.249642)
							(end 0.2794 -0.1778)
						)
						(arc
							(start 0.2794 0.1778)
							(mid 0.249642 0.249642)
							(end 0.1778 0.2794)
						)
					)
					(width 0)
					(fill yes)
				)
			)
		)
	)
	(footprint ""
		(layer "B.Cu")
		(at 249.8344 -35.0012 90)
		(property "Reference" "C487"
			(at 0 0 90)
			(layer "B.SilkS")
			(hide yes)
			(effects
				(font
					(size 1.27 1.27)
				)
				(justify mirror)
			)
		)
		(property "Value" "SCD1U16V1KX-1-GP"
			(at 2.8321 -1.7399 90)
			(unlocked yes)
			(layer "B.Fab")
			(hide yes)
			(effects
				(font
					(size 1.016 1.016)
					(thickness 0.1524)
				)
				(justify mirror)
			)
		)
		(property "Device Type" "C0201H13"
			(at 2.8321 -3.2639 90)
			(unlocked yes)
			(layer "B.Fab")
			(hide yes)
			(effects
				(font
					(size 1.016 1.016)
					(thickness 0.1524)
				)
				(justify mirror)
			)
		)
		(duplicate_pad_numbers_are_jumpers no)
		(fp_rect
			(start 0.2794 0.6477)
			(end -0.2794 -0.6477)
			(stroke
				(width 0)
				(type default)
			)
			(fill no)
			(layer "B.CrtYd")
		)
		(fp_rect
			(start 0.2794 0.6477)
			(end -0.2794 -0.6477)
			(stroke
				(width 0)
				(type default)
			)
			(fill no)
			(layer "B.Fab")
		)
		(pad "1" smd custom
			(at 0 -0.2794 270)
			(size 0.0762 0.0762)
			(layers "B.Cu" "B.Mask" "B.Paste")
			(net "DUT_VDDO")
			(options
				(clearance outline)
				(anchor circle)
			)
			(primitives
				(gr_poly
					(pts
						(arc
							(start 0.1524 0.127)
							(mid 0.137521 0.162921)
							(end 0.1016 0.1778)
						)
						(arc
							(start -0.1016 0.1778)
							(mid -0.137521 0.162921)
							(end -0.1524 0.127)
						)
						(arc
							(start -0.1524 -0.127)
							(mid -0.137521 -0.162921)
							(end -0.1016 -0.1778)
						)
						(arc
							(start 0.1016 -0.1778)
							(mid 0.137521 -0.162921)
							(end 0.1524 -0.127)
						)
					)
					(width 0)
					(fill yes)
				)
			)
		)
		(pad "2" smd custom
			(at 0 0.2794 270)
			(size 0.0762 0.0762)
			(layers "B.Cu" "B.Mask" "B.Paste")
			(net "GND")
			(options
				(clearance outline)
				(anchor circle)
			)
			(primitives
				(gr_poly
					(pts
						(arc
							(start 0.1524 0.127)
							(mid 0.137521 0.162921)
							(end 0.1016 0.1778)
						)
						(arc
							(start -0.1016 0.1778)
							(mid -0.137521 0.162921)
							(end -0.1524 0.127)
						)
						(arc
							(start -0.1524 -0.127)
							(mid -0.137521 -0.162921)
							(end -0.1016 -0.1778)
						)
						(arc
							(start 0.1016 -0.1778)
							(mid 0.137521 -0.162921)
							(end 0.1524 -0.127)
						)
					)
					(width 0)
					(fill yes)
				)
			)
		)
	)
	(footprint ""
		(layer "B.Cu")
		(at 243.586 -57.995058 90)
		(property "Reference" "C511"
			(at 0 0 90)
			(layer "B.SilkS")
			(hide yes)
			(effects
				(font
					(size 1.27 1.27)
				)
				(justify mirror)
			)
		)
		(property "Value" "SCD1U16V1KX-1-GP"
			(at 2.8321 -1.7399 90)
			(unlocked yes)
			(layer "B.Fab")
			(hide yes)
			(effects
				(font
					(size 1.016 1.016)
					(thickness 0.1524)
				)
				(justify mirror)
			)
		)
		(property "Device Type" "C0201H13"
			(at 2.8321 -3.2639 90)
			(unlocked yes)
			(layer "B.Fab")
			(hide yes)
			(effects
				(font
					(size 1.016 1.016)
					(thickness 0.1524)
				)
				(justify mirror)
			)
		)
		(duplicate_pad_numbers_are_jumpers no)
		(fp_rect
			(start 0.2794 0.6477)
			(end -0.2794 -0.6477)
			(stroke
				(width 0)
				(type default)
			)
			(fill no)
			(layer "B.CrtYd")
		)
		(fp_rect
			(start 0.2794 0.6477)
			(end -0.2794 -0.6477)
			(stroke
				(width 0)
				(type default)
			)
			(fill no)
			(layer "B.Fab")
		)
		(pad "1" smd custom
			(at 0 -0.2794 270)
			(size 0.0762 0.0762)
			(layers "B.Cu" "B.Mask" "B.Paste")
			(net "DUT_AVD_TX")
			(options
				(clearance outline)
				(anchor circle)
			)
			(primitives
				(gr_poly
					(pts
						(arc
							(start 0.1524 0.127)
							(mid 0.137521 0.162921)
							(end 0.1016 0.1778)
						)
						(arc
							(start -0.1016 0.1778)
							(mid -0.137521 0.162921)
							(end -0.1524 0.127)
						)
						(arc
							(start -0.1524 -0.127)
							(mid -0.137521 -0.162921)
							(end -0.1016 -0.1778)
						)
						(arc
							(start 0.1016 -0.1778)
							(mid 0.137521 -0.162921)
							(end 0.1524 -0.127)
						)
					)
					(width 0)
					(fill yes)
				)
			)
		)
		(pad "2" smd custom
			(at 0 0.2794 270)
			(size 0.0762 0.0762)
			(layers "B.Cu" "B.Mask" "B.Paste")
			(net "GND")
			(options
				(clearance outline)
				(anchor circle)
			)
			(primitives
				(gr_poly
					(pts
						(arc
							(start 0.1524 0.127)
							(mid 0.137521 0.162921)
							(end 0.1016 0.1778)
						)
						(arc
							(start -0.1016 0.1778)
							(mid -0.137521 0.162921)
							(end -0.1524 0.127)
						)
						(arc
							(start -0.1524 -0.127)
							(mid -0.137521 -0.162921)
							(end -0.1016 -0.1778)
						)
						(arc
							(start 0.1016 -0.1778)
							(mid 0.137521 -0.162921)
							(end 0.1524 -0.127)
						)
					)
					(width 0)
					(fill yes)
				)
			)
		)
	)
	(footprint ""
		(layer "B.Cu")
		(at 151.649176 -33.545272 180)
		(property "Reference" "C229"
			(at 0 0 0)
			(layer "B.SilkS")
			(hide yes)
			(effects
				(font
					(size 1.27 1.27)
				)
				(justify mirror)
			)
		)
		(property "Value" "SCD1U10V2KX-5GP"
			(at -1.1811 -2.7051 180)
			(unlocked yes)
			(layer "B.Fab")
			(hide yes)
			(effects
				(font
					(size 1.016 1.016)
					(thickness 0.1524)
				)
				(justify mirror)
			)
		)
		(property "Device Type" "C402H22"
			(at -1.1811 -4.2291 180)
			(unlocked yes)
			(layer "B.Fab")
			(hide yes)
			(effects
				(font
					(size 1.016 1.016)
					(thickness 0.1524)
				)
				(justify mirror)
			)
		)
		(duplicate_pad_numbers_are_jumpers no)
		(fp_rect
			(start 0.4318 0.9525)
			(end -0.4318 -0.9525)
			(stroke
				(width 0)
				(type default)
			)
			(fill no)
			(layer "B.CrtYd")
		)
		(fp_rect
			(start 0.4318 0.9525)
			(end -0.4318 -0.9525)
			(stroke
				(width 0)
				(type default)
			)
			(fill no)
			(layer "B.Fab")
		)
		(pad "1" smd custom
			(at 0 -0.4445)
			(size 0.1524 0.1524)
			(layers "B.Cu" "B.Mask" "B.Paste")
			(net "GND")
			(options
				(clearance outline)
				(anchor circle)
			)
			(primitives
				(gr_poly
					(pts
						(arc
							(start 0.3048 0.2032)
							(mid 0.275042 0.275042)
							(end 0.2032 0.3048)
						)
						(arc
							(start -0.2032 0.3048)
							(mid -0.275042 0.275042)
							(end -0.3048 0.2032)
						)
						(arc
							(start -0.3048 -0.2032)
							(mid -0.275042 -0.275042)
							(end -0.2032 -0.3048)
						)
						(arc
							(start 0.2032 -0.3048)
							(mid 0.275042 -0.275042)
							(end 0.3048 -0.2032)
						)
					)
					(width 0)
					(fill yes)
				)
			)
		)
		(pad "2" smd custom
			(at 0 0.4445)
			(size 0.1524 0.1524)
			(layers "B.Cu" "B.Mask" "B.Paste")
			(net "P3V3_STBY")
			(options
				(clearance outline)
				(anchor circle)
			)
			(primitives
				(gr_poly
					(pts
						(arc
							(start 0.3048 0.2032)
							(mid 0.275042 0.275042)
							(end 0.2032 0.3048)
						)
						(arc
							(start -0.2032 0.3048)
							(mid -0.275042 0.275042)
							(end -0.3048 0.2032)
						)
						(arc
							(start -0.3048 -0.2032)
							(mid -0.275042 -0.275042)
							(end -0.2032 -0.3048)
						)
						(arc
							(start 0.2032 -0.3048)
							(mid 0.275042 -0.275042)
							(end 0.3048 -0.2032)
						)
					)
					(width 0)
					(fill yes)
				)
			)
		)
	)
	(footprint ""
		(layer "B.Cu")
		(at 342.1126 -175.7426)
		(property "Reference" "R3245"
			(at 0 0 0)
			(layer "B.SilkS")
			(hide yes)
			(effects
				(font
					(size 1.27 1.27)
				)
				(justify mirror)
			)
		)
		(property "Value" "0R2J-2-GP"
			(at -0.064008 -3.993896 0)
			(unlocked yes)
			(layer "B.Fab")
			(hide yes)
			(effects
				(font
					(size 1.016 1.016)
					(thickness 0.1524)
				)
				(justify mirror)
			)
		)
		(property "Device Type" "R402H16"
			(at -0.064008 -5.517896 0)
			(unlocked yes)
			(layer "B.Fab")
			(hide yes)
			(effects
				(font
					(size 1.016 1.016)
					(thickness 0.1524)
				)
				(justify mirror)
			)
		)
		(duplicate_pad_numbers_are_jumpers no)
		(fp_line
			(start -0.508 -0.9398)
			(end 0.508 -0.9398)
			(stroke
				(width 0.1524)
				(type default)
			)
			(layer "B.SilkS")
		)
		(fp_line
			(start 0.508 -0.9398)
			(end 0.508 0.9398)
			(stroke
				(width 0.1524)
				(type default)
			)
			(layer "B.SilkS")
		)
		(fp_rect
			(start 0.508 0.9398)
			(end -0.508 -0.9398)
			(stroke
				(width 0)
				(type default)
			)
			(fill no)
			(layer "B.CrtYd")
		)
		(fp_rect
			(start 0.508 0.9398)
			(end -0.508 -0.9398)
			(stroke
				(width 0)
				(type default)
			)
			(fill no)
			(layer "B.Fab")
		)
		(pad "1" smd custom
			(at 0 -0.4445 180)
			(size 0.1397 0.1397)
			(layers "B.Cu" "B.Mask" "B.Paste")
			(net "SSD_PERST_Y14")
			(options
				(clearance outline)
				(anchor circle)
			)
			(primitives
				(gr_poly
					(pts
						(arc
							(start -0.1778 0.2794)
							(mid -0.249642 0.249642)
							(end -0.2794 0.1778)
						)
						(arc
							(start -0.2794 -0.1778)
							(mid -0.249642 -0.249642)
							(end -0.1778 -0.2794)
						)
						(arc
							(start 0.1778 -0.2794)
							(mid 0.249642 -0.249642)
							(end 0.2794 -0.1778)
						)
						(arc
							(start 0.2794 0.1778)
							(mid 0.249642 0.249642)
							(end 0.1778 0.2794)
						)
					)
					(width 0)
					(fill yes)
				)
			)
		)
		(pad "2" smd custom
			(at 0 0.4445 180)
			(size 0.1397 0.1397)
			(layers "B.Cu" "B.Mask" "B.Paste")
			(net "SSD_PERST#14_R")
			(options
				(clearance outline)
				(anchor circle)
			)
			(primitives
				(gr_poly
					(pts
						(arc
							(start -0.1778 0.2794)
							(mid -0.249642 0.249642)
							(end -0.2794 0.1778)
						)
						(arc
							(start -0.2794 -0.1778)
							(mid -0.249642 -0.249642)
							(end -0.1778 -0.2794)
						)
						(arc
							(start 0.1778 -0.2794)
							(mid 0.249642 -0.249642)
							(end 0.2794 -0.1778)
						)
						(arc
							(start 0.2794 0.1778)
							(mid 0.249642 0.249642)
							(end 0.1778 0.2794)
						)
					)
					(width 0)
					(fill yes)
				)
			)
		)
	)
	(footprint ""
		(layer "B.Cu")
		(at 37.1221 -114.55146 180)
		(property "Reference" "R464"
			(at 0 0 0)
			(layer "B.SilkS")
			(hide yes)
			(effects
				(font
					(size 1.27 1.27)
				)
				(justify mirror)
			)
		)
		(property "Value" "0R2J-2-GP"
			(at -0.064008 -3.993896 180)
			(unlocked yes)
			(layer "B.Fab")
			(hide yes)
			(effects
				(font
					(size 1.016 1.016)
					(thickness 0.1524)
				)
				(justify mirror)
			)
		)
		(property "Device Type" "R402H16"
			(at -0.064008 -5.517896 180)
			(unlocked yes)
			(layer "B.Fab")
			(hide yes)
			(effects
				(font
					(size 1.016 1.016)
					(thickness 0.1524)
				)
				(justify mirror)
			)
		)
		(duplicate_pad_numbers_are_jumpers no)
		(fp_line
			(start 0.508 -0.9398)
			(end 0.508 0.9398)
			(stroke
				(width 0.1524)
				(type default)
			)
			(layer "B.SilkS")
		)
		(fp_line
			(start -0.508 -0.9398)
			(end 0.508 -0.9398)
			(stroke
				(width 0.1524)
				(type default)
			)
			(layer "B.SilkS")
		)
		(fp_rect
			(start 0.508 0.9398)
			(end -0.508 -0.9398)
			(stroke
				(width 0)
				(type default)
			)
			(fill no)
			(layer "B.CrtYd")
		)
		(fp_rect
			(start 0.508 0.9398)
			(end -0.508 -0.9398)
			(stroke
				(width 0)
				(type default)
			)
			(fill no)
			(layer "B.Fab")
		)
		(pad "1" smd custom
			(at 0 -0.4445)
			(size 0.1397 0.1397)
			(layers "B.Cu" "B.Mask" "B.Paste")
			(net "GND")
			(options
				(clearance outline)
				(anchor circle)
			)
			(primitives
				(gr_poly
					(pts
						(arc
							(start -0.1778 0.2794)
							(mid -0.249642 0.249642)
							(end -0.2794 0.1778)
						)
						(arc
							(start -0.2794 -0.1778)
							(mid -0.249642 -0.249642)
							(end -0.1778 -0.2794)
						)
						(arc
							(start 0.1778 -0.2794)
							(mid 0.249642 -0.249642)
							(end 0.2794 -0.1778)
						)
						(arc
							(start 0.2794 0.1778)
							(mid 0.249642 0.249642)
							(end 0.1778 0.2794)
						)
					)
					(width 0)
					(fill yes)
				)
			)
		)
		(pad "2" smd custom
			(at 0 0.4445)
			(size 0.1397 0.1397)
			(layers "B.Cu" "B.Mask" "B.Paste")
			(net "RMII_BMC_PHY_TXD0")
			(options
				(clearance outline)
				(anchor circle)
			)
			(primitives
				(gr_poly
					(pts
						(arc
							(start -0.1778 0.2794)
							(mid -0.249642 0.249642)
							(end -0.2794 0.1778)
						)
						(arc
							(start -0.2794 -0.1778)
							(mid -0.249642 -0.249642)
							(end -0.1778 -0.2794)
						)
						(arc
							(start 0.1778 -0.2794)
							(mid 0.249642 -0.249642)
							(end 0.2794 -0.1778)
						)
						(arc
							(start 0.2794 0.1778)
							(mid 0.249642 0.249642)
							(end 0.1778 0.2794)
						)
					)
					(width 0)
					(fill yes)
				)
			)
		)
	)
	(footprint ""
		(layer "B.Cu")
		(at 42.129456 -135.618982)
		(property "Reference" "TP191"
			(at 0 0 0)
			(layer "B.SilkS")
			(hide yes)
			(effects
				(font
					(size 1.27 1.27)
				)
				(justify mirror)
			)
		)
		(property "Value" "TPAD28-2-GP"
			(at 0.0127 -1.6637 0)
			(unlocked yes)
			(layer "B.Fab")
			(hide yes)
			(effects
				(font
					(size 1.016 1.016)
					(thickness 0.1524)
				)
				(justify mirror)
			)
		)
		(property "Device Type" "TPAD28"
			(at 0.0127 -3.1877 0)
			(unlocked yes)
			(layer "B.Fab")
			(hide yes)
			(effects
				(font
					(size 1.016 1.016)
					(thickness 0.1524)
				)
				(justify mirror)
			)
		)
		(duplicate_pad_numbers_are_jumpers no)
		(fp_poly
			(pts
				(arc
					(start 0.3556 0)
					(mid -0.3556 0)
					(end 0.3556 0)
				)
			)
			(stroke
				(width 0)
				(type default)
			)
			(fill no)
			(layer "B.CrtYd")
		)
		(fp_poly
			(pts
				(arc
					(start 0.6096 0)
					(mid -0.6096 0)
					(end 0.6096 0)
				)
			)
			(stroke
				(width 0)
				(type default)
			)
			(fill no)
			(layer "B.Fab")
		)
		(pad "1" smd circle
			(at 0 0 180)
			(size 0.7112 0.7112)
			(layers "B.Cu" "B.Mask" "B.Paste")
			(net "TP_GPIOO7")
		)
	)
	(footprint ""
		(layer "B.Cu")
		(at 72.39 -190.627)
		(property "Reference" "R143"
			(at 0 0 0)
			(layer "B.SilkS")
			(hide yes)
			(effects
				(font
					(size 1.27 1.27)
				)
				(justify mirror)
			)
		)
		(property "Value" "4K7R2F-GP"
			(at -0.064008 -3.993896 0)
			(unlocked yes)
			(layer "B.Fab")
			(hide yes)
			(effects
				(font
					(size 1.016 1.016)
					(thickness 0.1524)
				)
				(justify mirror)
			)
		)
		(property "Device Type" "R402H16"
			(at -0.064008 -5.517896 0)
			(unlocked yes)
			(layer "B.Fab")
			(hide yes)
			(effects
				(font
					(size 1.016 1.016)
					(thickness 0.1524)
				)
				(justify mirror)
			)
		)
		(duplicate_pad_numbers_are_jumpers no)
		(fp_line
			(start -0.508 -0.9398)
			(end 0.508 -0.9398)
			(stroke
				(width 0.1524)
				(type default)
			)
			(layer "B.SilkS")
		)
		(fp_line
			(start 0.508 -0.9398)
			(end 0.508 0.9398)
			(stroke
				(width 0.1524)
				(type default)
			)
			(layer "B.SilkS")
		)
		(fp_rect
			(start 0.508 0.9398)
			(end -0.508 -0.9398)
			(stroke
				(width 0)
				(type default)
			)
			(fill no)
			(layer "B.CrtYd")
		)
		(fp_rect
			(start 0.508 0.9398)
			(end -0.508 -0.9398)
			(stroke
				(width 0)
				(type default)
			)
			(fill no)
			(layer "B.Fab")
		)
		(pad "1" smd custom
			(at 0 -0.4445 180)
			(size 0.1397 0.1397)
			(layers "B.Cu" "B.Mask" "B.Paste")
			(net "BMC_SSD_RST#0_A0")
			(options
				(clearance outline)
				(anchor circle)
			)
			(primitives
				(gr_poly
					(pts
						(arc
							(start -0.1778 0.2794)
							(mid -0.249642 0.249642)
							(end -0.2794 0.1778)
						)
						(arc
							(start -0.2794 -0.1778)
							(mid -0.249642 -0.249642)
							(end -0.1778 -0.2794)
						)
						(arc
							(start 0.1778 -0.2794)
							(mid 0.249642 -0.249642)
							(end 0.2794 -0.1778)
						)
						(arc
							(start 0.2794 0.1778)
							(mid 0.249642 0.249642)
							(end 0.1778 0.2794)
						)
					)
					(width 0)
					(fill yes)
				)
			)
		)
		(pad "2" smd custom
			(at 0 0.4445 180)
			(size 0.1397 0.1397)
			(layers "B.Cu" "B.Mask" "B.Paste")
			(net "P3V3_STBY")
			(options
				(clearance outline)
				(anchor circle)
			)
			(primitives
				(gr_poly
					(pts
						(arc
							(start -0.1778 0.2794)
							(mid -0.249642 0.249642)
							(end -0.2794 0.1778)
						)
						(arc
							(start -0.2794 -0.1778)
							(mid -0.249642 -0.249642)
							(end -0.1778 -0.2794)
						)
						(arc
							(start 0.1778 -0.2794)
							(mid 0.249642 -0.249642)
							(end 0.2794 -0.1778)
						)
						(arc
							(start 0.2794 0.1778)
							(mid 0.249642 0.249642)
							(end 0.1778 0.2794)
						)
					)
					(width 0)
					(fill yes)
				)
			)
		)
	)
	(footprint ""
		(layer "B.Cu")
		(at 131.5212 -196.3928)
		(property "Reference" "R4125"
			(at 0 0 0)
			(layer "B.SilkS")
			(hide yes)
			(effects
				(font
					(size 1.27 1.27)
				)
				(justify mirror)
			)
		)
		(property "Value" "4K7R2F-GP"
			(at -0.064008 -3.993896 0)
			(unlocked yes)
			(layer "B.Fab")
			(hide yes)
			(effects
				(font
					(size 1.016 1.016)
					(thickness 0.1524)
				)
				(justify mirror)
			)
		)
		(property "Device Type" "R402H16"
			(at -0.064008 -5.517896 0)
			(unlocked yes)
			(layer "B.Fab")
			(hide yes)
			(effects
				(font
					(size 1.016 1.016)
					(thickness 0.1524)
				)
				(justify mirror)
			)
		)
		(duplicate_pad_numbers_are_jumpers no)
		(fp_line
			(start -0.508 -0.9398)
			(end 0.508 -0.9398)
			(stroke
				(width 0.1524)
				(type default)
			)
			(layer "B.SilkS")
		)
		(fp_line
			(start 0.508 -0.9398)
			(end 0.508 0.9398)
			(stroke
				(width 0.1524)
				(type default)
			)
			(layer "B.SilkS")
		)
		(fp_rect
			(start 0.508 0.9398)
			(end -0.508 -0.9398)
			(stroke
				(width 0)
				(type default)
			)
			(fill no)
			(layer "B.CrtYd")
		)
		(fp_rect
			(start 0.508 0.9398)
			(end -0.508 -0.9398)
			(stroke
				(width 0)
				(type default)
			)
			(fill no)
			(layer "B.Fab")
		)
		(pad "1" smd custom
			(at 0 -0.4445 180)
			(size 0.1397 0.1397)
			(layers "B.Cu" "B.Mask" "B.Paste")
			(net "SSD_PRSNT#2")
			(options
				(clearance outline)
				(anchor circle)
			)
			(primitives
				(gr_poly
					(pts
						(arc
							(start -0.1778 0.2794)
							(mid -0.249642 0.249642)
							(end -0.2794 0.1778)
						)
						(arc
							(start -0.2794 -0.1778)
							(mid -0.249642 -0.249642)
							(end -0.1778 -0.2794)
						)
						(arc
							(start 0.1778 -0.2794)
							(mid 0.249642 -0.249642)
							(end 0.2794 -0.1778)
						)
						(arc
							(start 0.2794 0.1778)
							(mid 0.249642 0.249642)
							(end 0.1778 0.2794)
						)
					)
					(width 0)
					(fill yes)
				)
			)
		)
		(pad "2" smd custom
			(at 0 0.4445 180)
			(size 0.1397 0.1397)
			(layers "B.Cu" "B.Mask" "B.Paste")
			(net "P3V3_STBY")
			(options
				(clearance outline)
				(anchor circle)
			)
			(primitives
				(gr_poly
					(pts
						(arc
							(start -0.1778 0.2794)
							(mid -0.249642 0.249642)
							(end -0.2794 0.1778)
						)
						(arc
							(start -0.2794 -0.1778)
							(mid -0.249642 -0.249642)
							(end -0.1778 -0.2794)
						)
						(arc
							(start 0.1778 -0.2794)
							(mid 0.249642 -0.249642)
							(end 0.2794 -0.1778)
						)
						(arc
							(start 0.2794 0.1778)
							(mid 0.249642 0.249642)
							(end 0.1778 0.2794)
						)
					)
					(width 0)
					(fill yes)
				)
			)
		)
	)
	(footprint ""
		(layer "B.Cu")
		(at 270.63065 -12.845542 180)
		(property "Reference" "R722"
			(at 0 0 0)
			(layer "B.SilkS")
			(hide yes)
			(effects
				(font
					(size 1.27 1.27)
				)
				(justify mirror)
			)
		)
		(property "Value" "0R2J-2-GP"
			(at -0.064008 -3.993896 180)
			(unlocked yes)
			(layer "B.Fab")
			(hide yes)
			(effects
				(font
					(size 1.016 1.016)
					(thickness 0.1524)
				)
				(justify mirror)
			)
		)
		(property "Device Type" "R402H16"
			(at -0.064008 -5.517896 180)
			(unlocked yes)
			(layer "B.Fab")
			(hide yes)
			(effects
				(font
					(size 1.016 1.016)
					(thickness 0.1524)
				)
				(justify mirror)
			)
		)
		(duplicate_pad_numbers_are_jumpers no)
		(fp_line
			(start 0.508 -0.9398)
			(end 0.508 0.9398)
			(stroke
				(width 0.1524)
				(type default)
			)
			(layer "B.SilkS")
		)
		(fp_line
			(start -0.508 -0.9398)
			(end 0.508 -0.9398)
			(stroke
				(width 0.1524)
				(type default)
			)
			(layer "B.SilkS")
		)
		(fp_rect
			(start 0.508 0.9398)
			(end -0.508 -0.9398)
			(stroke
				(width 0)
				(type default)
			)
			(fill no)
			(layer "B.CrtYd")
		)
		(fp_rect
			(start 0.508 0.9398)
			(end -0.508 -0.9398)
			(stroke
				(width 0)
				(type default)
			)
			(fill no)
			(layer "B.Fab")
		)
		(pad "1" smd custom
			(at 0 -0.4445)
			(size 0.1397 0.1397)
			(layers "B.Cu" "B.Mask" "B.Paste")
			(net "HOST5_RST_N_C")
			(options
				(clearance outline)
				(anchor circle)
			)
			(primitives
				(gr_poly
					(pts
						(arc
							(start -0.1778 0.2794)
							(mid -0.249642 0.249642)
							(end -0.2794 0.1778)
						)
						(arc
							(start -0.2794 -0.1778)
							(mid -0.249642 -0.249642)
							(end -0.1778 -0.2794)
						)
						(arc
							(start 0.1778 -0.2794)
							(mid 0.249642 -0.249642)
							(end 0.2794 -0.1778)
						)
						(arc
							(start 0.2794 0.1778)
							(mid 0.249642 0.249642)
							(end 0.1778 0.2794)
						)
					)
					(width 0)
					(fill yes)
				)
			)
		)
		(pad "2" smd custom
			(at 0 0.4445)
			(size 0.1397 0.1397)
			(layers "B.Cu" "B.Mask" "B.Paste")
			(net "P3V3_STBY")
			(options
				(clearance outline)
				(anchor circle)
			)
			(primitives
				(gr_poly
					(pts
						(arc
							(start -0.1778 0.2794)
							(mid -0.249642 0.249642)
							(end -0.2794 0.1778)
						)
						(arc
							(start -0.2794 -0.1778)
							(mid -0.249642 -0.249642)
							(end -0.1778 -0.2794)
						)
						(arc
							(start 0.1778 -0.2794)
							(mid 0.249642 -0.249642)
							(end 0.2794 -0.1778)
						)
						(arc
							(start 0.2794 0.1778)
							(mid 0.249642 0.249642)
							(end 0.1778 0.2794)
						)
					)
					(width 0)
					(fill yes)
				)
			)
		)
	)
	(footprint ""
		(layer "B.Cu")
		(at 22.240494 -81.667858 180)
		(property "Reference" "C640"
			(at 0 0 0)
			(layer "B.SilkS")
			(hide yes)
			(effects
				(font
					(size 1.27 1.27)
				)
				(justify mirror)
			)
		)
		(property "Value" "SC10U6D3V5KX-4GP"
			(at 0.0762 -6.1214 180)
			(unlocked yes)
			(layer "B.Fab")
			(hide yes)
			(effects
				(font
					(size 1.016 1.016)
					(thickness 0.1524)
				)
				(justify mirror)
			)
		)
		(property "Device Type" "C805H58"
			(at 0.0762 -8.1534 180)
			(unlocked yes)
			(layer "B.Fab")
			(hide yes)
			(effects
				(font
					(size 1.016 1.016)
					(thickness 0.1524)
				)
				(justify mirror)
			)
		)
		(duplicate_pad_numbers_are_jumpers no)
		(fp_line
			(start -0.635 0)
			(end 0.635 0)
			(stroke
				(width 0.508)
				(type default)
			)
			(layer "B.SilkS")
		)
		(fp_rect
			(start 0.9652 1.778)
			(end -0.9652 -1.778)
			(stroke
				(width 0)
				(type default)
			)
			(fill no)
			(layer "B.CrtYd")
		)
		(fp_poly
			(pts
				(xy 0.9652 -1.778) (xy -0.9652 -1.778) (xy -0.9652 1.778) (xy 0.9652 1.778)
			)
			(stroke
				(width 0)
				(type default)
			)
			(fill no)
			(layer "B.Fab")
		)
		(pad "1" smd rect
			(at 0 -0.9652)
			(size 1.397 1.143)
			(layers "B.Cu" "B.Mask" "B.Paste")
			(net "P0V9_I210")
		)
		(pad "2" smd rect
			(at 0 0.9652)
			(size 1.397 1.143)
			(layers "B.Cu" "B.Mask" "B.Paste")
			(net "GND")
		)
	)
	(footprint ""
		(layer "B.Cu")
		(at 23.796498 -128.037336 90)
		(property "Reference" "R364"
			(at 0 0 90)
			(layer "B.SilkS")
			(hide yes)
			(effects
				(font
					(size 1.27 1.27)
				)
				(justify mirror)
			)
		)
		(property "Value" "3K3R2F-2-GP"
			(at -0.064008 -3.993896 90)
			(unlocked yes)
			(layer "B.Fab")
			(hide yes)
			(effects
				(font
					(size 1.016 1.016)
					(thickness 0.1524)
				)
				(justify mirror)
			)
		)
		(property "Device Type" "R402H16"
			(at -0.064008 -5.517896 90)
			(unlocked yes)
			(layer "B.Fab")
			(hide yes)
			(effects
				(font
					(size 1.016 1.016)
					(thickness 0.1524)
				)
				(justify mirror)
			)
		)
		(duplicate_pad_numbers_are_jumpers no)
		(fp_line
			(start 0.508 -0.9398)
			(end 0.508 0.9398)
			(stroke
				(width 0.1524)
				(type default)
			)
			(layer "B.SilkS")
		)
		(fp_line
			(start -0.508 -0.9398)
			(end 0.508 -0.9398)
			(stroke
				(width 0.1524)
				(type default)
			)
			(layer "B.SilkS")
		)
		(fp_rect
			(start 0.508 0.9398)
			(end -0.508 -0.9398)
			(stroke
				(width 0)
				(type default)
			)
			(fill no)
			(layer "B.CrtYd")
		)
		(fp_rect
			(start 0.508 0.9398)
			(end -0.508 -0.9398)
			(stroke
				(width 0)
				(type default)
			)
			(fill no)
			(layer "B.Fab")
		)
		(pad "1" smd custom
			(at 0 -0.4445 270)
			(size 0.1397 0.1397)
			(layers "B.Cu" "B.Mask" "B.Paste")
			(net "P3V3_STBY")
			(options
				(clearance outline)
				(anchor circle)
			)
			(primitives
				(gr_poly
					(pts
						(arc
							(start -0.1778 0.2794)
							(mid -0.249642 0.249642)
							(end -0.2794 0.1778)
						)
						(arc
							(start -0.2794 -0.1778)
							(mid -0.249642 -0.249642)
							(end -0.1778 -0.2794)
						)
						(arc
							(start 0.1778 -0.2794)
							(mid 0.249642 -0.249642)
							(end 0.2794 -0.1778)
						)
						(arc
							(start 0.2794 0.1778)
							(mid 0.249642 0.249642)
							(end 0.1778 0.2794)
						)
					)
					(width 0)
					(fill yes)
				)
			)
		)
		(pad "2" smd custom
			(at 0 0.4445 270)
			(size 0.1397 0.1397)
			(layers "B.Cu" "B.Mask" "B.Paste")
			(net "ROMA14")
			(options
				(clearance outline)
				(anchor circle)
			)
			(primitives
				(gr_poly
					(pts
						(arc
							(start -0.1778 0.2794)
							(mid -0.249642 0.249642)
							(end -0.2794 0.1778)
						)
						(arc
							(start -0.2794 -0.1778)
							(mid -0.249642 -0.249642)
							(end -0.1778 -0.2794)
						)
						(arc
							(start 0.1778 -0.2794)
							(mid 0.249642 -0.249642)
							(end 0.2794 -0.1778)
						)
						(arc
							(start 0.2794 0.1778)
							(mid 0.249642 0.249642)
							(end 0.1778 0.2794)
						)
					)
					(width 0)
					(fill yes)
				)
			)
		)
	)
	(footprint ""
		(layer "B.Cu")
		(at 252.603 -59.9948 -90)
		(property "Reference" "C578"
			(at 0 0 90)
			(layer "B.SilkS")
			(hide yes)
			(effects
				(font
					(size 1.27 1.27)
				)
				(justify mirror)
			)
		)
		(property "Value" "SCD1U16V1KX-1-GP"
			(at 2.8321 -1.7399 270)
			(unlocked yes)
			(layer "B.Fab")
			(hide yes)
			(effects
				(font
					(size 1.016 1.016)
					(thickness 0.1524)
				)
				(justify mirror)
			)
		)
		(property "Device Type" "C0201H13"
			(at 2.8321 -3.2639 270)
			(unlocked yes)
			(layer "B.Fab")
			(hide yes)
			(effects
				(font
					(size 1.016 1.016)
					(thickness 0.1524)
				)
				(justify mirror)
			)
		)
		(duplicate_pad_numbers_are_jumpers no)
		(fp_rect
			(start 0.2794 0.6477)
			(end -0.2794 -0.6477)
			(stroke
				(width 0)
				(type default)
			)
			(fill no)
			(layer "B.CrtYd")
		)
		(fp_rect
			(start 0.2794 0.6477)
			(end -0.2794 -0.6477)
			(stroke
				(width 0)
				(type default)
			)
			(fill no)
			(layer "B.Fab")
		)
		(pad "1" smd custom
			(at 0 -0.2794 90)
			(size 0.0762 0.0762)
			(layers "B.Cu" "B.Mask" "B.Paste")
			(net "DUT_AVD_PCIE")
			(options
				(clearance outline)
				(anchor circle)
			)
			(primitives
				(gr_poly
					(pts
						(arc
							(start 0.1524 0.127)
							(mid 0.137521 0.162921)
							(end 0.1016 0.1778)
						)
						(arc
							(start -0.1016 0.1778)
							(mid -0.137521 0.162921)
							(end -0.1524 0.127)
						)
						(arc
							(start -0.1524 -0.127)
							(mid -0.137521 -0.162921)
							(end -0.1016 -0.1778)
						)
						(arc
							(start 0.1016 -0.1778)
							(mid 0.137521 -0.162921)
							(end 0.1524 -0.127)
						)
					)
					(width 0)
					(fill yes)
				)
			)
		)
		(pad "2" smd custom
			(at 0 0.2794 90)
			(size 0.0762 0.0762)
			(layers "B.Cu" "B.Mask" "B.Paste")
			(net "GND")
			(options
				(clearance outline)
				(anchor circle)
			)
			(primitives
				(gr_poly
					(pts
						(arc
							(start 0.1524 0.127)
							(mid 0.137521 0.162921)
							(end 0.1016 0.1778)
						)
						(arc
							(start -0.1016 0.1778)
							(mid -0.137521 0.162921)
							(end -0.1524 0.127)
						)
						(arc
							(start -0.1524 -0.127)
							(mid -0.137521 -0.162921)
							(end -0.1016 -0.1778)
						)
						(arc
							(start 0.1016 -0.1778)
							(mid 0.137521 -0.162921)
							(end 0.1524 -0.127)
						)
					)
					(width 0)
					(fill yes)
				)
			)
		)
	)
	(footprint ""
		(layer "B.Cu")
		(at 20.955 -137.795 -90)
		(property "Reference" "R636"
			(at 0 0 90)
			(layer "B.SilkS")
			(hide yes)
			(effects
				(font
					(size 1.27 1.27)
				)
				(justify mirror)
			)
		)
		(property "Value" "0R2J-2-GP"
			(at -0.064008 -3.993896 270)
			(unlocked yes)
			(layer "B.Fab")
			(hide yes)
			(effects
				(font
					(size 1.016 1.016)
					(thickness 0.1524)
				)
				(justify mirror)
			)
		)
		(property "Device Type" "R402H16"
			(at -0.064008 -5.517896 270)
			(unlocked yes)
			(layer "B.Fab")
			(hide yes)
			(effects
				(font
					(size 1.016 1.016)
					(thickness 0.1524)
				)
				(justify mirror)
			)
		)
		(duplicate_pad_numbers_are_jumpers no)
		(fp_line
			(start -0.508 -0.9398)
			(end 0.508 -0.9398)
			(stroke
				(width 0.1524)
				(type default)
			)
			(layer "B.SilkS")
		)
		(fp_line
			(start 0.508 -0.9398)
			(end 0.508 0.9398)
			(stroke
				(width 0.1524)
				(type default)
			)
			(layer "B.SilkS")
		)
		(fp_rect
			(start 0.508 0.9398)
			(end -0.508 -0.9398)
			(stroke
				(width 0)
				(type default)
			)
			(fill no)
			(layer "B.CrtYd")
		)
		(fp_rect
			(start 0.508 0.9398)
			(end -0.508 -0.9398)
			(stroke
				(width 0)
				(type default)
			)
			(fill no)
			(layer "B.Fab")
		)
		(pad "1" smd custom
			(at 0 -0.4445 90)
			(size 0.1397 0.1397)
			(layers "B.Cu" "B.Mask" "B.Paste")
			(net "ROMD2")
			(options
				(clearance outline)
				(anchor circle)
			)
			(primitives
				(gr_poly
					(pts
						(arc
							(start -0.1778 0.2794)
							(mid -0.249642 0.249642)
							(end -0.2794 0.1778)
						)
						(arc
							(start -0.2794 -0.1778)
							(mid -0.249642 -0.249642)
							(end -0.1778 -0.2794)
						)
						(arc
							(start 0.1778 -0.2794)
							(mid 0.249642 -0.249642)
							(end 0.2794 -0.1778)
						)
						(arc
							(start 0.2794 0.1778)
							(mid 0.249642 0.249642)
							(end 0.1778 0.2794)
						)
					)
					(width 0)
					(fill yes)
				)
			)
		)
		(pad "2" smd custom
			(at 0 0.4445 90)
			(size 0.1397 0.1397)
			(layers "B.Cu" "B.Mask" "B.Paste")
			(net "ROMD2_R")
			(options
				(clearance outline)
				(anchor circle)
			)
			(primitives
				(gr_poly
					(pts
						(arc
							(start -0.1778 0.2794)
							(mid -0.249642 0.249642)
							(end -0.2794 0.1778)
						)
						(arc
							(start -0.2794 -0.1778)
							(mid -0.249642 -0.249642)
							(end -0.1778 -0.2794)
						)
						(arc
							(start 0.1778 -0.2794)
							(mid 0.249642 -0.249642)
							(end 0.2794 -0.1778)
						)
						(arc
							(start 0.2794 0.1778)
							(mid 0.249642 0.249642)
							(end 0.1778 0.2794)
						)
					)
					(width 0)
					(fill yes)
				)
			)
		)
	)
	(footprint ""
		(layer "B.Cu")
		(at 208.333848 -4.043426)
		(property "Reference" "R3711"
			(at 0 0 0)
			(layer "B.SilkS")
			(hide yes)
			(effects
				(font
					(size 1.27 1.27)
				)
				(justify mirror)
			)
		)
		(property "Value" "1KR2F-3-GP"
			(at -0.064008 -3.993896 0)
			(unlocked yes)
			(layer "B.Fab")
			(hide yes)
			(effects
				(font
					(size 1.016 1.016)
					(thickness 0.1524)
				)
				(justify mirror)
			)
		)
		(property "Device Type" "R402H16"
			(at -0.064008 -5.517896 0)
			(unlocked yes)
			(layer "B.Fab")
			(hide yes)
			(effects
				(font
					(size 1.016 1.016)
					(thickness 0.1524)
				)
				(justify mirror)
			)
		)
		(duplicate_pad_numbers_are_jumpers no)
		(fp_line
			(start -0.508 -0.9398)
			(end 0.508 -0.9398)
			(stroke
				(width 0.1524)
				(type default)
			)
			(layer "B.SilkS")
		)
		(fp_line
			(start 0.508 -0.9398)
			(end 0.508 0.9398)
			(stroke
				(width 0.1524)
				(type default)
			)
			(layer "B.SilkS")
		)
		(fp_rect
			(start 0.508 0.9398)
			(end -0.508 -0.9398)
			(stroke
				(width 0)
				(type default)
			)
			(fill no)
			(layer "B.CrtYd")
		)
		(fp_rect
			(start 0.508 0.9398)
			(end -0.508 -0.9398)
			(stroke
				(width 0)
				(type default)
			)
			(fill no)
			(layer "B.Fab")
		)
		(pad "1" smd custom
			(at 0 -0.4445 180)
			(size 0.1397 0.1397)
			(layers "B.Cu" "B.Mask" "B.Paste")
			(net "HOST8_RST_N")
			(options
				(clearance outline)
				(anchor circle)
			)
			(primitives
				(gr_poly
					(pts
						(arc
							(start -0.1778 0.2794)
							(mid -0.249642 0.249642)
							(end -0.2794 0.1778)
						)
						(arc
							(start -0.2794 -0.1778)
							(mid -0.249642 -0.249642)
							(end -0.1778 -0.2794)
						)
						(arc
							(start 0.1778 -0.2794)
							(mid 0.249642 -0.249642)
							(end 0.2794 -0.1778)
						)
						(arc
							(start 0.2794 0.1778)
							(mid 0.249642 0.249642)
							(end 0.1778 0.2794)
						)
					)
					(width 0)
					(fill yes)
				)
			)
		)
		(pad "2" smd custom
			(at 0 0.4445 180)
			(size 0.1397 0.1397)
			(layers "B.Cu" "B.Mask" "B.Paste")
			(net "P3V3_STBY")
			(options
				(clearance outline)
				(anchor circle)
			)
			(primitives
				(gr_poly
					(pts
						(arc
							(start -0.1778 0.2794)
							(mid -0.249642 0.249642)
							(end -0.2794 0.1778)
						)
						(arc
							(start -0.2794 -0.1778)
							(mid -0.249642 -0.249642)
							(end -0.1778 -0.2794)
						)
						(arc
							(start 0.1778 -0.2794)
							(mid 0.249642 -0.249642)
							(end 0.2794 -0.1778)
						)
						(arc
							(start 0.2794 0.1778)
							(mid 0.249642 0.249642)
							(end 0.1778 0.2794)
						)
					)
					(width 0)
					(fill yes)
				)
			)
		)
	)
	(footprint ""
		(layer "B.Cu")
		(at 248.59996 -40.999918 180)
		(property "Reference" "TP206"
			(at 0 0 0)
			(layer "B.SilkS")
			(hide yes)
			(effects
				(font
					(size 1.27 1.27)
				)
				(justify mirror)
			)
		)
		(property "Value" "TPAD28-2-GP"
			(at 0.0127 -1.6637 180)
			(unlocked yes)
			(layer "B.Fab")
			(hide yes)
			(effects
				(font
					(size 1.016 1.016)
					(thickness 0.1524)
				)
				(justify mirror)
			)
		)
		(property "Device Type" "TPAD28"
			(at 0.0127 -3.1877 180)
			(unlocked yes)
			(layer "B.Fab")
			(hide yes)
			(effects
				(font
					(size 1.016 1.016)
					(thickness 0.1524)
				)
				(justify mirror)
			)
		)
		(duplicate_pad_numbers_are_jumpers no)
		(fp_poly
			(pts
				(arc
					(start -0.3556 0)
					(mid 0.3556 0)
					(end -0.3556 0)
				)
			)
			(stroke
				(width 0)
				(type default)
			)
			(fill no)
			(layer "B.CrtYd")
		)
		(fp_poly
			(pts
				(arc
					(start -0.6096 0)
					(mid 0.6096 0)
					(end -0.6096 0)
				)
			)
			(stroke
				(width 0)
				(type default)
			)
			(fill no)
			(layer "B.Fab")
		)
		(pad "1" smd circle
			(at 0 0)
			(size 0.7112 0.7112)
			(layers "B.Cu" "B.Mask" "B.Paste")
			(net "GPIO107_R")
		)
	)
	(footprint ""
		(layer "B.Cu")
		(at 230.251 -23.241 180)
		(property "Reference" "R825"
			(at 0 0 0)
			(layer "B.SilkS")
			(hide yes)
			(effects
				(font
					(size 1.27 1.27)
				)
				(justify mirror)
			)
		)
		(property "Value" "0R2J-2-GP"
			(at -0.064008 -3.993896 180)
			(unlocked yes)
			(layer "B.Fab")
			(hide yes)
			(effects
				(font
					(size 1.016 1.016)
					(thickness 0.1524)
				)
				(justify mirror)
			)
		)
		(property "Device Type" "R402H16"
			(at -0.064008 -5.517896 180)
			(unlocked yes)
			(layer "B.Fab")
			(hide yes)
			(effects
				(font
					(size 1.016 1.016)
					(thickness 0.1524)
				)
				(justify mirror)
			)
		)
		(duplicate_pad_numbers_are_jumpers no)
		(fp_line
			(start 0.508 -0.9398)
			(end 0.508 0.9398)
			(stroke
				(width 0.1524)
				(type default)
			)
			(layer "B.SilkS")
		)
		(fp_line
			(start -0.508 -0.9398)
			(end 0.508 -0.9398)
			(stroke
				(width 0.1524)
				(type default)
			)
			(layer "B.SilkS")
		)
		(fp_rect
			(start 0.508 0.9398)
			(end -0.508 -0.9398)
			(stroke
				(width 0)
				(type default)
			)
			(fill no)
			(layer "B.CrtYd")
		)
		(fp_rect
			(start 0.508 0.9398)
			(end -0.508 -0.9398)
			(stroke
				(width 0)
				(type default)
			)
			(fill no)
			(layer "B.Fab")
		)
		(pad "1" smd custom
			(at 0 -0.4445)
			(size 0.1397 0.1397)
			(layers "B.Cu" "B.Mask" "B.Paste")
			(net "HOST1_RST_N_LS")
			(options
				(clearance outline)
				(anchor circle)
			)
			(primitives
				(gr_poly
					(pts
						(arc
							(start -0.1778 0.2794)
							(mid -0.249642 0.249642)
							(end -0.2794 0.1778)
						)
						(arc
							(start -0.2794 -0.1778)
							(mid -0.249642 -0.249642)
							(end -0.1778 -0.2794)
						)
						(arc
							(start 0.1778 -0.2794)
							(mid 0.249642 -0.249642)
							(end 0.2794 -0.1778)
						)
						(arc
							(start 0.2794 0.1778)
							(mid 0.249642 0.249642)
							(end 0.1778 0.2794)
						)
					)
					(width 0)
					(fill yes)
				)
			)
		)
		(pad "2" smd custom
			(at 0 0.4445)
			(size 0.1397 0.1397)
			(layers "B.Cu" "B.Mask" "B.Paste")
			(net "LBI_ADDR_0_R")
			(options
				(clearance outline)
				(anchor circle)
			)
			(primitives
				(gr_poly
					(pts
						(arc
							(start -0.1778 0.2794)
							(mid -0.249642 0.249642)
							(end -0.2794 0.1778)
						)
						(arc
							(start -0.2794 -0.1778)
							(mid -0.249642 -0.249642)
							(end -0.1778 -0.2794)
						)
						(arc
							(start 0.1778 -0.2794)
							(mid 0.249642 -0.249642)
							(end 0.2794 -0.1778)
						)
						(arc
							(start 0.2794 0.1778)
							(mid 0.249642 0.249642)
							(end 0.1778 0.2794)
						)
					)
					(width 0)
					(fill yes)
				)
			)
		)
	)
	(footprint ""
		(layer "B.Cu")
		(at 71.731124 -183.235092)
		(property "Reference" "R4102"
			(at 0 0 0)
			(layer "B.SilkS")
			(hide yes)
			(effects
				(font
					(size 1.27 1.27)
				)
				(justify mirror)
			)
		)
		(property "Value" "4K7R2F-GP"
			(at -0.064008 -3.993896 0)
			(unlocked yes)
			(layer "B.Fab")
			(hide yes)
			(effects
				(font
					(size 1.016 1.016)
					(thickness 0.1524)
				)
				(justify mirror)
			)
		)
		(property "Device Type" "R402H16"
			(at -0.064008 -5.517896 0)
			(unlocked yes)
			(layer "B.Fab")
			(hide yes)
			(effects
				(font
					(size 1.016 1.016)
					(thickness 0.1524)
				)
				(justify mirror)
			)
		)
		(duplicate_pad_numbers_are_jumpers no)
		(fp_line
			(start -0.508 -0.9398)
			(end 0.508 -0.9398)
			(stroke
				(width 0.1524)
				(type default)
			)
			(layer "B.SilkS")
		)
		(fp_line
			(start 0.508 -0.9398)
			(end 0.508 0.9398)
			(stroke
				(width 0.1524)
				(type default)
			)
			(layer "B.SilkS")
		)
		(fp_rect
			(start 0.508 0.9398)
			(end -0.508 -0.9398)
			(stroke
				(width 0)
				(type default)
			)
			(fill no)
			(layer "B.CrtYd")
		)
		(fp_rect
			(start 0.508 0.9398)
			(end -0.508 -0.9398)
			(stroke
				(width 0)
				(type default)
			)
			(fill no)
			(layer "B.Fab")
		)
		(pad "1" smd custom
			(at 0 -0.4445 180)
			(size 0.1397 0.1397)
			(layers "B.Cu" "B.Mask" "B.Paste")
			(net "SSD_PRSNT#0")
			(options
				(clearance outline)
				(anchor circle)
			)
			(primitives
				(gr_poly
					(pts
						(arc
							(start -0.1778 0.2794)
							(mid -0.249642 0.249642)
							(end -0.2794 0.1778)
						)
						(arc
							(start -0.2794 -0.1778)
							(mid -0.249642 -0.249642)
							(end -0.1778 -0.2794)
						)
						(arc
							(start 0.1778 -0.2794)
							(mid 0.249642 -0.249642)
							(end 0.2794 -0.1778)
						)
						(arc
							(start 0.2794 0.1778)
							(mid 0.249642 0.249642)
							(end 0.1778 0.2794)
						)
					)
					(width 0)
					(fill yes)
				)
			)
		)
		(pad "2" smd custom
			(at 0 0.4445 180)
			(size 0.1397 0.1397)
			(layers "B.Cu" "B.Mask" "B.Paste")
			(net "P3V3_STBY")
			(options
				(clearance outline)
				(anchor circle)
			)
			(primitives
				(gr_poly
					(pts
						(arc
							(start -0.1778 0.2794)
							(mid -0.249642 0.249642)
							(end -0.2794 0.1778)
						)
						(arc
							(start -0.2794 -0.1778)
							(mid -0.249642 -0.249642)
							(end -0.1778 -0.2794)
						)
						(arc
							(start 0.1778 -0.2794)
							(mid 0.249642 -0.249642)
							(end 0.2794 -0.1778)
						)
						(arc
							(start 0.2794 0.1778)
							(mid 0.249642 0.249642)
							(end 0.1778 0.2794)
						)
					)
					(width 0)
					(fill yes)
				)
			)
		)
	)
	(footprint ""
		(layer "B.Cu")
		(at 27.9654 -184.8866 -90)
		(property "Reference" "R443"
			(at 0 0 90)
			(layer "B.SilkS")
			(hide yes)
			(effects
				(font
					(size 1.27 1.27)
				)
				(justify mirror)
			)
		)
		(property "Value" "0R2J-2-GP"
			(at -0.064008 -3.993896 270)
			(unlocked yes)
			(layer "B.Fab")
			(hide yes)
			(effects
				(font
					(size 1.016 1.016)
					(thickness 0.1524)
				)
				(justify mirror)
			)
		)
		(property "Device Type" "R402H16"
			(at -0.064008 -5.517896 270)
			(unlocked yes)
			(layer "B.Fab")
			(hide yes)
			(effects
				(font
					(size 1.016 1.016)
					(thickness 0.1524)
				)
				(justify mirror)
			)
		)
		(duplicate_pad_numbers_are_jumpers no)
		(fp_line
			(start -0.508 -0.9398)
			(end 0.508 -0.9398)
			(stroke
				(width 0.1524)
				(type default)
			)
			(layer "B.SilkS")
		)
		(fp_line
			(start 0.508 -0.9398)
			(end 0.508 0.9398)
			(stroke
				(width 0.1524)
				(type default)
			)
			(layer "B.SilkS")
		)
		(fp_rect
			(start 0.508 0.9398)
			(end -0.508 -0.9398)
			(stroke
				(width 0)
				(type default)
			)
			(fill no)
			(layer "B.CrtYd")
		)
		(fp_rect
			(start 0.508 0.9398)
			(end -0.508 -0.9398)
			(stroke
				(width 0)
				(type default)
			)
			(fill no)
			(layer "B.Fab")
		)
		(pad "1" smd custom
			(at 0 -0.4445 90)
			(size 0.1397 0.1397)
			(layers "B.Cu" "B.Mask" "B.Paste")
			(net "BMC_I2C5_D_PEB_DEVICE_SDA")
			(options
				(clearance outline)
				(anchor circle)
			)
			(primitives
				(gr_poly
					(pts
						(arc
							(start -0.1778 0.2794)
							(mid -0.249642 0.249642)
							(end -0.2794 0.1778)
						)
						(arc
							(start -0.2794 -0.1778)
							(mid -0.249642 -0.249642)
							(end -0.1778 -0.2794)
						)
						(arc
							(start 0.1778 -0.2794)
							(mid 0.249642 -0.249642)
							(end 0.2794 -0.1778)
						)
						(arc
							(start 0.2794 0.1778)
							(mid 0.249642 0.249642)
							(end 0.1778 0.2794)
						)
					)
					(width 0)
					(fill yes)
				)
			)
		)
		(pad "2" smd custom
			(at 0 0.4445 90)
			(size 0.1397 0.1397)
			(layers "B.Cu" "B.Mask" "B.Paste")
			(net "BMC_I2C5_D_PEB_SDA")
			(options
				(clearance outline)
				(anchor circle)
			)
			(primitives
				(gr_poly
					(pts
						(arc
							(start -0.1778 0.2794)
							(mid -0.249642 0.249642)
							(end -0.2794 0.1778)
						)
						(arc
							(start -0.2794 -0.1778)
							(mid -0.249642 -0.249642)
							(end -0.1778 -0.2794)
						)
						(arc
							(start 0.1778 -0.2794)
							(mid 0.249642 -0.249642)
							(end 0.2794 -0.1778)
						)
						(arc
							(start 0.2794 0.1778)
							(mid 0.249642 0.249642)
							(end 0.1778 0.2794)
						)
					)
					(width 0)
					(fill yes)
				)
			)
		)
	)
	(footprint ""
		(layer "B.Cu")
		(at 252.603 -53.992272 -90)
		(property "Reference" "C581"
			(at 0 0 90)
			(layer "B.SilkS")
			(hide yes)
			(effects
				(font
					(size 1.27 1.27)
				)
				(justify mirror)
			)
		)
		(property "Value" "SCD1U16V1KX-1-GP"
			(at 2.8321 -1.7399 270)
			(unlocked yes)
			(layer "B.Fab")
			(hide yes)
			(effects
				(font
					(size 1.016 1.016)
					(thickness 0.1524)
				)
				(justify mirror)
			)
		)
		(property "Device Type" "C0201H13"
			(at 2.8321 -3.2639 270)
			(unlocked yes)
			(layer "B.Fab")
			(hide yes)
			(effects
				(font
					(size 1.016 1.016)
					(thickness 0.1524)
				)
				(justify mirror)
			)
		)
		(duplicate_pad_numbers_are_jumpers no)
		(fp_rect
			(start 0.2794 0.6477)
			(end -0.2794 -0.6477)
			(stroke
				(width 0)
				(type default)
			)
			(fill no)
			(layer "B.CrtYd")
		)
		(fp_rect
			(start 0.2794 0.6477)
			(end -0.2794 -0.6477)
			(stroke
				(width 0)
				(type default)
			)
			(fill no)
			(layer "B.Fab")
		)
		(pad "1" smd custom
			(at 0 -0.2794 90)
			(size 0.0762 0.0762)
			(layers "B.Cu" "B.Mask" "B.Paste")
			(net "DUT_AVD_PCIE")
			(options
				(clearance outline)
				(anchor circle)
			)
			(primitives
				(gr_poly
					(pts
						(arc
							(start 0.1524 0.127)
							(mid 0.137521 0.162921)
							(end 0.1016 0.1778)
						)
						(arc
							(start -0.1016 0.1778)
							(mid -0.137521 0.162921)
							(end -0.1524 0.127)
						)
						(arc
							(start -0.1524 -0.127)
							(mid -0.137521 -0.162921)
							(end -0.1016 -0.1778)
						)
						(arc
							(start 0.1016 -0.1778)
							(mid 0.137521 -0.162921)
							(end 0.1524 -0.127)
						)
					)
					(width 0)
					(fill yes)
				)
			)
		)
		(pad "2" smd custom
			(at 0 0.2794 90)
			(size 0.0762 0.0762)
			(layers "B.Cu" "B.Mask" "B.Paste")
			(net "GND")
			(options
				(clearance outline)
				(anchor circle)
			)
			(primitives
				(gr_poly
					(pts
						(arc
							(start 0.1524 0.127)
							(mid 0.137521 0.162921)
							(end 0.1016 0.1778)
						)
						(arc
							(start -0.1016 0.1778)
							(mid -0.137521 0.162921)
							(end -0.1524 0.127)
						)
						(arc
							(start -0.1524 -0.127)
							(mid -0.137521 -0.162921)
							(end -0.1016 -0.1778)
						)
						(arc
							(start 0.1016 -0.1778)
							(mid 0.137521 -0.162921)
							(end 0.1524 -0.127)
						)
					)
					(width 0)
					(fill yes)
				)
			)
		)
	)
	(footprint ""
		(layer "B.Cu")
		(at 43.5102 -187.4012 180)
		(property "Reference" "R870"
			(at 0 0 0)
			(layer "B.SilkS")
			(hide yes)
			(effects
				(font
					(size 1.27 1.27)
				)
				(justify mirror)
			)
		)
		(property "Value" "0R2J-2-GP"
			(at -0.064008 -3.993896 180)
			(unlocked yes)
			(layer "B.Fab")
			(hide yes)
			(effects
				(font
					(size 1.016 1.016)
					(thickness 0.1524)
				)
				(justify mirror)
			)
		)
		(property "Device Type" "R402H16"
			(at -0.064008 -5.517896 180)
			(unlocked yes)
			(layer "B.Fab")
			(hide yes)
			(effects
				(font
					(size 1.016 1.016)
					(thickness 0.1524)
				)
				(justify mirror)
			)
		)
		(duplicate_pad_numbers_are_jumpers no)
		(fp_line
			(start 0.508 -0.9398)
			(end 0.508 0.9398)
			(stroke
				(width 0.1524)
				(type default)
			)
			(layer "B.SilkS")
		)
		(fp_line
			(start -0.508 -0.9398)
			(end 0.508 -0.9398)
			(stroke
				(width 0.1524)
				(type default)
			)
			(layer "B.SilkS")
		)
		(fp_rect
			(start 0.508 0.9398)
			(end -0.508 -0.9398)
			(stroke
				(width 0)
				(type default)
			)
			(fill no)
			(layer "B.CrtYd")
		)
		(fp_rect
			(start 0.508 0.9398)
			(end -0.508 -0.9398)
			(stroke
				(width 0)
				(type default)
			)
			(fill no)
			(layer "B.Fab")
		)
		(pad "1" smd custom
			(at 0 -0.4445)
			(size 0.1397 0.1397)
			(layers "B.Cu" "B.Mask" "B.Paste")
			(net "BMC_I2C9_CLKBUF2_SCL")
			(options
				(clearance outline)
				(anchor circle)
			)
			(primitives
				(gr_poly
					(pts
						(arc
							(start -0.1778 0.2794)
							(mid -0.249642 0.249642)
							(end -0.2794 0.1778)
						)
						(arc
							(start -0.2794 -0.1778)
							(mid -0.249642 -0.249642)
							(end -0.1778 -0.2794)
						)
						(arc
							(start 0.1778 -0.2794)
							(mid 0.249642 -0.249642)
							(end 0.2794 -0.1778)
						)
						(arc
							(start 0.2794 0.1778)
							(mid 0.249642 0.249642)
							(end 0.1778 0.2794)
						)
					)
					(width 0)
					(fill yes)
				)
			)
		)
		(pad "2" smd custom
			(at 0 0.4445)
			(size 0.1397 0.1397)
			(layers "B.Cu" "B.Mask" "B.Paste")
			(net "BUF_I2C9_CLKBUF2_SCL")
			(options
				(clearance outline)
				(anchor circle)
			)
			(primitives
				(gr_poly
					(pts
						(arc
							(start -0.1778 0.2794)
							(mid -0.249642 0.249642)
							(end -0.2794 0.1778)
						)
						(arc
							(start -0.2794 -0.1778)
							(mid -0.249642 -0.249642)
							(end -0.1778 -0.2794)
						)
						(arc
							(start 0.1778 -0.2794)
							(mid 0.249642 -0.249642)
							(end 0.2794 -0.1778)
						)
						(arc
							(start 0.2794 0.1778)
							(mid 0.249642 0.249642)
							(end 0.1778 0.2794)
						)
					)
					(width 0)
					(fill yes)
				)
			)
		)
	)
	(footprint ""
		(layer "B.Cu")
		(at 34.9504 -127.339852)
		(property "Reference" "TP107"
			(at 0 0 0)
			(layer "B.SilkS")
			(hide yes)
			(effects
				(font
					(size 1.27 1.27)
				)
				(justify mirror)
			)
		)
		(property "Value" "TPAD28-2-GP"
			(at 0.0127 -1.6637 0)
			(unlocked yes)
			(layer "B.Fab")
			(hide yes)
			(effects
				(font
					(size 1.016 1.016)
					(thickness 0.1524)
				)
				(justify mirror)
			)
		)
		(property "Device Type" "TPAD28"
			(at 0.0127 -3.1877 0)
			(unlocked yes)
			(layer "B.Fab")
			(hide yes)
			(effects
				(font
					(size 1.016 1.016)
					(thickness 0.1524)
				)
				(justify mirror)
			)
		)
		(duplicate_pad_numbers_are_jumpers no)
		(fp_poly
			(pts
				(arc
					(start 0.3556 0)
					(mid -0.3556 0)
					(end 0.3556 0)
				)
			)
			(stroke
				(width 0)
				(type default)
			)
			(fill no)
			(layer "B.CrtYd")
		)
		(fp_poly
			(pts
				(arc
					(start 0.6096 0)
					(mid -0.6096 0)
					(end 0.6096 0)
				)
			)
			(stroke
				(width 0)
				(type default)
			)
			(fill no)
			(layer "B.Fab")
		)
		(pad "1" smd circle
			(at 0 0 180)
			(size 0.7112 0.7112)
			(layers "B.Cu" "B.Mask" "B.Paste")
			(net "TP_GPIOB2")
		)
	)
	(footprint ""
		(layer "B.Cu")
		(at 233.5911 -35.0012 180)
		(property "Reference" "TP199"
			(at 0 0 0)
			(layer "B.SilkS")
			(hide yes)
			(effects
				(font
					(size 1.27 1.27)
				)
				(justify mirror)
			)
		)
		(property "Value" "TPAD28-2-GP"
			(at 0.0127 -1.6637 180)
			(unlocked yes)
			(layer "B.Fab")
			(hide yes)
			(effects
				(font
					(size 1.016 1.016)
					(thickness 0.1524)
				)
				(justify mirror)
			)
		)
		(property "Device Type" "TPAD28"
			(at 0.0127 -3.1877 180)
			(unlocked yes)
			(layer "B.Fab")
			(hide yes)
			(effects
				(font
					(size 1.016 1.016)
					(thickness 0.1524)
				)
				(justify mirror)
			)
		)
		(duplicate_pad_numbers_are_jumpers no)
		(fp_poly
			(pts
				(arc
					(start -0.3556 0)
					(mid 0.3556 0)
					(end -0.3556 0)
				)
			)
			(stroke
				(width 0)
				(type default)
			)
			(fill no)
			(layer "B.CrtYd")
		)
		(fp_poly
			(pts
				(arc
					(start -0.6096 0)
					(mid 0.6096 0)
					(end -0.6096 0)
				)
			)
			(stroke
				(width 0)
				(type default)
			)
			(fill no)
			(layer "B.Fab")
		)
		(pad "1" smd circle
			(at 0 0)
			(size 0.7112 0.7112)
			(layers "B.Cu" "B.Mask" "B.Paste")
			(net "RMII_TXD_1")
		)
	)
	(footprint ""
		(layer "B.Cu")
		(at 177.485802 -71.071232 90)
		(property "Reference" "PG29"
			(at 0 0 90)
			(layer "B.SilkS")
			(hide yes)
			(effects
				(font
					(size 1.27 1.27)
				)
				(justify mirror)
			)
		)
		(property "Value" "GAP-CLOSE-PWR-3-GP"
			(at -0.0254 -6.5786 90)
			(unlocked yes)
			(layer "B.Fab")
			(hide yes)
			(effects
				(font
					(size 1.016 1.016)
					(thickness 0.1524)
				)
				(justify mirror)
			)
		)
		(property "Device Type" "GAP-CLOSE-PWR-3"
			(at -0.0254 -8.255 90)
			(unlocked yes)
			(layer "B.Fab")
			(hide yes)
			(effects
				(font
					(size 1.016 1.016)
					(thickness 0.1524)
				)
				(justify mirror)
			)
		)
		(duplicate_pad_numbers_are_jumpers no)
		(fp_rect
			(start 0.7112 0.4572)
			(end -0.7112 -0.4572)
			(stroke
				(width 0)
				(type default)
			)
			(fill no)
			(layer "B.CrtYd")
		)
		(fp_poly
			(pts
				(xy 0.7112 -0.4572) (xy -0.7112 -0.4572) (xy -0.7112 0.4572) (xy 0.7112 0.4572)
			)
			(stroke
				(width 0)
				(type default)
			)
			(fill no)
			(layer "B.Fab")
		)
		(pad "1" smd rect
			(at 0.3048 0 270)
			(size 0.6604 0.762)
			(layers "B.Cu" "B.Mask" "B.Paste")
			(net "DUT_AVD_TX")
		)
		(pad "2" smd rect
			(at -0.3048 0 270)
			(size 0.6604 0.762)
			(layers "B.Cu" "B.Mask" "B.Paste")
			(net "P0V9")
		)
	)
	(footprint ""
		(layer "B.Cu")
		(at 310.007 -57.023 180)
		(property "Reference" "PG38"
			(at 0 0 0)
			(layer "B.SilkS")
			(hide yes)
			(effects
				(font
					(size 1.27 1.27)
				)
				(justify mirror)
			)
		)
		(property "Value" "GAP-CLOSE-PWR-3-GP"
			(at -0.0254 -6.5786 180)
			(unlocked yes)
			(layer "B.Fab")
			(hide yes)
			(effects
				(font
					(size 1.016 1.016)
					(thickness 0.1524)
				)
				(justify mirror)
			)
		)
		(property "Device Type" "GAP-CLOSE-PWR-3"
			(at -0.0254 -8.255 180)
			(unlocked yes)
			(layer "B.Fab")
			(hide yes)
			(effects
				(font
					(size 1.016 1.016)
					(thickness 0.1524)
				)
				(justify mirror)
			)
		)
		(duplicate_pad_numbers_are_jumpers no)
		(fp_rect
			(start 0.7112 0.4572)
			(end -0.7112 -0.4572)
			(stroke
				(width 0)
				(type default)
			)
			(fill no)
			(layer "B.CrtYd")
		)
		(fp_poly
			(pts
				(xy 0.7112 -0.4572) (xy -0.7112 -0.4572) (xy -0.7112 0.4572) (xy 0.7112 0.4572)
			)
			(stroke
				(width 0)
				(type default)
			)
			(fill no)
			(layer "B.Fab")
		)
		(pad "1" smd rect
			(at 0.3048 0)
			(size 0.6604 0.762)
			(layers "B.Cu" "B.Mask" "B.Paste")
			(net "DUT_VDD")
		)
		(pad "2" smd rect
			(at -0.3048 0)
			(size 0.6604 0.762)
			(layers "B.Cu" "B.Mask" "B.Paste")
			(net "P0V9_E")
		)
	)
	(footprint ""
		(layer "B.Cu")
		(at 42.126154 -158.987744 180)
		(property "Reference" "C182"
			(at 0 0 0)
			(layer "B.SilkS")
			(hide yes)
			(effects
				(font
					(size 1.27 1.27)
				)
				(justify mirror)
			)
		)
		(property "Value" "SCD1U16V2KX-3GP"
			(at -1.1811 -2.7051 180)
			(unlocked yes)
			(layer "B.Fab")
			(hide yes)
			(effects
				(font
					(size 1.016 1.016)
					(thickness 0.1524)
				)
				(justify mirror)
			)
		)
		(property "Device Type" "C402H22"
			(at -1.1811 -4.2291 180)
			(unlocked yes)
			(layer "B.Fab")
			(hide yes)
			(effects
				(font
					(size 1.016 1.016)
					(thickness 0.1524)
				)
				(justify mirror)
			)
		)
		(duplicate_pad_numbers_are_jumpers no)
		(fp_rect
			(start 0.4318 0.9525)
			(end -0.4318 -0.9525)
			(stroke
				(width 0)
				(type default)
			)
			(fill no)
			(layer "B.CrtYd")
		)
		(fp_rect
			(start 0.4318 0.9525)
			(end -0.4318 -0.9525)
			(stroke
				(width 0)
				(type default)
			)
			(fill no)
			(layer "B.Fab")
		)
		(pad "1" smd custom
			(at 0 -0.4445)
			(size 0.1524 0.1524)
			(layers "B.Cu" "B.Mask" "B.Paste")
			(net "P1V53_STBY")
			(options
				(clearance outline)
				(anchor circle)
			)
			(primitives
				(gr_poly
					(pts
						(arc
							(start 0.3048 0.2032)
							(mid 0.275042 0.275042)
							(end 0.2032 0.3048)
						)
						(arc
							(start -0.2032 0.3048)
							(mid -0.275042 0.275042)
							(end -0.3048 0.2032)
						)
						(arc
							(start -0.3048 -0.2032)
							(mid -0.275042 -0.275042)
							(end -0.2032 -0.3048)
						)
						(arc
							(start 0.2032 -0.3048)
							(mid 0.275042 -0.275042)
							(end 0.3048 -0.2032)
						)
					)
					(width 0)
					(fill yes)
				)
			)
		)
		(pad "2" smd custom
			(at 0 0.4445)
			(size 0.1524 0.1524)
			(layers "B.Cu" "B.Mask" "B.Paste")
			(net "GND")
			(options
				(clearance outline)
				(anchor circle)
			)
			(primitives
				(gr_poly
					(pts
						(arc
							(start 0.3048 0.2032)
							(mid 0.275042 0.275042)
							(end 0.2032 0.3048)
						)
						(arc
							(start -0.2032 0.3048)
							(mid -0.275042 0.275042)
							(end -0.3048 0.2032)
						)
						(arc
							(start -0.3048 -0.2032)
							(mid -0.275042 -0.275042)
							(end -0.2032 -0.3048)
						)
						(arc
							(start 0.2032 -0.3048)
							(mid 0.275042 -0.275042)
							(end 0.3048 -0.2032)
						)
					)
					(width 0)
					(fill yes)
				)
			)
		)
	)
	(footprint ""
		(layer "B.Cu")
		(at 343.154 -71.501 180)
		(property "Reference" "PR162"
			(at 0 0 0)
			(layer "B.SilkS")
			(hide yes)
			(effects
				(font
					(size 1.27 1.27)
				)
				(justify mirror)
			)
		)
		(property "Value" "187KR2F-GP"
			(at -0.064008 -3.993896 180)
			(unlocked yes)
			(layer "B.Fab")
			(hide yes)
			(effects
				(font
					(size 1.016 1.016)
					(thickness 0.1524)
				)
				(justify mirror)
			)
		)
		(property "Device Type" "R402H16"
			(at -0.064008 -5.517896 180)
			(unlocked yes)
			(layer "B.Fab")
			(hide yes)
			(effects
				(font
					(size 1.016 1.016)
					(thickness 0.1524)
				)
				(justify mirror)
			)
		)
		(duplicate_pad_numbers_are_jumpers no)
		(fp_line
			(start 0.508 -0.9398)
			(end 0.508 0.9398)
			(stroke
				(width 0.1524)
				(type default)
			)
			(layer "B.SilkS")
		)
		(fp_line
			(start -0.508 -0.9398)
			(end 0.508 -0.9398)
			(stroke
				(width 0.1524)
				(type default)
			)
			(layer "B.SilkS")
		)
		(fp_rect
			(start 0.508 0.9398)
			(end -0.508 -0.9398)
			(stroke
				(width 0)
				(type default)
			)
			(fill no)
			(layer "B.CrtYd")
		)
		(fp_rect
			(start 0.508 0.9398)
			(end -0.508 -0.9398)
			(stroke
				(width 0)
				(type default)
			)
			(fill no)
			(layer "B.Fab")
		)
		(pad "1" smd custom
			(at 0 -0.4445)
			(size 0.1397 0.1397)
			(layers "B.Cu" "B.Mask" "B.Paste")
			(net "P0V9_E_RF")
			(options
				(clearance outline)
				(anchor circle)
			)
			(primitives
				(gr_poly
					(pts
						(arc
							(start -0.1778 0.2794)
							(mid -0.249642 0.249642)
							(end -0.2794 0.1778)
						)
						(arc
							(start -0.2794 -0.1778)
							(mid -0.249642 -0.249642)
							(end -0.1778 -0.2794)
						)
						(arc
							(start 0.1778 -0.2794)
							(mid 0.249642 -0.249642)
							(end 0.2794 -0.1778)
						)
						(arc
							(start 0.2794 0.1778)
							(mid 0.249642 0.249642)
							(end 0.1778 0.2794)
						)
					)
					(width 0)
					(fill yes)
				)
			)
		)
		(pad "2" smd custom
			(at 0 0.4445)
			(size 0.1397 0.1397)
			(layers "B.Cu" "B.Mask" "B.Paste")
			(net "AGND_P0V9_E")
			(options
				(clearance outline)
				(anchor circle)
			)
			(primitives
				(gr_poly
					(pts
						(arc
							(start -0.1778 0.2794)
							(mid -0.249642 0.249642)
							(end -0.2794 0.1778)
						)
						(arc
							(start -0.2794 -0.1778)
							(mid -0.249642 -0.249642)
							(end -0.1778 -0.2794)
						)
						(arc
							(start 0.1778 -0.2794)
							(mid 0.249642 -0.249642)
							(end 0.2794 -0.1778)
						)
						(arc
							(start 0.2794 0.1778)
							(mid 0.249642 0.249642)
							(end 0.1778 0.2794)
						)
					)
					(width 0)
					(fill yes)
				)
			)
		)
	)
	(footprint ""
		(layer "B.Cu")
		(at 24.139144 -133.671564 90)
		(property "Reference" "R351"
			(at 0 0 90)
			(layer "B.SilkS")
			(hide yes)
			(effects
				(font
					(size 1.27 1.27)
				)
				(justify mirror)
			)
		)
		(property "Value" "3K3R2F-2-GP"
			(at -0.064008 -3.993896 90)
			(unlocked yes)
			(layer "B.Fab")
			(hide yes)
			(effects
				(font
					(size 1.016 1.016)
					(thickness 0.1524)
				)
				(justify mirror)
			)
		)
		(property "Device Type" "R402H16"
			(at -0.064008 -5.517896 90)
			(unlocked yes)
			(layer "B.Fab")
			(hide yes)
			(effects
				(font
					(size 1.016 1.016)
					(thickness 0.1524)
				)
				(justify mirror)
			)
		)
		(duplicate_pad_numbers_are_jumpers no)
		(fp_line
			(start 0.508 -0.9398)
			(end 0.508 0.9398)
			(stroke
				(width 0.1524)
				(type default)
			)
			(layer "B.SilkS")
		)
		(fp_line
			(start -0.508 -0.9398)
			(end 0.508 -0.9398)
			(stroke
				(width 0.1524)
				(type default)
			)
			(layer "B.SilkS")
		)
		(fp_rect
			(start 0.508 0.9398)
			(end -0.508 -0.9398)
			(stroke
				(width 0)
				(type default)
			)
			(fill no)
			(layer "B.CrtYd")
		)
		(fp_rect
			(start 0.508 0.9398)
			(end -0.508 -0.9398)
			(stroke
				(width 0)
				(type default)
			)
			(fill no)
			(layer "B.Fab")
		)
		(pad "1" smd custom
			(at 0 -0.4445 270)
			(size 0.1397 0.1397)
			(layers "B.Cu" "B.Mask" "B.Paste")
			(net "P3V3_STBY")
			(options
				(clearance outline)
				(anchor circle)
			)
			(primitives
				(gr_poly
					(pts
						(arc
							(start -0.1778 0.2794)
							(mid -0.249642 0.249642)
							(end -0.2794 0.1778)
						)
						(arc
							(start -0.2794 -0.1778)
							(mid -0.249642 -0.249642)
							(end -0.1778 -0.2794)
						)
						(arc
							(start 0.1778 -0.2794)
							(mid 0.249642 -0.249642)
							(end 0.2794 -0.1778)
						)
						(arc
							(start 0.2794 0.1778)
							(mid 0.249642 0.249642)
							(end 0.1778 0.2794)
						)
					)
					(width 0)
					(fill yes)
				)
			)
		)
		(pad "2" smd custom
			(at 0 0.4445 270)
			(size 0.1397 0.1397)
			(layers "B.Cu" "B.Mask" "B.Paste")
			(net "ROMA3")
			(options
				(clearance outline)
				(anchor circle)
			)
			(primitives
				(gr_poly
					(pts
						(arc
							(start -0.1778 0.2794)
							(mid -0.249642 0.249642)
							(end -0.2794 0.1778)
						)
						(arc
							(start -0.2794 -0.1778)
							(mid -0.249642 -0.249642)
							(end -0.1778 -0.2794)
						)
						(arc
							(start 0.1778 -0.2794)
							(mid 0.249642 -0.249642)
							(end 0.2794 -0.1778)
						)
						(arc
							(start 0.2794 0.1778)
							(mid 0.249642 0.249642)
							(end 0.1778 0.2794)
						)
					)
					(width 0)
					(fill yes)
				)
			)
		)
	)
	(footprint ""
		(layer "B.Cu")
		(at 233.8832 -36.4236)
		(property "Reference" "TP122"
			(at 0 0 0)
			(layer "B.SilkS")
			(hide yes)
			(effects
				(font
					(size 1.27 1.27)
				)
				(justify mirror)
			)
		)
		(property "Value" "TPAD28-2-GP"
			(at 0.0127 -1.6637 0)
			(unlocked yes)
			(layer "B.Fab")
			(hide yes)
			(effects
				(font
					(size 1.016 1.016)
					(thickness 0.1524)
				)
				(justify mirror)
			)
		)
		(property "Device Type" "TPAD28"
			(at 0.0127 -3.1877 0)
			(unlocked yes)
			(layer "B.Fab")
			(hide yes)
			(effects
				(font
					(size 1.016 1.016)
					(thickness 0.1524)
				)
				(justify mirror)
			)
		)
		(duplicate_pad_numbers_are_jumpers no)
		(fp_poly
			(pts
				(arc
					(start 0.3556 0)
					(mid -0.3556 0)
					(end 0.3556 0)
				)
			)
			(stroke
				(width 0)
				(type default)
			)
			(fill no)
			(layer "B.CrtYd")
		)
		(fp_poly
			(pts
				(arc
					(start 0.6096 0)
					(mid -0.6096 0)
					(end 0.6096 0)
				)
			)
			(stroke
				(width 0)
				(type default)
			)
			(fill no)
			(layer "B.Fab")
		)
		(pad "1" smd circle
			(at 0 0 180)
			(size 0.7112 0.7112)
			(layers "B.Cu" "B.Mask" "B.Paste")
			(net "LBI_ADDR_10")
		)
	)
	(footprint ""
		(layer "B.Cu")
		(at 19.9136 -186.2582 -90)
		(property "Reference" "R2119"
			(at 0 0 90)
			(layer "B.SilkS")
			(hide yes)
			(effects
				(font
					(size 1.27 1.27)
				)
				(justify mirror)
			)
		)
		(property "Value" "10R2F-L-GP"
			(at -0.064008 -3.993896 270)
			(unlocked yes)
			(layer "B.Fab")
			(hide yes)
			(effects
				(font
					(size 1.016 1.016)
					(thickness 0.1524)
				)
				(justify mirror)
			)
		)
		(property "Device Type" "R402H14"
			(at -0.064008 -5.517896 270)
			(unlocked yes)
			(layer "B.Fab")
			(hide yes)
			(effects
				(font
					(size 1.016 1.016)
					(thickness 0.1524)
				)
				(justify mirror)
			)
		)
		(duplicate_pad_numbers_are_jumpers no)
		(fp_line
			(start -0.508 -0.9398)
			(end 0.508 -0.9398)
			(stroke
				(width 0.1524)
				(type default)
			)
			(layer "B.SilkS")
		)
		(fp_line
			(start 0.508 -0.9398)
			(end 0.508 0.9398)
			(stroke
				(width 0.1524)
				(type default)
			)
			(layer "B.SilkS")
		)
		(fp_rect
			(start 0.508 0.9398)
			(end -0.508 -0.9398)
			(stroke
				(width 0)
				(type default)
			)
			(fill no)
			(layer "B.CrtYd")
		)
		(fp_rect
			(start 0.508 0.9398)
			(end -0.508 -0.9398)
			(stroke
				(width 0)
				(type default)
			)
			(fill no)
			(layer "B.Fab")
		)
		(pad "1" smd custom
			(at 0 -0.4445 90)
			(size 0.1397 0.1397)
			(layers "B.Cu" "B.Mask" "B.Paste")
			(net "MB0_CM_SENSE_R1_P")
			(options
				(clearance outline)
				(anchor circle)
			)
			(primitives
				(gr_poly
					(pts
						(arc
							(start -0.1778 0.2794)
							(mid -0.249642 0.249642)
							(end -0.2794 0.1778)
						)
						(arc
							(start -0.2794 -0.1778)
							(mid -0.249642 -0.249642)
							(end -0.1778 -0.2794)
						)
						(arc
							(start 0.1778 -0.2794)
							(mid 0.249642 -0.249642)
							(end 0.2794 -0.1778)
						)
						(arc
							(start 0.2794 0.1778)
							(mid 0.249642 0.249642)
							(end 0.1778 0.2794)
						)
					)
					(width 0)
					(fill yes)
				)
			)
		)
		(pad "2" smd custom
			(at 0 0.4445 90)
			(size 0.1397 0.1397)
			(layers "B.Cu" "B.Mask" "B.Paste")
			(net "MB0_CM_SENSE_P")
			(options
				(clearance outline)
				(anchor circle)
			)
			(primitives
				(gr_poly
					(pts
						(arc
							(start -0.1778 0.2794)
							(mid -0.249642 0.249642)
							(end -0.2794 0.1778)
						)
						(arc
							(start -0.2794 -0.1778)
							(mid -0.249642 -0.249642)
							(end -0.1778 -0.2794)
						)
						(arc
							(start 0.1778 -0.2794)
							(mid 0.249642 -0.249642)
							(end 0.2794 -0.1778)
						)
						(arc
							(start 0.2794 0.1778)
							(mid 0.249642 0.249642)
							(end 0.1778 0.2794)
						)
					)
					(width 0)
					(fill yes)
				)
			)
		)
	)
	(footprint ""
		(layer "B.Cu")
		(at 38.062154 -158.987744 180)
		(property "Reference" "C171"
			(at 0 0 0)
			(layer "B.SilkS")
			(hide yes)
			(effects
				(font
					(size 1.27 1.27)
				)
				(justify mirror)
			)
		)
		(property "Value" "SCD1U16V2KX-3GP"
			(at -1.1811 -2.7051 180)
			(unlocked yes)
			(layer "B.Fab")
			(hide yes)
			(effects
				(font
					(size 1.016 1.016)
					(thickness 0.1524)
				)
				(justify mirror)
			)
		)
		(property "Device Type" "C402H22"
			(at -1.1811 -4.2291 180)
			(unlocked yes)
			(layer "B.Fab")
			(hide yes)
			(effects
				(font
					(size 1.016 1.016)
					(thickness 0.1524)
				)
				(justify mirror)
			)
		)
		(duplicate_pad_numbers_are_jumpers no)
		(fp_rect
			(start 0.4318 0.9525)
			(end -0.4318 -0.9525)
			(stroke
				(width 0)
				(type default)
			)
			(fill no)
			(layer "B.CrtYd")
		)
		(fp_rect
			(start 0.4318 0.9525)
			(end -0.4318 -0.9525)
			(stroke
				(width 0)
				(type default)
			)
			(fill no)
			(layer "B.Fab")
		)
		(pad "1" smd custom
			(at 0 -0.4445)
			(size 0.1524 0.1524)
			(layers "B.Cu" "B.Mask" "B.Paste")
			(net "P1V53_STBY")
			(options
				(clearance outline)
				(anchor circle)
			)
			(primitives
				(gr_poly
					(pts
						(arc
							(start 0.3048 0.2032)
							(mid 0.275042 0.275042)
							(end 0.2032 0.3048)
						)
						(arc
							(start -0.2032 0.3048)
							(mid -0.275042 0.275042)
							(end -0.3048 0.2032)
						)
						(arc
							(start -0.3048 -0.2032)
							(mid -0.275042 -0.275042)
							(end -0.2032 -0.3048)
						)
						(arc
							(start 0.2032 -0.3048)
							(mid 0.275042 -0.275042)
							(end 0.3048 -0.2032)
						)
					)
					(width 0)
					(fill yes)
				)
			)
		)
		(pad "2" smd custom
			(at 0 0.4445)
			(size 0.1524 0.1524)
			(layers "B.Cu" "B.Mask" "B.Paste")
			(net "GND")
			(options
				(clearance outline)
				(anchor circle)
			)
			(primitives
				(gr_poly
					(pts
						(arc
							(start 0.3048 0.2032)
							(mid 0.275042 0.275042)
							(end 0.2032 0.3048)
						)
						(arc
							(start -0.2032 0.3048)
							(mid -0.275042 0.275042)
							(end -0.3048 0.2032)
						)
						(arc
							(start -0.3048 -0.2032)
							(mid -0.275042 -0.275042)
							(end -0.2032 -0.3048)
						)
						(arc
							(start 0.2032 -0.3048)
							(mid 0.275042 -0.275042)
							(end 0.3048 -0.2032)
						)
					)
					(width 0)
					(fill yes)
				)
			)
		)
	)
	(footprint ""
		(layer "B.Cu")
		(at 223.1644 -199.898)
		(property "Reference" "R3226"
			(at 0 0 0)
			(layer "B.SilkS")
			(hide yes)
			(effects
				(font
					(size 1.27 1.27)
				)
				(justify mirror)
			)
		)
		(property "Value" "0R2J-2-GP"
			(at -0.064008 -3.993896 0)
			(unlocked yes)
			(layer "B.Fab")
			(hide yes)
			(effects
				(font
					(size 1.016 1.016)
					(thickness 0.1524)
				)
				(justify mirror)
			)
		)
		(property "Device Type" "R402H16"
			(at -0.064008 -5.517896 0)
			(unlocked yes)
			(layer "B.Fab")
			(hide yes)
			(effects
				(font
					(size 1.016 1.016)
					(thickness 0.1524)
				)
				(justify mirror)
			)
		)
		(duplicate_pad_numbers_are_jumpers no)
		(fp_line
			(start -0.508 -0.9398)
			(end 0.508 -0.9398)
			(stroke
				(width 0.1524)
				(type default)
			)
			(layer "B.SilkS")
		)
		(fp_line
			(start 0.508 -0.9398)
			(end 0.508 0.9398)
			(stroke
				(width 0.1524)
				(type default)
			)
			(layer "B.SilkS")
		)
		(fp_rect
			(start 0.508 0.9398)
			(end -0.508 -0.9398)
			(stroke
				(width 0)
				(type default)
			)
			(fill no)
			(layer "B.CrtYd")
		)
		(fp_rect
			(start 0.508 0.9398)
			(end -0.508 -0.9398)
			(stroke
				(width 0)
				(type default)
			)
			(fill no)
			(layer "B.Fab")
		)
		(pad "1" smd custom
			(at 0 -0.4445 180)
			(size 0.1397 0.1397)
			(layers "B.Cu" "B.Mask" "B.Paste")
			(net "BMC_SSD_RST#8")
			(options
				(clearance outline)
				(anchor circle)
			)
			(primitives
				(gr_poly
					(pts
						(arc
							(start -0.1778 0.2794)
							(mid -0.249642 0.249642)
							(end -0.2794 0.1778)
						)
						(arc
							(start -0.2794 -0.1778)
							(mid -0.249642 -0.249642)
							(end -0.1778 -0.2794)
						)
						(arc
							(start 0.1778 -0.2794)
							(mid 0.249642 -0.249642)
							(end 0.2794 -0.1778)
						)
						(arc
							(start 0.2794 0.1778)
							(mid 0.249642 0.249642)
							(end 0.1778 0.2794)
						)
					)
					(width 0)
					(fill yes)
				)
			)
		)
		(pad "2" smd custom
			(at 0 0.4445 180)
			(size 0.1397 0.1397)
			(layers "B.Cu" "B.Mask" "B.Paste")
			(net "BMC_SSD_RST#0_A8")
			(options
				(clearance outline)
				(anchor circle)
			)
			(primitives
				(gr_poly
					(pts
						(arc
							(start -0.1778 0.2794)
							(mid -0.249642 0.249642)
							(end -0.2794 0.1778)
						)
						(arc
							(start -0.2794 -0.1778)
							(mid -0.249642 -0.249642)
							(end -0.1778 -0.2794)
						)
						(arc
							(start 0.1778 -0.2794)
							(mid 0.249642 -0.249642)
							(end 0.2794 -0.1778)
						)
						(arc
							(start 0.2794 0.1778)
							(mid 0.249642 0.249642)
							(end 0.1778 0.2794)
						)
					)
					(width 0)
					(fill yes)
				)
			)
		)
	)
	(footprint ""
		(layer "B.Cu")
		(at 247.599962 -35.999928)
		(property "Reference" "TP290"
			(at 0 0 0)
			(layer "B.SilkS")
			(hide yes)
			(effects
				(font
					(size 1.27 1.27)
				)
				(justify mirror)
			)
		)
		(property "Value" "TPAD28-2-GP"
			(at 0.0127 -1.6637 0)
			(unlocked yes)
			(layer "B.Fab")
			(hide yes)
			(effects
				(font
					(size 1.016 1.016)
					(thickness 0.1524)
				)
				(justify mirror)
			)
		)
		(property "Device Type" "TPAD28"
			(at 0.0127 -3.1877 0)
			(unlocked yes)
			(layer "B.Fab")
			(hide yes)
			(effects
				(font
					(size 1.016 1.016)
					(thickness 0.1524)
				)
				(justify mirror)
			)
		)
		(duplicate_pad_numbers_are_jumpers no)
		(fp_poly
			(pts
				(arc
					(start 0.3556 0)
					(mid -0.3556 0)
					(end 0.3556 0)
				)
			)
			(stroke
				(width 0)
				(type default)
			)
			(fill no)
			(layer "B.CrtYd")
		)
		(fp_poly
			(pts
				(arc
					(start 0.6096 0)
					(mid -0.6096 0)
					(end 0.6096 0)
				)
			)
			(stroke
				(width 0)
				(type default)
			)
			(fill no)
			(layer "B.Fab")
		)
		(pad "1" smd circle
			(at 0 0 180)
			(size 0.7112 0.7112)
			(layers "B.Cu" "B.Mask" "B.Paste")
			(net "TWI_SDA6")
		)
	)
	(footprint ""
		(layer "B.Cu")
		(at 64.135 -122.301 90)
		(property "Reference" "R245"
			(at 0 0 90)
			(layer "B.SilkS")
			(hide yes)
			(effects
				(font
					(size 1.27 1.27)
				)
				(justify mirror)
			)
		)
		(property "Value" "0R2J-2-GP"
			(at -0.064008 -3.993896 90)
			(unlocked yes)
			(layer "B.Fab")
			(hide yes)
			(effects
				(font
					(size 1.016 1.016)
					(thickness 0.1524)
				)
				(justify mirror)
			)
		)
		(property "Device Type" "R402H16"
			(at -0.064008 -5.517896 90)
			(unlocked yes)
			(layer "B.Fab")
			(hide yes)
			(effects
				(font
					(size 1.016 1.016)
					(thickness 0.1524)
				)
				(justify mirror)
			)
		)
		(duplicate_pad_numbers_are_jumpers no)
		(fp_line
			(start 0.508 -0.9398)
			(end 0.508 0.9398)
			(stroke
				(width 0.1524)
				(type default)
			)
			(layer "B.SilkS")
		)
		(fp_line
			(start -0.508 -0.9398)
			(end 0.508 -0.9398)
			(stroke
				(width 0.1524)
				(type default)
			)
			(layer "B.SilkS")
		)
		(fp_rect
			(start 0.508 0.9398)
			(end -0.508 -0.9398)
			(stroke
				(width 0)
				(type default)
			)
			(fill no)
			(layer "B.CrtYd")
		)
		(fp_rect
			(start 0.508 0.9398)
			(end -0.508 -0.9398)
			(stroke
				(width 0)
				(type default)
			)
			(fill no)
			(layer "B.Fab")
		)
		(pad "1" smd custom
			(at 0 -0.4445 270)
			(size 0.1397 0.1397)
			(layers "B.Cu" "B.Mask" "B.Paste")
			(net "BMC_I2C4_MINI4_SDA_S")
			(options
				(clearance outline)
				(anchor circle)
			)
			(primitives
				(gr_poly
					(pts
						(arc
							(start -0.1778 0.2794)
							(mid -0.249642 0.249642)
							(end -0.2794 0.1778)
						)
						(arc
							(start -0.2794 -0.1778)
							(mid -0.249642 -0.249642)
							(end -0.1778 -0.2794)
						)
						(arc
							(start 0.1778 -0.2794)
							(mid 0.249642 -0.249642)
							(end 0.2794 -0.1778)
						)
						(arc
							(start 0.2794 0.1778)
							(mid 0.249642 0.249642)
							(end 0.1778 0.2794)
						)
					)
					(width 0)
					(fill yes)
				)
			)
		)
		(pad "2" smd custom
			(at 0 0.4445 270)
			(size 0.1397 0.1397)
			(layers "B.Cu" "B.Mask" "B.Paste")
			(net "BMC0_SMB4_DAT")
			(options
				(clearance outline)
				(anchor circle)
			)
			(primitives
				(gr_poly
					(pts
						(arc
							(start -0.1778 0.2794)
							(mid -0.249642 0.249642)
							(end -0.2794 0.1778)
						)
						(arc
							(start -0.2794 -0.1778)
							(mid -0.249642 -0.249642)
							(end -0.1778 -0.2794)
						)
						(arc
							(start 0.1778 -0.2794)
							(mid 0.249642 -0.249642)
							(end 0.2794 -0.1778)
						)
						(arc
							(start 0.2794 0.1778)
							(mid 0.249642 0.249642)
							(end 0.1778 0.2794)
						)
					)
					(width 0)
					(fill yes)
				)
			)
		)
	)
	(footprint ""
		(layer "B.Cu")
		(at 236.601 -37.0078 180)
		(property "Reference" "R7"
			(at 0 0 0)
			(layer "B.SilkS")
			(hide yes)
			(effects
				(font
					(size 1.27 1.27)
				)
				(justify mirror)
			)
		)
		(property "Value" "33R1J-GP"
			(at 3.3274 -1.3335 180)
			(unlocked yes)
			(layer "B.Fab")
			(hide yes)
			(effects
				(font
					(size 1.016 1.016)
					(thickness 0.1524)
				)
				(justify mirror)
			)
		)
		(property "Device Type" "R0201H12"
			(at 3.3274 -2.8575 180)
			(unlocked yes)
			(layer "B.Fab")
			(hide yes)
			(effects
				(font
					(size 1.016 1.016)
					(thickness 0.1524)
				)
				(justify mirror)
			)
		)
		(duplicate_pad_numbers_are_jumpers no)
		(fp_rect
			(start 0.2794 0.6477)
			(end -0.2794 -0.6477)
			(stroke
				(width 0)
				(type default)
			)
			(fill no)
			(layer "B.CrtYd")
		)
		(fp_rect
			(start 0.2794 0.6477)
			(end -0.2794 -0.6477)
			(stroke
				(width 0)
				(type default)
			)
			(fill no)
			(layer "B.Fab")
		)
		(pad "1" smd custom
			(at 0 -0.2794)
			(size 0.0762 0.0762)
			(layers "B.Cu" "B.Mask" "B.Paste")
			(net "PCIE_REFCLK_H1_N")
			(options
				(clearance outline)
				(anchor circle)
			)
			(primitives
				(gr_poly
					(pts
						(arc
							(start 0.1524 0.127)
							(mid 0.137521 0.162921)
							(end 0.1016 0.1778)
						)
						(arc
							(start -0.1016 0.1778)
							(mid -0.137521 0.162921)
							(end -0.1524 0.127)
						)
						(arc
							(start -0.1524 -0.127)
							(mid -0.137521 -0.162921)
							(end -0.1016 -0.1778)
						)
						(arc
							(start 0.1016 -0.1778)
							(mid 0.137521 -0.162921)
							(end 0.1524 -0.127)
						)
					)
					(width 0)
					(fill yes)
				)
			)
		)
		(pad "2" smd custom
			(at 0 0.2794)
			(size 0.0762 0.0762)
			(layers "B.Cu" "B.Mask" "B.Paste")
			(net "PCIE_REFCLK_H1_P")
			(options
				(clearance outline)
				(anchor circle)
			)
			(primitives
				(gr_poly
					(pts
						(arc
							(start 0.1524 0.127)
							(mid 0.137521 0.162921)
							(end 0.1016 0.1778)
						)
						(arc
							(start -0.1016 0.1778)
							(mid -0.137521 0.162921)
							(end -0.1524 0.127)
						)
						(arc
							(start -0.1524 -0.127)
							(mid -0.137521 -0.162921)
							(end -0.1016 -0.1778)
						)
						(arc
							(start 0.1016 -0.1778)
							(mid 0.137521 -0.162921)
							(end 0.1524 -0.127)
						)
					)
					(width 0)
					(fill yes)
				)
			)
		)
	)
	(footprint ""
		(layer "B.Cu")
		(at 178.0794 -67.691)
		(property "Reference" "PG25"
			(at 0 0 0)
			(layer "B.SilkS")
			(hide yes)
			(effects
				(font
					(size 1.27 1.27)
				)
				(justify mirror)
			)
		)
		(property "Value" "GAP-CLOSE-PWR-3-GP"
			(at -0.0254 -6.5786 0)
			(unlocked yes)
			(layer "B.Fab")
			(hide yes)
			(effects
				(font
					(size 1.016 1.016)
					(thickness 0.1524)
				)
				(justify mirror)
			)
		)
		(property "Device Type" "GAP-CLOSE-PWR-3"
			(at -0.0254 -8.255 0)
			(unlocked yes)
			(layer "B.Fab")
			(hide yes)
			(effects
				(font
					(size 1.016 1.016)
					(thickness 0.1524)
				)
				(justify mirror)
			)
		)
		(duplicate_pad_numbers_are_jumpers no)
		(fp_rect
			(start 0.7112 0.4572)
			(end -0.7112 -0.4572)
			(stroke
				(width 0)
				(type default)
			)
			(fill no)
			(layer "B.CrtYd")
		)
		(fp_poly
			(pts
				(xy 0.7112 -0.4572) (xy -0.7112 -0.4572) (xy -0.7112 0.4572) (xy 0.7112 0.4572)
			)
			(stroke
				(width 0)
				(type default)
			)
			(fill no)
			(layer "B.Fab")
		)
		(pad "1" smd rect
			(at 0.3048 0 180)
			(size 0.6604 0.762)
			(layers "B.Cu" "B.Mask" "B.Paste")
			(net "DUT_AVD_PCIE")
		)
		(pad "2" smd rect
			(at -0.3048 0 180)
			(size 0.6604 0.762)
			(layers "B.Cu" "B.Mask" "B.Paste")
			(net "P0V9")
		)
	)
	(footprint ""
		(layer "B.Cu")
		(at 235.966 -23.241 180)
		(property "Reference" "R786"
			(at 0 0 0)
			(layer "B.SilkS")
			(hide yes)
			(effects
				(font
					(size 1.27 1.27)
				)
				(justify mirror)
			)
		)
		(property "Value" "4K7R2F-GP"
			(at -0.064008 -3.993896 180)
			(unlocked yes)
			(layer "B.Fab")
			(hide yes)
			(effects
				(font
					(size 1.016 1.016)
					(thickness 0.1524)
				)
				(justify mirror)
			)
		)
		(property "Device Type" "R402H16"
			(at -0.064008 -5.517896 180)
			(unlocked yes)
			(layer "B.Fab")
			(hide yes)
			(effects
				(font
					(size 1.016 1.016)
					(thickness 0.1524)
				)
				(justify mirror)
			)
		)
		(duplicate_pad_numbers_are_jumpers no)
		(fp_line
			(start 0.508 -0.9398)
			(end 0.508 0.9398)
			(stroke
				(width 0.1524)
				(type default)
			)
			(layer "B.SilkS")
		)
		(fp_line
			(start -0.508 -0.9398)
			(end 0.508 -0.9398)
			(stroke
				(width 0.1524)
				(type default)
			)
			(layer "B.SilkS")
		)
		(fp_rect
			(start 0.508 0.9398)
			(end -0.508 -0.9398)
			(stroke
				(width 0)
				(type default)
			)
			(fill no)
			(layer "B.CrtYd")
		)
		(fp_rect
			(start 0.508 0.9398)
			(end -0.508 -0.9398)
			(stroke
				(width 0)
				(type default)
			)
			(fill no)
			(layer "B.Fab")
		)
		(pad "1" smd custom
			(at 0 -0.4445)
			(size 0.1397 0.1397)
			(layers "B.Cu" "B.Mask" "B.Paste")
			(net "BOOTSTRAP6")
			(options
				(clearance outline)
				(anchor circle)
			)
			(primitives
				(gr_poly
					(pts
						(arc
							(start -0.1778 0.2794)
							(mid -0.249642 0.249642)
							(end -0.2794 0.1778)
						)
						(arc
							(start -0.2794 -0.1778)
							(mid -0.249642 -0.249642)
							(end -0.1778 -0.2794)
						)
						(arc
							(start 0.1778 -0.2794)
							(mid 0.249642 -0.249642)
							(end 0.2794 -0.1778)
						)
						(arc
							(start 0.2794 0.1778)
							(mid 0.249642 0.249642)
							(end 0.1778 0.2794)
						)
					)
					(width 0)
					(fill yes)
				)
			)
		)
		(pad "2" smd custom
			(at 0 0.4445)
			(size 0.1397 0.1397)
			(layers "B.Cu" "B.Mask" "B.Paste")
			(net "BOOTSTRAP_R_6")
			(options
				(clearance outline)
				(anchor circle)
			)
			(primitives
				(gr_poly
					(pts
						(arc
							(start -0.1778 0.2794)
							(mid -0.249642 0.249642)
							(end -0.2794 0.1778)
						)
						(arc
							(start -0.2794 -0.1778)
							(mid -0.249642 -0.249642)
							(end -0.1778 -0.2794)
						)
						(arc
							(start 0.1778 -0.2794)
							(mid 0.249642 -0.249642)
							(end 0.2794 -0.1778)
						)
						(arc
							(start 0.2794 0.1778)
							(mid 0.249642 0.249642)
							(end 0.1778 0.2794)
						)
					)
					(width 0)
					(fill yes)
				)
			)
		)
	)
	(footprint ""
		(layer "B.Cu")
		(at 247.1166 -43.997372 -90)
		(property "Reference" "C449"
			(at 0 0 90)
			(layer "B.SilkS")
			(hide yes)
			(effects
				(font
					(size 1.27 1.27)
				)
				(justify mirror)
			)
		)
		(property "Value" "SCD1U16V1KX-1-GP"
			(at 2.8321 -1.7399 270)
			(unlocked yes)
			(layer "B.Fab")
			(hide yes)
			(effects
				(font
					(size 1.016 1.016)
					(thickness 0.1524)
				)
				(justify mirror)
			)
		)
		(property "Device Type" "C0201H13"
			(at 2.8321 -3.2639 270)
			(unlocked yes)
			(layer "B.Fab")
			(hide yes)
			(effects
				(font
					(size 1.016 1.016)
					(thickness 0.1524)
				)
				(justify mirror)
			)
		)
		(duplicate_pad_numbers_are_jumpers no)
		(fp_rect
			(start 0.2794 0.6477)
			(end -0.2794 -0.6477)
			(stroke
				(width 0)
				(type default)
			)
			(fill no)
			(layer "B.CrtYd")
		)
		(fp_rect
			(start 0.2794 0.6477)
			(end -0.2794 -0.6477)
			(stroke
				(width 0)
				(type default)
			)
			(fill no)
			(layer "B.Fab")
		)
		(pad "1" smd custom
			(at 0 -0.2794 90)
			(size 0.0762 0.0762)
			(layers "B.Cu" "B.Mask" "B.Paste")
			(net "DUT_VDD")
			(options
				(clearance outline)
				(anchor circle)
			)
			(primitives
				(gr_poly
					(pts
						(arc
							(start 0.1524 0.127)
							(mid 0.137521 0.162921)
							(end 0.1016 0.1778)
						)
						(arc
							(start -0.1016 0.1778)
							(mid -0.137521 0.162921)
							(end -0.1524 0.127)
						)
						(arc
							(start -0.1524 -0.127)
							(mid -0.137521 -0.162921)
							(end -0.1016 -0.1778)
						)
						(arc
							(start 0.1016 -0.1778)
							(mid 0.137521 -0.162921)
							(end 0.1524 -0.127)
						)
					)
					(width 0)
					(fill yes)
				)
			)
		)
		(pad "2" smd custom
			(at 0 0.2794 90)
			(size 0.0762 0.0762)
			(layers "B.Cu" "B.Mask" "B.Paste")
			(net "GND")
			(options
				(clearance outline)
				(anchor circle)
			)
			(primitives
				(gr_poly
					(pts
						(arc
							(start 0.1524 0.127)
							(mid 0.137521 0.162921)
							(end 0.1016 0.1778)
						)
						(arc
							(start -0.1016 0.1778)
							(mid -0.137521 0.162921)
							(end -0.1524 0.127)
						)
						(arc
							(start -0.1524 -0.127)
							(mid -0.137521 -0.162921)
							(end -0.1016 -0.1778)
						)
						(arc
							(start 0.1016 -0.1778)
							(mid 0.137521 -0.162921)
							(end 0.1524 -0.127)
						)
					)
					(width 0)
					(fill yes)
				)
			)
		)
	)
	(footprint ""
		(layer "B.Cu")
		(at 143.002508 -34.44113 180)
		(property "Reference" "C225"
			(at 0 0 0)
			(layer "B.SilkS")
			(hide yes)
			(effects
				(font
					(size 1.27 1.27)
				)
				(justify mirror)
			)
		)
		(property "Value" "SCD1U10V2KX-5GP"
			(at -1.1811 -2.7051 180)
			(unlocked yes)
			(layer "B.Fab")
			(hide yes)
			(effects
				(font
					(size 1.016 1.016)
					(thickness 0.1524)
				)
				(justify mirror)
			)
		)
		(property "Device Type" "C402H22"
			(at -1.1811 -4.2291 180)
			(unlocked yes)
			(layer "B.Fab")
			(hide yes)
			(effects
				(font
					(size 1.016 1.016)
					(thickness 0.1524)
				)
				(justify mirror)
			)
		)
		(duplicate_pad_numbers_are_jumpers no)
		(fp_rect
			(start 0.4318 0.9525)
			(end -0.4318 -0.9525)
			(stroke
				(width 0)
				(type default)
			)
			(fill no)
			(layer "B.CrtYd")
		)
		(fp_rect
			(start 0.4318 0.9525)
			(end -0.4318 -0.9525)
			(stroke
				(width 0)
				(type default)
			)
			(fill no)
			(layer "B.Fab")
		)
		(pad "1" smd custom
			(at 0 -0.4445)
			(size 0.1524 0.1524)
			(layers "B.Cu" "B.Mask" "B.Paste")
			(net "GND")
			(options
				(clearance outline)
				(anchor circle)
			)
			(primitives
				(gr_poly
					(pts
						(arc
							(start 0.3048 0.2032)
							(mid 0.275042 0.275042)
							(end 0.2032 0.3048)
						)
						(arc
							(start -0.2032 0.3048)
							(mid -0.275042 0.275042)
							(end -0.3048 0.2032)
						)
						(arc
							(start -0.3048 -0.2032)
							(mid -0.275042 -0.275042)
							(end -0.2032 -0.3048)
						)
						(arc
							(start 0.2032 -0.3048)
							(mid 0.275042 -0.275042)
							(end 0.3048 -0.2032)
						)
					)
					(width 0)
					(fill yes)
				)
			)
		)
		(pad "2" smd custom
			(at 0 0.4445)
			(size 0.1524 0.1524)
			(layers "B.Cu" "B.Mask" "B.Paste")
			(net "P3V3_STBY")
			(options
				(clearance outline)
				(anchor circle)
			)
			(primitives
				(gr_poly
					(pts
						(arc
							(start 0.3048 0.2032)
							(mid 0.275042 0.275042)
							(end 0.2032 0.3048)
						)
						(arc
							(start -0.2032 0.3048)
							(mid -0.275042 0.275042)
							(end -0.3048 0.2032)
						)
						(arc
							(start -0.3048 -0.2032)
							(mid -0.275042 -0.275042)
							(end -0.2032 -0.3048)
						)
						(arc
							(start 0.2032 -0.3048)
							(mid 0.275042 -0.275042)
							(end 0.3048 -0.2032)
						)
					)
					(width 0)
					(fill yes)
				)
			)
		)
	)
	(footprint ""
		(layer "B.Cu")
		(at 241.2238 -28.6766)
		(property "Reference" "TP263"
			(at 0 0 0)
			(layer "B.SilkS")
			(hide yes)
			(effects
				(font
					(size 1.27 1.27)
				)
				(justify mirror)
			)
		)
		(property "Value" "TPAD28-2-GP"
			(at 0.0127 -1.6637 0)
			(unlocked yes)
			(layer "B.Fab")
			(hide yes)
			(effects
				(font
					(size 1.016 1.016)
					(thickness 0.1524)
				)
				(justify mirror)
			)
		)
		(property "Device Type" "TPAD28"
			(at 0.0127 -3.1877 0)
			(unlocked yes)
			(layer "B.Fab")
			(hide yes)
			(effects
				(font
					(size 1.016 1.016)
					(thickness 0.1524)
				)
				(justify mirror)
			)
		)
		(duplicate_pad_numbers_are_jumpers no)
		(fp_poly
			(pts
				(arc
					(start 0.3556 0)
					(mid -0.3556 0)
					(end 0.3556 0)
				)
			)
			(stroke
				(width 0)
				(type default)
			)
			(fill no)
			(layer "B.CrtYd")
		)
		(fp_poly
			(pts
				(arc
					(start 0.6096 0)
					(mid -0.6096 0)
					(end 0.6096 0)
				)
			)
			(stroke
				(width 0)
				(type default)
			)
			(fill no)
			(layer "B.Fab")
		)
		(pad "1" smd circle
			(at 0 0 180)
			(size 0.7112 0.7112)
			(layers "B.Cu" "B.Mask" "B.Paste")
			(net "LBI_DATA_5")
		)
	)
	(footprint ""
		(layer "B.Cu")
		(at 39.54272 -114.53622 180)
		(property "Reference" "R444"
			(at 0 0 0)
			(layer "B.SilkS")
			(hide yes)
			(effects
				(font
					(size 1.27 1.27)
				)
				(justify mirror)
			)
		)
		(property "Value" "0R2J-2-GP"
			(at -0.064008 -3.993896 180)
			(unlocked yes)
			(layer "B.Fab")
			(hide yes)
			(effects
				(font
					(size 1.016 1.016)
					(thickness 0.1524)
				)
				(justify mirror)
			)
		)
		(property "Device Type" "R402H16"
			(at -0.064008 -5.517896 180)
			(unlocked yes)
			(layer "B.Fab")
			(hide yes)
			(effects
				(font
					(size 1.016 1.016)
					(thickness 0.1524)
				)
				(justify mirror)
			)
		)
		(duplicate_pad_numbers_are_jumpers no)
		(fp_line
			(start 0.508 -0.9398)
			(end 0.508 0.9398)
			(stroke
				(width 0.1524)
				(type default)
			)
			(layer "B.SilkS")
		)
		(fp_line
			(start -0.508 -0.9398)
			(end 0.508 -0.9398)
			(stroke
				(width 0.1524)
				(type default)
			)
			(layer "B.SilkS")
		)
		(fp_rect
			(start 0.508 0.9398)
			(end -0.508 -0.9398)
			(stroke
				(width 0)
				(type default)
			)
			(fill no)
			(layer "B.CrtYd")
		)
		(fp_rect
			(start 0.508 0.9398)
			(end -0.508 -0.9398)
			(stroke
				(width 0)
				(type default)
			)
			(fill no)
			(layer "B.Fab")
		)
		(pad "1" smd custom
			(at 0 -0.4445)
			(size 0.1397 0.1397)
			(layers "B.Cu" "B.Mask" "B.Paste")
			(net "GND")
			(options
				(clearance outline)
				(anchor circle)
			)
			(primitives
				(gr_poly
					(pts
						(arc
							(start -0.1778 0.2794)
							(mid -0.249642 0.249642)
							(end -0.2794 0.1778)
						)
						(arc
							(start -0.2794 -0.1778)
							(mid -0.249642 -0.249642)
							(end -0.1778 -0.2794)
						)
						(arc
							(start 0.1778 -0.2794)
							(mid 0.249642 -0.249642)
							(end 0.2794 -0.1778)
						)
						(arc
							(start 0.2794 0.1778)
							(mid 0.249642 0.249642)
							(end 0.1778 0.2794)
						)
					)
					(width 0)
					(fill yes)
				)
			)
		)
		(pad "2" smd custom
			(at 0 0.4445)
			(size 0.1397 0.1397)
			(layers "B.Cu" "B.Mask" "B.Paste")
			(net "RMII_PHY_BMC_RXD1")
			(options
				(clearance outline)
				(anchor circle)
			)
			(primitives
				(gr_poly
					(pts
						(arc
							(start -0.1778 0.2794)
							(mid -0.249642 0.249642)
							(end -0.2794 0.1778)
						)
						(arc
							(start -0.2794 -0.1778)
							(mid -0.249642 -0.249642)
							(end -0.1778 -0.2794)
						)
						(arc
							(start 0.1778 -0.2794)
							(mid 0.249642 -0.249642)
							(end 0.2794 -0.1778)
						)
						(arc
							(start 0.2794 0.1778)
							(mid 0.249642 0.249642)
							(end 0.1778 0.2794)
						)
					)
					(width 0)
					(fill yes)
				)
			)
		)
	)
	(footprint ""
		(layer "B.Cu")
		(at 59.2074 -128.524 90)
		(property "Reference" "R456"
			(at 0 0 90)
			(layer "B.SilkS")
			(hide yes)
			(effects
				(font
					(size 1.27 1.27)
				)
				(justify mirror)
			)
		)
		(property "Value" "4K7R2F-GP"
			(at -0.064008 -3.993896 90)
			(unlocked yes)
			(layer "B.Fab")
			(hide yes)
			(effects
				(font
					(size 1.016 1.016)
					(thickness 0.1524)
				)
				(justify mirror)
			)
		)
		(property "Device Type" "R402H16"
			(at -0.064008 -5.517896 90)
			(unlocked yes)
			(layer "B.Fab")
			(hide yes)
			(effects
				(font
					(size 1.016 1.016)
					(thickness 0.1524)
				)
				(justify mirror)
			)
		)
		(duplicate_pad_numbers_are_jumpers no)
		(fp_line
			(start 0.508 -0.9398)
			(end 0.508 0.9398)
			(stroke
				(width 0.1524)
				(type default)
			)
			(layer "B.SilkS")
		)
		(fp_line
			(start -0.508 -0.9398)
			(end 0.508 -0.9398)
			(stroke
				(width 0.1524)
				(type default)
			)
			(layer "B.SilkS")
		)
		(fp_rect
			(start 0.508 0.9398)
			(end -0.508 -0.9398)
			(stroke
				(width 0)
				(type default)
			)
			(fill no)
			(layer "B.CrtYd")
		)
		(fp_rect
			(start 0.508 0.9398)
			(end -0.508 -0.9398)
			(stroke
				(width 0)
				(type default)
			)
			(fill no)
			(layer "B.Fab")
		)
		(pad "1" smd custom
			(at 0 -0.4445 270)
			(size 0.1397 0.1397)
			(layers "B.Cu" "B.Mask" "B.Paste")
			(net "BMC_I2C14_MINI8_SCL_S")
			(options
				(clearance outline)
				(anchor circle)
			)
			(primitives
				(gr_poly
					(pts
						(arc
							(start -0.1778 0.2794)
							(mid -0.249642 0.249642)
							(end -0.2794 0.1778)
						)
						(arc
							(start -0.2794 -0.1778)
							(mid -0.249642 -0.249642)
							(end -0.1778 -0.2794)
						)
						(arc
							(start 0.1778 -0.2794)
							(mid 0.249642 -0.249642)
							(end 0.2794 -0.1778)
						)
						(arc
							(start 0.2794 0.1778)
							(mid 0.249642 0.249642)
							(end 0.1778 0.2794)
						)
					)
					(width 0)
					(fill yes)
				)
			)
		)
		(pad "2" smd custom
			(at 0 0.4445 270)
			(size 0.1397 0.1397)
			(layers "B.Cu" "B.Mask" "B.Paste")
			(net "P3V3_STBY")
			(options
				(clearance outline)
				(anchor circle)
			)
			(primitives
				(gr_poly
					(pts
						(arc
							(start -0.1778 0.2794)
							(mid -0.249642 0.249642)
							(end -0.2794 0.1778)
						)
						(arc
							(start -0.2794 -0.1778)
							(mid -0.249642 -0.249642)
							(end -0.1778 -0.2794)
						)
						(arc
							(start 0.1778 -0.2794)
							(mid 0.249642 -0.249642)
							(end 0.2794 -0.1778)
						)
						(arc
							(start 0.2794 0.1778)
							(mid 0.249642 0.249642)
							(end 0.1778 0.2794)
						)
					)
					(width 0)
					(fill yes)
				)
			)
		)
	)
	(footprint ""
		(layer "B.Cu")
		(at 213.614 -197.231)
		(property "Reference" "R271"
			(at 0 0 0)
			(layer "B.SilkS")
			(hide yes)
			(effects
				(font
					(size 1.27 1.27)
				)
				(justify mirror)
			)
		)
		(property "Value" "4K7R2F-GP"
			(at -0.064008 -3.993896 0)
			(unlocked yes)
			(layer "B.Fab")
			(hide yes)
			(effects
				(font
					(size 1.016 1.016)
					(thickness 0.1524)
				)
				(justify mirror)
			)
		)
		(property "Device Type" "R402H16"
			(at -0.064008 -5.517896 0)
			(unlocked yes)
			(layer "B.Fab")
			(hide yes)
			(effects
				(font
					(size 1.016 1.016)
					(thickness 0.1524)
				)
				(justify mirror)
			)
		)
		(duplicate_pad_numbers_are_jumpers no)
		(fp_line
			(start -0.508 -0.9398)
			(end 0.508 -0.9398)
			(stroke
				(width 0.1524)
				(type default)
			)
			(layer "B.SilkS")
		)
		(fp_line
			(start 0.508 -0.9398)
			(end 0.508 0.9398)
			(stroke
				(width 0.1524)
				(type default)
			)
			(layer "B.SilkS")
		)
		(fp_rect
			(start 0.508 0.9398)
			(end -0.508 -0.9398)
			(stroke
				(width 0)
				(type default)
			)
			(fill no)
			(layer "B.CrtYd")
		)
		(fp_rect
			(start 0.508 0.9398)
			(end -0.508 -0.9398)
			(stroke
				(width 0)
				(type default)
			)
			(fill no)
			(layer "B.Fab")
		)
		(pad "1" smd custom
			(at 0 -0.4445 180)
			(size 0.1397 0.1397)
			(layers "B.Cu" "B.Mask" "B.Paste")
			(net "BMC_SSD_RST#0_A13")
			(options
				(clearance outline)
				(anchor circle)
			)
			(primitives
				(gr_poly
					(pts
						(arc
							(start -0.1778 0.2794)
							(mid -0.249642 0.249642)
							(end -0.2794 0.1778)
						)
						(arc
							(start -0.2794 -0.1778)
							(mid -0.249642 -0.249642)
							(end -0.1778 -0.2794)
						)
						(arc
							(start 0.1778 -0.2794)
							(mid 0.249642 -0.249642)
							(end 0.2794 -0.1778)
						)
						(arc
							(start 0.2794 0.1778)
							(mid 0.249642 0.249642)
							(end 0.1778 0.2794)
						)
					)
					(width 0)
					(fill yes)
				)
			)
		)
		(pad "2" smd custom
			(at 0 0.4445 180)
			(size 0.1397 0.1397)
			(layers "B.Cu" "B.Mask" "B.Paste")
			(net "P3V3_STBY")
			(options
				(clearance outline)
				(anchor circle)
			)
			(primitives
				(gr_poly
					(pts
						(arc
							(start -0.1778 0.2794)
							(mid -0.249642 0.249642)
							(end -0.2794 0.1778)
						)
						(arc
							(start -0.2794 -0.1778)
							(mid -0.249642 -0.249642)
							(end -0.1778 -0.2794)
						)
						(arc
							(start 0.1778 -0.2794)
							(mid 0.249642 -0.249642)
							(end 0.2794 -0.1778)
						)
						(arc
							(start 0.2794 0.1778)
							(mid 0.249642 0.249642)
							(end 0.1778 0.2794)
						)
					)
					(width 0)
					(fill yes)
				)
			)
		)
	)
	(footprint ""
		(layer "B.Cu")
		(at 13.507212 -74.913236 90)
		(property "Reference" "C629"
			(at 0 0 90)
			(layer "B.SilkS")
			(hide yes)
			(effects
				(font
					(size 1.27 1.27)
				)
				(justify mirror)
			)
		)
		(property "Value" "SCD1U16V2KX-3GP"
			(at -1.1811 -2.7051 90)
			(unlocked yes)
			(layer "B.Fab")
			(hide yes)
			(effects
				(font
					(size 1.016 1.016)
					(thickness 0.1524)
				)
				(justify mirror)
			)
		)
		(property "Device Type" "C402H22"
			(at -1.1811 -4.2291 90)
			(unlocked yes)
			(layer "B.Fab")
			(hide yes)
			(effects
				(font
					(size 1.016 1.016)
					(thickness 0.1524)
				)
				(justify mirror)
			)
		)
		(duplicate_pad_numbers_are_jumpers no)
		(fp_rect
			(start 0.4318 0.9525)
			(end -0.4318 -0.9525)
			(stroke
				(width 0)
				(type default)
			)
			(fill no)
			(layer "B.CrtYd")
		)
		(fp_rect
			(start 0.4318 0.9525)
			(end -0.4318 -0.9525)
			(stroke
				(width 0)
				(type default)
			)
			(fill no)
			(layer "B.Fab")
		)
		(pad "1" smd custom
			(at 0 -0.4445 270)
			(size 0.1524 0.1524)
			(layers "B.Cu" "B.Mask" "B.Paste")
			(net "P3V3_STBY")
			(options
				(clearance outline)
				(anchor circle)
			)
			(primitives
				(gr_poly
					(pts
						(arc
							(start 0.3048 0.2032)
							(mid 0.275042 0.275042)
							(end 0.2032 0.3048)
						)
						(arc
							(start -0.2032 0.3048)
							(mid -0.275042 0.275042)
							(end -0.3048 0.2032)
						)
						(arc
							(start -0.3048 -0.2032)
							(mid -0.275042 -0.275042)
							(end -0.2032 -0.3048)
						)
						(arc
							(start 0.2032 -0.3048)
							(mid 0.275042 -0.275042)
							(end 0.3048 -0.2032)
						)
					)
					(width 0)
					(fill yes)
				)
			)
		)
		(pad "2" smd custom
			(at 0 0.4445 270)
			(size 0.1524 0.1524)
			(layers "B.Cu" "B.Mask" "B.Paste")
			(net "GND")
			(options
				(clearance outline)
				(anchor circle)
			)
			(primitives
				(gr_poly
					(pts
						(arc
							(start 0.3048 0.2032)
							(mid 0.275042 0.275042)
							(end 0.2032 0.3048)
						)
						(arc
							(start -0.2032 0.3048)
							(mid -0.275042 0.275042)
							(end -0.3048 0.2032)
						)
						(arc
							(start -0.3048 -0.2032)
							(mid -0.275042 -0.275042)
							(end -0.2032 -0.3048)
						)
						(arc
							(start 0.2032 -0.3048)
							(mid 0.275042 -0.275042)
							(end 0.3048 -0.2032)
						)
					)
					(width 0)
					(fill yes)
				)
			)
		)
	)
	(footprint ""
		(layer "B.Cu")
		(at 127.972058 -33.503616 180)
		(property "Reference" "C220"
			(at 0 0 0)
			(layer "B.SilkS")
			(hide yes)
			(effects
				(font
					(size 1.27 1.27)
				)
				(justify mirror)
			)
		)
		(property "Value" "SCD1U10V2KX-5GP"
			(at -1.1811 -2.7051 180)
			(unlocked yes)
			(layer "B.Fab")
			(hide yes)
			(effects
				(font
					(size 1.016 1.016)
					(thickness 0.1524)
				)
				(justify mirror)
			)
		)
		(property "Device Type" "C402H22"
			(at -1.1811 -4.2291 180)
			(unlocked yes)
			(layer "B.Fab")
			(hide yes)
			(effects
				(font
					(size 1.016 1.016)
					(thickness 0.1524)
				)
				(justify mirror)
			)
		)
		(duplicate_pad_numbers_are_jumpers no)
		(fp_rect
			(start 0.4318 0.9525)
			(end -0.4318 -0.9525)
			(stroke
				(width 0)
				(type default)
			)
			(fill no)
			(layer "B.CrtYd")
		)
		(fp_rect
			(start 0.4318 0.9525)
			(end -0.4318 -0.9525)
			(stroke
				(width 0)
				(type default)
			)
			(fill no)
			(layer "B.Fab")
		)
		(pad "1" smd custom
			(at 0 -0.4445)
			(size 0.1524 0.1524)
			(layers "B.Cu" "B.Mask" "B.Paste")
			(net "GND")
			(options
				(clearance outline)
				(anchor circle)
			)
			(primitives
				(gr_poly
					(pts
						(arc
							(start 0.3048 0.2032)
							(mid 0.275042 0.275042)
							(end 0.2032 0.3048)
						)
						(arc
							(start -0.2032 0.3048)
							(mid -0.275042 0.275042)
							(end -0.3048 0.2032)
						)
						(arc
							(start -0.3048 -0.2032)
							(mid -0.275042 -0.275042)
							(end -0.2032 -0.3048)
						)
						(arc
							(start 0.2032 -0.3048)
							(mid 0.275042 -0.275042)
							(end 0.3048 -0.2032)
						)
					)
					(width 0)
					(fill yes)
				)
			)
		)
		(pad "2" smd custom
			(at 0 0.4445)
			(size 0.1524 0.1524)
			(layers "B.Cu" "B.Mask" "B.Paste")
			(net "P3V3_STBY")
			(options
				(clearance outline)
				(anchor circle)
			)
			(primitives
				(gr_poly
					(pts
						(arc
							(start 0.3048 0.2032)
							(mid 0.275042 0.275042)
							(end 0.2032 0.3048)
						)
						(arc
							(start -0.2032 0.3048)
							(mid -0.275042 0.275042)
							(end -0.3048 0.2032)
						)
						(arc
							(start -0.3048 -0.2032)
							(mid -0.275042 -0.275042)
							(end -0.2032 -0.3048)
						)
						(arc
							(start 0.2032 -0.3048)
							(mid 0.275042 -0.275042)
							(end 0.3048 -0.2032)
						)
					)
					(width 0)
					(fill yes)
				)
			)
		)
	)
	(footprint ""
		(layer "B.Cu")
		(at 18.3642 -138.6078 90)
		(property "Reference" "R2978"
			(at 0 0 90)
			(layer "B.SilkS")
			(hide yes)
			(effects
				(font
					(size 1.27 1.27)
				)
				(justify mirror)
			)
		)
		(property "Value" "10KR2F-2-GP"
			(at -0.064008 -3.993896 90)
			(unlocked yes)
			(layer "B.Fab")
			(hide yes)
			(effects
				(font
					(size 1.016 1.016)
					(thickness 0.1524)
				)
				(justify mirror)
			)
		)
		(property "Device Type" "R402H16"
			(at -0.064008 -5.517896 90)
			(unlocked yes)
			(layer "B.Fab")
			(hide yes)
			(effects
				(font
					(size 1.016 1.016)
					(thickness 0.1524)
				)
				(justify mirror)
			)
		)
		(duplicate_pad_numbers_are_jumpers no)
		(fp_line
			(start 0.508 -0.9398)
			(end 0.508 0.9398)
			(stroke
				(width 0.1524)
				(type default)
			)
			(layer "B.SilkS")
		)
		(fp_line
			(start -0.508 -0.9398)
			(end 0.508 -0.9398)
			(stroke
				(width 0.1524)
				(type default)
			)
			(layer "B.SilkS")
		)
		(fp_rect
			(start 0.508 0.9398)
			(end -0.508 -0.9398)
			(stroke
				(width 0)
				(type default)
			)
			(fill no)
			(layer "B.CrtYd")
		)
		(fp_rect
			(start 0.508 0.9398)
			(end -0.508 -0.9398)
			(stroke
				(width 0)
				(type default)
			)
			(fill no)
			(layer "B.Fab")
		)
		(pad "1" smd custom
			(at 0 -0.4445 270)
			(size 0.1397 0.1397)
			(layers "B.Cu" "B.Mask" "B.Paste")
			(net "P3V3_STBY")
			(options
				(clearance outline)
				(anchor circle)
			)
			(primitives
				(gr_poly
					(pts
						(arc
							(start -0.1778 0.2794)
							(mid -0.249642 0.249642)
							(end -0.2794 0.1778)
						)
						(arc
							(start -0.2794 -0.1778)
							(mid -0.249642 -0.249642)
							(end -0.1778 -0.2794)
						)
						(arc
							(start 0.1778 -0.2794)
							(mid 0.249642 -0.249642)
							(end 0.2794 -0.1778)
						)
						(arc
							(start 0.2794 0.1778)
							(mid 0.249642 0.249642)
							(end 0.1778 0.2794)
						)
					)
					(width 0)
					(fill yes)
				)
			)
		)
		(pad "2" smd custom
			(at 0 0.4445 270)
			(size 0.1397 0.1397)
			(layers "B.Cu" "B.Mask" "B.Paste")
			(net "BP_PRSNT_N")
			(options
				(clearance outline)
				(anchor circle)
			)
			(primitives
				(gr_poly
					(pts
						(arc
							(start -0.1778 0.2794)
							(mid -0.249642 0.249642)
							(end -0.2794 0.1778)
						)
						(arc
							(start -0.2794 -0.1778)
							(mid -0.249642 -0.249642)
							(end -0.1778 -0.2794)
						)
						(arc
							(start 0.1778 -0.2794)
							(mid 0.249642 -0.249642)
							(end 0.2794 -0.1778)
						)
						(arc
							(start 0.2794 0.1778)
							(mid 0.249642 0.249642)
							(end 0.1778 0.2794)
						)
					)
					(width 0)
					(fill yes)
				)
			)
		)
	)
	(footprint ""
		(layer "B.Cu")
		(at 241.6048 -37.0586 180)
		(property "Reference" "R6"
			(at 0 0 0)
			(layer "B.SilkS")
			(hide yes)
			(effects
				(font
					(size 1.27 1.27)
				)
				(justify mirror)
			)
		)
		(property "Value" "33R1J-GP"
			(at 3.3274 -1.3335 180)
			(unlocked yes)
			(layer "B.Fab")
			(hide yes)
			(effects
				(font
					(size 1.016 1.016)
					(thickness 0.1524)
				)
				(justify mirror)
			)
		)
		(property "Device Type" "R0201H12"
			(at 3.3274 -2.8575 180)
			(unlocked yes)
			(layer "B.Fab")
			(hide yes)
			(effects
				(font
					(size 1.016 1.016)
					(thickness 0.1524)
				)
				(justify mirror)
			)
		)
		(duplicate_pad_numbers_are_jumpers no)
		(fp_rect
			(start 0.2794 0.6477)
			(end -0.2794 -0.6477)
			(stroke
				(width 0)
				(type default)
			)
			(fill no)
			(layer "B.CrtYd")
		)
		(fp_rect
			(start 0.2794 0.6477)
			(end -0.2794 -0.6477)
			(stroke
				(width 0)
				(type default)
			)
			(fill no)
			(layer "B.Fab")
		)
		(pad "1" smd custom
			(at 0 -0.2794)
			(size 0.0762 0.0762)
			(layers "B.Cu" "B.Mask" "B.Paste")
			(net "PCIE_REFCLK_H0_N")
			(options
				(clearance outline)
				(anchor circle)
			)
			(primitives
				(gr_poly
					(pts
						(arc
							(start 0.1524 0.127)
							(mid 0.137521 0.162921)
							(end 0.1016 0.1778)
						)
						(arc
							(start -0.1016 0.1778)
							(mid -0.137521 0.162921)
							(end -0.1524 0.127)
						)
						(arc
							(start -0.1524 -0.127)
							(mid -0.137521 -0.162921)
							(end -0.1016 -0.1778)
						)
						(arc
							(start 0.1016 -0.1778)
							(mid 0.137521 -0.162921)
							(end 0.1524 -0.127)
						)
					)
					(width 0)
					(fill yes)
				)
			)
		)
		(pad "2" smd custom
			(at 0 0.2794)
			(size 0.0762 0.0762)
			(layers "B.Cu" "B.Mask" "B.Paste")
			(net "PCIE_REFCLK_H0_P")
			(options
				(clearance outline)
				(anchor circle)
			)
			(primitives
				(gr_poly
					(pts
						(arc
							(start 0.1524 0.127)
							(mid 0.137521 0.162921)
							(end 0.1016 0.1778)
						)
						(arc
							(start -0.1016 0.1778)
							(mid -0.137521 0.162921)
							(end -0.1524 0.127)
						)
						(arc
							(start -0.1524 -0.127)
							(mid -0.137521 -0.162921)
							(end -0.1016 -0.1778)
						)
						(arc
							(start 0.1016 -0.1778)
							(mid 0.137521 -0.162921)
							(end 0.1524 -0.127)
						)
					)
					(width 0)
					(fill yes)
				)
			)
		)
	)
	(footprint ""
		(layer "B.Cu")
		(at 321.673728 -38.896798)
		(property "Reference" "C254"
			(at 0 0 0)
			(layer "B.SilkS")
			(hide yes)
			(effects
				(font
					(size 1.27 1.27)
				)
				(justify mirror)
			)
		)
		(property "Value" "SCD1U10V2KX-5GP"
			(at -1.1811 -2.7051 0)
			(unlocked yes)
			(layer "B.Fab")
			(hide yes)
			(effects
				(font
					(size 1.016 1.016)
					(thickness 0.1524)
				)
				(justify mirror)
			)
		)
		(property "Device Type" "C402H22"
			(at -1.1811 -4.2291 0)
			(unlocked yes)
			(layer "B.Fab")
			(hide yes)
			(effects
				(font
					(size 1.016 1.016)
					(thickness 0.1524)
				)
				(justify mirror)
			)
		)
		(duplicate_pad_numbers_are_jumpers no)
		(fp_rect
			(start 0.4318 0.9525)
			(end -0.4318 -0.9525)
			(stroke
				(width 0)
				(type default)
			)
			(fill no)
			(layer "B.CrtYd")
		)
		(fp_rect
			(start 0.4318 0.9525)
			(end -0.4318 -0.9525)
			(stroke
				(width 0)
				(type default)
			)
			(fill no)
			(layer "B.Fab")
		)
		(pad "1" smd custom
			(at 0 -0.4445 180)
			(size 0.1524 0.1524)
			(layers "B.Cu" "B.Mask" "B.Paste")
			(net "GND")
			(options
				(clearance outline)
				(anchor circle)
			)
			(primitives
				(gr_poly
					(pts
						(arc
							(start 0.3048 0.2032)
							(mid 0.275042 0.275042)
							(end 0.2032 0.3048)
						)
						(arc
							(start -0.2032 0.3048)
							(mid -0.275042 0.275042)
							(end -0.3048 0.2032)
						)
						(arc
							(start -0.3048 -0.2032)
							(mid -0.275042 -0.275042)
							(end -0.2032 -0.3048)
						)
						(arc
							(start 0.2032 -0.3048)
							(mid 0.275042 -0.275042)
							(end 0.3048 -0.2032)
						)
					)
					(width 0)
					(fill yes)
				)
			)
		)
		(pad "2" smd custom
			(at 0 0.4445 180)
			(size 0.1524 0.1524)
			(layers "B.Cu" "B.Mask" "B.Paste")
			(net "P3V3_STBY")
			(options
				(clearance outline)
				(anchor circle)
			)
			(primitives
				(gr_poly
					(pts
						(arc
							(start 0.3048 0.2032)
							(mid 0.275042 0.275042)
							(end 0.2032 0.3048)
						)
						(arc
							(start -0.2032 0.3048)
							(mid -0.275042 0.275042)
							(end -0.3048 0.2032)
						)
						(arc
							(start -0.3048 -0.2032)
							(mid -0.275042 -0.275042)
							(end -0.2032 -0.3048)
						)
						(arc
							(start 0.2032 -0.3048)
							(mid 0.275042 -0.275042)
							(end 0.3048 -0.2032)
						)
					)
					(width 0)
					(fill yes)
				)
			)
		)
	)
	(footprint ""
		(layer "B.Cu")
		(at 223.393 -20.447)
		(property "Reference" "R3708"
			(at 0 0 0)
			(layer "B.SilkS")
			(hide yes)
			(effects
				(font
					(size 1.27 1.27)
				)
				(justify mirror)
			)
		)
		(property "Value" "4K7R2F-GP"
			(at -0.064008 -3.993896 0)
			(unlocked yes)
			(layer "B.Fab")
			(hide yes)
			(effects
				(font
					(size 1.016 1.016)
					(thickness 0.1524)
				)
				(justify mirror)
			)
		)
		(property "Device Type" "R402H16"
			(at -0.064008 -5.517896 0)
			(unlocked yes)
			(layer "B.Fab")
			(hide yes)
			(effects
				(font
					(size 1.016 1.016)
					(thickness 0.1524)
				)
				(justify mirror)
			)
		)
		(duplicate_pad_numbers_are_jumpers no)
		(fp_line
			(start -0.508 -0.9398)
			(end 0.508 -0.9398)
			(stroke
				(width 0.1524)
				(type default)
			)
			(layer "B.SilkS")
		)
		(fp_line
			(start 0.508 -0.9398)
			(end 0.508 0.9398)
			(stroke
				(width 0.1524)
				(type default)
			)
			(layer "B.SilkS")
		)
		(fp_rect
			(start 0.508 0.9398)
			(end -0.508 -0.9398)
			(stroke
				(width 0)
				(type default)
			)
			(fill no)
			(layer "B.CrtYd")
		)
		(fp_rect
			(start 0.508 0.9398)
			(end -0.508 -0.9398)
			(stroke
				(width 0)
				(type default)
			)
			(fill no)
			(layer "B.Fab")
		)
		(pad "1" smd custom
			(at 0 -0.4445 180)
			(size 0.1397 0.1397)
			(layers "B.Cu" "B.Mask" "B.Paste")
			(net "HOST7_RST_N_LS")
			(options
				(clearance outline)
				(anchor circle)
			)
			(primitives
				(gr_poly
					(pts
						(arc
							(start -0.1778 0.2794)
							(mid -0.249642 0.249642)
							(end -0.2794 0.1778)
						)
						(arc
							(start -0.2794 -0.1778)
							(mid -0.249642 -0.249642)
							(end -0.1778 -0.2794)
						)
						(arc
							(start 0.1778 -0.2794)
							(mid 0.249642 -0.249642)
							(end 0.2794 -0.1778)
						)
						(arc
							(start 0.2794 0.1778)
							(mid 0.249642 0.249642)
							(end 0.1778 0.2794)
						)
					)
					(width 0)
					(fill yes)
				)
			)
		)
		(pad "2" smd custom
			(at 0 0.4445 180)
			(size 0.1397 0.1397)
			(layers "B.Cu" "B.Mask" "B.Paste")
			(net "DUT_VDDO")
			(options
				(clearance outline)
				(anchor circle)
			)
			(primitives
				(gr_poly
					(pts
						(arc
							(start -0.1778 0.2794)
							(mid -0.249642 0.249642)
							(end -0.2794 0.1778)
						)
						(arc
							(start -0.2794 -0.1778)
							(mid -0.249642 -0.249642)
							(end -0.1778 -0.2794)
						)
						(arc
							(start 0.1778 -0.2794)
							(mid 0.249642 -0.249642)
							(end 0.2794 -0.1778)
						)
						(arc
							(start 0.2794 0.1778)
							(mid 0.249642 0.249642)
							(end 0.1778 0.2794)
						)
					)
					(width 0)
					(fill yes)
				)
			)
		)
	)
	(footprint ""
		(layer "B.Cu")
		(at 252.6538 -26.1112)
		(property "Reference" "R1"
			(at 0 0 0)
			(layer "B.SilkS")
			(hide yes)
			(effects
				(font
					(size 1.27 1.27)
				)
				(justify mirror)
			)
		)
		(property "Value" "0R2J-2-GP"
			(at -0.064008 -3.993896 0)
			(unlocked yes)
			(layer "B.Fab")
			(hide yes)
			(effects
				(font
					(size 1.016 1.016)
					(thickness 0.1524)
				)
				(justify mirror)
			)
		)
		(property "Device Type" "R402H16"
			(at -0.064008 -5.517896 0)
			(unlocked yes)
			(layer "B.Fab")
			(hide yes)
			(effects
				(font
					(size 1.016 1.016)
					(thickness 0.1524)
				)
				(justify mirror)
			)
		)
		(duplicate_pad_numbers_are_jumpers no)
		(fp_line
			(start -0.508 -0.9398)
			(end 0.508 -0.9398)
			(stroke
				(width 0.1524)
				(type default)
			)
			(layer "B.SilkS")
		)
		(fp_line
			(start 0.508 -0.9398)
			(end 0.508 0.9398)
			(stroke
				(width 0.1524)
				(type default)
			)
			(layer "B.SilkS")
		)
		(fp_rect
			(start 0.508 0.9398)
			(end -0.508 -0.9398)
			(stroke
				(width 0)
				(type default)
			)
			(fill no)
			(layer "B.CrtYd")
		)
		(fp_rect
			(start 0.508 0.9398)
			(end -0.508 -0.9398)
			(stroke
				(width 0)
				(type default)
			)
			(fill no)
			(layer "B.Fab")
		)
		(pad "1" smd custom
			(at 0 -0.4445 180)
			(size 0.1397 0.1397)
			(layers "B.Cu" "B.Mask" "B.Paste")
			(net "AVS_ENB_R")
			(options
				(clearance outline)
				(anchor circle)
			)
			(primitives
				(gr_poly
					(pts
						(arc
							(start -0.1778 0.2794)
							(mid -0.249642 0.249642)
							(end -0.2794 0.1778)
						)
						(arc
							(start -0.2794 -0.1778)
							(mid -0.249642 -0.249642)
							(end -0.1778 -0.2794)
						)
						(arc
							(start 0.1778 -0.2794)
							(mid 0.249642 -0.249642)
							(end 0.2794 -0.1778)
						)
						(arc
							(start 0.2794 0.1778)
							(mid 0.249642 0.249642)
							(end 0.1778 0.2794)
						)
					)
					(width 0)
					(fill yes)
				)
			)
		)
		(pad "2" smd custom
			(at 0 0.4445 180)
			(size 0.1397 0.1397)
			(layers "B.Cu" "B.Mask" "B.Paste")
			(net "AVS_ENB")
			(options
				(clearance outline)
				(anchor circle)
			)
			(primitives
				(gr_poly
					(pts
						(arc
							(start -0.1778 0.2794)
							(mid -0.249642 0.249642)
							(end -0.2794 0.1778)
						)
						(arc
							(start -0.2794 -0.1778)
							(mid -0.249642 -0.249642)
							(end -0.1778 -0.2794)
						)
						(arc
							(start 0.1778 -0.2794)
							(mid 0.249642 -0.249642)
							(end 0.2794 -0.1778)
						)
						(arc
							(start 0.2794 0.1778)
							(mid 0.249642 0.249642)
							(end 0.1778 0.2794)
						)
					)
					(width 0)
					(fill yes)
				)
			)
		)
	)
	(footprint ""
		(layer "B.Cu")
		(at 228.6254 -45.000672 90)
		(property "Reference" "C489"
			(at 0 0 90)
			(layer "B.SilkS")
			(hide yes)
			(effects
				(font
					(size 1.27 1.27)
				)
				(justify mirror)
			)
		)
		(property "Value" "SCD1U16V1KX-1-GP"
			(at 2.8321 -1.7399 90)
			(unlocked yes)
			(layer "B.Fab")
			(hide yes)
			(effects
				(font
					(size 1.016 1.016)
					(thickness 0.1524)
				)
				(justify mirror)
			)
		)
		(property "Device Type" "C0201H13"
			(at 2.8321 -3.2639 90)
			(unlocked yes)
			(layer "B.Fab")
			(hide yes)
			(effects
				(font
					(size 1.016 1.016)
					(thickness 0.1524)
				)
				(justify mirror)
			)
		)
		(duplicate_pad_numbers_are_jumpers no)
		(fp_rect
			(start 0.2794 0.6477)
			(end -0.2794 -0.6477)
			(stroke
				(width 0)
				(type default)
			)
			(fill no)
			(layer "B.CrtYd")
		)
		(fp_rect
			(start 0.2794 0.6477)
			(end -0.2794 -0.6477)
			(stroke
				(width 0)
				(type default)
			)
			(fill no)
			(layer "B.Fab")
		)
		(pad "1" smd custom
			(at 0 -0.2794 270)
			(size 0.0762 0.0762)
			(layers "B.Cu" "B.Mask" "B.Paste")
			(net "DUT_AVD_PCIE")
			(options
				(clearance outline)
				(anchor circle)
			)
			(primitives
				(gr_poly
					(pts
						(arc
							(start 0.1524 0.127)
							(mid 0.137521 0.162921)
							(end 0.1016 0.1778)
						)
						(arc
							(start -0.1016 0.1778)
							(mid -0.137521 0.162921)
							(end -0.1524 0.127)
						)
						(arc
							(start -0.1524 -0.127)
							(mid -0.137521 -0.162921)
							(end -0.1016 -0.1778)
						)
						(arc
							(start 0.1016 -0.1778)
							(mid 0.137521 -0.162921)
							(end 0.1524 -0.127)
						)
					)
					(width 0)
					(fill yes)
				)
			)
		)
		(pad "2" smd custom
			(at 0 0.2794 270)
			(size 0.0762 0.0762)
			(layers "B.Cu" "B.Mask" "B.Paste")
			(net "GND")
			(options
				(clearance outline)
				(anchor circle)
			)
			(primitives
				(gr_poly
					(pts
						(arc
							(start 0.1524 0.127)
							(mid 0.137521 0.162921)
							(end 0.1016 0.1778)
						)
						(arc
							(start -0.1016 0.1778)
							(mid -0.137521 0.162921)
							(end -0.1524 0.127)
						)
						(arc
							(start -0.1524 -0.127)
							(mid -0.137521 -0.162921)
							(end -0.1016 -0.1778)
						)
						(arc
							(start 0.1016 -0.1778)
							(mid 0.137521 -0.162921)
							(end 0.1524 -0.127)
						)
					)
					(width 0)
					(fill yes)
				)
			)
		)
	)
	(footprint ""
		(layer "B.Cu")
		(at 180.9242 -71.628 180)
		(property "Reference" "C618"
			(at 0 0 0)
			(layer "B.SilkS")
			(hide yes)
			(effects
				(font
					(size 1.27 1.27)
				)
				(justify mirror)
			)
		)
		(property "Value" "SC4D7U16V5KX-1-GP"
			(at 0.0762 -6.1214 180)
			(unlocked yes)
			(layer "B.Fab")
			(hide yes)
			(effects
				(font
					(size 1.016 1.016)
					(thickness 0.1524)
				)
				(justify mirror)
			)
		)
		(property "Device Type" "C805H56"
			(at 0.0762 -8.1534 180)
			(unlocked yes)
			(layer "B.Fab")
			(hide yes)
			(effects
				(font
					(size 1.016 1.016)
					(thickness 0.1524)
				)
				(justify mirror)
			)
		)
		(duplicate_pad_numbers_are_jumpers no)
		(fp_line
			(start -0.635 0)
			(end 0.635 0)
			(stroke
				(width 0.508)
				(type default)
			)
			(layer "B.SilkS")
		)
		(fp_rect
			(start 0.9652 1.778)
			(end -0.9652 -1.778)
			(stroke
				(width 0)
				(type default)
			)
			(fill no)
			(layer "B.CrtYd")
		)
		(fp_poly
			(pts
				(xy 0.9652 -1.778) (xy -0.9652 -1.778) (xy -0.9652 1.778) (xy 0.9652 1.778)
			)
			(stroke
				(width 0)
				(type default)
			)
			(fill no)
			(layer "B.Fab")
		)
		(pad "1" smd rect
			(at 0 -0.9652)
			(size 1.397 1.143)
			(layers "B.Cu" "B.Mask" "B.Paste")
			(net "DUT_AVD_PCIE")
		)
		(pad "2" smd rect
			(at 0 0.9652)
			(size 1.397 1.143)
			(layers "B.Cu" "B.Mask" "B.Paste")
			(net "GND")
		)
	)
	(footprint ""
		(layer "B.Cu")
		(at 20.400518 -125.497844 90)
		(property "Reference" "R241"
			(at 0 0 90)
			(layer "B.SilkS")
			(hide yes)
			(effects
				(font
					(size 1.27 1.27)
				)
				(justify mirror)
			)
		)
		(property "Value" "0R2J-2-GP"
			(at -0.064008 -3.993896 90)
			(unlocked yes)
			(layer "B.Fab")
			(hide yes)
			(effects
				(font
					(size 1.016 1.016)
					(thickness 0.1524)
				)
				(justify mirror)
			)
		)
		(property "Device Type" "R402H16"
			(at -0.064008 -5.517896 90)
			(unlocked yes)
			(layer "B.Fab")
			(hide yes)
			(effects
				(font
					(size 1.016 1.016)
					(thickness 0.1524)
				)
				(justify mirror)
			)
		)
		(duplicate_pad_numbers_are_jumpers no)
		(fp_line
			(start 0.508 -0.9398)
			(end 0.508 0.9398)
			(stroke
				(width 0.1524)
				(type default)
			)
			(layer "B.SilkS")
		)
		(fp_line
			(start -0.508 -0.9398)
			(end 0.508 -0.9398)
			(stroke
				(width 0.1524)
				(type default)
			)
			(layer "B.SilkS")
		)
		(fp_rect
			(start 0.508 0.9398)
			(end -0.508 -0.9398)
			(stroke
				(width 0)
				(type default)
			)
			(fill no)
			(layer "B.CrtYd")
		)
		(fp_rect
			(start 0.508 0.9398)
			(end -0.508 -0.9398)
			(stroke
				(width 0)
				(type default)
			)
			(fill no)
			(layer "B.Fab")
		)
		(pad "1" smd custom
			(at 0 -0.4445 270)
			(size 0.1397 0.1397)
			(layers "B.Cu" "B.Mask" "B.Paste")
			(net "BMC_I2C2_MINI2_SDA_S")
			(options
				(clearance outline)
				(anchor circle)
			)
			(primitives
				(gr_poly
					(pts
						(arc
							(start -0.1778 0.2794)
							(mid -0.249642 0.249642)
							(end -0.2794 0.1778)
						)
						(arc
							(start -0.2794 -0.1778)
							(mid -0.249642 -0.249642)
							(end -0.1778 -0.2794)
						)
						(arc
							(start 0.1778 -0.2794)
							(mid 0.249642 -0.249642)
							(end 0.2794 -0.1778)
						)
						(arc
							(start 0.2794 0.1778)
							(mid 0.249642 0.249642)
							(end 0.1778 0.2794)
						)
					)
					(width 0)
					(fill yes)
				)
			)
		)
		(pad "2" smd custom
			(at 0 0.4445 270)
			(size 0.1397 0.1397)
			(layers "B.Cu" "B.Mask" "B.Paste")
			(net "BMC0_SMB2_DAT")
			(options
				(clearance outline)
				(anchor circle)
			)
			(primitives
				(gr_poly
					(pts
						(arc
							(start -0.1778 0.2794)
							(mid -0.249642 0.249642)
							(end -0.2794 0.1778)
						)
						(arc
							(start -0.2794 -0.1778)
							(mid -0.249642 -0.249642)
							(end -0.1778 -0.2794)
						)
						(arc
							(start 0.1778 -0.2794)
							(mid 0.249642 -0.249642)
							(end 0.2794 -0.1778)
						)
						(arc
							(start 0.2794 0.1778)
							(mid 0.249642 0.249642)
							(end 0.1778 0.2794)
						)
					)
					(width 0)
					(fill yes)
				)
			)
		)
	)
	(footprint ""
		(layer "B.Cu")
		(at 225.114104 -203.710032 180)
		(property "Reference" "R4138"
			(at 0 0 0)
			(layer "B.SilkS")
			(hide yes)
			(effects
				(font
					(size 1.27 1.27)
				)
				(justify mirror)
			)
		)
		(property "Value" "4K7R2F-GP"
			(at -0.064008 -3.993896 180)
			(unlocked yes)
			(layer "B.Fab")
			(hide yes)
			(effects
				(font
					(size 1.016 1.016)
					(thickness 0.1524)
				)
				(justify mirror)
			)
		)
		(property "Device Type" "R402H16"
			(at -0.064008 -5.517896 180)
			(unlocked yes)
			(layer "B.Fab")
			(hide yes)
			(effects
				(font
					(size 1.016 1.016)
					(thickness 0.1524)
				)
				(justify mirror)
			)
		)
		(duplicate_pad_numbers_are_jumpers no)
		(fp_line
			(start 0.508 -0.9398)
			(end 0.508 0.9398)
			(stroke
				(width 0.1524)
				(type default)
			)
			(layer "B.SilkS")
		)
		(fp_line
			(start -0.508 -0.9398)
			(end 0.508 -0.9398)
			(stroke
				(width 0.1524)
				(type default)
			)
			(layer "B.SilkS")
		)
		(fp_rect
			(start 0.508 0.9398)
			(end -0.508 -0.9398)
			(stroke
				(width 0)
				(type default)
			)
			(fill no)
			(layer "B.CrtYd")
		)
		(fp_rect
			(start 0.508 0.9398)
			(end -0.508 -0.9398)
			(stroke
				(width 0)
				(type default)
			)
			(fill no)
			(layer "B.Fab")
		)
		(pad "1" smd custom
			(at 0 -0.4445)
			(size 0.1397 0.1397)
			(layers "B.Cu" "B.Mask" "B.Paste")
			(net "SSD_PERST#12")
			(options
				(clearance outline)
				(anchor circle)
			)
			(primitives
				(gr_poly
					(pts
						(arc
							(start -0.1778 0.2794)
							(mid -0.249642 0.249642)
							(end -0.2794 0.1778)
						)
						(arc
							(start -0.2794 -0.1778)
							(mid -0.249642 -0.249642)
							(end -0.1778 -0.2794)
						)
						(arc
							(start 0.1778 -0.2794)
							(mid 0.249642 -0.249642)
							(end 0.2794 -0.1778)
						)
						(arc
							(start 0.2794 0.1778)
							(mid 0.249642 0.249642)
							(end 0.1778 0.2794)
						)
					)
					(width 0)
					(fill yes)
				)
			)
		)
		(pad "2" smd custom
			(at 0 0.4445)
			(size 0.1397 0.1397)
			(layers "B.Cu" "B.Mask" "B.Paste")
			(net "P3V3_STBY")
			(options
				(clearance outline)
				(anchor circle)
			)
			(primitives
				(gr_poly
					(pts
						(arc
							(start -0.1778 0.2794)
							(mid -0.249642 0.249642)
							(end -0.2794 0.1778)
						)
						(arc
							(start -0.2794 -0.1778)
							(mid -0.249642 -0.249642)
							(end -0.1778 -0.2794)
						)
						(arc
							(start 0.1778 -0.2794)
							(mid 0.249642 -0.249642)
							(end 0.2794 -0.1778)
						)
						(arc
							(start 0.2794 0.1778)
							(mid 0.249642 0.249642)
							(end 0.1778 0.2794)
						)
					)
					(width 0)
					(fill yes)
				)
			)
		)
	)
	(footprint ""
		(layer "B.Cu")
		(at 53.721 -135.763 -90)
		(property "Reference" "R322"
			(at 0 0 90)
			(layer "B.SilkS")
			(hide yes)
			(effects
				(font
					(size 1.27 1.27)
				)
				(justify mirror)
			)
		)
		(property "Value" "0R2J-2-GP"
			(at -0.064008 -3.993896 270)
			(unlocked yes)
			(layer "B.Fab")
			(hide yes)
			(effects
				(font
					(size 1.016 1.016)
					(thickness 0.1524)
				)
				(justify mirror)
			)
		)
		(property "Device Type" "R402H16"
			(at -0.064008 -5.517896 270)
			(unlocked yes)
			(layer "B.Fab")
			(hide yes)
			(effects
				(font
					(size 1.016 1.016)
					(thickness 0.1524)
				)
				(justify mirror)
			)
		)
		(duplicate_pad_numbers_are_jumpers no)
		(fp_line
			(start -0.508 -0.9398)
			(end 0.508 -0.9398)
			(stroke
				(width 0.1524)
				(type default)
			)
			(layer "B.SilkS")
		)
		(fp_line
			(start 0.508 -0.9398)
			(end 0.508 0.9398)
			(stroke
				(width 0.1524)
				(type default)
			)
			(layer "B.SilkS")
		)
		(fp_rect
			(start 0.508 0.9398)
			(end -0.508 -0.9398)
			(stroke
				(width 0)
				(type default)
			)
			(fill no)
			(layer "B.CrtYd")
		)
		(fp_rect
			(start 0.508 0.9398)
			(end -0.508 -0.9398)
			(stroke
				(width 0)
				(type default)
			)
			(fill no)
			(layer "B.Fab")
		)
		(pad "1" smd custom
			(at 0 -0.4445 90)
			(size 0.1397 0.1397)
			(layers "B.Cu" "B.Mask" "B.Paste")
			(net "ADC_P0V9_E")
			(options
				(clearance outline)
				(anchor circle)
			)
			(primitives
				(gr_poly
					(pts
						(arc
							(start -0.1778 0.2794)
							(mid -0.249642 0.249642)
							(end -0.2794 0.1778)
						)
						(arc
							(start -0.2794 -0.1778)
							(mid -0.249642 -0.249642)
							(end -0.1778 -0.2794)
						)
						(arc
							(start 0.1778 -0.2794)
							(mid 0.249642 -0.249642)
							(end 0.2794 -0.1778)
						)
						(arc
							(start 0.2794 0.1778)
							(mid 0.249642 0.249642)
							(end 0.1778 0.2794)
						)
					)
					(width 0)
					(fill yes)
				)
			)
		)
		(pad "2" smd custom
			(at 0 0.4445 90)
			(size 0.1397 0.1397)
			(layers "B.Cu" "B.Mask" "B.Paste")
			(net "ADC_P0V9_E_BMC")
			(options
				(clearance outline)
				(anchor circle)
			)
			(primitives
				(gr_poly
					(pts
						(arc
							(start -0.1778 0.2794)
							(mid -0.249642 0.249642)
							(end -0.2794 0.1778)
						)
						(arc
							(start -0.2794 -0.1778)
							(mid -0.249642 -0.249642)
							(end -0.1778 -0.2794)
						)
						(arc
							(start 0.1778 -0.2794)
							(mid 0.249642 -0.249642)
							(end 0.2794 -0.1778)
						)
						(arc
							(start 0.2794 0.1778)
							(mid 0.249642 0.249642)
							(end 0.1778 0.2794)
						)
					)
					(width 0)
					(fill yes)
				)
			)
		)
	)
	(footprint ""
		(layer "B.Cu")
		(at 40.259 -133.223)
		(property "Reference" "C211"
			(at 0 0 0)
			(layer "B.SilkS")
			(hide yes)
			(effects
				(font
					(size 1.27 1.27)
				)
				(justify mirror)
			)
		)
		(property "Value" "SC220P50V2KX-3GP"
			(at -1.1811 -2.7051 0)
			(unlocked yes)
			(layer "B.Fab")
			(hide yes)
			(effects
				(font
					(size 1.016 1.016)
					(thickness 0.1524)
				)
				(justify mirror)
			)
		)
		(property "Device Type" "C402H22"
			(at -1.1811 -4.2291 0)
			(unlocked yes)
			(layer "B.Fab")
			(hide yes)
			(effects
				(font
					(size 1.016 1.016)
					(thickness 0.1524)
				)
				(justify mirror)
			)
		)
		(duplicate_pad_numbers_are_jumpers no)
		(fp_rect
			(start 0.4318 0.9525)
			(end -0.4318 -0.9525)
			(stroke
				(width 0)
				(type default)
			)
			(fill no)
			(layer "B.CrtYd")
		)
		(fp_rect
			(start 0.4318 0.9525)
			(end -0.4318 -0.9525)
			(stroke
				(width 0)
				(type default)
			)
			(fill no)
			(layer "B.Fab")
		)
		(pad "1" smd custom
			(at 0 -0.4445 180)
			(size 0.1524 0.1524)
			(layers "B.Cu" "B.Mask" "B.Paste")
			(net "P3V3_STBY")
			(options
				(clearance outline)
				(anchor circle)
			)
			(primitives
				(gr_poly
					(pts
						(arc
							(start 0.3048 0.2032)
							(mid 0.275042 0.275042)
							(end 0.2032 0.3048)
						)
						(arc
							(start -0.2032 0.3048)
							(mid -0.275042 0.275042)
							(end -0.3048 0.2032)
						)
						(arc
							(start -0.3048 -0.2032)
							(mid -0.275042 -0.275042)
							(end -0.2032 -0.3048)
						)
						(arc
							(start 0.2032 -0.3048)
							(mid 0.275042 -0.275042)
							(end 0.3048 -0.2032)
						)
					)
					(width 0)
					(fill yes)
				)
			)
		)
		(pad "2" smd custom
			(at 0 0.4445 180)
			(size 0.1524 0.1524)
			(layers "B.Cu" "B.Mask" "B.Paste")
			(net "GND")
			(options
				(clearance outline)
				(anchor circle)
			)
			(primitives
				(gr_poly
					(pts
						(arc
							(start 0.3048 0.2032)
							(mid 0.275042 0.275042)
							(end 0.2032 0.3048)
						)
						(arc
							(start -0.2032 0.3048)
							(mid -0.275042 0.275042)
							(end -0.3048 0.2032)
						)
						(arc
							(start -0.3048 -0.2032)
							(mid -0.275042 -0.275042)
							(end -0.2032 -0.3048)
						)
						(arc
							(start 0.2032 -0.3048)
							(mid 0.275042 -0.275042)
							(end 0.3048 -0.2032)
						)
					)
					(width 0)
					(fill yes)
				)
			)
		)
	)
	(footprint ""
		(layer "B.Cu")
		(at 219.964 -20.955 90)
		(property "Reference" "TP213"
			(at 0 0 90)
			(layer "B.SilkS")
			(hide yes)
			(effects
				(font
					(size 1.27 1.27)
				)
				(justify mirror)
			)
		)
		(property "Value" "TPAD28-2-GP"
			(at 0.0127 -1.6637 90)
			(unlocked yes)
			(layer "B.Fab")
			(hide yes)
			(effects
				(font
					(size 1.016 1.016)
					(thickness 0.1524)
				)
				(justify mirror)
			)
		)
		(property "Device Type" "TPAD28"
			(at 0.0127 -3.1877 90)
			(unlocked yes)
			(layer "B.Fab")
			(hide yes)
			(effects
				(font
					(size 1.016 1.016)
					(thickness 0.1524)
				)
				(justify mirror)
			)
		)
		(duplicate_pad_numbers_are_jumpers no)
		(fp_poly
			(pts
				(arc
					(start 0 0.3556)
					(mid 0 -0.3556)
					(end 0 0.3556)
				)
			)
			(stroke
				(width 0)
				(type default)
			)
			(fill no)
			(layer "B.CrtYd")
		)
		(fp_poly
			(pts
				(arc
					(start 0 0.6096)
					(mid 0 -0.6096)
					(end 0 0.6096)
				)
			)
			(stroke
				(width 0)
				(type default)
			)
			(fill no)
			(layer "B.Fab")
		)
		(pad "1" smd circle
			(at 0 0 270)
			(size 0.7112 0.7112)
			(layers "B.Cu" "B.Mask" "B.Paste")
			(net "MDIO")
		)
	)
	(footprint ""
		(layer "B.Cu")
		(at 66.938652 -122.3264 -90)
		(property "Reference" "R262"
			(at 0 0 90)
			(layer "B.SilkS")
			(hide yes)
			(effects
				(font
					(size 1.27 1.27)
				)
				(justify mirror)
			)
		)
		(property "Value" "0R2J-2-GP"
			(at -0.064008 -3.993896 270)
			(unlocked yes)
			(layer "B.Fab")
			(hide yes)
			(effects
				(font
					(size 1.016 1.016)
					(thickness 0.1524)
				)
				(justify mirror)
			)
		)
		(property "Device Type" "R402H16"
			(at -0.064008 -5.517896 270)
			(unlocked yes)
			(layer "B.Fab")
			(hide yes)
			(effects
				(font
					(size 1.016 1.016)
					(thickness 0.1524)
				)
				(justify mirror)
			)
		)
		(duplicate_pad_numbers_are_jumpers no)
		(fp_line
			(start -0.508 -0.9398)
			(end 0.508 -0.9398)
			(stroke
				(width 0.1524)
				(type default)
			)
			(layer "B.SilkS")
		)
		(fp_line
			(start 0.508 -0.9398)
			(end 0.508 0.9398)
			(stroke
				(width 0.1524)
				(type default)
			)
			(layer "B.SilkS")
		)
		(fp_rect
			(start 0.508 0.9398)
			(end -0.508 -0.9398)
			(stroke
				(width 0)
				(type default)
			)
			(fill no)
			(layer "B.CrtYd")
		)
		(fp_rect
			(start 0.508 0.9398)
			(end -0.508 -0.9398)
			(stroke
				(width 0)
				(type default)
			)
			(fill no)
			(layer "B.Fab")
		)
		(pad "1" smd custom
			(at 0 -0.4445 90)
			(size 0.1397 0.1397)
			(layers "B.Cu" "B.Mask" "B.Paste")
			(net "LAN_SMB_DAT")
			(options
				(clearance outline)
				(anchor circle)
			)
			(primitives
				(gr_poly
					(pts
						(arc
							(start -0.1778 0.2794)
							(mid -0.249642 0.249642)
							(end -0.2794 0.1778)
						)
						(arc
							(start -0.2794 -0.1778)
							(mid -0.249642 -0.249642)
							(end -0.1778 -0.2794)
						)
						(arc
							(start 0.1778 -0.2794)
							(mid 0.249642 -0.249642)
							(end 0.2794 -0.1778)
						)
						(arc
							(start 0.2794 0.1778)
							(mid 0.249642 0.249642)
							(end 0.1778 0.2794)
						)
					)
					(width 0)
					(fill yes)
				)
			)
		)
		(pad "2" smd custom
			(at 0 0.4445 90)
			(size 0.1397 0.1397)
			(layers "B.Cu" "B.Mask" "B.Paste")
			(net "BMC0_SMB4_DAT")
			(options
				(clearance outline)
				(anchor circle)
			)
			(primitives
				(gr_poly
					(pts
						(arc
							(start -0.1778 0.2794)
							(mid -0.249642 0.249642)
							(end -0.2794 0.1778)
						)
						(arc
							(start -0.2794 -0.1778)
							(mid -0.249642 -0.249642)
							(end -0.1778 -0.2794)
						)
						(arc
							(start 0.1778 -0.2794)
							(mid 0.249642 -0.249642)
							(end 0.2794 -0.1778)
						)
						(arc
							(start 0.2794 0.1778)
							(mid 0.249642 0.249642)
							(end 0.1778 0.2794)
						)
					)
					(width 0)
					(fill yes)
				)
			)
		)
	)
	(footprint ""
		(layer "B.Cu")
		(at 74.803 -37.465)
		(property "Reference" "PC30"
			(at 0 0 0)
			(layer "B.SilkS")
			(hide yes)
			(effects
				(font
					(size 1.27 1.27)
				)
				(justify mirror)
			)
		)
		(property "Value" "SCD1U25V2KX-2-GP"
			(at -1.1811 -2.7051 0)
			(unlocked yes)
			(layer "B.Fab")
			(hide yes)
			(effects
				(font
					(size 1.016 1.016)
					(thickness 0.1524)
				)
				(justify mirror)
			)
		)
		(property "Device Type" "C402H22"
			(at -1.1811 -4.2291 0)
			(unlocked yes)
			(layer "B.Fab")
			(hide yes)
			(effects
				(font
					(size 1.016 1.016)
					(thickness 0.1524)
				)
				(justify mirror)
			)
		)
		(duplicate_pad_numbers_are_jumpers no)
		(fp_rect
			(start 0.4318 0.9525)
			(end -0.4318 -0.9525)
			(stroke
				(width 0)
				(type default)
			)
			(fill no)
			(layer "B.CrtYd")
		)
		(fp_rect
			(start 0.4318 0.9525)
			(end -0.4318 -0.9525)
			(stroke
				(width 0)
				(type default)
			)
			(fill no)
			(layer "B.Fab")
		)
		(pad "1" smd custom
			(at 0 -0.4445 180)
			(size 0.1524 0.1524)
			(layers "B.Cu" "B.Mask" "B.Paste")
			(net "P3V3_PWR")
			(options
				(clearance outline)
				(anchor circle)
			)
			(primitives
				(gr_poly
					(pts
						(arc
							(start 0.3048 0.2032)
							(mid 0.275042 0.275042)
							(end 0.2032 0.3048)
						)
						(arc
							(start -0.2032 0.3048)
							(mid -0.275042 0.275042)
							(end -0.3048 0.2032)
						)
						(arc
							(start -0.3048 -0.2032)
							(mid -0.275042 -0.275042)
							(end -0.2032 -0.3048)
						)
						(arc
							(start 0.2032 -0.3048)
							(mid 0.275042 -0.275042)
							(end 0.3048 -0.2032)
						)
					)
					(width 0)
					(fill yes)
				)
			)
		)
		(pad "2" smd custom
			(at 0 0.4445 180)
			(size 0.1524 0.1524)
			(layers "B.Cu" "B.Mask" "B.Paste")
			(net "P3V3_STBY_LL_R")
			(options
				(clearance outline)
				(anchor circle)
			)
			(primitives
				(gr_poly
					(pts
						(arc
							(start 0.3048 0.2032)
							(mid 0.275042 0.275042)
							(end 0.2032 0.3048)
						)
						(arc
							(start -0.2032 0.3048)
							(mid -0.275042 0.275042)
							(end -0.3048 0.2032)
						)
						(arc
							(start -0.3048 -0.2032)
							(mid -0.275042 -0.275042)
							(end -0.2032 -0.3048)
						)
						(arc
							(start 0.2032 -0.3048)
							(mid 0.275042 -0.275042)
							(end 0.3048 -0.2032)
						)
					)
					(width 0)
					(fill yes)
				)
			)
		)
	)
	(footprint ""
		(layer "B.Cu")
		(at 21.837904 -73.989692 -90)
		(property "Reference" "C634"
			(at 0 0 90)
			(layer "B.SilkS")
			(hide yes)
			(effects
				(font
					(size 1.27 1.27)
				)
				(justify mirror)
			)
		)
		(property "Value" "SC10U6D3V5KX-4GP"
			(at 0.0762 -6.1214 270)
			(unlocked yes)
			(layer "B.Fab")
			(hide yes)
			(effects
				(font
					(size 1.016 1.016)
					(thickness 0.1524)
				)
				(justify mirror)
			)
		)
		(property "Device Type" "C805H58"
			(at 0.0762 -8.1534 270)
			(unlocked yes)
			(layer "B.Fab")
			(hide yes)
			(effects
				(font
					(size 1.016 1.016)
					(thickness 0.1524)
				)
				(justify mirror)
			)
		)
		(duplicate_pad_numbers_are_jumpers no)
		(fp_line
			(start -0.635 0)
			(end 0.635 0)
			(stroke
				(width 0.508)
				(type default)
			)
			(layer "B.SilkS")
		)
		(fp_rect
			(start 0.9652 1.778)
			(end -0.9652 -1.778)
			(stroke
				(width 0)
				(type default)
			)
			(fill no)
			(layer "B.CrtYd")
		)
		(fp_poly
			(pts
				(xy 0.9652 -1.778) (xy -0.9652 -1.778) (xy -0.9652 1.778) (xy 0.9652 1.778)
			)
			(stroke
				(width 0)
				(type default)
			)
			(fill no)
			(layer "B.Fab")
		)
		(pad "1" smd rect
			(at 0 -0.9652 90)
			(size 1.397 1.143)
			(layers "B.Cu" "B.Mask" "B.Paste")
			(net "P0V9_I210")
		)
		(pad "2" smd rect
			(at 0 0.9652 90)
			(size 1.397 1.143)
			(layers "B.Cu" "B.Mask" "B.Paste")
			(net "GND")
		)
	)
	(footprint ""
		(layer "B.Cu")
		(at 145.88363 -33.53562)
		(property "Reference" "R2919"
			(at 0 0 0)
			(layer "B.SilkS")
			(hide yes)
			(effects
				(font
					(size 1.27 1.27)
				)
				(justify mirror)
			)
		)
		(property "Value" "0R2J-2-GP"
			(at -0.064008 -3.993896 0)
			(unlocked yes)
			(layer "B.Fab")
			(hide yes)
			(effects
				(font
					(size 1.016 1.016)
					(thickness 0.1524)
				)
				(justify mirror)
			)
		)
		(property "Device Type" "R402H16"
			(at -0.064008 -5.517896 0)
			(unlocked yes)
			(layer "B.Fab")
			(hide yes)
			(effects
				(font
					(size 1.016 1.016)
					(thickness 0.1524)
				)
				(justify mirror)
			)
		)
		(duplicate_pad_numbers_are_jumpers no)
		(fp_line
			(start -0.508 -0.9398)
			(end 0.508 -0.9398)
			(stroke
				(width 0.1524)
				(type default)
			)
			(layer "B.SilkS")
		)
		(fp_line
			(start 0.508 -0.9398)
			(end 0.508 0.9398)
			(stroke
				(width 0.1524)
				(type default)
			)
			(layer "B.SilkS")
		)
		(fp_rect
			(start 0.508 0.9398)
			(end -0.508 -0.9398)
			(stroke
				(width 0)
				(type default)
			)
			(fill no)
			(layer "B.CrtYd")
		)
		(fp_rect
			(start 0.508 0.9398)
			(end -0.508 -0.9398)
			(stroke
				(width 0)
				(type default)
			)
			(fill no)
			(layer "B.Fab")
		)
		(pad "1" smd custom
			(at 0 -0.4445 180)
			(size 0.1397 0.1397)
			(layers "B.Cu" "B.Mask" "B.Paste")
			(net "BMC_I2C2_MINI2_SDA")
			(options
				(clearance outline)
				(anchor circle)
			)
			(primitives
				(gr_poly
					(pts
						(arc
							(start -0.1778 0.2794)
							(mid -0.249642 0.249642)
							(end -0.2794 0.1778)
						)
						(arc
							(start -0.2794 -0.1778)
							(mid -0.249642 -0.249642)
							(end -0.1778 -0.2794)
						)
						(arc
							(start 0.1778 -0.2794)
							(mid 0.249642 -0.249642)
							(end 0.2794 -0.1778)
						)
						(arc
							(start 0.2794 0.1778)
							(mid 0.249642 0.249642)
							(end 0.1778 0.2794)
						)
					)
					(width 0)
					(fill yes)
				)
			)
		)
		(pad "2" smd custom
			(at 0 0.4445 180)
			(size 0.1397 0.1397)
			(layers "B.Cu" "B.Mask" "B.Paste")
			(net "8644_SDA_R_2")
			(options
				(clearance outline)
				(anchor circle)
			)
			(primitives
				(gr_poly
					(pts
						(arc
							(start -0.1778 0.2794)
							(mid -0.249642 0.249642)
							(end -0.2794 0.1778)
						)
						(arc
							(start -0.2794 -0.1778)
							(mid -0.249642 -0.249642)
							(end -0.1778 -0.2794)
						)
						(arc
							(start 0.1778 -0.2794)
							(mid 0.249642 -0.249642)
							(end 0.2794 -0.1778)
						)
						(arc
							(start 0.2794 0.1778)
							(mid 0.249642 0.249642)
							(end 0.1778 0.2794)
						)
					)
					(width 0)
					(fill yes)
				)
			)
		)
	)
	(footprint ""
		(layer "B.Cu")
		(at 156.470604 -33.592008)
		(property "Reference" "R2923"
			(at 0 0 0)
			(layer "B.SilkS")
			(hide yes)
			(effects
				(font
					(size 1.27 1.27)
				)
				(justify mirror)
			)
		)
		(property "Value" "0R2J-2-GP"
			(at -0.064008 -3.993896 0)
			(unlocked yes)
			(layer "B.Fab")
			(hide yes)
			(effects
				(font
					(size 1.016 1.016)
					(thickness 0.1524)
				)
				(justify mirror)
			)
		)
		(property "Device Type" "R402H16"
			(at -0.064008 -5.517896 0)
			(unlocked yes)
			(layer "B.Fab")
			(hide yes)
			(effects
				(font
					(size 1.016 1.016)
					(thickness 0.1524)
				)
				(justify mirror)
			)
		)
		(duplicate_pad_numbers_are_jumpers no)
		(fp_line
			(start -0.508 -0.9398)
			(end 0.508 -0.9398)
			(stroke
				(width 0.1524)
				(type default)
			)
			(layer "B.SilkS")
		)
		(fp_line
			(start 0.508 -0.9398)
			(end 0.508 0.9398)
			(stroke
				(width 0.1524)
				(type default)
			)
			(layer "B.SilkS")
		)
		(fp_rect
			(start 0.508 0.9398)
			(end -0.508 -0.9398)
			(stroke
				(width 0)
				(type default)
			)
			(fill no)
			(layer "B.CrtYd")
		)
		(fp_rect
			(start 0.508 0.9398)
			(end -0.508 -0.9398)
			(stroke
				(width 0)
				(type default)
			)
			(fill no)
			(layer "B.Fab")
		)
		(pad "1" smd custom
			(at 0 -0.4445 180)
			(size 0.1397 0.1397)
			(layers "B.Cu" "B.Mask" "B.Paste")
			(net "BMC_I2C3_MINI3_SDA")
			(options
				(clearance outline)
				(anchor circle)
			)
			(primitives
				(gr_poly
					(pts
						(arc
							(start -0.1778 0.2794)
							(mid -0.249642 0.249642)
							(end -0.2794 0.1778)
						)
						(arc
							(start -0.2794 -0.1778)
							(mid -0.249642 -0.249642)
							(end -0.1778 -0.2794)
						)
						(arc
							(start 0.1778 -0.2794)
							(mid 0.249642 -0.249642)
							(end 0.2794 -0.1778)
						)
						(arc
							(start 0.2794 0.1778)
							(mid 0.249642 0.249642)
							(end 0.1778 0.2794)
						)
					)
					(width 0)
					(fill yes)
				)
			)
		)
		(pad "2" smd custom
			(at 0 0.4445 180)
			(size 0.1397 0.1397)
			(layers "B.Cu" "B.Mask" "B.Paste")
			(net "8644_SDA_R_3")
			(options
				(clearance outline)
				(anchor circle)
			)
			(primitives
				(gr_poly
					(pts
						(arc
							(start -0.1778 0.2794)
							(mid -0.249642 0.249642)
							(end -0.2794 0.1778)
						)
						(arc
							(start -0.2794 -0.1778)
							(mid -0.249642 -0.249642)
							(end -0.1778 -0.2794)
						)
						(arc
							(start 0.1778 -0.2794)
							(mid 0.249642 -0.249642)
							(end 0.2794 -0.1778)
						)
						(arc
							(start 0.2794 0.1778)
							(mid 0.249642 0.249642)
							(end 0.1778 0.2794)
						)
					)
					(width 0)
					(fill yes)
				)
			)
		)
	)
	(footprint ""
		(layer "B.Cu")
		(at 216.5096 -194.0306)
		(property "Reference" "R3242"
			(at 0 0 0)
			(layer "B.SilkS")
			(hide yes)
			(effects
				(font
					(size 1.27 1.27)
				)
				(justify mirror)
			)
		)
		(property "Value" "0R2J-2-GP"
			(at -0.064008 -3.993896 0)
			(unlocked yes)
			(layer "B.Fab")
			(hide yes)
			(effects
				(font
					(size 1.016 1.016)
					(thickness 0.1524)
				)
				(justify mirror)
			)
		)
		(property "Device Type" "R402H16"
			(at -0.064008 -5.517896 0)
			(unlocked yes)
			(layer "B.Fab")
			(hide yes)
			(effects
				(font
					(size 1.016 1.016)
					(thickness 0.1524)
				)
				(justify mirror)
			)
		)
		(duplicate_pad_numbers_are_jumpers no)
		(fp_line
			(start -0.508 -0.9398)
			(end 0.508 -0.9398)
			(stroke
				(width 0.1524)
				(type default)
			)
			(layer "B.SilkS")
		)
		(fp_line
			(start 0.508 -0.9398)
			(end 0.508 0.9398)
			(stroke
				(width 0.1524)
				(type default)
			)
			(layer "B.SilkS")
		)
		(fp_rect
			(start 0.508 0.9398)
			(end -0.508 -0.9398)
			(stroke
				(width 0)
				(type default)
			)
			(fill no)
			(layer "B.CrtYd")
		)
		(fp_rect
			(start 0.508 0.9398)
			(end -0.508 -0.9398)
			(stroke
				(width 0)
				(type default)
			)
			(fill no)
			(layer "B.Fab")
		)
		(pad "1" smd custom
			(at 0 -0.4445 180)
			(size 0.1397 0.1397)
			(layers "B.Cu" "B.Mask" "B.Paste")
			(net "SSD_PERST_Y13")
			(options
				(clearance outline)
				(anchor circle)
			)
			(primitives
				(gr_poly
					(pts
						(arc
							(start -0.1778 0.2794)
							(mid -0.249642 0.249642)
							(end -0.2794 0.1778)
						)
						(arc
							(start -0.2794 -0.1778)
							(mid -0.249642 -0.249642)
							(end -0.1778 -0.2794)
						)
						(arc
							(start 0.1778 -0.2794)
							(mid 0.249642 -0.249642)
							(end 0.2794 -0.1778)
						)
						(arc
							(start 0.2794 0.1778)
							(mid 0.249642 0.249642)
							(end 0.1778 0.2794)
						)
					)
					(width 0)
					(fill yes)
				)
			)
		)
		(pad "2" smd custom
			(at 0 0.4445 180)
			(size 0.1397 0.1397)
			(layers "B.Cu" "B.Mask" "B.Paste")
			(net "SSD_PERST#13_R")
			(options
				(clearance outline)
				(anchor circle)
			)
			(primitives
				(gr_poly
					(pts
						(arc
							(start -0.1778 0.2794)
							(mid -0.249642 0.249642)
							(end -0.2794 0.1778)
						)
						(arc
							(start -0.2794 -0.1778)
							(mid -0.249642 -0.249642)
							(end -0.1778 -0.2794)
						)
						(arc
							(start 0.1778 -0.2794)
							(mid 0.249642 -0.249642)
							(end 0.2794 -0.1778)
						)
						(arc
							(start 0.2794 0.1778)
							(mid 0.249642 0.249642)
							(end 0.1778 0.2794)
						)
					)
					(width 0)
					(fill yes)
				)
			)
		)
	)
	(footprint ""
		(layer "B.Cu")
		(at 227.6856 -40.004746 -90)
		(property "Reference" "C556"
			(at 0 0 90)
			(layer "B.SilkS")
			(hide yes)
			(effects
				(font
					(size 1.27 1.27)
				)
				(justify mirror)
			)
		)
		(property "Value" "SCD1U16V1KX-1-GP"
			(at 2.8321 -1.7399 270)
			(unlocked yes)
			(layer "B.Fab")
			(hide yes)
			(effects
				(font
					(size 1.016 1.016)
					(thickness 0.1524)
				)
				(justify mirror)
			)
		)
		(property "Device Type" "C0201H13"
			(at 2.8321 -3.2639 270)
			(unlocked yes)
			(layer "B.Fab")
			(hide yes)
			(effects
				(font
					(size 1.016 1.016)
					(thickness 0.1524)
				)
				(justify mirror)
			)
		)
		(duplicate_pad_numbers_are_jumpers no)
		(fp_rect
			(start 0.2794 0.6477)
			(end -0.2794 -0.6477)
			(stroke
				(width 0)
				(type default)
			)
			(fill no)
			(layer "B.CrtYd")
		)
		(fp_rect
			(start 0.2794 0.6477)
			(end -0.2794 -0.6477)
			(stroke
				(width 0)
				(type default)
			)
			(fill no)
			(layer "B.Fab")
		)
		(pad "1" smd custom
			(at 0 -0.2794 90)
			(size 0.0762 0.0762)
			(layers "B.Cu" "B.Mask" "B.Paste")
			(net "DUT_AVD_PCIE")
			(options
				(clearance outline)
				(anchor circle)
			)
			(primitives
				(gr_poly
					(pts
						(arc
							(start 0.1524 0.127)
							(mid 0.137521 0.162921)
							(end 0.1016 0.1778)
						)
						(arc
							(start -0.1016 0.1778)
							(mid -0.137521 0.162921)
							(end -0.1524 0.127)
						)
						(arc
							(start -0.1524 -0.127)
							(mid -0.137521 -0.162921)
							(end -0.1016 -0.1778)
						)
						(arc
							(start 0.1016 -0.1778)
							(mid 0.137521 -0.162921)
							(end 0.1524 -0.127)
						)
					)
					(width 0)
					(fill yes)
				)
			)
		)
		(pad "2" smd custom
			(at 0 0.2794 90)
			(size 0.0762 0.0762)
			(layers "B.Cu" "B.Mask" "B.Paste")
			(net "GND")
			(options
				(clearance outline)
				(anchor circle)
			)
			(primitives
				(gr_poly
					(pts
						(arc
							(start 0.1524 0.127)
							(mid 0.137521 0.162921)
							(end 0.1016 0.1778)
						)
						(arc
							(start -0.1016 0.1778)
							(mid -0.137521 0.162921)
							(end -0.1524 0.127)
						)
						(arc
							(start -0.1524 -0.127)
							(mid -0.137521 -0.162921)
							(end -0.1016 -0.1778)
						)
						(arc
							(start 0.1016 -0.1778)
							(mid 0.137521 -0.162921)
							(end 0.1524 -0.127)
						)
					)
					(width 0)
					(fill yes)
				)
			)
		)
	)
	(footprint ""
		(layer "B.Cu")
		(at 346.329 -67.056 180)
		(property "Reference" "PC184"
			(at 0 0 0)
			(layer "B.SilkS")
			(hide yes)
			(effects
				(font
					(size 1.27 1.27)
				)
				(justify mirror)
			)
		)
		(property "Value" "SC4D7U25V5KX-1-GP"
			(at 0.0762 -6.1214 180)
			(unlocked yes)
			(layer "B.Fab")
			(hide yes)
			(effects
				(font
					(size 1.016 1.016)
					(thickness 0.1524)
				)
				(justify mirror)
			)
		)
		(property "Device Type" "C805H58"
			(at 0.0762 -8.1534 180)
			(unlocked yes)
			(layer "B.Fab")
			(hide yes)
			(effects
				(font
					(size 1.016 1.016)
					(thickness 0.1524)
				)
				(justify mirror)
			)
		)
		(duplicate_pad_numbers_are_jumpers no)
		(fp_line
			(start -0.635 0)
			(end 0.635 0)
			(stroke
				(width 0.508)
				(type default)
			)
			(layer "B.SilkS")
		)
		(fp_rect
			(start 0.9652 1.778)
			(end -0.9652 -1.778)
			(stroke
				(width 0)
				(type default)
			)
			(fill no)
			(layer "B.CrtYd")
		)
		(fp_poly
			(pts
				(xy 0.9652 -1.778) (xy -0.9652 -1.778) (xy -0.9652 1.778) (xy 0.9652 1.778)
			)
			(stroke
				(width 0)
				(type default)
			)
			(fill no)
			(layer "B.Fab")
		)
		(pad "1" smd rect
			(at 0 -0.9652)
			(size 1.397 1.143)
			(layers "B.Cu" "B.Mask" "B.Paste")
			(net "P0V9_E_VDD")
		)
		(pad "2" smd rect
			(at 0 0.9652)
			(size 1.397 1.143)
			(layers "B.Cu" "B.Mask" "B.Paste")
			(net "GND")
		)
	)
	(footprint ""
		(layer "B.Cu")
		(at 40.005 -118.872)
		(property "Reference" "TP153"
			(at 0 0 0)
			(layer "B.SilkS")
			(hide yes)
			(effects
				(font
					(size 1.27 1.27)
				)
				(justify mirror)
			)
		)
		(property "Value" "TPAD28-2-GP"
			(at 0.0127 -1.6637 0)
			(unlocked yes)
			(layer "B.Fab")
			(hide yes)
			(effects
				(font
					(size 1.016 1.016)
					(thickness 0.1524)
				)
				(justify mirror)
			)
		)
		(property "Device Type" "TPAD28"
			(at 0.0127 -3.1877 0)
			(unlocked yes)
			(layer "B.Fab")
			(hide yes)
			(effects
				(font
					(size 1.016 1.016)
					(thickness 0.1524)
				)
				(justify mirror)
			)
		)
		(duplicate_pad_numbers_are_jumpers no)
		(fp_poly
			(pts
				(arc
					(start 0.3556 0)
					(mid -0.3556 0)
					(end 0.3556 0)
				)
			)
			(stroke
				(width 0)
				(type default)
			)
			(fill no)
			(layer "B.CrtYd")
		)
		(fp_poly
			(pts
				(arc
					(start 0.6096 0)
					(mid -0.6096 0)
					(end 0.6096 0)
				)
			)
			(stroke
				(width 0)
				(type default)
			)
			(fill no)
			(layer "B.Fab")
		)
		(pad "1" smd circle
			(at 0 0 180)
			(size 0.7112 0.7112)
			(layers "B.Cu" "B.Mask" "B.Paste")
			(net "TP_GPIOU3")
		)
	)
	(footprint ""
		(layer "B.Cu")
		(at 235.1024 -51.9938 -90)
		(property "Reference" "C33"
			(at 0 0 90)
			(layer "B.SilkS")
			(hide yes)
			(effects
				(font
					(size 1.27 1.27)
				)
				(justify mirror)
			)
		)
		(property "Value" "SCD1U16V1KX-1-GP"
			(at 2.8321 -1.7399 270)
			(unlocked yes)
			(layer "B.Fab")
			(hide yes)
			(effects
				(font
					(size 1.016 1.016)
					(thickness 0.1524)
				)
				(justify mirror)
			)
		)
		(property "Device Type" "C0201H13"
			(at 2.8321 -3.2639 270)
			(unlocked yes)
			(layer "B.Fab")
			(hide yes)
			(effects
				(font
					(size 1.016 1.016)
					(thickness 0.1524)
				)
				(justify mirror)
			)
		)
		(duplicate_pad_numbers_are_jumpers no)
		(fp_rect
			(start 0.2794 0.6477)
			(end -0.2794 -0.6477)
			(stroke
				(width 0)
				(type default)
			)
			(fill no)
			(layer "B.CrtYd")
		)
		(fp_rect
			(start 0.2794 0.6477)
			(end -0.2794 -0.6477)
			(stroke
				(width 0)
				(type default)
			)
			(fill no)
			(layer "B.Fab")
		)
		(pad "1" smd custom
			(at 0 -0.2794 90)
			(size 0.0762 0.0762)
			(layers "B.Cu" "B.Mask" "B.Paste")
			(net "DUT_VDD")
			(options
				(clearance outline)
				(anchor circle)
			)
			(primitives
				(gr_poly
					(pts
						(arc
							(start 0.1524 0.127)
							(mid 0.137521 0.162921)
							(end 0.1016 0.1778)
						)
						(arc
							(start -0.1016 0.1778)
							(mid -0.137521 0.162921)
							(end -0.1524 0.127)
						)
						(arc
							(start -0.1524 -0.127)
							(mid -0.137521 -0.162921)
							(end -0.1016 -0.1778)
						)
						(arc
							(start 0.1016 -0.1778)
							(mid 0.137521 -0.162921)
							(end 0.1524 -0.127)
						)
					)
					(width 0)
					(fill yes)
				)
			)
		)
		(pad "2" smd custom
			(at 0 0.2794 90)
			(size 0.0762 0.0762)
			(layers "B.Cu" "B.Mask" "B.Paste")
			(net "GND")
			(options
				(clearance outline)
				(anchor circle)
			)
			(primitives
				(gr_poly
					(pts
						(arc
							(start 0.1524 0.127)
							(mid 0.137521 0.162921)
							(end 0.1016 0.1778)
						)
						(arc
							(start -0.1016 0.1778)
							(mid -0.137521 0.162921)
							(end -0.1524 0.127)
						)
						(arc
							(start -0.1524 -0.127)
							(mid -0.137521 -0.162921)
							(end -0.1016 -0.1778)
						)
						(arc
							(start 0.1016 -0.1778)
							(mid 0.137521 -0.162921)
							(end 0.1524 -0.127)
						)
					)
					(width 0)
					(fill yes)
				)
			)
		)
	)
	(footprint ""
		(layer "B.Cu")
		(at 232.61066 -41.00068 -90)
		(property "Reference" "TP204"
			(at 0 0 90)
			(layer "B.SilkS")
			(hide yes)
			(effects
				(font
					(size 1.27 1.27)
				)
				(justify mirror)
			)
		)
		(property "Value" "TPAD28-2-GP"
			(at 0.0127 -1.6637 270)
			(unlocked yes)
			(layer "B.Fab")
			(hide yes)
			(effects
				(font
					(size 1.016 1.016)
					(thickness 0.1524)
				)
				(justify mirror)
			)
		)
		(property "Device Type" "TPAD28"
			(at 0.0127 -3.1877 270)
			(unlocked yes)
			(layer "B.Fab")
			(hide yes)
			(effects
				(font
					(size 1.016 1.016)
					(thickness 0.1524)
				)
				(justify mirror)
			)
		)
		(duplicate_pad_numbers_are_jumpers no)
		(fp_poly
			(pts
				(arc
					(start 0 -0.3556)
					(mid 0 0.3556)
					(end 0 -0.3556)
				)
			)
			(stroke
				(width 0)
				(type default)
			)
			(fill no)
			(layer "B.CrtYd")
		)
		(fp_poly
			(pts
				(arc
					(start 0 -0.6096)
					(mid 0 0.6096)
					(end 0 -0.6096)
				)
			)
			(stroke
				(width 0)
				(type default)
			)
			(fill no)
			(layer "B.Fab")
		)
		(pad "1" smd circle
			(at 0 0 90)
			(size 0.7112 0.7112)
			(layers "B.Cu" "B.Mask" "B.Paste")
			(net "RMII_CRS_DV")
		)
	)
	(footprint ""
		(layer "B.Cu")
		(at 222.25 -23.241 180)
		(property "Reference" "R832"
			(at 0 0 0)
			(layer "B.SilkS")
			(hide yes)
			(effects
				(font
					(size 1.27 1.27)
				)
				(justify mirror)
			)
		)
		(property "Value" "0R2J-2-GP"
			(at -0.064008 -3.993896 180)
			(unlocked yes)
			(layer "B.Fab")
			(hide yes)
			(effects
				(font
					(size 1.016 1.016)
					(thickness 0.1524)
				)
				(justify mirror)
			)
		)
		(property "Device Type" "R402H16"
			(at -0.064008 -5.517896 180)
			(unlocked yes)
			(layer "B.Fab")
			(hide yes)
			(effects
				(font
					(size 1.016 1.016)
					(thickness 0.1524)
				)
				(justify mirror)
			)
		)
		(duplicate_pad_numbers_are_jumpers no)
		(fp_line
			(start 0.508 -0.9398)
			(end 0.508 0.9398)
			(stroke
				(width 0.1524)
				(type default)
			)
			(layer "B.SilkS")
		)
		(fp_line
			(start -0.508 -0.9398)
			(end 0.508 -0.9398)
			(stroke
				(width 0.1524)
				(type default)
			)
			(layer "B.SilkS")
		)
		(fp_rect
			(start 0.508 0.9398)
			(end -0.508 -0.9398)
			(stroke
				(width 0)
				(type default)
			)
			(fill no)
			(layer "B.CrtYd")
		)
		(fp_rect
			(start 0.508 0.9398)
			(end -0.508 -0.9398)
			(stroke
				(width 0)
				(type default)
			)
			(fill no)
			(layer "B.Fab")
		)
		(pad "1" smd custom
			(at 0 -0.4445)
			(size 0.1397 0.1397)
			(layers "B.Cu" "B.Mask" "B.Paste")
			(net "HOST8_RST_N_LS")
			(options
				(clearance outline)
				(anchor circle)
			)
			(primitives
				(gr_poly
					(pts
						(arc
							(start -0.1778 0.2794)
							(mid -0.249642 0.249642)
							(end -0.2794 0.1778)
						)
						(arc
							(start -0.2794 -0.1778)
							(mid -0.249642 -0.249642)
							(end -0.1778 -0.2794)
						)
						(arc
							(start 0.1778 -0.2794)
							(mid 0.249642 -0.249642)
							(end 0.2794 -0.1778)
						)
						(arc
							(start 0.2794 0.1778)
							(mid 0.249642 0.249642)
							(end 0.1778 0.2794)
						)
					)
					(width 0)
					(fill yes)
				)
			)
		)
		(pad "2" smd custom
			(at 0 0.4445)
			(size 0.1397 0.1397)
			(layers "B.Cu" "B.Mask" "B.Paste")
			(net "LBI_ADDR_7_R")
			(options
				(clearance outline)
				(anchor circle)
			)
			(primitives
				(gr_poly
					(pts
						(arc
							(start -0.1778 0.2794)
							(mid -0.249642 0.249642)
							(end -0.2794 0.1778)
						)
						(arc
							(start -0.2794 -0.1778)
							(mid -0.249642 -0.249642)
							(end -0.1778 -0.2794)
						)
						(arc
							(start 0.1778 -0.2794)
							(mid 0.249642 -0.249642)
							(end 0.2794 -0.1778)
						)
						(arc
							(start 0.2794 0.1778)
							(mid 0.249642 0.249642)
							(end 0.1778 0.2794)
						)
					)
					(width 0)
					(fill yes)
				)
			)
		)
	)
	(footprint ""
		(layer "B.Cu")
		(at 20.955 -135.763 90)
		(property "Reference" "R638"
			(at 0 0 90)
			(layer "B.SilkS")
			(hide yes)
			(effects
				(font
					(size 1.27 1.27)
				)
				(justify mirror)
			)
		)
		(property "Value" "22R2F-1-GP"
			(at -0.064008 -3.993896 90)
			(unlocked yes)
			(layer "B.Fab")
			(hide yes)
			(effects
				(font
					(size 1.016 1.016)
					(thickness 0.1524)
				)
				(justify mirror)
			)
		)
		(property "Device Type" "R402H16"
			(at -0.064008 -5.517896 90)
			(unlocked yes)
			(layer "B.Fab")
			(hide yes)
			(effects
				(font
					(size 1.016 1.016)
					(thickness 0.1524)
				)
				(justify mirror)
			)
		)
		(duplicate_pad_numbers_are_jumpers no)
		(fp_line
			(start 0.508 -0.9398)
			(end 0.508 0.9398)
			(stroke
				(width 0.1524)
				(type default)
			)
			(layer "B.SilkS")
		)
		(fp_line
			(start -0.508 -0.9398)
			(end 0.508 -0.9398)
			(stroke
				(width 0.1524)
				(type default)
			)
			(layer "B.SilkS")
		)
		(fp_rect
			(start 0.508 0.9398)
			(end -0.508 -0.9398)
			(stroke
				(width 0)
				(type default)
			)
			(fill no)
			(layer "B.CrtYd")
		)
		(fp_rect
			(start 0.508 0.9398)
			(end -0.508 -0.9398)
			(stroke
				(width 0)
				(type default)
			)
			(fill no)
			(layer "B.Fab")
		)
		(pad "1" smd custom
			(at 0 -0.4445 270)
			(size 0.1397 0.1397)
			(layers "B.Cu" "B.Mask" "B.Paste")
			(net "ROMD0_R")
			(options
				(clearance outline)
				(anchor circle)
			)
			(primitives
				(gr_poly
					(pts
						(arc
							(start -0.1778 0.2794)
							(mid -0.249642 0.249642)
							(end -0.2794 0.1778)
						)
						(arc
							(start -0.2794 -0.1778)
							(mid -0.249642 -0.249642)
							(end -0.1778 -0.2794)
						)
						(arc
							(start 0.1778 -0.2794)
							(mid 0.249642 -0.249642)
							(end 0.2794 -0.1778)
						)
						(arc
							(start 0.2794 0.1778)
							(mid 0.249642 0.249642)
							(end 0.1778 0.2794)
						)
					)
					(width 0)
					(fill yes)
				)
			)
		)
		(pad "2" smd custom
			(at 0 0.4445 270)
			(size 0.1397 0.1397)
			(layers "B.Cu" "B.Mask" "B.Paste")
			(net "ROMD0")
			(options
				(clearance outline)
				(anchor circle)
			)
			(primitives
				(gr_poly
					(pts
						(arc
							(start -0.1778 0.2794)
							(mid -0.249642 0.249642)
							(end -0.2794 0.1778)
						)
						(arc
							(start -0.2794 -0.1778)
							(mid -0.249642 -0.249642)
							(end -0.1778 -0.2794)
						)
						(arc
							(start 0.1778 -0.2794)
							(mid 0.249642 -0.249642)
							(end 0.2794 -0.1778)
						)
						(arc
							(start 0.2794 0.1778)
							(mid 0.249642 0.249642)
							(end 0.1778 0.2794)
						)
					)
					(width 0)
					(fill yes)
				)
			)
		)
	)
	(footprint ""
		(layer "B.Cu")
		(at 41.656 -201.549 180)
		(property "Reference" "R882"
			(at 0 0 0)
			(layer "B.SilkS")
			(hide yes)
			(effects
				(font
					(size 1.27 1.27)
				)
				(justify mirror)
			)
		)
		(property "Value" "0R2J-2-GP"
			(at -0.064008 -3.993896 180)
			(unlocked yes)
			(layer "B.Fab")
			(hide yes)
			(effects
				(font
					(size 1.016 1.016)
					(thickness 0.1524)
				)
				(justify mirror)
			)
		)
		(property "Device Type" "R402H16"
			(at -0.064008 -5.517896 180)
			(unlocked yes)
			(layer "B.Fab")
			(hide yes)
			(effects
				(font
					(size 1.016 1.016)
					(thickness 0.1524)
				)
				(justify mirror)
			)
		)
		(duplicate_pad_numbers_are_jumpers no)
		(fp_line
			(start 0.508 -0.9398)
			(end 0.508 0.9398)
			(stroke
				(width 0.1524)
				(type default)
			)
			(layer "B.SilkS")
		)
		(fp_line
			(start -0.508 -0.9398)
			(end 0.508 -0.9398)
			(stroke
				(width 0.1524)
				(type default)
			)
			(layer "B.SilkS")
		)
		(fp_rect
			(start 0.508 0.9398)
			(end -0.508 -0.9398)
			(stroke
				(width 0)
				(type default)
			)
			(fill no)
			(layer "B.CrtYd")
		)
		(fp_rect
			(start 0.508 0.9398)
			(end -0.508 -0.9398)
			(stroke
				(width 0)
				(type default)
			)
			(fill no)
			(layer "B.Fab")
		)
		(pad "1" smd custom
			(at 0 -0.4445)
			(size 0.1397 0.1397)
			(layers "B.Cu" "B.Mask" "B.Paste")
			(net "BMC_I2C6_C_FCB_SCL")
			(options
				(clearance outline)
				(anchor circle)
			)
			(primitives
				(gr_poly
					(pts
						(arc
							(start -0.1778 0.2794)
							(mid -0.249642 0.249642)
							(end -0.2794 0.1778)
						)
						(arc
							(start -0.2794 -0.1778)
							(mid -0.249642 -0.249642)
							(end -0.1778 -0.2794)
						)
						(arc
							(start 0.1778 -0.2794)
							(mid 0.249642 -0.249642)
							(end 0.2794 -0.1778)
						)
						(arc
							(start 0.2794 0.1778)
							(mid 0.249642 0.249642)
							(end 0.1778 0.2794)
						)
					)
					(width 0)
					(fill yes)
				)
			)
		)
		(pad "2" smd custom
			(at 0 0.4445)
			(size 0.1397 0.1397)
			(layers "B.Cu" "B.Mask" "B.Paste")
			(net "BUF_I2C6_C_FCB_SCL")
			(options
				(clearance outline)
				(anchor circle)
			)
			(primitives
				(gr_poly
					(pts
						(arc
							(start -0.1778 0.2794)
							(mid -0.249642 0.249642)
							(end -0.2794 0.1778)
						)
						(arc
							(start -0.2794 -0.1778)
							(mid -0.249642 -0.249642)
							(end -0.1778 -0.2794)
						)
						(arc
							(start 0.1778 -0.2794)
							(mid 0.249642 -0.249642)
							(end 0.2794 -0.1778)
						)
						(arc
							(start 0.2794 0.1778)
							(mid 0.249642 0.249642)
							(end 0.1778 0.2794)
						)
					)
					(width 0)
					(fill yes)
				)
			)
		)
	)
	(footprint ""
		(layer "B.Cu")
		(at 213.932008 -4.064)
		(property "Reference" "R3715"
			(at 0 0 0)
			(layer "B.SilkS")
			(hide yes)
			(effects
				(font
					(size 1.27 1.27)
				)
				(justify mirror)
			)
		)
		(property "Value" "1KR2F-3-GP"
			(at -0.064008 -3.993896 0)
			(unlocked yes)
			(layer "B.Fab")
			(hide yes)
			(effects
				(font
					(size 1.016 1.016)
					(thickness 0.1524)
				)
				(justify mirror)
			)
		)
		(property "Device Type" "R402H16"
			(at -0.064008 -5.517896 0)
			(unlocked yes)
			(layer "B.Fab")
			(hide yes)
			(effects
				(font
					(size 1.016 1.016)
					(thickness 0.1524)
				)
				(justify mirror)
			)
		)
		(duplicate_pad_numbers_are_jumpers no)
		(fp_line
			(start -0.508 -0.9398)
			(end 0.508 -0.9398)
			(stroke
				(width 0.1524)
				(type default)
			)
			(layer "B.SilkS")
		)
		(fp_line
			(start 0.508 -0.9398)
			(end 0.508 0.9398)
			(stroke
				(width 0.1524)
				(type default)
			)
			(layer "B.SilkS")
		)
		(fp_rect
			(start 0.508 0.9398)
			(end -0.508 -0.9398)
			(stroke
				(width 0)
				(type default)
			)
			(fill no)
			(layer "B.CrtYd")
		)
		(fp_rect
			(start 0.508 0.9398)
			(end -0.508 -0.9398)
			(stroke
				(width 0)
				(type default)
			)
			(fill no)
			(layer "B.Fab")
		)
		(pad "1" smd custom
			(at 0 -0.4445 180)
			(size 0.1397 0.1397)
			(layers "B.Cu" "B.Mask" "B.Paste")
			(net "HOST3_RST_N")
			(options
				(clearance outline)
				(anchor circle)
			)
			(primitives
				(gr_poly
					(pts
						(arc
							(start -0.1778 0.2794)
							(mid -0.249642 0.249642)
							(end -0.2794 0.1778)
						)
						(arc
							(start -0.2794 -0.1778)
							(mid -0.249642 -0.249642)
							(end -0.1778 -0.2794)
						)
						(arc
							(start 0.1778 -0.2794)
							(mid 0.249642 -0.249642)
							(end 0.2794 -0.1778)
						)
						(arc
							(start 0.2794 0.1778)
							(mid 0.249642 0.249642)
							(end 0.1778 0.2794)
						)
					)
					(width 0)
					(fill yes)
				)
			)
		)
		(pad "2" smd custom
			(at 0 0.4445 180)
			(size 0.1397 0.1397)
			(layers "B.Cu" "B.Mask" "B.Paste")
			(net "P3V3_STBY")
			(options
				(clearance outline)
				(anchor circle)
			)
			(primitives
				(gr_poly
					(pts
						(arc
							(start -0.1778 0.2794)
							(mid -0.249642 0.249642)
							(end -0.2794 0.1778)
						)
						(arc
							(start -0.2794 -0.1778)
							(mid -0.249642 -0.249642)
							(end -0.1778 -0.2794)
						)
						(arc
							(start 0.1778 -0.2794)
							(mid 0.249642 -0.249642)
							(end 0.2794 -0.1778)
						)
						(arc
							(start 0.2794 0.1778)
							(mid 0.249642 0.249642)
							(end 0.1778 0.2794)
						)
					)
					(width 0)
					(fill yes)
				)
			)
		)
	)
	(footprint ""
		(layer "B.Cu")
		(at 70.6247 -186.694318)
		(property "Reference" "R3236"
			(at 0 0 0)
			(layer "B.SilkS")
			(hide yes)
			(effects
				(font
					(size 1.27 1.27)
				)
				(justify mirror)
			)
		)
		(property "Value" "0R2J-2-GP"
			(at -0.064008 -3.993896 0)
			(unlocked yes)
			(layer "B.Fab")
			(hide yes)
			(effects
				(font
					(size 1.016 1.016)
					(thickness 0.1524)
				)
				(justify mirror)
			)
		)
		(property "Device Type" "R402H16"
			(at -0.064008 -5.517896 0)
			(unlocked yes)
			(layer "B.Fab")
			(hide yes)
			(effects
				(font
					(size 1.016 1.016)
					(thickness 0.1524)
				)
				(justify mirror)
			)
		)
		(duplicate_pad_numbers_are_jumpers no)
		(fp_line
			(start -0.508 -0.9398)
			(end 0.508 -0.9398)
			(stroke
				(width 0.1524)
				(type default)
			)
			(layer "B.SilkS")
		)
		(fp_line
			(start 0.508 -0.9398)
			(end 0.508 0.9398)
			(stroke
				(width 0.1524)
				(type default)
			)
			(layer "B.SilkS")
		)
		(fp_rect
			(start 0.508 0.9398)
			(end -0.508 -0.9398)
			(stroke
				(width 0)
				(type default)
			)
			(fill no)
			(layer "B.CrtYd")
		)
		(fp_rect
			(start 0.508 0.9398)
			(end -0.508 -0.9398)
			(stroke
				(width 0)
				(type default)
			)
			(fill no)
			(layer "B.Fab")
		)
		(pad "1" smd custom
			(at 0 -0.4445 180)
			(size 0.1397 0.1397)
			(layers "B.Cu" "B.Mask" "B.Paste")
			(net "SSD_PERST_Y11")
			(options
				(clearance outline)
				(anchor circle)
			)
			(primitives
				(gr_poly
					(pts
						(arc
							(start -0.1778 0.2794)
							(mid -0.249642 0.249642)
							(end -0.2794 0.1778)
						)
						(arc
							(start -0.2794 -0.1778)
							(mid -0.249642 -0.249642)
							(end -0.1778 -0.2794)
						)
						(arc
							(start 0.1778 -0.2794)
							(mid 0.249642 -0.249642)
							(end 0.2794 -0.1778)
						)
						(arc
							(start 0.2794 0.1778)
							(mid 0.249642 0.249642)
							(end 0.1778 0.2794)
						)
					)
					(width 0)
					(fill yes)
				)
			)
		)
		(pad "2" smd custom
			(at 0 0.4445 180)
			(size 0.1397 0.1397)
			(layers "B.Cu" "B.Mask" "B.Paste")
			(net "SSD_PERST#11_R")
			(options
				(clearance outline)
				(anchor circle)
			)
			(primitives
				(gr_poly
					(pts
						(arc
							(start -0.1778 0.2794)
							(mid -0.249642 0.249642)
							(end -0.2794 0.1778)
						)
						(arc
							(start -0.2794 -0.1778)
							(mid -0.249642 -0.249642)
							(end -0.1778 -0.2794)
						)
						(arc
							(start 0.1778 -0.2794)
							(mid 0.249642 -0.249642)
							(end 0.2794 -0.1778)
						)
						(arc
							(start 0.2794 0.1778)
							(mid 0.249642 0.249642)
							(end 0.1778 0.2794)
						)
					)
					(width 0)
					(fill yes)
				)
			)
		)
	)
	(footprint ""
		(layer "B.Cu")
		(at 20.955 -127.635 90)
		(property "Reference" "R344"
			(at 0 0 90)
			(layer "B.SilkS")
			(hide yes)
			(effects
				(font
					(size 1.27 1.27)
				)
				(justify mirror)
			)
		)
		(property "Value" "3K3R2F-2-GP"
			(at -0.064008 -3.993896 90)
			(unlocked yes)
			(layer "B.Fab")
			(hide yes)
			(effects
				(font
					(size 1.016 1.016)
					(thickness 0.1524)
				)
				(justify mirror)
			)
		)
		(property "Device Type" "R402H16"
			(at -0.064008 -5.517896 90)
			(unlocked yes)
			(layer "B.Fab")
			(hide yes)
			(effects
				(font
					(size 1.016 1.016)
					(thickness 0.1524)
				)
				(justify mirror)
			)
		)
		(duplicate_pad_numbers_are_jumpers no)
		(fp_line
			(start 0.508 -0.9398)
			(end 0.508 0.9398)
			(stroke
				(width 0.1524)
				(type default)
			)
			(layer "B.SilkS")
		)
		(fp_line
			(start -0.508 -0.9398)
			(end 0.508 -0.9398)
			(stroke
				(width 0.1524)
				(type default)
			)
			(layer "B.SilkS")
		)
		(fp_rect
			(start 0.508 0.9398)
			(end -0.508 -0.9398)
			(stroke
				(width 0)
				(type default)
			)
			(fill no)
			(layer "B.CrtYd")
		)
		(fp_rect
			(start 0.508 0.9398)
			(end -0.508 -0.9398)
			(stroke
				(width 0)
				(type default)
			)
			(fill no)
			(layer "B.Fab")
		)
		(pad "1" smd custom
			(at 0 -0.4445 270)
			(size 0.1397 0.1397)
			(layers "B.Cu" "B.Mask" "B.Paste")
			(net "P3V3_STBY")
			(options
				(clearance outline)
				(anchor circle)
			)
			(primitives
				(gr_poly
					(pts
						(arc
							(start -0.1778 0.2794)
							(mid -0.249642 0.249642)
							(end -0.2794 0.1778)
						)
						(arc
							(start -0.2794 -0.1778)
							(mid -0.249642 -0.249642)
							(end -0.1778 -0.2794)
						)
						(arc
							(start 0.1778 -0.2794)
							(mid 0.249642 -0.249642)
							(end 0.2794 -0.1778)
						)
						(arc
							(start 0.2794 0.1778)
							(mid 0.249642 0.249642)
							(end 0.1778 0.2794)
						)
					)
					(width 0)
					(fill yes)
				)
			)
		)
		(pad "2" smd custom
			(at 0 0.4445 270)
			(size 0.1397 0.1397)
			(layers "B.Cu" "B.Mask" "B.Paste")
			(net "ROMA9")
			(options
				(clearance outline)
				(anchor circle)
			)
			(primitives
				(gr_poly
					(pts
						(arc
							(start -0.1778 0.2794)
							(mid -0.249642 0.249642)
							(end -0.2794 0.1778)
						)
						(arc
							(start -0.2794 -0.1778)
							(mid -0.249642 -0.249642)
							(end -0.1778 -0.2794)
						)
						(arc
							(start 0.1778 -0.2794)
							(mid 0.249642 -0.249642)
							(end 0.2794 -0.1778)
						)
						(arc
							(start 0.2794 0.1778)
							(mid 0.249642 0.249642)
							(end 0.1778 0.2794)
						)
					)
					(width 0)
					(fill yes)
				)
			)
		)
	)
	(footprint ""
		(layer "B.Cu")
		(at 239.1664 -51.9938 -90)
		(property "Reference" "C30"
			(at 0 0 90)
			(layer "B.SilkS")
			(hide yes)
			(effects
				(font
					(size 1.27 1.27)
				)
				(justify mirror)
			)
		)
		(property "Value" "SCD1U16V1KX-1-GP"
			(at 2.8321 -1.7399 270)
			(unlocked yes)
			(layer "B.Fab")
			(hide yes)
			(effects
				(font
					(size 1.016 1.016)
					(thickness 0.1524)
				)
				(justify mirror)
			)
		)
		(property "Device Type" "C0201H13"
			(at 2.8321 -3.2639 270)
			(unlocked yes)
			(layer "B.Fab")
			(hide yes)
			(effects
				(font
					(size 1.016 1.016)
					(thickness 0.1524)
				)
				(justify mirror)
			)
		)
		(duplicate_pad_numbers_are_jumpers no)
		(fp_rect
			(start 0.2794 0.6477)
			(end -0.2794 -0.6477)
			(stroke
				(width 0)
				(type default)
			)
			(fill no)
			(layer "B.CrtYd")
		)
		(fp_rect
			(start 0.2794 0.6477)
			(end -0.2794 -0.6477)
			(stroke
				(width 0)
				(type default)
			)
			(fill no)
			(layer "B.Fab")
		)
		(pad "1" smd custom
			(at 0 -0.2794 90)
			(size 0.0762 0.0762)
			(layers "B.Cu" "B.Mask" "B.Paste")
			(net "DUT_VDD")
			(options
				(clearance outline)
				(anchor circle)
			)
			(primitives
				(gr_poly
					(pts
						(arc
							(start 0.1524 0.127)
							(mid 0.137521 0.162921)
							(end 0.1016 0.1778)
						)
						(arc
							(start -0.1016 0.1778)
							(mid -0.137521 0.162921)
							(end -0.1524 0.127)
						)
						(arc
							(start -0.1524 -0.127)
							(mid -0.137521 -0.162921)
							(end -0.1016 -0.1778)
						)
						(arc
							(start 0.1016 -0.1778)
							(mid 0.137521 -0.162921)
							(end 0.1524 -0.127)
						)
					)
					(width 0)
					(fill yes)
				)
			)
		)
		(pad "2" smd custom
			(at 0 0.2794 90)
			(size 0.0762 0.0762)
			(layers "B.Cu" "B.Mask" "B.Paste")
			(net "GND")
			(options
				(clearance outline)
				(anchor circle)
			)
			(primitives
				(gr_poly
					(pts
						(arc
							(start 0.1524 0.127)
							(mid 0.137521 0.162921)
							(end 0.1016 0.1778)
						)
						(arc
							(start -0.1016 0.1778)
							(mid -0.137521 0.162921)
							(end -0.1524 0.127)
						)
						(arc
							(start -0.1524 -0.127)
							(mid -0.137521 -0.162921)
							(end -0.1016 -0.1778)
						)
						(arc
							(start 0.1016 -0.1778)
							(mid 0.137521 -0.162921)
							(end 0.1524 -0.127)
						)
					)
					(width 0)
					(fill yes)
				)
			)
		)
	)
	(footprint ""
		(layer "B.Cu")
		(at 73.578212 -192.641474)
		(property "Reference" "R3202"
			(at 0 0 0)
			(layer "B.SilkS")
			(hide yes)
			(effects
				(font
					(size 1.27 1.27)
				)
				(justify mirror)
			)
		)
		(property "Value" "0R2J-2-GP"
			(at -0.064008 -3.993896 0)
			(unlocked yes)
			(layer "B.Fab")
			(hide yes)
			(effects
				(font
					(size 1.016 1.016)
					(thickness 0.1524)
				)
				(justify mirror)
			)
		)
		(property "Device Type" "R402H16"
			(at -0.064008 -5.517896 0)
			(unlocked yes)
			(layer "B.Fab")
			(hide yes)
			(effects
				(font
					(size 1.016 1.016)
					(thickness 0.1524)
				)
				(justify mirror)
			)
		)
		(duplicate_pad_numbers_are_jumpers no)
		(fp_line
			(start -0.508 -0.9398)
			(end 0.508 -0.9398)
			(stroke
				(width 0.1524)
				(type default)
			)
			(layer "B.SilkS")
		)
		(fp_line
			(start 0.508 -0.9398)
			(end 0.508 0.9398)
			(stroke
				(width 0.1524)
				(type default)
			)
			(layer "B.SilkS")
		)
		(fp_rect
			(start 0.508 0.9398)
			(end -0.508 -0.9398)
			(stroke
				(width 0)
				(type default)
			)
			(fill no)
			(layer "B.CrtYd")
		)
		(fp_rect
			(start 0.508 0.9398)
			(end -0.508 -0.9398)
			(stroke
				(width 0)
				(type default)
			)
			(fill no)
			(layer "B.Fab")
		)
		(pad "1" smd custom
			(at 0 -0.4445 180)
			(size 0.1397 0.1397)
			(layers "B.Cu" "B.Mask" "B.Paste")
			(net "BMC_SSD_RST#0")
			(options
				(clearance outline)
				(anchor circle)
			)
			(primitives
				(gr_poly
					(pts
						(arc
							(start -0.1778 0.2794)
							(mid -0.249642 0.249642)
							(end -0.2794 0.1778)
						)
						(arc
							(start -0.2794 -0.1778)
							(mid -0.249642 -0.249642)
							(end -0.1778 -0.2794)
						)
						(arc
							(start 0.1778 -0.2794)
							(mid 0.249642 -0.249642)
							(end 0.2794 -0.1778)
						)
						(arc
							(start 0.2794 0.1778)
							(mid 0.249642 0.249642)
							(end 0.1778 0.2794)
						)
					)
					(width 0)
					(fill yes)
				)
			)
		)
		(pad "2" smd custom
			(at 0 0.4445 180)
			(size 0.1397 0.1397)
			(layers "B.Cu" "B.Mask" "B.Paste")
			(net "BMC_SSD_RST#0_A0")
			(options
				(clearance outline)
				(anchor circle)
			)
			(primitives
				(gr_poly
					(pts
						(arc
							(start -0.1778 0.2794)
							(mid -0.249642 0.249642)
							(end -0.2794 0.1778)
						)
						(arc
							(start -0.2794 -0.1778)
							(mid -0.249642 -0.249642)
							(end -0.1778 -0.2794)
						)
						(arc
							(start 0.1778 -0.2794)
							(mid 0.249642 -0.249642)
							(end 0.2794 -0.1778)
						)
						(arc
							(start 0.2794 0.1778)
							(mid 0.249642 0.249642)
							(end 0.1778 0.2794)
						)
					)
					(width 0)
					(fill yes)
				)
			)
		)
	)
	(footprint ""
		(layer "B.Cu")
		(at 246.126 -67.945 90)
		(property "Reference" "C507"
			(at 0 0 90)
			(layer "B.SilkS")
			(hide yes)
			(effects
				(font
					(size 1.27 1.27)
				)
				(justify mirror)
			)
		)
		(property "Value" "SC4D7U16V5KX-1-GP"
			(at 0.0762 -6.1214 90)
			(unlocked yes)
			(layer "B.Fab")
			(hide yes)
			(effects
				(font
					(size 1.016 1.016)
					(thickness 0.1524)
				)
				(justify mirror)
			)
		)
		(property "Device Type" "C805H56"
			(at 0.0762 -8.1534 90)
			(unlocked yes)
			(layer "B.Fab")
			(hide yes)
			(effects
				(font
					(size 1.016 1.016)
					(thickness 0.1524)
				)
				(justify mirror)
			)
		)
		(duplicate_pad_numbers_are_jumpers no)
		(fp_line
			(start -0.635 0)
			(end 0.635 0)
			(stroke
				(width 0.508)
				(type default)
			)
			(layer "B.SilkS")
		)
		(fp_rect
			(start 0.9652 1.778)
			(end -0.9652 -1.778)
			(stroke
				(width 0)
				(type default)
			)
			(fill no)
			(layer "B.CrtYd")
		)
		(fp_poly
			(pts
				(xy 0.9652 -1.778) (xy -0.9652 -1.778) (xy -0.9652 1.778) (xy 0.9652 1.778)
			)
			(stroke
				(width 0)
				(type default)
			)
			(fill no)
			(layer "B.Fab")
		)
		(pad "1" smd rect
			(at 0 -0.9652 270)
			(size 1.397 1.143)
			(layers "B.Cu" "B.Mask" "B.Paste")
			(net "DUT_AVD_TX")
		)
		(pad "2" smd rect
			(at 0 0.9652 270)
			(size 1.397 1.143)
			(layers "B.Cu" "B.Mask" "B.Paste")
			(net "GND")
		)
	)
	(footprint ""
		(layer "B.Cu")
		(at 70.033388 -189.603126)
		(property "Reference" "U75"
			(at 0 0 0)
			(layer "B.SilkS")
			(hide yes)
			(effects
				(font
					(size 1.27 1.27)
				)
				(justify mirror)
			)
		)
		(property "Value" "SN74LVC1G08DCKR-GP"
			(at 2.3368 -8.6868 0)
			(unlocked yes)
			(layer "B.Fab")
			(hide yes)
			(effects
				(font
					(size 1.016 1.016)
					(thickness 0.1524)
				)
				(justify mirror)
			)
		)
		(property "Device Type" "SC70-5H44"
			(at 2.3114 -10.414 0)
			(unlocked yes)
			(layer "B.Fab")
			(hide yes)
			(effects
				(font
					(size 1.016 1.016)
					(thickness 0.1524)
				)
				(justify mirror)
			)
		)
		(duplicate_pad_numbers_are_jumpers no)
		(fp_line
			(start -1.3843 -1.8034)
			(end -1.3843 -1.1176)
			(stroke
				(width 0.3302)
				(type default)
			)
			(layer "B.SilkS")
		)
		(fp_line
			(start -1.27 -1.7018)
			(end -1.27 1.7018)
			(stroke
				(width 0.1524)
				(type default)
			)
			(layer "B.SilkS")
		)
		(fp_line
			(start -1.27 1.7018)
			(end 1.27 1.7018)
			(stroke
				(width 0.1524)
				(type default)
			)
			(layer "B.SilkS")
		)
		(fp_line
			(start -0.6604 -1.8034)
			(end -1.3843 -1.8034)
			(stroke
				(width 0.3302)
				(type default)
			)
			(layer "B.SilkS")
		)
		(fp_line
			(start 1.27 -1.7018)
			(end -1.27 -1.7018)
			(stroke
				(width 0.1524)
				(type default)
			)
			(layer "B.SilkS")
		)
		(fp_line
			(start 1.27 1.7018)
			(end 1.27 -1.7018)
			(stroke
				(width 0.1524)
				(type default)
			)
			(layer "B.SilkS")
		)
		(fp_rect
			(start 1.524 1.9558)
			(end -1.524 -1.9558)
			(stroke
				(width 0)
				(type default)
			)
			(fill no)
			(layer "B.CrtYd")
		)
		(fp_poly
			(pts
				(xy 1.524 -1.9558) (xy -1.524 -1.9558) (xy -1.524 1.9558) (xy 1.524 1.9558)
			)
			(stroke
				(width 0)
				(type default)
			)
			(fill no)
			(layer "B.Fab")
		)
		(pad "1" smd rect
			(at -0.65024 -0.8255 180)
			(size 0.4064 1.2192)
			(layers "B.Cu" "B.Mask" "B.Paste")
			(net "BMC_SSD_RST#0_A11")
		)
		(pad "2" smd rect
			(at 0 -0.8255 180)
			(size 0.4064 1.2192)
			(layers "B.Cu" "B.Mask" "B.Paste")
			(net "SSD_PERST#0_B11")
		)
		(pad "3" smd rect
			(at 0.65024 -0.8255 180)
			(size 0.4064 1.2192)
			(layers "B.Cu" "B.Mask" "B.Paste")
			(net "GND")
		)
		(pad "4" smd rect
			(at 0.65024 0.8255 180)
			(size 0.4064 1.2192)
			(layers "B.Cu" "B.Mask" "B.Paste")
			(net "SSD_PERST_Y11")
		)
		(pad "5" smd rect
			(at -0.65024 0.8255 180)
			(size 0.4064 1.2192)
			(layers "B.Cu" "B.Mask" "B.Paste")
			(net "P3V3_STBY")
		)
	)
	(footprint ""
		(layer "B.Cu")
		(at 217.805 -198.12)
		(property "Reference" "R145"
			(at 0 0 0)
			(layer "B.SilkS")
			(hide yes)
			(effects
				(font
					(size 1.27 1.27)
				)
				(justify mirror)
			)
		)
		(property "Value" "4K7R2F-GP"
			(at -0.064008 -3.993896 0)
			(unlocked yes)
			(layer "B.Fab")
			(hide yes)
			(effects
				(font
					(size 1.016 1.016)
					(thickness 0.1524)
				)
				(justify mirror)
			)
		)
		(property "Device Type" "R402H16"
			(at -0.064008 -5.517896 0)
			(unlocked yes)
			(layer "B.Fab")
			(hide yes)
			(effects
				(font
					(size 1.016 1.016)
					(thickness 0.1524)
				)
				(justify mirror)
			)
		)
		(duplicate_pad_numbers_are_jumpers no)
		(fp_line
			(start -0.508 -0.9398)
			(end 0.508 -0.9398)
			(stroke
				(width 0.1524)
				(type default)
			)
			(layer "B.SilkS")
		)
		(fp_line
			(start 0.508 -0.9398)
			(end 0.508 0.9398)
			(stroke
				(width 0.1524)
				(type default)
			)
			(layer "B.SilkS")
		)
		(fp_rect
			(start 0.508 0.9398)
			(end -0.508 -0.9398)
			(stroke
				(width 0)
				(type default)
			)
			(fill no)
			(layer "B.CrtYd")
		)
		(fp_rect
			(start 0.508 0.9398)
			(end -0.508 -0.9398)
			(stroke
				(width 0)
				(type default)
			)
			(fill no)
			(layer "B.Fab")
		)
		(pad "1" smd custom
			(at 0 -0.4445 180)
			(size 0.1397 0.1397)
			(layers "B.Cu" "B.Mask" "B.Paste")
			(net "BMC_SSD_RST#0_A3")
			(options
				(clearance outline)
				(anchor circle)
			)
			(primitives
				(gr_poly
					(pts
						(arc
							(start -0.1778 0.2794)
							(mid -0.249642 0.249642)
							(end -0.2794 0.1778)
						)
						(arc
							(start -0.2794 -0.1778)
							(mid -0.249642 -0.249642)
							(end -0.1778 -0.2794)
						)
						(arc
							(start 0.1778 -0.2794)
							(mid 0.249642 -0.249642)
							(end 0.2794 -0.1778)
						)
						(arc
							(start 0.2794 0.1778)
							(mid 0.249642 0.249642)
							(end 0.1778 0.2794)
						)
					)
					(width 0)
					(fill yes)
				)
			)
		)
		(pad "2" smd custom
			(at 0 0.4445 180)
			(size 0.1397 0.1397)
			(layers "B.Cu" "B.Mask" "B.Paste")
			(net "P3V3_STBY")
			(options
				(clearance outline)
				(anchor circle)
			)
			(primitives
				(gr_poly
					(pts
						(arc
							(start -0.1778 0.2794)
							(mid -0.249642 0.249642)
							(end -0.2794 0.1778)
						)
						(arc
							(start -0.2794 -0.1778)
							(mid -0.249642 -0.249642)
							(end -0.1778 -0.2794)
						)
						(arc
							(start 0.1778 -0.2794)
							(mid 0.249642 -0.249642)
							(end 0.2794 -0.1778)
						)
						(arc
							(start 0.2794 0.1778)
							(mid 0.249642 0.249642)
							(end 0.1778 0.2794)
						)
					)
					(width 0)
					(fill yes)
				)
			)
		)
	)
	(footprint ""
		(layer "B.Cu")
		(at 45.72 -131.445 90)
		(property "Reference" "R337"
			(at 0 0 90)
			(layer "B.SilkS")
			(hide yes)
			(effects
				(font
					(size 1.27 1.27)
				)
				(justify mirror)
			)
		)
		(property "Value" "49K9R2F-L-GP"
			(at -0.064008 -3.993896 90)
			(unlocked yes)
			(layer "B.Fab")
			(hide yes)
			(effects
				(font
					(size 1.016 1.016)
					(thickness 0.1524)
				)
				(justify mirror)
			)
		)
		(property "Device Type" "R402H16"
			(at -0.064008 -5.517896 90)
			(unlocked yes)
			(layer "B.Fab")
			(hide yes)
			(effects
				(font
					(size 1.016 1.016)
					(thickness 0.1524)
				)
				(justify mirror)
			)
		)
		(duplicate_pad_numbers_are_jumpers no)
		(fp_line
			(start 0.508 -0.9398)
			(end 0.508 0.9398)
			(stroke
				(width 0.1524)
				(type default)
			)
			(layer "B.SilkS")
		)
		(fp_line
			(start -0.508 -0.9398)
			(end 0.508 -0.9398)
			(stroke
				(width 0.1524)
				(type default)
			)
			(layer "B.SilkS")
		)
		(fp_rect
			(start 0.508 0.9398)
			(end -0.508 -0.9398)
			(stroke
				(width 0)
				(type default)
			)
			(fill no)
			(layer "B.CrtYd")
		)
		(fp_rect
			(start 0.508 0.9398)
			(end -0.508 -0.9398)
			(stroke
				(width 0)
				(type default)
			)
			(fill no)
			(layer "B.Fab")
		)
		(pad "1" smd custom
			(at 0 -0.4445 270)
			(size 0.1397 0.1397)
			(layers "B.Cu" "B.Mask" "B.Paste")
			(net "GND")
			(options
				(clearance outline)
				(anchor circle)
			)
			(primitives
				(gr_poly
					(pts
						(arc
							(start -0.1778 0.2794)
							(mid -0.249642 0.249642)
							(end -0.2794 0.1778)
						)
						(arc
							(start -0.2794 -0.1778)
							(mid -0.249642 -0.249642)
							(end -0.1778 -0.2794)
						)
						(arc
							(start 0.1778 -0.2794)
							(mid 0.249642 -0.249642)
							(end 0.2794 -0.1778)
						)
						(arc
							(start 0.2794 0.1778)
							(mid 0.249642 0.249642)
							(end 0.1778 0.2794)
						)
					)
					(width 0)
					(fill yes)
				)
			)
		)
		(pad "2" smd custom
			(at 0 0.4445 270)
			(size 0.1397 0.1397)
			(layers "B.Cu" "B.Mask" "B.Paste")
			(net "ADCVREXT")
			(options
				(clearance outline)
				(anchor circle)
			)
			(primitives
				(gr_poly
					(pts
						(arc
							(start -0.1778 0.2794)
							(mid -0.249642 0.249642)
							(end -0.2794 0.1778)
						)
						(arc
							(start -0.2794 -0.1778)
							(mid -0.249642 -0.249642)
							(end -0.1778 -0.2794)
						)
						(arc
							(start 0.1778 -0.2794)
							(mid 0.249642 -0.249642)
							(end 0.2794 -0.1778)
						)
						(arc
							(start 0.2794 0.1778)
							(mid 0.249642 0.249642)
							(end 0.1778 0.2794)
						)
					)
					(width 0)
					(fill yes)
				)
			)
		)
	)
	(footprint ""
		(layer "B.Cu")
		(at 244.599968 -39.99992 -90)
		(property "Reference" "TP238"
			(at 0 0 90)
			(layer "B.SilkS")
			(hide yes)
			(effects
				(font
					(size 1.27 1.27)
				)
				(justify mirror)
			)
		)
		(property "Value" "TPAD28-2-GP"
			(at 0.0127 -1.6637 270)
			(unlocked yes)
			(layer "B.Fab")
			(hide yes)
			(effects
				(font
					(size 1.016 1.016)
					(thickness 0.1524)
				)
				(justify mirror)
			)
		)
		(property "Device Type" "TPAD28"
			(at 0.0127 -3.1877 270)
			(unlocked yes)
			(layer "B.Fab")
			(hide yes)
			(effects
				(font
					(size 1.016 1.016)
					(thickness 0.1524)
				)
				(justify mirror)
			)
		)
		(duplicate_pad_numbers_are_jumpers no)
		(fp_poly
			(pts
				(arc
					(start 0 -0.3556)
					(mid 0 0.3556)
					(end 0 -0.3556)
				)
			)
			(stroke
				(width 0)
				(type default)
			)
			(fill no)
			(layer "B.CrtYd")
		)
		(fp_poly
			(pts
				(arc
					(start 0 -0.6096)
					(mid 0 0.6096)
					(end 0 -0.6096)
				)
			)
			(stroke
				(width 0)
				(type default)
			)
			(fill no)
			(layer "B.Fab")
		)
		(pad "1" smd circle
			(at 0 0 90)
			(size 0.7112 0.7112)
			(layers "B.Cu" "B.Mask" "B.Paste")
			(net "RS232_UCTSB0")
		)
	)
	(footprint ""
		(layer "B.Cu")
		(at 226.568 -59.9948 -90)
		(property "Reference" "C544"
			(at 0 0 90)
			(layer "B.SilkS")
			(hide yes)
			(effects
				(font
					(size 1.27 1.27)
				)
				(justify mirror)
			)
		)
		(property "Value" "SCD1U16V1KX-1-GP"
			(at 2.8321 -1.7399 270)
			(unlocked yes)
			(layer "B.Fab")
			(hide yes)
			(effects
				(font
					(size 1.016 1.016)
					(thickness 0.1524)
				)
				(justify mirror)
			)
		)
		(property "Device Type" "C0201H13"
			(at 2.8321 -3.2639 270)
			(unlocked yes)
			(layer "B.Fab")
			(hide yes)
			(effects
				(font
					(size 1.016 1.016)
					(thickness 0.1524)
				)
				(justify mirror)
			)
		)
		(duplicate_pad_numbers_are_jumpers no)
		(fp_rect
			(start 0.2794 0.6477)
			(end -0.2794 -0.6477)
			(stroke
				(width 0)
				(type default)
			)
			(fill no)
			(layer "B.CrtYd")
		)
		(fp_rect
			(start 0.2794 0.6477)
			(end -0.2794 -0.6477)
			(stroke
				(width 0)
				(type default)
			)
			(fill no)
			(layer "B.Fab")
		)
		(pad "1" smd custom
			(at 0 -0.2794 90)
			(size 0.0762 0.0762)
			(layers "B.Cu" "B.Mask" "B.Paste")
			(net "DUT_AVD_PCIE")
			(options
				(clearance outline)
				(anchor circle)
			)
			(primitives
				(gr_poly
					(pts
						(arc
							(start 0.1524 0.127)
							(mid 0.137521 0.162921)
							(end 0.1016 0.1778)
						)
						(arc
							(start -0.1016 0.1778)
							(mid -0.137521 0.162921)
							(end -0.1524 0.127)
						)
						(arc
							(start -0.1524 -0.127)
							(mid -0.137521 -0.162921)
							(end -0.1016 -0.1778)
						)
						(arc
							(start 0.1016 -0.1778)
							(mid 0.137521 -0.162921)
							(end 0.1524 -0.127)
						)
					)
					(width 0)
					(fill yes)
				)
			)
		)
		(pad "2" smd custom
			(at 0 0.2794 90)
			(size 0.0762 0.0762)
			(layers "B.Cu" "B.Mask" "B.Paste")
			(net "GND")
			(options
				(clearance outline)
				(anchor circle)
			)
			(primitives
				(gr_poly
					(pts
						(arc
							(start 0.1524 0.127)
							(mid 0.137521 0.162921)
							(end 0.1016 0.1778)
						)
						(arc
							(start -0.1016 0.1778)
							(mid -0.137521 0.162921)
							(end -0.1524 0.127)
						)
						(arc
							(start -0.1524 -0.127)
							(mid -0.137521 -0.162921)
							(end -0.1016 -0.1778)
						)
						(arc
							(start 0.1016 -0.1778)
							(mid 0.137521 -0.162921)
							(end 0.1524 -0.127)
						)
					)
					(width 0)
					(fill yes)
				)
			)
		)
	)
	(footprint ""
		(layer "B.Cu")
		(at 82.145124 -195.427092 180)
		(property "Reference" "R4111"
			(at 0 0 0)
			(layer "B.SilkS")
			(hide yes)
			(effects
				(font
					(size 1.27 1.27)
				)
				(justify mirror)
			)
		)
		(property "Value" "4K7R2F-GP"
			(at -0.064008 -3.993896 180)
			(unlocked yes)
			(layer "B.Fab")
			(hide yes)
			(effects
				(font
					(size 1.016 1.016)
					(thickness 0.1524)
				)
				(justify mirror)
			)
		)
		(property "Device Type" "R402H16"
			(at -0.064008 -5.517896 180)
			(unlocked yes)
			(layer "B.Fab")
			(hide yes)
			(effects
				(font
					(size 1.016 1.016)
					(thickness 0.1524)
				)
				(justify mirror)
			)
		)
		(duplicate_pad_numbers_are_jumpers no)
		(fp_line
			(start 0.508 -0.9398)
			(end 0.508 0.9398)
			(stroke
				(width 0.1524)
				(type default)
			)
			(layer "B.SilkS")
		)
		(fp_line
			(start -0.508 -0.9398)
			(end 0.508 -0.9398)
			(stroke
				(width 0.1524)
				(type default)
			)
			(layer "B.SilkS")
		)
		(fp_rect
			(start 0.508 0.9398)
			(end -0.508 -0.9398)
			(stroke
				(width 0)
				(type default)
			)
			(fill no)
			(layer "B.CrtYd")
		)
		(fp_rect
			(start 0.508 0.9398)
			(end -0.508 -0.9398)
			(stroke
				(width 0)
				(type default)
			)
			(fill no)
			(layer "B.Fab")
		)
		(pad "1" smd custom
			(at 0 -0.4445)
			(size 0.1397 0.1397)
			(layers "B.Cu" "B.Mask" "B.Paste")
			(net "SSD_PRSNT#10")
			(options
				(clearance outline)
				(anchor circle)
			)
			(primitives
				(gr_poly
					(pts
						(arc
							(start -0.1778 0.2794)
							(mid -0.249642 0.249642)
							(end -0.2794 0.1778)
						)
						(arc
							(start -0.2794 -0.1778)
							(mid -0.249642 -0.249642)
							(end -0.1778 -0.2794)
						)
						(arc
							(start 0.1778 -0.2794)
							(mid 0.249642 -0.249642)
							(end 0.2794 -0.1778)
						)
						(arc
							(start 0.2794 0.1778)
							(mid 0.249642 0.249642)
							(end 0.1778 0.2794)
						)
					)
					(width 0)
					(fill yes)
				)
			)
		)
		(pad "2" smd custom
			(at 0 0.4445)
			(size 0.1397 0.1397)
			(layers "B.Cu" "B.Mask" "B.Paste")
			(net "P3V3_STBY")
			(options
				(clearance outline)
				(anchor circle)
			)
			(primitives
				(gr_poly
					(pts
						(arc
							(start -0.1778 0.2794)
							(mid -0.249642 0.249642)
							(end -0.2794 0.1778)
						)
						(arc
							(start -0.2794 -0.1778)
							(mid -0.249642 -0.249642)
							(end -0.1778 -0.2794)
						)
						(arc
							(start 0.1778 -0.2794)
							(mid 0.249642 -0.249642)
							(end 0.2794 -0.1778)
						)
						(arc
							(start 0.2794 0.1778)
							(mid 0.249642 0.249642)
							(end 0.1778 0.2794)
						)
					)
					(width 0)
					(fill yes)
				)
			)
		)
	)
	(footprint ""
		(layer "B.Cu")
		(at 75.184 -146.939 -90)
		(property "Reference" "R192"
			(at 0 0 90)
			(layer "B.SilkS")
			(hide yes)
			(effects
				(font
					(size 1.27 1.27)
				)
				(justify mirror)
			)
		)
		(property "Value" "8K2R2J-3-GP"
			(at -0.064008 -3.993896 270)
			(unlocked yes)
			(layer "B.Fab")
			(hide yes)
			(effects
				(font
					(size 1.016 1.016)
					(thickness 0.1524)
				)
				(justify mirror)
			)
		)
		(property "Device Type" "R402H16"
			(at -0.064008 -5.517896 270)
			(unlocked yes)
			(layer "B.Fab")
			(hide yes)
			(effects
				(font
					(size 1.016 1.016)
					(thickness 0.1524)
				)
				(justify mirror)
			)
		)
		(duplicate_pad_numbers_are_jumpers no)
		(fp_line
			(start -0.508 -0.9398)
			(end 0.508 -0.9398)
			(stroke
				(width 0.1524)
				(type default)
			)
			(layer "B.SilkS")
		)
		(fp_line
			(start 0.508 -0.9398)
			(end 0.508 0.9398)
			(stroke
				(width 0.1524)
				(type default)
			)
			(layer "B.SilkS")
		)
		(fp_rect
			(start 0.508 0.9398)
			(end -0.508 -0.9398)
			(stroke
				(width 0)
				(type default)
			)
			(fill no)
			(layer "B.CrtYd")
		)
		(fp_rect
			(start 0.508 0.9398)
			(end -0.508 -0.9398)
			(stroke
				(width 0)
				(type default)
			)
			(fill no)
			(layer "B.Fab")
		)
		(pad "1" smd custom
			(at 0 -0.4445 90)
			(size 0.1397 0.1397)
			(layers "B.Cu" "B.Mask" "B.Paste")
			(net "P3V3_STBY")
			(options
				(clearance outline)
				(anchor circle)
			)
			(primitives
				(gr_poly
					(pts
						(arc
							(start -0.1778 0.2794)
							(mid -0.249642 0.249642)
							(end -0.2794 0.1778)
						)
						(arc
							(start -0.2794 -0.1778)
							(mid -0.249642 -0.249642)
							(end -0.1778 -0.2794)
						)
						(arc
							(start 0.1778 -0.2794)
							(mid 0.249642 -0.249642)
							(end 0.2794 -0.1778)
						)
						(arc
							(start 0.2794 0.1778)
							(mid 0.249642 0.249642)
							(end 0.1778 0.2794)
						)
					)
					(width 0)
					(fill yes)
				)
			)
		)
		(pad "2" smd custom
			(at 0 0.4445 90)
			(size 0.1397 0.1397)
			(layers "B.Cu" "B.Mask" "B.Paste")
			(net "EEPROM_A0_R")
			(options
				(clearance outline)
				(anchor circle)
			)
			(primitives
				(gr_poly
					(pts
						(arc
							(start -0.1778 0.2794)
							(mid -0.249642 0.249642)
							(end -0.2794 0.1778)
						)
						(arc
							(start -0.2794 -0.1778)
							(mid -0.249642 -0.249642)
							(end -0.1778 -0.2794)
						)
						(arc
							(start 0.1778 -0.2794)
							(mid 0.249642 -0.249642)
							(end 0.2794 -0.1778)
						)
						(arc
							(start 0.2794 0.1778)
							(mid 0.249642 0.249642)
							(end 0.1778 0.2794)
						)
					)
					(width 0)
					(fill yes)
				)
			)
		)
	)
	(footprint ""
		(layer "B.Cu")
		(at 54.031642 -122.860816 -90)
		(property "Reference" "R467"
			(at 0 0 90)
			(layer "B.SilkS")
			(hide yes)
			(effects
				(font
					(size 1.27 1.27)
				)
				(justify mirror)
			)
		)
		(property "Value" "0R2J-2-GP"
			(at -0.064008 -3.993896 270)
			(unlocked yes)
			(layer "B.Fab")
			(hide yes)
			(effects
				(font
					(size 1.016 1.016)
					(thickness 0.1524)
				)
				(justify mirror)
			)
		)
		(property "Device Type" "R402H16"
			(at -0.064008 -5.517896 270)
			(unlocked yes)
			(layer "B.Fab")
			(hide yes)
			(effects
				(font
					(size 1.016 1.016)
					(thickness 0.1524)
				)
				(justify mirror)
			)
		)
		(duplicate_pad_numbers_are_jumpers no)
		(fp_line
			(start -0.508 -0.9398)
			(end 0.508 -0.9398)
			(stroke
				(width 0.1524)
				(type default)
			)
			(layer "B.SilkS")
		)
		(fp_line
			(start 0.508 -0.9398)
			(end 0.508 0.9398)
			(stroke
				(width 0.1524)
				(type default)
			)
			(layer "B.SilkS")
		)
		(fp_rect
			(start 0.508 0.9398)
			(end -0.508 -0.9398)
			(stroke
				(width 0)
				(type default)
			)
			(fill no)
			(layer "B.CrtYd")
		)
		(fp_rect
			(start 0.508 0.9398)
			(end -0.508 -0.9398)
			(stroke
				(width 0)
				(type default)
			)
			(fill no)
			(layer "B.Fab")
		)
		(pad "1" smd custom
			(at 0 -0.4445 90)
			(size 0.1397 0.1397)
			(layers "B.Cu" "B.Mask" "B.Paste")
			(net "BMC_I2C8_CLKBUF1_SDA")
			(options
				(clearance outline)
				(anchor circle)
			)
			(primitives
				(gr_poly
					(pts
						(arc
							(start -0.1778 0.2794)
							(mid -0.249642 0.249642)
							(end -0.2794 0.1778)
						)
						(arc
							(start -0.2794 -0.1778)
							(mid -0.249642 -0.249642)
							(end -0.1778 -0.2794)
						)
						(arc
							(start 0.1778 -0.2794)
							(mid 0.249642 -0.249642)
							(end 0.2794 -0.1778)
						)
						(arc
							(start 0.2794 0.1778)
							(mid 0.249642 0.249642)
							(end 0.1778 0.2794)
						)
					)
					(width 0)
					(fill yes)
				)
			)
		)
		(pad "2" smd custom
			(at 0 0.4445 90)
			(size 0.1397 0.1397)
			(layers "B.Cu" "B.Mask" "B.Paste")
			(net "BMC0_SMB8_DAT")
			(options
				(clearance outline)
				(anchor circle)
			)
			(primitives
				(gr_poly
					(pts
						(arc
							(start -0.1778 0.2794)
							(mid -0.249642 0.249642)
							(end -0.2794 0.1778)
						)
						(arc
							(start -0.2794 -0.1778)
							(mid -0.249642 -0.249642)
							(end -0.1778 -0.2794)
						)
						(arc
							(start 0.1778 -0.2794)
							(mid 0.249642 -0.249642)
							(end 0.2794 -0.1778)
						)
						(arc
							(start 0.2794 0.1778)
							(mid 0.249642 0.249642)
							(end 0.1778 0.2794)
						)
					)
					(width 0)
					(fill yes)
				)
			)
		)
	)
	(footprint ""
		(layer "B.Cu")
		(at 181.64302 -12.0396 180)
		(property "Reference" "R303"
			(at 0 0 0)
			(layer "B.SilkS")
			(hide yes)
			(effects
				(font
					(size 1.27 1.27)
				)
				(justify mirror)
			)
		)
		(property "Value" "0R2J-2-GP"
			(at -0.064008 -3.993896 180)
			(unlocked yes)
			(layer "B.Fab")
			(hide yes)
			(effects
				(font
					(size 1.016 1.016)
					(thickness 0.1524)
				)
				(justify mirror)
			)
		)
		(property "Device Type" "R402H16"
			(at -0.064008 -5.517896 180)
			(unlocked yes)
			(layer "B.Fab")
			(hide yes)
			(effects
				(font
					(size 1.016 1.016)
					(thickness 0.1524)
				)
				(justify mirror)
			)
		)
		(duplicate_pad_numbers_are_jumpers no)
		(fp_line
			(start 0.508 -0.9398)
			(end 0.508 0.9398)
			(stroke
				(width 0.1524)
				(type default)
			)
			(layer "B.SilkS")
		)
		(fp_line
			(start -0.508 -0.9398)
			(end 0.508 -0.9398)
			(stroke
				(width 0.1524)
				(type default)
			)
			(layer "B.SilkS")
		)
		(fp_rect
			(start 0.508 0.9398)
			(end -0.508 -0.9398)
			(stroke
				(width 0)
				(type default)
			)
			(fill no)
			(layer "B.CrtYd")
		)
		(fp_rect
			(start 0.508 0.9398)
			(end -0.508 -0.9398)
			(stroke
				(width 0)
				(type default)
			)
			(fill no)
			(layer "B.Fab")
		)
		(pad "1" smd custom
			(at 0 -0.4445)
			(size 0.1397 0.1397)
			(layers "B.Cu" "B.Mask" "B.Paste")
			(net "CLK_P_3_R")
			(options
				(clearance outline)
				(anchor circle)
			)
			(primitives
				(gr_poly
					(pts
						(arc
							(start -0.1778 0.2794)
							(mid -0.249642 0.249642)
							(end -0.2794 0.1778)
						)
						(arc
							(start -0.2794 -0.1778)
							(mid -0.249642 -0.249642)
							(end -0.1778 -0.2794)
						)
						(arc
							(start 0.1778 -0.2794)
							(mid 0.249642 -0.249642)
							(end 0.2794 -0.1778)
						)
						(arc
							(start 0.2794 0.1778)
							(mid 0.249642 0.249642)
							(end 0.1778 0.2794)
						)
					)
					(width 0)
					(fill yes)
				)
			)
		)
		(pad "2" smd custom
			(at 0 0.4445)
			(size 0.1397 0.1397)
			(layers "B.Cu" "B.Mask" "B.Paste")
			(net "PCIE_REFCLK_H3_P_R")
			(options
				(clearance outline)
				(anchor circle)
			)
			(primitives
				(gr_poly
					(pts
						(arc
							(start -0.1778 0.2794)
							(mid -0.249642 0.249642)
							(end -0.2794 0.1778)
						)
						(arc
							(start -0.2794 -0.1778)
							(mid -0.249642 -0.249642)
							(end -0.1778 -0.2794)
						)
						(arc
							(start 0.1778 -0.2794)
							(mid 0.249642 -0.249642)
							(end 0.2794 -0.1778)
						)
						(arc
							(start 0.2794 0.1778)
							(mid 0.249642 0.249642)
							(end 0.1778 0.2794)
						)
					)
					(width 0)
					(fill yes)
				)
			)
		)
	)
	(footprint ""
		(layer "B.Cu")
		(at 240.538 -23.241)
		(property "Reference" "R798"
			(at 0 0 0)
			(layer "B.SilkS")
			(hide yes)
			(effects
				(font
					(size 1.27 1.27)
				)
				(justify mirror)
			)
		)
		(property "Value" "4K7R2F-GP"
			(at -0.064008 -3.993896 0)
			(unlocked yes)
			(layer "B.Fab")
			(hide yes)
			(effects
				(font
					(size 1.016 1.016)
					(thickness 0.1524)
				)
				(justify mirror)
			)
		)
		(property "Device Type" "R402H16"
			(at -0.064008 -5.517896 0)
			(unlocked yes)
			(layer "B.Fab")
			(hide yes)
			(effects
				(font
					(size 1.016 1.016)
					(thickness 0.1524)
				)
				(justify mirror)
			)
		)
		(duplicate_pad_numbers_are_jumpers no)
		(fp_line
			(start -0.508 -0.9398)
			(end 0.508 -0.9398)
			(stroke
				(width 0.1524)
				(type default)
			)
			(layer "B.SilkS")
		)
		(fp_line
			(start 0.508 -0.9398)
			(end 0.508 0.9398)
			(stroke
				(width 0.1524)
				(type default)
			)
			(layer "B.SilkS")
		)
		(fp_rect
			(start 0.508 0.9398)
			(end -0.508 -0.9398)
			(stroke
				(width 0)
				(type default)
			)
			(fill no)
			(layer "B.CrtYd")
		)
		(fp_rect
			(start 0.508 0.9398)
			(end -0.508 -0.9398)
			(stroke
				(width 0)
				(type default)
			)
			(fill no)
			(layer "B.Fab")
		)
		(pad "1" smd custom
			(at 0 -0.4445 180)
			(size 0.1397 0.1397)
			(layers "B.Cu" "B.Mask" "B.Paste")
			(net "GND")
			(options
				(clearance outline)
				(anchor circle)
			)
			(primitives
				(gr_poly
					(pts
						(arc
							(start -0.1778 0.2794)
							(mid -0.249642 0.249642)
							(end -0.2794 0.1778)
						)
						(arc
							(start -0.2794 -0.1778)
							(mid -0.249642 -0.249642)
							(end -0.1778 -0.2794)
						)
						(arc
							(start 0.1778 -0.2794)
							(mid 0.249642 -0.249642)
							(end 0.2794 -0.1778)
						)
						(arc
							(start 0.2794 0.1778)
							(mid 0.249642 0.249642)
							(end 0.1778 0.2794)
						)
					)
					(width 0)
					(fill yes)
				)
			)
		)
		(pad "2" smd custom
			(at 0 0.4445 180)
			(size 0.1397 0.1397)
			(layers "B.Cu" "B.Mask" "B.Paste")
			(net "BOOTSTRAP3")
			(options
				(clearance outline)
				(anchor circle)
			)
			(primitives
				(gr_poly
					(pts
						(arc
							(start -0.1778 0.2794)
							(mid -0.249642 0.249642)
							(end -0.2794 0.1778)
						)
						(arc
							(start -0.2794 -0.1778)
							(mid -0.249642 -0.249642)
							(end -0.1778 -0.2794)
						)
						(arc
							(start 0.1778 -0.2794)
							(mid 0.249642 -0.249642)
							(end 0.2794 -0.1778)
						)
						(arc
							(start 0.2794 0.1778)
							(mid 0.249642 0.249642)
							(end 0.1778 0.2794)
						)
					)
					(width 0)
					(fill yes)
				)
			)
		)
	)
	(footprint ""
		(layer "B.Cu")
		(at 340.995 -60.96 -90)
		(property "Reference" "PC170"
			(at 0 0 90)
			(layer "B.SilkS")
			(hide yes)
			(effects
				(font
					(size 1.27 1.27)
				)
				(justify mirror)
			)
		)
		(property "Value" "SC10U25V5KX-GP"
			(at 0.0762 -6.1214 270)
			(unlocked yes)
			(layer "B.Fab")
			(hide yes)
			(effects
				(font
					(size 1.016 1.016)
					(thickness 0.1524)
				)
				(justify mirror)
			)
		)
		(property "Device Type" "C805H56"
			(at 0.0762 -8.1534 270)
			(unlocked yes)
			(layer "B.Fab")
			(hide yes)
			(effects
				(font
					(size 1.016 1.016)
					(thickness 0.1524)
				)
				(justify mirror)
			)
		)
		(duplicate_pad_numbers_are_jumpers no)
		(fp_line
			(start -0.635 0)
			(end 0.635 0)
			(stroke
				(width 0.508)
				(type default)
			)
			(layer "B.SilkS")
		)
		(fp_rect
			(start 0.9652 1.778)
			(end -0.9652 -1.778)
			(stroke
				(width 0)
				(type default)
			)
			(fill no)
			(layer "B.CrtYd")
		)
		(fp_poly
			(pts
				(xy 0.9652 -1.778) (xy -0.9652 -1.778) (xy -0.9652 1.778) (xy 0.9652 1.778)
			)
			(stroke
				(width 0)
				(type default)
			)
			(fill no)
			(layer "B.Fab")
		)
		(pad "1" smd rect
			(at 0 -0.9652 90)
			(size 1.397 1.143)
			(layers "B.Cu" "B.Mask" "B.Paste")
			(net "P0V9_E_VIN")
		)
		(pad "2" smd rect
			(at 0 0.9652 90)
			(size 1.397 1.143)
			(layers "B.Cu" "B.Mask" "B.Paste")
			(net "GND")
		)
	)
	(footprint ""
		(layer "B.Cu")
		(at 334.01 -63.627 90)
		(property "Reference" "PR154"
			(at 0 0 90)
			(layer "B.SilkS")
			(hide yes)
			(effects
				(font
					(size 1.27 1.27)
				)
				(justify mirror)
			)
		)
		(property "Value" "3D01R5F-GP"
			(at 0 -8.9535 90)
			(unlocked yes)
			(layer "B.Fab")
			(hide yes)
			(effects
				(font
					(size 1.27 1.016)
					(thickness 0.1524)
				)
				(justify mirror)
			)
		)
		(property "Device Type" "R805H24"
			(at 0 -10.6299 90)
			(unlocked yes)
			(layer "B.Fab")
			(hide yes)
			(effects
				(font
					(size 1.27 1.016)
					(thickness 0.1524)
				)
				(justify mirror)
			)
		)
		(duplicate_pad_numbers_are_jumpers no)
		(fp_line
			(start 0.889 -1.7018)
			(end 0.889 0.2794)
			(stroke
				(width 0.1524)
				(type default)
			)
			(layer "B.SilkS")
		)
		(fp_line
			(start -0.889 -1.7018)
			(end 0.889 -1.7018)
			(stroke
				(width 0.1524)
				(type default)
			)
			(layer "B.SilkS")
		)
		(fp_line
			(start -0.889 -1.7018)
			(end -0.889 -0.381)
			(stroke
				(width 0.1524)
				(type default)
			)
			(layer "B.SilkS")
		)
		(fp_line
			(start 0.889 0.0762)
			(end 0.889 1.7018)
			(stroke
				(width 0.1524)
				(type default)
			)
			(layer "B.SilkS")
		)
		(fp_line
			(start 0.889 1.7018)
			(end -0.889 1.7018)
			(stroke
				(width 0.1524)
				(type default)
			)
			(layer "B.SilkS")
		)
		(fp_line
			(start -0.889 1.7018)
			(end -0.889 -0.508)
			(stroke
				(width 0.1524)
				(type default)
			)
			(layer "B.SilkS")
		)
		(fp_poly
			(pts
				(xy -0.9652 -1.778) (xy -0.9652 1.778) (xy 0.9652 1.778) (xy 0.9652 -1.778)
			)
			(stroke
				(width 0)
				(type default)
			)
			(fill no)
			(layer "B.CrtYd")
		)
		(fp_rect
			(start 0.9652 1.778)
			(end -0.9652 -1.778)
			(stroke
				(width 0)
				(type default)
			)
			(fill no)
			(layer "B.Fab")
		)
		(pad "1" smd rect
			(at 0 -0.9652 270)
			(size 1.397 1.143)
			(layers "B.Cu" "B.Mask" "B.Paste")
			(net "P0V9_E_LX")
		)
		(pad "2" smd rect
			(at 0 0.9652 270)
			(size 1.397 1.143)
			(layers "B.Cu" "B.Mask" "B.Paste")
			(net "P0V9_E_SNB")
		)
	)
	(footprint ""
		(layer "B.Cu")
		(at 252.603 -45.000672 -90)
		(property "Reference" "C613"
			(at 0 0 90)
			(layer "B.SilkS")
			(hide yes)
			(effects
				(font
					(size 1.27 1.27)
				)
				(justify mirror)
			)
		)
		(property "Value" "SCD1U16V1KX-1-GP"
			(at 2.8321 -1.7399 270)
			(unlocked yes)
			(layer "B.Fab")
			(hide yes)
			(effects
				(font
					(size 1.016 1.016)
					(thickness 0.1524)
				)
				(justify mirror)
			)
		)
		(property "Device Type" "C0201H13"
			(at 2.8321 -3.2639 270)
			(unlocked yes)
			(layer "B.Fab")
			(hide yes)
			(effects
				(font
					(size 1.016 1.016)
					(thickness 0.1524)
				)
				(justify mirror)
			)
		)
		(duplicate_pad_numbers_are_jumpers no)
		(fp_rect
			(start 0.2794 0.6477)
			(end -0.2794 -0.6477)
			(stroke
				(width 0)
				(type default)
			)
			(fill no)
			(layer "B.CrtYd")
		)
		(fp_rect
			(start 0.2794 0.6477)
			(end -0.2794 -0.6477)
			(stroke
				(width 0)
				(type default)
			)
			(fill no)
			(layer "B.Fab")
		)
		(pad "1" smd custom
			(at 0 -0.2794 90)
			(size 0.0762 0.0762)
			(layers "B.Cu" "B.Mask" "B.Paste")
			(net "DUT_AVD_PCIE")
			(options
				(clearance outline)
				(anchor circle)
			)
			(primitives
				(gr_poly
					(pts
						(arc
							(start 0.1524 0.127)
							(mid 0.137521 0.162921)
							(end 0.1016 0.1778)
						)
						(arc
							(start -0.1016 0.1778)
							(mid -0.137521 0.162921)
							(end -0.1524 0.127)
						)
						(arc
							(start -0.1524 -0.127)
							(mid -0.137521 -0.162921)
							(end -0.1016 -0.1778)
						)
						(arc
							(start 0.1016 -0.1778)
							(mid 0.137521 -0.162921)
							(end 0.1524 -0.127)
						)
					)
					(width 0)
					(fill yes)
				)
			)
		)
		(pad "2" smd custom
			(at 0 0.2794 90)
			(size 0.0762 0.0762)
			(layers "B.Cu" "B.Mask" "B.Paste")
			(net "GND")
			(options
				(clearance outline)
				(anchor circle)
			)
			(primitives
				(gr_poly
					(pts
						(arc
							(start 0.1524 0.127)
							(mid 0.137521 0.162921)
							(end 0.1016 0.1778)
						)
						(arc
							(start -0.1016 0.1778)
							(mid -0.137521 0.162921)
							(end -0.1524 0.127)
						)
						(arc
							(start -0.1524 -0.127)
							(mid -0.137521 -0.162921)
							(end -0.1016 -0.1778)
						)
						(arc
							(start 0.1016 -0.1778)
							(mid 0.137521 -0.162921)
							(end 0.1524 -0.127)
						)
					)
					(width 0)
					(fill yes)
				)
			)
		)
	)
	(footprint ""
		(layer "B.Cu")
		(at 57.15 -136.271)
		(property "Reference" "R5763"
			(at 0 0 0)
			(layer "B.SilkS")
			(hide yes)
			(effects
				(font
					(size 1.27 1.27)
				)
				(justify mirror)
			)
		)
		(property "Value" "1KR2F-3-GP"
			(at -0.064008 -3.993896 0)
			(unlocked yes)
			(layer "B.Fab")
			(hide yes)
			(effects
				(font
					(size 1.016 1.016)
					(thickness 0.1524)
				)
				(justify mirror)
			)
		)
		(property "Device Type" "R402H16"
			(at -0.064008 -5.517896 0)
			(unlocked yes)
			(layer "B.Fab")
			(hide yes)
			(effects
				(font
					(size 1.016 1.016)
					(thickness 0.1524)
				)
				(justify mirror)
			)
		)
		(duplicate_pad_numbers_are_jumpers no)
		(fp_line
			(start -0.508 -0.9398)
			(end 0.508 -0.9398)
			(stroke
				(width 0.1524)
				(type default)
			)
			(layer "B.SilkS")
		)
		(fp_line
			(start 0.508 -0.9398)
			(end 0.508 0.9398)
			(stroke
				(width 0.1524)
				(type default)
			)
			(layer "B.SilkS")
		)
		(fp_rect
			(start 0.508 0.9398)
			(end -0.508 -0.9398)
			(stroke
				(width 0)
				(type default)
			)
			(fill no)
			(layer "B.CrtYd")
		)
		(fp_rect
			(start 0.508 0.9398)
			(end -0.508 -0.9398)
			(stroke
				(width 0)
				(type default)
			)
			(fill no)
			(layer "B.Fab")
		)
		(pad "1" smd custom
			(at 0 -0.4445 180)
			(size 0.1397 0.1397)
			(layers "B.Cu" "B.Mask" "B.Paste")
			(net "P0V9_E")
			(options
				(clearance outline)
				(anchor circle)
			)
			(primitives
				(gr_poly
					(pts
						(arc
							(start -0.1778 0.2794)
							(mid -0.249642 0.249642)
							(end -0.2794 0.1778)
						)
						(arc
							(start -0.2794 -0.1778)
							(mid -0.249642 -0.249642)
							(end -0.1778 -0.2794)
						)
						(arc
							(start 0.1778 -0.2794)
							(mid 0.249642 -0.249642)
							(end 0.2794 -0.1778)
						)
						(arc
							(start 0.2794 0.1778)
							(mid 0.249642 0.249642)
							(end 0.1778 0.2794)
						)
					)
					(width 0)
					(fill yes)
				)
			)
		)
		(pad "2" smd custom
			(at 0 0.4445 180)
			(size 0.1397 0.1397)
			(layers "B.Cu" "B.Mask" "B.Paste")
			(net "ADC_P0V9_E")
			(options
				(clearance outline)
				(anchor circle)
			)
			(primitives
				(gr_poly
					(pts
						(arc
							(start -0.1778 0.2794)
							(mid -0.249642 0.249642)
							(end -0.2794 0.1778)
						)
						(arc
							(start -0.2794 -0.1778)
							(mid -0.249642 -0.249642)
							(end -0.1778 -0.2794)
						)
						(arc
							(start 0.1778 -0.2794)
							(mid 0.249642 -0.249642)
							(end 0.2794 -0.1778)
						)
						(arc
							(start 0.2794 0.1778)
							(mid 0.249642 0.249642)
							(end 0.1778 0.2794)
						)
					)
					(width 0)
					(fill yes)
				)
			)
		)
	)
	(footprint ""
		(layer "B.Cu")
		(at 176.063402 -62.714632)
		(property "Reference" "PC205"
			(at 0 0 0)
			(layer "B.SilkS")
			(hide yes)
			(effects
				(font
					(size 1.27 1.27)
				)
				(justify mirror)
			)
		)
		(property "Value" "SC22U6D3V5MX-5-GP"
			(at 0.0762 -6.1214 0)
			(unlocked yes)
			(layer "B.Fab")
			(hide yes)
			(effects
				(font
					(size 1.016 1.016)
					(thickness 0.1524)
				)
				(justify mirror)
			)
		)
		(property "Device Type" "C805H56"
			(at 0.0762 -8.1534 0)
			(unlocked yes)
			(layer "B.Fab")
			(hide yes)
			(effects
				(font
					(size 1.016 1.016)
					(thickness 0.1524)
				)
				(justify mirror)
			)
		)
		(duplicate_pad_numbers_are_jumpers no)
		(fp_line
			(start -0.635 0)
			(end 0.635 0)
			(stroke
				(width 0.508)
				(type default)
			)
			(layer "B.SilkS")
		)
		(fp_rect
			(start 0.9652 1.778)
			(end -0.9652 -1.778)
			(stroke
				(width 0)
				(type default)
			)
			(fill no)
			(layer "B.CrtYd")
		)
		(fp_poly
			(pts
				(xy 0.9652 -1.778) (xy -0.9652 -1.778) (xy -0.9652 1.778) (xy 0.9652 1.778)
			)
			(stroke
				(width 0)
				(type default)
			)
			(fill no)
			(layer "B.Fab")
		)
		(pad "1" smd rect
			(at 0 -0.9652 180)
			(size 1.397 1.143)
			(layers "B.Cu" "B.Mask" "B.Paste")
			(net "P0V9")
		)
		(pad "2" smd rect
			(at 0 0.9652 180)
			(size 1.397 1.143)
			(layers "B.Cu" "B.Mask" "B.Paste")
			(net "GND")
		)
	)
	(footprint ""
		(layer "B.Cu")
		(at 144.86763 -33.53562)
		(property "Reference" "R2927"
			(at 0 0 0)
			(layer "B.SilkS")
			(hide yes)
			(effects
				(font
					(size 1.27 1.27)
				)
				(justify mirror)
			)
		)
		(property "Value" "0R2J-2-GP"
			(at -0.064008 -3.993896 0)
			(unlocked yes)
			(layer "B.Fab")
			(hide yes)
			(effects
				(font
					(size 1.016 1.016)
					(thickness 0.1524)
				)
				(justify mirror)
			)
		)
		(property "Device Type" "R402H16"
			(at -0.064008 -5.517896 0)
			(unlocked yes)
			(layer "B.Fab")
			(hide yes)
			(effects
				(font
					(size 1.016 1.016)
					(thickness 0.1524)
				)
				(justify mirror)
			)
		)
		(duplicate_pad_numbers_are_jumpers no)
		(fp_line
			(start -0.508 -0.9398)
			(end 0.508 -0.9398)
			(stroke
				(width 0.1524)
				(type default)
			)
			(layer "B.SilkS")
		)
		(fp_line
			(start 0.508 -0.9398)
			(end 0.508 0.9398)
			(stroke
				(width 0.1524)
				(type default)
			)
			(layer "B.SilkS")
		)
		(fp_rect
			(start 0.508 0.9398)
			(end -0.508 -0.9398)
			(stroke
				(width 0)
				(type default)
			)
			(fill no)
			(layer "B.CrtYd")
		)
		(fp_rect
			(start 0.508 0.9398)
			(end -0.508 -0.9398)
			(stroke
				(width 0)
				(type default)
			)
			(fill no)
			(layer "B.Fab")
		)
		(pad "1" smd custom
			(at 0 -0.4445 180)
			(size 0.1397 0.1397)
			(layers "B.Cu" "B.Mask" "B.Paste")
			(net "CBL_PRSNT_N_2")
			(options
				(clearance outline)
				(anchor circle)
			)
			(primitives
				(gr_poly
					(pts
						(arc
							(start -0.1778 0.2794)
							(mid -0.249642 0.249642)
							(end -0.2794 0.1778)
						)
						(arc
							(start -0.2794 -0.1778)
							(mid -0.249642 -0.249642)
							(end -0.1778 -0.2794)
						)
						(arc
							(start 0.1778 -0.2794)
							(mid 0.249642 -0.249642)
							(end 0.2794 -0.1778)
						)
						(arc
							(start 0.2794 0.1778)
							(mid 0.249642 0.249642)
							(end 0.1778 0.2794)
						)
					)
					(width 0)
					(fill yes)
				)
			)
		)
		(pad "2" smd custom
			(at 0 0.4445 180)
			(size 0.1397 0.1397)
			(layers "B.Cu" "B.Mask" "B.Paste")
			(net "8644_SDA_R_2")
			(options
				(clearance outline)
				(anchor circle)
			)
			(primitives
				(gr_poly
					(pts
						(arc
							(start -0.1778 0.2794)
							(mid -0.249642 0.249642)
							(end -0.2794 0.1778)
						)
						(arc
							(start -0.2794 -0.1778)
							(mid -0.249642 -0.249642)
							(end -0.1778 -0.2794)
						)
						(arc
							(start 0.1778 -0.2794)
							(mid 0.249642 -0.249642)
							(end 0.2794 -0.1778)
						)
						(arc
							(start 0.2794 0.1778)
							(mid 0.249642 0.249642)
							(end 0.1778 0.2794)
						)
					)
					(width 0)
					(fill yes)
				)
			)
		)
	)
	(footprint ""
		(layer "B.Cu")
		(at 63.49873 -25.516332)
		(property "Reference" "R700"
			(at 0 0 0)
			(layer "B.SilkS")
			(hide yes)
			(effects
				(font
					(size 1.27 1.27)
				)
				(justify mirror)
			)
		)
		(property "Value" "4K7R2F-GP"
			(at -0.064008 -3.993896 0)
			(unlocked yes)
			(layer "B.Fab")
			(hide yes)
			(effects
				(font
					(size 1.016 1.016)
					(thickness 0.1524)
				)
				(justify mirror)
			)
		)
		(property "Device Type" "R402H16"
			(at -0.064008 -5.517896 0)
			(unlocked yes)
			(layer "B.Fab")
			(hide yes)
			(effects
				(font
					(size 1.016 1.016)
					(thickness 0.1524)
				)
				(justify mirror)
			)
		)
		(duplicate_pad_numbers_are_jumpers no)
		(fp_line
			(start -0.508 -0.9398)
			(end 0.508 -0.9398)
			(stroke
				(width 0.1524)
				(type default)
			)
			(layer "B.SilkS")
		)
		(fp_line
			(start 0.508 -0.9398)
			(end 0.508 0.9398)
			(stroke
				(width 0.1524)
				(type default)
			)
			(layer "B.SilkS")
		)
		(fp_rect
			(start 0.508 0.9398)
			(end -0.508 -0.9398)
			(stroke
				(width 0)
				(type default)
			)
			(fill no)
			(layer "B.CrtYd")
		)
		(fp_rect
			(start 0.508 0.9398)
			(end -0.508 -0.9398)
			(stroke
				(width 0)
				(type default)
			)
			(fill no)
			(layer "B.Fab")
		)
		(pad "1" smd custom
			(at 0 -0.4445 180)
			(size 0.1397 0.1397)
			(layers "B.Cu" "B.Mask" "B.Paste")
			(net "P3V3_STBY")
			(options
				(clearance outline)
				(anchor circle)
			)
			(primitives
				(gr_poly
					(pts
						(arc
							(start -0.1778 0.2794)
							(mid -0.249642 0.249642)
							(end -0.2794 0.1778)
						)
						(arc
							(start -0.2794 -0.1778)
							(mid -0.249642 -0.249642)
							(end -0.1778 -0.2794)
						)
						(arc
							(start 0.1778 -0.2794)
							(mid 0.249642 -0.249642)
							(end 0.2794 -0.1778)
						)
						(arc
							(start 0.2794 0.1778)
							(mid 0.249642 0.249642)
							(end 0.1778 0.2794)
						)
					)
					(width 0)
					(fill yes)
				)
			)
		)
		(pad "2" smd custom
			(at 0 0.4445 180)
			(size 0.1397 0.1397)
			(layers "B.Cu" "B.Mask" "B.Paste")
			(net "IPMB_CLK")
			(options
				(clearance outline)
				(anchor circle)
			)
			(primitives
				(gr_poly
					(pts
						(arc
							(start -0.1778 0.2794)
							(mid -0.249642 0.249642)
							(end -0.2794 0.1778)
						)
						(arc
							(start -0.2794 -0.1778)
							(mid -0.249642 -0.249642)
							(end -0.1778 -0.2794)
						)
						(arc
							(start 0.1778 -0.2794)
							(mid 0.249642 -0.249642)
							(end 0.2794 -0.1778)
						)
						(arc
							(start 0.2794 0.1778)
							(mid 0.249642 0.249642)
							(end 0.1778 0.2794)
						)
					)
					(width 0)
					(fill yes)
				)
			)
		)
	)
	(footprint ""
		(layer "B.Cu")
		(at 166.37 -33.528)
		(property "Reference" "R2922"
			(at 0 0 0)
			(layer "B.SilkS")
			(hide yes)
			(effects
				(font
					(size 1.27 1.27)
				)
				(justify mirror)
			)
		)
		(property "Value" "0R2J-2-GP"
			(at -0.064008 -3.993896 0)
			(unlocked yes)
			(layer "B.Fab")
			(hide yes)
			(effects
				(font
					(size 1.016 1.016)
					(thickness 0.1524)
				)
				(justify mirror)
			)
		)
		(property "Device Type" "R402H16"
			(at -0.064008 -5.517896 0)
			(unlocked yes)
			(layer "B.Fab")
			(hide yes)
			(effects
				(font
					(size 1.016 1.016)
					(thickness 0.1524)
				)
				(justify mirror)
			)
		)
		(duplicate_pad_numbers_are_jumpers no)
		(fp_line
			(start -0.508 -0.9398)
			(end 0.508 -0.9398)
			(stroke
				(width 0.1524)
				(type default)
			)
			(layer "B.SilkS")
		)
		(fp_line
			(start 0.508 -0.9398)
			(end 0.508 0.9398)
			(stroke
				(width 0.1524)
				(type default)
			)
			(layer "B.SilkS")
		)
		(fp_rect
			(start 0.508 0.9398)
			(end -0.508 -0.9398)
			(stroke
				(width 0)
				(type default)
			)
			(fill no)
			(layer "B.CrtYd")
		)
		(fp_rect
			(start 0.508 0.9398)
			(end -0.508 -0.9398)
			(stroke
				(width 0)
				(type default)
			)
			(fill no)
			(layer "B.Fab")
		)
		(pad "1" smd custom
			(at 0 -0.4445 180)
			(size 0.1397 0.1397)
			(layers "B.Cu" "B.Mask" "B.Paste")
			(net "CBL_PRSNT_N_4")
			(options
				(clearance outline)
				(anchor circle)
			)
			(primitives
				(gr_poly
					(pts
						(arc
							(start -0.1778 0.2794)
							(mid -0.249642 0.249642)
							(end -0.2794 0.1778)
						)
						(arc
							(start -0.2794 -0.1778)
							(mid -0.249642 -0.249642)
							(end -0.1778 -0.2794)
						)
						(arc
							(start 0.1778 -0.2794)
							(mid 0.249642 -0.249642)
							(end 0.2794 -0.1778)
						)
						(arc
							(start 0.2794 0.1778)
							(mid 0.249642 0.249642)
							(end 0.1778 0.2794)
						)
					)
					(width 0)
					(fill yes)
				)
			)
		)
		(pad "2" smd custom
			(at 0 0.4445 180)
			(size 0.1397 0.1397)
			(layers "B.Cu" "B.Mask" "B.Paste")
			(net "8644_CBL_PRSNT_R_4")
			(options
				(clearance outline)
				(anchor circle)
			)
			(primitives
				(gr_poly
					(pts
						(arc
							(start -0.1778 0.2794)
							(mid -0.249642 0.249642)
							(end -0.2794 0.1778)
						)
						(arc
							(start -0.2794 -0.1778)
							(mid -0.249642 -0.249642)
							(end -0.1778 -0.2794)
						)
						(arc
							(start 0.1778 -0.2794)
							(mid 0.249642 -0.249642)
							(end 0.2794 -0.1778)
						)
						(arc
							(start 0.2794 0.1778)
							(mid 0.249642 0.249642)
							(end 0.1778 0.2794)
						)
					)
					(width 0)
					(fill yes)
				)
			)
		)
	)
	(footprint ""
		(layer "B.Cu")
		(at 17.4244 -133.8326 90)
		(property "Reference" "R255"
			(at 0 0 90)
			(layer "B.SilkS")
			(hide yes)
			(effects
				(font
					(size 1.27 1.27)
				)
				(justify mirror)
			)
		)
		(property "Value" "4K7R2F-GP"
			(at -0.064008 -3.993896 90)
			(unlocked yes)
			(layer "B.Fab")
			(hide yes)
			(effects
				(font
					(size 1.016 1.016)
					(thickness 0.1524)
				)
				(justify mirror)
			)
		)
		(property "Device Type" "R402H16"
			(at -0.064008 -5.517896 90)
			(unlocked yes)
			(layer "B.Fab")
			(hide yes)
			(effects
				(font
					(size 1.016 1.016)
					(thickness 0.1524)
				)
				(justify mirror)
			)
		)
		(duplicate_pad_numbers_are_jumpers no)
		(fp_line
			(start 0.508 -0.9398)
			(end 0.508 0.9398)
			(stroke
				(width 0.1524)
				(type default)
			)
			(layer "B.SilkS")
		)
		(fp_line
			(start -0.508 -0.9398)
			(end 0.508 -0.9398)
			(stroke
				(width 0.1524)
				(type default)
			)
			(layer "B.SilkS")
		)
		(fp_rect
			(start 0.508 0.9398)
			(end -0.508 -0.9398)
			(stroke
				(width 0)
				(type default)
			)
			(fill no)
			(layer "B.CrtYd")
		)
		(fp_rect
			(start 0.508 0.9398)
			(end -0.508 -0.9398)
			(stroke
				(width 0)
				(type default)
			)
			(fill no)
			(layer "B.Fab")
		)
		(pad "1" smd custom
			(at 0 -0.4445 270)
			(size 0.1397 0.1397)
			(layers "B.Cu" "B.Mask" "B.Paste")
			(net "EXP_TRAY_ID")
			(options
				(clearance outline)
				(anchor circle)
			)
			(primitives
				(gr_poly
					(pts
						(arc
							(start -0.1778 0.2794)
							(mid -0.249642 0.249642)
							(end -0.2794 0.1778)
						)
						(arc
							(start -0.2794 -0.1778)
							(mid -0.249642 -0.249642)
							(end -0.1778 -0.2794)
						)
						(arc
							(start 0.1778 -0.2794)
							(mid 0.249642 -0.249642)
							(end 0.2794 -0.1778)
						)
						(arc
							(start 0.2794 0.1778)
							(mid 0.249642 0.249642)
							(end 0.1778 0.2794)
						)
					)
					(width 0)
					(fill yes)
				)
			)
		)
		(pad "2" smd custom
			(at 0 0.4445 270)
			(size 0.1397 0.1397)
			(layers "B.Cu" "B.Mask" "B.Paste")
			(net "P3V3_STBY")
			(options
				(clearance outline)
				(anchor circle)
			)
			(primitives
				(gr_poly
					(pts
						(arc
							(start -0.1778 0.2794)
							(mid -0.249642 0.249642)
							(end -0.2794 0.1778)
						)
						(arc
							(start -0.2794 -0.1778)
							(mid -0.249642 -0.249642)
							(end -0.1778 -0.2794)
						)
						(arc
							(start 0.1778 -0.2794)
							(mid 0.249642 -0.249642)
							(end 0.2794 -0.1778)
						)
						(arc
							(start 0.2794 0.1778)
							(mid 0.249642 0.249642)
							(end 0.1778 0.2794)
						)
					)
					(width 0)
					(fill yes)
				)
			)
		)
	)
	(footprint ""
		(layer "B.Cu")
		(at 241.681 -23.241)
		(property "Reference" "R810"
			(at 0 0 0)
			(layer "B.SilkS")
			(hide yes)
			(effects
				(font
					(size 1.27 1.27)
				)
				(justify mirror)
			)
		)
		(property "Value" "4K7R2F-GP"
			(at -0.064008 -3.993896 0)
			(unlocked yes)
			(layer "B.Fab")
			(hide yes)
			(effects
				(font
					(size 1.016 1.016)
					(thickness 0.1524)
				)
				(justify mirror)
			)
		)
		(property "Device Type" "R402H16"
			(at -0.064008 -5.517896 0)
			(unlocked yes)
			(layer "B.Fab")
			(hide yes)
			(effects
				(font
					(size 1.016 1.016)
					(thickness 0.1524)
				)
				(justify mirror)
			)
		)
		(duplicate_pad_numbers_are_jumpers no)
		(fp_line
			(start -0.508 -0.9398)
			(end 0.508 -0.9398)
			(stroke
				(width 0.1524)
				(type default)
			)
			(layer "B.SilkS")
		)
		(fp_line
			(start 0.508 -0.9398)
			(end 0.508 0.9398)
			(stroke
				(width 0.1524)
				(type default)
			)
			(layer "B.SilkS")
		)
		(fp_rect
			(start 0.508 0.9398)
			(end -0.508 -0.9398)
			(stroke
				(width 0)
				(type default)
			)
			(fill no)
			(layer "B.CrtYd")
		)
		(fp_rect
			(start 0.508 0.9398)
			(end -0.508 -0.9398)
			(stroke
				(width 0)
				(type default)
			)
			(fill no)
			(layer "B.Fab")
		)
		(pad "1" smd custom
			(at 0 -0.4445 180)
			(size 0.1397 0.1397)
			(layers "B.Cu" "B.Mask" "B.Paste")
			(net "GND")
			(options
				(clearance outline)
				(anchor circle)
			)
			(primitives
				(gr_poly
					(pts
						(arc
							(start -0.1778 0.2794)
							(mid -0.249642 0.249642)
							(end -0.2794 0.1778)
						)
						(arc
							(start -0.2794 -0.1778)
							(mid -0.249642 -0.249642)
							(end -0.1778 -0.2794)
						)
						(arc
							(start 0.1778 -0.2794)
							(mid 0.249642 -0.249642)
							(end 0.2794 -0.1778)
						)
						(arc
							(start 0.2794 0.1778)
							(mid 0.249642 0.249642)
							(end 0.1778 0.2794)
						)
					)
					(width 0)
					(fill yes)
				)
			)
		)
		(pad "2" smd custom
			(at 0 0.4445 180)
			(size 0.1397 0.1397)
			(layers "B.Cu" "B.Mask" "B.Paste")
			(net "BOOTSTRAP5")
			(options
				(clearance outline)
				(anchor circle)
			)
			(primitives
				(gr_poly
					(pts
						(arc
							(start -0.1778 0.2794)
							(mid -0.249642 0.249642)
							(end -0.2794 0.1778)
						)
						(arc
							(start -0.2794 -0.1778)
							(mid -0.249642 -0.249642)
							(end -0.1778 -0.2794)
						)
						(arc
							(start 0.1778 -0.2794)
							(mid 0.249642 -0.249642)
							(end 0.2794 -0.1778)
						)
						(arc
							(start 0.2794 0.1778)
							(mid 0.249642 0.249642)
							(end 0.1778 0.2794)
						)
					)
					(width 0)
					(fill yes)
				)
			)
		)
	)
	(footprint ""
		(layer "B.Cu")
		(at 77.769212 -186.545474)
		(property "Reference" "C415"
			(at 0 0 0)
			(layer "B.SilkS")
			(hide yes)
			(effects
				(font
					(size 1.27 1.27)
				)
				(justify mirror)
			)
		)
		(property "Value" "SCD1U25V2KX-2-GP"
			(at -1.1811 -2.7051 0)
			(unlocked yes)
			(layer "B.Fab")
			(hide yes)
			(effects
				(font
					(size 1.016 1.016)
					(thickness 0.1524)
				)
				(justify mirror)
			)
		)
		(property "Device Type" "C402H22"
			(at -1.1811 -4.2291 0)
			(unlocked yes)
			(layer "B.Fab")
			(hide yes)
			(effects
				(font
					(size 1.016 1.016)
					(thickness 0.1524)
				)
				(justify mirror)
			)
		)
		(duplicate_pad_numbers_are_jumpers no)
		(fp_rect
			(start 0.4318 0.9525)
			(end -0.4318 -0.9525)
			(stroke
				(width 0)
				(type default)
			)
			(fill no)
			(layer "B.CrtYd")
		)
		(fp_rect
			(start 0.4318 0.9525)
			(end -0.4318 -0.9525)
			(stroke
				(width 0)
				(type default)
			)
			(fill no)
			(layer "B.Fab")
		)
		(pad "1" smd custom
			(at 0 -0.4445 180)
			(size 0.1524 0.1524)
			(layers "B.Cu" "B.Mask" "B.Paste")
			(net "P3V3_STBY")
			(options
				(clearance outline)
				(anchor circle)
			)
			(primitives
				(gr_poly
					(pts
						(arc
							(start 0.3048 0.2032)
							(mid 0.275042 0.275042)
							(end 0.2032 0.3048)
						)
						(arc
							(start -0.2032 0.3048)
							(mid -0.275042 0.275042)
							(end -0.3048 0.2032)
						)
						(arc
							(start -0.3048 -0.2032)
							(mid -0.275042 -0.275042)
							(end -0.2032 -0.3048)
						)
						(arc
							(start 0.2032 -0.3048)
							(mid 0.275042 -0.275042)
							(end 0.3048 -0.2032)
						)
					)
					(width 0)
					(fill yes)
				)
			)
		)
		(pad "2" smd custom
			(at 0 0.4445 180)
			(size 0.1524 0.1524)
			(layers "B.Cu" "B.Mask" "B.Paste")
			(net "GND")
			(options
				(clearance outline)
				(anchor circle)
			)
			(primitives
				(gr_poly
					(pts
						(arc
							(start 0.3048 0.2032)
							(mid 0.275042 0.275042)
							(end 0.2032 0.3048)
						)
						(arc
							(start -0.2032 0.3048)
							(mid -0.275042 0.275042)
							(end -0.3048 0.2032)
						)
						(arc
							(start -0.3048 -0.2032)
							(mid -0.275042 -0.275042)
							(end -0.2032 -0.3048)
						)
						(arc
							(start 0.2032 -0.3048)
							(mid 0.275042 -0.275042)
							(end 0.3048 -0.2032)
						)
					)
					(width 0)
					(fill yes)
				)
			)
		)
	)
	(footprint ""
		(layer "B.Cu")
		(at 54.031642 -123.876816 -90)
		(property "Reference" "R466"
			(at 0 0 90)
			(layer "B.SilkS")
			(hide yes)
			(effects
				(font
					(size 1.27 1.27)
				)
				(justify mirror)
			)
		)
		(property "Value" "0R2J-2-GP"
			(at -0.064008 -3.993896 270)
			(unlocked yes)
			(layer "B.Fab")
			(hide yes)
			(effects
				(font
					(size 1.016 1.016)
					(thickness 0.1524)
				)
				(justify mirror)
			)
		)
		(property "Device Type" "R402H16"
			(at -0.064008 -5.517896 270)
			(unlocked yes)
			(layer "B.Fab")
			(hide yes)
			(effects
				(font
					(size 1.016 1.016)
					(thickness 0.1524)
				)
				(justify mirror)
			)
		)
		(duplicate_pad_numbers_are_jumpers no)
		(fp_line
			(start -0.508 -0.9398)
			(end 0.508 -0.9398)
			(stroke
				(width 0.1524)
				(type default)
			)
			(layer "B.SilkS")
		)
		(fp_line
			(start 0.508 -0.9398)
			(end 0.508 0.9398)
			(stroke
				(width 0.1524)
				(type default)
			)
			(layer "B.SilkS")
		)
		(fp_rect
			(start 0.508 0.9398)
			(end -0.508 -0.9398)
			(stroke
				(width 0)
				(type default)
			)
			(fill no)
			(layer "B.CrtYd")
		)
		(fp_rect
			(start 0.508 0.9398)
			(end -0.508 -0.9398)
			(stroke
				(width 0)
				(type default)
			)
			(fill no)
			(layer "B.Fab")
		)
		(pad "1" smd custom
			(at 0 -0.4445 90)
			(size 0.1397 0.1397)
			(layers "B.Cu" "B.Mask" "B.Paste")
			(net "BMC_I2C8_CLKBUF1_SCL")
			(options
				(clearance outline)
				(anchor circle)
			)
			(primitives
				(gr_poly
					(pts
						(arc
							(start -0.1778 0.2794)
							(mid -0.249642 0.249642)
							(end -0.2794 0.1778)
						)
						(arc
							(start -0.2794 -0.1778)
							(mid -0.249642 -0.249642)
							(end -0.1778 -0.2794)
						)
						(arc
							(start 0.1778 -0.2794)
							(mid 0.249642 -0.249642)
							(end 0.2794 -0.1778)
						)
						(arc
							(start 0.2794 0.1778)
							(mid 0.249642 0.249642)
							(end 0.1778 0.2794)
						)
					)
					(width 0)
					(fill yes)
				)
			)
		)
		(pad "2" smd custom
			(at 0 0.4445 90)
			(size 0.1397 0.1397)
			(layers "B.Cu" "B.Mask" "B.Paste")
			(net "BMC0_SMB8_CLK")
			(options
				(clearance outline)
				(anchor circle)
			)
			(primitives
				(gr_poly
					(pts
						(arc
							(start -0.1778 0.2794)
							(mid -0.249642 0.249642)
							(end -0.2794 0.1778)
						)
						(arc
							(start -0.2794 -0.1778)
							(mid -0.249642 -0.249642)
							(end -0.1778 -0.2794)
						)
						(arc
							(start 0.1778 -0.2794)
							(mid 0.249642 -0.249642)
							(end 0.2794 -0.1778)
						)
						(arc
							(start 0.2794 0.1778)
							(mid 0.249642 0.249642)
							(end 0.1778 0.2794)
						)
					)
					(width 0)
					(fill yes)
				)
			)
		)
	)
	(footprint ""
		(layer "B.Cu")
		(at 211.2772 -45.6438 90)
		(property "Reference" "C729"
			(at 0 0 90)
			(layer "B.SilkS")
			(hide yes)
			(effects
				(font
					(size 1.27 1.27)
				)
				(justify mirror)
			)
		)
		(property "Value" "SCD22U10V2KX-1GP"
			(at -1.1811 -2.7051 90)
			(unlocked yes)
			(layer "B.Fab")
			(hide yes)
			(effects
				(font
					(size 1.016 1.016)
					(thickness 0.1524)
				)
				(justify mirror)
			)
		)
		(property "Device Type" "C402H22"
			(at -1.1811 -4.2291 90)
			(unlocked yes)
			(layer "B.Fab")
			(hide yes)
			(effects
				(font
					(size 1.016 1.016)
					(thickness 0.1524)
				)
				(justify mirror)
			)
		)
		(duplicate_pad_numbers_are_jumpers no)
		(fp_rect
			(start 0.4318 0.9525)
			(end -0.4318 -0.9525)
			(stroke
				(width 0)
				(type default)
			)
			(fill no)
			(layer "B.CrtYd")
		)
		(fp_rect
			(start 0.4318 0.9525)
			(end -0.4318 -0.9525)
			(stroke
				(width 0)
				(type default)
			)
			(fill no)
			(layer "B.Fab")
		)
		(pad "1" smd custom
			(at 0 -0.4445 270)
			(size 0.1524 0.1524)
			(layers "B.Cu" "B.Mask" "B.Paste")
			(net "BMC_PETXP")
			(options
				(clearance outline)
				(anchor circle)
			)
			(primitives
				(gr_poly
					(pts
						(arc
							(start 0.3048 0.2032)
							(mid 0.275042 0.275042)
							(end 0.2032 0.3048)
						)
						(arc
							(start -0.2032 0.3048)
							(mid -0.275042 0.275042)
							(end -0.3048 0.2032)
						)
						(arc
							(start -0.3048 -0.2032)
							(mid -0.275042 -0.275042)
							(end -0.2032 -0.3048)
						)
						(arc
							(start 0.2032 -0.3048)
							(mid 0.275042 -0.275042)
							(end 0.3048 -0.2032)
						)
					)
					(width 0)
					(fill yes)
				)
			)
		)
		(pad "2" smd custom
			(at 0 0.4445 270)
			(size 0.1524 0.1524)
			(layers "B.Cu" "B.Mask" "B.Paste")
			(net "PCIE_RX_P76")
			(options
				(clearance outline)
				(anchor circle)
			)
			(primitives
				(gr_poly
					(pts
						(arc
							(start 0.3048 0.2032)
							(mid 0.275042 0.275042)
							(end 0.2032 0.3048)
						)
						(arc
							(start -0.2032 0.3048)
							(mid -0.275042 0.275042)
							(end -0.3048 0.2032)
						)
						(arc
							(start -0.3048 -0.2032)
							(mid -0.275042 -0.275042)
							(end -0.2032 -0.3048)
						)
						(arc
							(start 0.2032 -0.3048)
							(mid 0.275042 -0.275042)
							(end 0.3048 -0.2032)
						)
					)
					(width 0)
					(fill yes)
				)
			)
		)
	)
	(footprint ""
		(layer "B.Cu")
		(at 252.603 -48.988472 -90)
		(property "Reference" "C609"
			(at 0 0 90)
			(layer "B.SilkS")
			(hide yes)
			(effects
				(font
					(size 1.27 1.27)
				)
				(justify mirror)
			)
		)
		(property "Value" "SCD1U16V1KX-1-GP"
			(at 2.8321 -1.7399 270)
			(unlocked yes)
			(layer "B.Fab")
			(hide yes)
			(effects
				(font
					(size 1.016 1.016)
					(thickness 0.1524)
				)
				(justify mirror)
			)
		)
		(property "Device Type" "C0201H13"
			(at 2.8321 -3.2639 270)
			(unlocked yes)
			(layer "B.Fab")
			(hide yes)
			(effects
				(font
					(size 1.016 1.016)
					(thickness 0.1524)
				)
				(justify mirror)
			)
		)
		(duplicate_pad_numbers_are_jumpers no)
		(fp_rect
			(start 0.2794 0.6477)
			(end -0.2794 -0.6477)
			(stroke
				(width 0)
				(type default)
			)
			(fill no)
			(layer "B.CrtYd")
		)
		(fp_rect
			(start 0.2794 0.6477)
			(end -0.2794 -0.6477)
			(stroke
				(width 0)
				(type default)
			)
			(fill no)
			(layer "B.Fab")
		)
		(pad "1" smd custom
			(at 0 -0.2794 90)
			(size 0.0762 0.0762)
			(layers "B.Cu" "B.Mask" "B.Paste")
			(net "DUT_AVD_PCIE")
			(options
				(clearance outline)
				(anchor circle)
			)
			(primitives
				(gr_poly
					(pts
						(arc
							(start 0.1524 0.127)
							(mid 0.137521 0.162921)
							(end 0.1016 0.1778)
						)
						(arc
							(start -0.1016 0.1778)
							(mid -0.137521 0.162921)
							(end -0.1524 0.127)
						)
						(arc
							(start -0.1524 -0.127)
							(mid -0.137521 -0.162921)
							(end -0.1016 -0.1778)
						)
						(arc
							(start 0.1016 -0.1778)
							(mid 0.137521 -0.162921)
							(end 0.1524 -0.127)
						)
					)
					(width 0)
					(fill yes)
				)
			)
		)
		(pad "2" smd custom
			(at 0 0.2794 90)
			(size 0.0762 0.0762)
			(layers "B.Cu" "B.Mask" "B.Paste")
			(net "GND")
			(options
				(clearance outline)
				(anchor circle)
			)
			(primitives
				(gr_poly
					(pts
						(arc
							(start 0.1524 0.127)
							(mid 0.137521 0.162921)
							(end 0.1016 0.1778)
						)
						(arc
							(start -0.1016 0.1778)
							(mid -0.137521 0.162921)
							(end -0.1524 0.127)
						)
						(arc
							(start -0.1524 -0.127)
							(mid -0.137521 -0.162921)
							(end -0.1016 -0.1778)
						)
						(arc
							(start 0.1016 -0.1778)
							(mid 0.137521 -0.162921)
							(end 0.1524 -0.127)
						)
					)
					(width 0)
					(fill yes)
				)
			)
		)
	)
	(footprint ""
		(layer "B.Cu")
		(at 163.058602 -60.098432)
		(property "Reference" "PR174"
			(at 0 0 0)
			(layer "B.SilkS")
			(hide yes)
			(effects
				(font
					(size 1.27 1.27)
				)
				(justify mirror)
			)
		)
		(property "Value" "2K21R2F-GP"
			(at -0.064008 -3.993896 0)
			(unlocked yes)
			(layer "B.Fab")
			(hide yes)
			(effects
				(font
					(size 1.016 1.016)
					(thickness 0.1524)
				)
				(justify mirror)
			)
		)
		(property "Device Type" "R402H16"
			(at -0.064008 -5.517896 0)
			(unlocked yes)
			(layer "B.Fab")
			(hide yes)
			(effects
				(font
					(size 1.016 1.016)
					(thickness 0.1524)
				)
				(justify mirror)
			)
		)
		(duplicate_pad_numbers_are_jumpers no)
		(fp_line
			(start -0.508 -0.9398)
			(end 0.508 -0.9398)
			(stroke
				(width 0.1524)
				(type default)
			)
			(layer "B.SilkS")
		)
		(fp_line
			(start 0.508 -0.9398)
			(end 0.508 0.9398)
			(stroke
				(width 0.1524)
				(type default)
			)
			(layer "B.SilkS")
		)
		(fp_rect
			(start 0.508 0.9398)
			(end -0.508 -0.9398)
			(stroke
				(width 0)
				(type default)
			)
			(fill no)
			(layer "B.CrtYd")
		)
		(fp_rect
			(start 0.508 0.9398)
			(end -0.508 -0.9398)
			(stroke
				(width 0)
				(type default)
			)
			(fill no)
			(layer "B.Fab")
		)
		(pad "1" smd custom
			(at 0 -0.4445 180)
			(size 0.1397 0.1397)
			(layers "B.Cu" "B.Mask" "B.Paste")
			(net "P0V9_LX")
			(options
				(clearance outline)
				(anchor circle)
			)
			(primitives
				(gr_poly
					(pts
						(arc
							(start -0.1778 0.2794)
							(mid -0.249642 0.249642)
							(end -0.2794 0.1778)
						)
						(arc
							(start -0.2794 -0.1778)
							(mid -0.249642 -0.249642)
							(end -0.1778 -0.2794)
						)
						(arc
							(start 0.1778 -0.2794)
							(mid 0.249642 -0.249642)
							(end 0.2794 -0.1778)
						)
						(arc
							(start 0.2794 0.1778)
							(mid 0.249642 0.249642)
							(end 0.1778 0.2794)
						)
					)
					(width 0)
					(fill yes)
				)
			)
		)
		(pad "2" smd custom
			(at 0 0.4445 180)
			(size 0.1397 0.1397)
			(layers "B.Cu" "B.Mask" "B.Paste")
			(net "P0V9_SW_R")
			(options
				(clearance outline)
				(anchor circle)
			)
			(primitives
				(gr_poly
					(pts
						(arc
							(start -0.1778 0.2794)
							(mid -0.249642 0.249642)
							(end -0.2794 0.1778)
						)
						(arc
							(start -0.2794 -0.1778)
							(mid -0.249642 -0.249642)
							(end -0.1778 -0.2794)
						)
						(arc
							(start 0.1778 -0.2794)
							(mid 0.249642 -0.249642)
							(end 0.2794 -0.1778)
						)
						(arc
							(start 0.2794 0.1778)
							(mid 0.249642 0.249642)
							(end 0.1778 0.2794)
						)
					)
					(width 0)
					(fill yes)
				)
			)
		)
	)
	(footprint ""
		(layer "B.Cu")
		(at 127.807212 -199.753474)
		(property "Reference" "C3210"
			(at 0 0 0)
			(layer "B.SilkS")
			(hide yes)
			(effects
				(font
					(size 1.27 1.27)
				)
				(justify mirror)
			)
		)
		(property "Value" "SCD1U25V2KX-2-GP"
			(at -1.1811 -2.7051 0)
			(unlocked yes)
			(layer "B.Fab")
			(hide yes)
			(effects
				(font
					(size 1.016 1.016)
					(thickness 0.1524)
				)
				(justify mirror)
			)
		)
		(property "Device Type" "C402H22"
			(at -1.1811 -4.2291 0)
			(unlocked yes)
			(layer "B.Fab")
			(hide yes)
			(effects
				(font
					(size 1.016 1.016)
					(thickness 0.1524)
				)
				(justify mirror)
			)
		)
		(duplicate_pad_numbers_are_jumpers no)
		(fp_rect
			(start 0.4318 0.9525)
			(end -0.4318 -0.9525)
			(stroke
				(width 0)
				(type default)
			)
			(fill no)
			(layer "B.CrtYd")
		)
		(fp_rect
			(start 0.4318 0.9525)
			(end -0.4318 -0.9525)
			(stroke
				(width 0)
				(type default)
			)
			(fill no)
			(layer "B.Fab")
		)
		(pad "1" smd custom
			(at 0 -0.4445 180)
			(size 0.1524 0.1524)
			(layers "B.Cu" "B.Mask" "B.Paste")
			(net "P3V3_STBY")
			(options
				(clearance outline)
				(anchor circle)
			)
			(primitives
				(gr_poly
					(pts
						(arc
							(start 0.3048 0.2032)
							(mid 0.275042 0.275042)
							(end 0.2032 0.3048)
						)
						(arc
							(start -0.2032 0.3048)
							(mid -0.275042 0.275042)
							(end -0.3048 0.2032)
						)
						(arc
							(start -0.3048 -0.2032)
							(mid -0.275042 -0.275042)
							(end -0.2032 -0.3048)
						)
						(arc
							(start 0.2032 -0.3048)
							(mid 0.275042 -0.275042)
							(end 0.3048 -0.2032)
						)
					)
					(width 0)
					(fill yes)
				)
			)
		)
		(pad "2" smd custom
			(at 0 0.4445 180)
			(size 0.1524 0.1524)
			(layers "B.Cu" "B.Mask" "B.Paste")
			(net "GND")
			(options
				(clearance outline)
				(anchor circle)
			)
			(primitives
				(gr_poly
					(pts
						(arc
							(start 0.3048 0.2032)
							(mid 0.275042 0.275042)
							(end 0.2032 0.3048)
						)
						(arc
							(start -0.2032 0.3048)
							(mid -0.275042 0.275042)
							(end -0.3048 0.2032)
						)
						(arc
							(start -0.3048 -0.2032)
							(mid -0.275042 -0.275042)
							(end -0.2032 -0.3048)
						)
						(arc
							(start 0.2032 -0.3048)
							(mid 0.275042 -0.275042)
							(end 0.3048 -0.2032)
						)
					)
					(width 0)
					(fill yes)
				)
			)
		)
	)
	(footprint ""
		(layer "B.Cu")
		(at 231.5972 -60.1218)
		(property "Reference" "C542"
			(at 0 0 0)
			(layer "B.SilkS")
			(hide yes)
			(effects
				(font
					(size 1.27 1.27)
				)
				(justify mirror)
			)
		)
		(property "Value" "SCD1U16V1KX-1-GP"
			(at 2.8321 -1.7399 0)
			(unlocked yes)
			(layer "B.Fab")
			(hide yes)
			(effects
				(font
					(size 1.016 1.016)
					(thickness 0.1524)
				)
				(justify mirror)
			)
		)
		(property "Device Type" "C0201H13"
			(at 2.8321 -3.2639 0)
			(unlocked yes)
			(layer "B.Fab")
			(hide yes)
			(effects
				(font
					(size 1.016 1.016)
					(thickness 0.1524)
				)
				(justify mirror)
			)
		)
		(duplicate_pad_numbers_are_jumpers no)
		(fp_rect
			(start 0.2794 0.6477)
			(end -0.2794 -0.6477)
			(stroke
				(width 0)
				(type default)
			)
			(fill no)
			(layer "B.CrtYd")
		)
		(fp_rect
			(start 0.2794 0.6477)
			(end -0.2794 -0.6477)
			(stroke
				(width 0)
				(type default)
			)
			(fill no)
			(layer "B.Fab")
		)
		(pad "1" smd custom
			(at 0 -0.2794 180)
			(size 0.0762 0.0762)
			(layers "B.Cu" "B.Mask" "B.Paste")
			(net "DUT_AVD_PCIE")
			(options
				(clearance outline)
				(anchor circle)
			)
			(primitives
				(gr_poly
					(pts
						(arc
							(start 0.1524 0.127)
							(mid 0.137521 0.162921)
							(end 0.1016 0.1778)
						)
						(arc
							(start -0.1016 0.1778)
							(mid -0.137521 0.162921)
							(end -0.1524 0.127)
						)
						(arc
							(start -0.1524 -0.127)
							(mid -0.137521 -0.162921)
							(end -0.1016 -0.1778)
						)
						(arc
							(start 0.1016 -0.1778)
							(mid 0.137521 -0.162921)
							(end 0.1524 -0.127)
						)
					)
					(width 0)
					(fill yes)
				)
			)
		)
		(pad "2" smd custom
			(at 0 0.2794 180)
			(size 0.0762 0.0762)
			(layers "B.Cu" "B.Mask" "B.Paste")
			(net "GND")
			(options
				(clearance outline)
				(anchor circle)
			)
			(primitives
				(gr_poly
					(pts
						(arc
							(start 0.1524 0.127)
							(mid 0.137521 0.162921)
							(end 0.1016 0.1778)
						)
						(arc
							(start -0.1016 0.1778)
							(mid -0.137521 0.162921)
							(end -0.1524 0.127)
						)
						(arc
							(start -0.1524 -0.127)
							(mid -0.137521 -0.162921)
							(end -0.1016 -0.1778)
						)
						(arc
							(start 0.1016 -0.1778)
							(mid 0.137521 -0.162921)
							(end 0.1524 -0.127)
						)
					)
					(width 0)
					(fill yes)
				)
			)
		)
	)
	(footprint ""
		(layer "B.Cu")
		(at 36.377118 -126.98984 180)
		(property "Reference" "C212"
			(at 0 0 0)
			(layer "B.SilkS")
			(hide yes)
			(effects
				(font
					(size 1.27 1.27)
				)
				(justify mirror)
			)
		)
		(property "Value" "SC1U10V2KX-4-GP"
			(at -1.1811 -2.7051 180)
			(unlocked yes)
			(layer "B.Fab")
			(hide yes)
			(effects
				(font
					(size 1.016 1.016)
					(thickness 0.1524)
				)
				(justify mirror)
			)
		)
		(property "Device Type" "C402H22"
			(at -1.1811 -4.2291 180)
			(unlocked yes)
			(layer "B.Fab")
			(hide yes)
			(effects
				(font
					(size 1.016 1.016)
					(thickness 0.1524)
				)
				(justify mirror)
			)
		)
		(duplicate_pad_numbers_are_jumpers no)
		(fp_rect
			(start 0.4318 0.9525)
			(end -0.4318 -0.9525)
			(stroke
				(width 0)
				(type default)
			)
			(fill no)
			(layer "B.CrtYd")
		)
		(fp_rect
			(start 0.4318 0.9525)
			(end -0.4318 -0.9525)
			(stroke
				(width 0)
				(type default)
			)
			(fill no)
			(layer "B.Fab")
		)
		(pad "1" smd custom
			(at 0 -0.4445)
			(size 0.1524 0.1524)
			(layers "B.Cu" "B.Mask" "B.Paste")
			(net "P1V26_STBY")
			(options
				(clearance outline)
				(anchor circle)
			)
			(primitives
				(gr_poly
					(pts
						(arc
							(start 0.3048 0.2032)
							(mid 0.275042 0.275042)
							(end 0.2032 0.3048)
						)
						(arc
							(start -0.2032 0.3048)
							(mid -0.275042 0.275042)
							(end -0.3048 0.2032)
						)
						(arc
							(start -0.3048 -0.2032)
							(mid -0.275042 -0.275042)
							(end -0.2032 -0.3048)
						)
						(arc
							(start 0.2032 -0.3048)
							(mid 0.275042 -0.275042)
							(end 0.3048 -0.2032)
						)
					)
					(width 0)
					(fill yes)
				)
			)
		)
		(pad "2" smd custom
			(at 0 0.4445)
			(size 0.1524 0.1524)
			(layers "B.Cu" "B.Mask" "B.Paste")
			(net "GND")
			(options
				(clearance outline)
				(anchor circle)
			)
			(primitives
				(gr_poly
					(pts
						(arc
							(start 0.3048 0.2032)
							(mid 0.275042 0.275042)
							(end 0.2032 0.3048)
						)
						(arc
							(start -0.2032 0.3048)
							(mid -0.275042 0.275042)
							(end -0.3048 0.2032)
						)
						(arc
							(start -0.3048 -0.2032)
							(mid -0.275042 -0.275042)
							(end -0.2032 -0.3048)
						)
						(arc
							(start 0.2032 -0.3048)
							(mid 0.275042 -0.275042)
							(end 0.3048 -0.2032)
						)
					)
					(width 0)
					(fill yes)
				)
			)
		)
	)
	(footprint ""
		(layer "B.Cu")
		(at 30.569154 -159.622744 180)
		(property "Reference" "C199"
			(at 0 0 0)
			(layer "B.SilkS")
			(hide yes)
			(effects
				(font
					(size 1.27 1.27)
				)
				(justify mirror)
			)
		)
		(property "Value" "SC1U10V2KX-4-GP"
			(at -1.1811 -2.7051 180)
			(unlocked yes)
			(layer "B.Fab")
			(hide yes)
			(effects
				(font
					(size 1.016 1.016)
					(thickness 0.1524)
				)
				(justify mirror)
			)
		)
		(property "Device Type" "C402H22"
			(at -1.1811 -4.2291 180)
			(unlocked yes)
			(layer "B.Fab")
			(hide yes)
			(effects
				(font
					(size 1.016 1.016)
					(thickness 0.1524)
				)
				(justify mirror)
			)
		)
		(duplicate_pad_numbers_are_jumpers no)
		(fp_rect
			(start 0.4318 0.9525)
			(end -0.4318 -0.9525)
			(stroke
				(width 0)
				(type default)
			)
			(fill no)
			(layer "B.CrtYd")
		)
		(fp_rect
			(start 0.4318 0.9525)
			(end -0.4318 -0.9525)
			(stroke
				(width 0)
				(type default)
			)
			(fill no)
			(layer "B.Fab")
		)
		(pad "1" smd custom
			(at 0 -0.4445)
			(size 0.1524 0.1524)
			(layers "B.Cu" "B.Mask" "B.Paste")
			(net "P1V53_STBY")
			(options
				(clearance outline)
				(anchor circle)
			)
			(primitives
				(gr_poly
					(pts
						(arc
							(start 0.3048 0.2032)
							(mid 0.275042 0.275042)
							(end 0.2032 0.3048)
						)
						(arc
							(start -0.2032 0.3048)
							(mid -0.275042 0.275042)
							(end -0.3048 0.2032)
						)
						(arc
							(start -0.3048 -0.2032)
							(mid -0.275042 -0.275042)
							(end -0.2032 -0.3048)
						)
						(arc
							(start 0.2032 -0.3048)
							(mid 0.275042 -0.275042)
							(end 0.3048 -0.2032)
						)
					)
					(width 0)
					(fill yes)
				)
			)
		)
		(pad "2" smd custom
			(at 0 0.4445)
			(size 0.1524 0.1524)
			(layers "B.Cu" "B.Mask" "B.Paste")
			(net "GND")
			(options
				(clearance outline)
				(anchor circle)
			)
			(primitives
				(gr_poly
					(pts
						(arc
							(start 0.3048 0.2032)
							(mid 0.275042 0.275042)
							(end 0.2032 0.3048)
						)
						(arc
							(start -0.2032 0.3048)
							(mid -0.275042 0.275042)
							(end -0.3048 0.2032)
						)
						(arc
							(start -0.3048 -0.2032)
							(mid -0.275042 -0.275042)
							(end -0.2032 -0.3048)
						)
						(arc
							(start 0.2032 -0.3048)
							(mid 0.275042 -0.275042)
							(end 0.3048 -0.2032)
						)
					)
					(width 0)
					(fill yes)
				)
			)
		)
	)
	(footprint ""
		(layer "B.Cu")
		(at 27.9654 -185.9026 -90)
		(property "Reference" "R448"
			(at 0 0 90)
			(layer "B.SilkS")
			(hide yes)
			(effects
				(font
					(size 1.27 1.27)
				)
				(justify mirror)
			)
		)
		(property "Value" "0R2J-2-GP"
			(at -0.064008 -3.993896 270)
			(unlocked yes)
			(layer "B.Fab")
			(hide yes)
			(effects
				(font
					(size 1.016 1.016)
					(thickness 0.1524)
				)
				(justify mirror)
			)
		)
		(property "Device Type" "R402H16"
			(at -0.064008 -5.517896 270)
			(unlocked yes)
			(layer "B.Fab")
			(hide yes)
			(effects
				(font
					(size 1.016 1.016)
					(thickness 0.1524)
				)
				(justify mirror)
			)
		)
		(duplicate_pad_numbers_are_jumpers no)
		(fp_line
			(start -0.508 -0.9398)
			(end 0.508 -0.9398)
			(stroke
				(width 0.1524)
				(type default)
			)
			(layer "B.SilkS")
		)
		(fp_line
			(start 0.508 -0.9398)
			(end 0.508 0.9398)
			(stroke
				(width 0.1524)
				(type default)
			)
			(layer "B.SilkS")
		)
		(fp_rect
			(start 0.508 0.9398)
			(end -0.508 -0.9398)
			(stroke
				(width 0)
				(type default)
			)
			(fill no)
			(layer "B.CrtYd")
		)
		(fp_rect
			(start 0.508 0.9398)
			(end -0.508 -0.9398)
			(stroke
				(width 0)
				(type default)
			)
			(fill no)
			(layer "B.Fab")
		)
		(pad "1" smd custom
			(at 0 -0.4445 90)
			(size 0.1397 0.1397)
			(layers "B.Cu" "B.Mask" "B.Paste")
			(net "BMC_I2C5_D_PEB_DEVICE_SCL")
			(options
				(clearance outline)
				(anchor circle)
			)
			(primitives
				(gr_poly
					(pts
						(arc
							(start -0.1778 0.2794)
							(mid -0.249642 0.249642)
							(end -0.2794 0.1778)
						)
						(arc
							(start -0.2794 -0.1778)
							(mid -0.249642 -0.249642)
							(end -0.1778 -0.2794)
						)
						(arc
							(start 0.1778 -0.2794)
							(mid 0.249642 -0.249642)
							(end 0.2794 -0.1778)
						)
						(arc
							(start 0.2794 0.1778)
							(mid 0.249642 0.249642)
							(end 0.1778 0.2794)
						)
					)
					(width 0)
					(fill yes)
				)
			)
		)
		(pad "2" smd custom
			(at 0 0.4445 90)
			(size 0.1397 0.1397)
			(layers "B.Cu" "B.Mask" "B.Paste")
			(net "BMC_I2C5_D_PEB_SCL")
			(options
				(clearance outline)
				(anchor circle)
			)
			(primitives
				(gr_poly
					(pts
						(arc
							(start -0.1778 0.2794)
							(mid -0.249642 0.249642)
							(end -0.2794 0.1778)
						)
						(arc
							(start -0.2794 -0.1778)
							(mid -0.249642 -0.249642)
							(end -0.1778 -0.2794)
						)
						(arc
							(start 0.1778 -0.2794)
							(mid 0.249642 -0.249642)
							(end 0.2794 -0.1778)
						)
						(arc
							(start 0.2794 0.1778)
							(mid 0.249642 0.249642)
							(end 0.1778 0.2794)
						)
					)
					(width 0)
					(fill yes)
				)
			)
		)
	)
	(footprint ""
		(layer "B.Cu")
		(at 20.955 -134.747 -90)
		(property "Reference" "R523"
			(at 0 0 90)
			(layer "B.SilkS")
			(hide yes)
			(effects
				(font
					(size 1.27 1.27)
				)
				(justify mirror)
			)
		)
		(property "Value" "0R2J-2-GP"
			(at -0.064008 -3.993896 270)
			(unlocked yes)
			(layer "B.Fab")
			(hide yes)
			(effects
				(font
					(size 1.016 1.016)
					(thickness 0.1524)
				)
				(justify mirror)
			)
		)
		(property "Device Type" "R402H16"
			(at -0.064008 -5.517896 270)
			(unlocked yes)
			(layer "B.Fab")
			(hide yes)
			(effects
				(font
					(size 1.016 1.016)
					(thickness 0.1524)
				)
				(justify mirror)
			)
		)
		(duplicate_pad_numbers_are_jumpers no)
		(fp_line
			(start -0.508 -0.9398)
			(end 0.508 -0.9398)
			(stroke
				(width 0.1524)
				(type default)
			)
			(layer "B.SilkS")
		)
		(fp_line
			(start 0.508 -0.9398)
			(end 0.508 0.9398)
			(stroke
				(width 0.1524)
				(type default)
			)
			(layer "B.SilkS")
		)
		(fp_rect
			(start 0.508 0.9398)
			(end -0.508 -0.9398)
			(stroke
				(width 0)
				(type default)
			)
			(fill no)
			(layer "B.CrtYd")
		)
		(fp_rect
			(start 0.508 0.9398)
			(end -0.508 -0.9398)
			(stroke
				(width 0)
				(type default)
			)
			(fill no)
			(layer "B.Fab")
		)
		(pad "1" smd custom
			(at 0 -0.4445 90)
			(size 0.1397 0.1397)
			(layers "B.Cu" "B.Mask" "B.Paste")
			(net "EXP_TRAY_ID_BMC")
			(options
				(clearance outline)
				(anchor circle)
			)
			(primitives
				(gr_poly
					(pts
						(arc
							(start -0.1778 0.2794)
							(mid -0.249642 0.249642)
							(end -0.2794 0.1778)
						)
						(arc
							(start -0.2794 -0.1778)
							(mid -0.249642 -0.249642)
							(end -0.1778 -0.2794)
						)
						(arc
							(start 0.1778 -0.2794)
							(mid 0.249642 -0.249642)
							(end 0.2794 -0.1778)
						)
						(arc
							(start 0.2794 0.1778)
							(mid 0.249642 0.249642)
							(end 0.1778 0.2794)
						)
					)
					(width 0)
					(fill yes)
				)
			)
		)
		(pad "2" smd custom
			(at 0 0.4445 90)
			(size 0.1397 0.1397)
			(layers "B.Cu" "B.Mask" "B.Paste")
			(net "EXP_TRAY_ID")
			(options
				(clearance outline)
				(anchor circle)
			)
			(primitives
				(gr_poly
					(pts
						(arc
							(start -0.1778 0.2794)
							(mid -0.249642 0.249642)
							(end -0.2794 0.1778)
						)
						(arc
							(start -0.2794 -0.1778)
							(mid -0.249642 -0.249642)
							(end -0.1778 -0.2794)
						)
						(arc
							(start 0.1778 -0.2794)
							(mid 0.249642 -0.249642)
							(end 0.2794 -0.1778)
						)
						(arc
							(start 0.2794 0.1778)
							(mid 0.249642 0.249642)
							(end 0.1778 0.2794)
						)
					)
					(width 0)
					(fill yes)
				)
			)
		)
	)
	(footprint ""
		(layer "B.Cu")
		(at 240.3856 -40.7162 180)
		(property "Reference" "C485"
			(at 0 0 0)
			(layer "B.SilkS")
			(hide yes)
			(effects
				(font
					(size 1.27 1.27)
				)
				(justify mirror)
			)
		)
		(property "Value" "SCD1U16V1KX-1-GP"
			(at 2.8321 -1.7399 180)
			(unlocked yes)
			(layer "B.Fab")
			(hide yes)
			(effects
				(font
					(size 1.016 1.016)
					(thickness 0.1524)
				)
				(justify mirror)
			)
		)
		(property "Device Type" "C0201H13"
			(at 2.8321 -3.2639 180)
			(unlocked yes)
			(layer "B.Fab")
			(hide yes)
			(effects
				(font
					(size 1.016 1.016)
					(thickness 0.1524)
				)
				(justify mirror)
			)
		)
		(duplicate_pad_numbers_are_jumpers no)
		(fp_rect
			(start 0.2794 0.6477)
			(end -0.2794 -0.6477)
			(stroke
				(width 0)
				(type default)
			)
			(fill no)
			(layer "B.CrtYd")
		)
		(fp_rect
			(start 0.2794 0.6477)
			(end -0.2794 -0.6477)
			(stroke
				(width 0)
				(type default)
			)
			(fill no)
			(layer "B.Fab")
		)
		(pad "1" smd custom
			(at 0 -0.2794)
			(size 0.0762 0.0762)
			(layers "B.Cu" "B.Mask" "B.Paste")
			(net "DUT_VDDO_REF")
			(options
				(clearance outline)
				(anchor circle)
			)
			(primitives
				(gr_poly
					(pts
						(arc
							(start 0.1524 0.127)
							(mid 0.137521 0.162921)
							(end 0.1016 0.1778)
						)
						(arc
							(start -0.1016 0.1778)
							(mid -0.137521 0.162921)
							(end -0.1524 0.127)
						)
						(arc
							(start -0.1524 -0.127)
							(mid -0.137521 -0.162921)
							(end -0.1016 -0.1778)
						)
						(arc
							(start 0.1016 -0.1778)
							(mid 0.137521 -0.162921)
							(end 0.1524 -0.127)
						)
					)
					(width 0)
					(fill yes)
				)
			)
		)
		(pad "2" smd custom
			(at 0 0.2794)
			(size 0.0762 0.0762)
			(layers "B.Cu" "B.Mask" "B.Paste")
			(net "GND")
			(options
				(clearance outline)
				(anchor circle)
			)
			(primitives
				(gr_poly
					(pts
						(arc
							(start 0.1524 0.127)
							(mid 0.137521 0.162921)
							(end 0.1016 0.1778)
						)
						(arc
							(start -0.1016 0.1778)
							(mid -0.137521 0.162921)
							(end -0.1524 0.127)
						)
						(arc
							(start -0.1524 -0.127)
							(mid -0.137521 -0.162921)
							(end -0.1016 -0.1778)
						)
						(arc
							(start 0.1016 -0.1778)
							(mid 0.137521 -0.162921)
							(end 0.1524 -0.127)
						)
					)
					(width 0)
					(fill yes)
				)
			)
		)
	)
	(footprint ""
		(layer "B.Cu")
		(at 232.605072 -45.457872)
		(property "Reference" "C546"
			(at 0 0 0)
			(layer "B.SilkS")
			(hide yes)
			(effects
				(font
					(size 1.27 1.27)
				)
				(justify mirror)
			)
		)
		(property "Value" "SCD1U16V1KX-1-GP"
			(at 2.8321 -1.7399 0)
			(unlocked yes)
			(layer "B.Fab")
			(hide yes)
			(effects
				(font
					(size 1.016 1.016)
					(thickness 0.1524)
				)
				(justify mirror)
			)
		)
		(property "Device Type" "C0201H13"
			(at 2.8321 -3.2639 0)
			(unlocked yes)
			(layer "B.Fab")
			(hide yes)
			(effects
				(font
					(size 1.016 1.016)
					(thickness 0.1524)
				)
				(justify mirror)
			)
		)
		(duplicate_pad_numbers_are_jumpers no)
		(fp_rect
			(start 0.2794 0.6477)
			(end -0.2794 -0.6477)
			(stroke
				(width 0)
				(type default)
			)
			(fill no)
			(layer "B.CrtYd")
		)
		(fp_rect
			(start 0.2794 0.6477)
			(end -0.2794 -0.6477)
			(stroke
				(width 0)
				(type default)
			)
			(fill no)
			(layer "B.Fab")
		)
		(pad "1" smd custom
			(at 0 -0.2794 180)
			(size 0.0762 0.0762)
			(layers "B.Cu" "B.Mask" "B.Paste")
			(net "DUT_AVD_PCIE")
			(options
				(clearance outline)
				(anchor circle)
			)
			(primitives
				(gr_poly
					(pts
						(arc
							(start 0.1524 0.127)
							(mid 0.137521 0.162921)
							(end 0.1016 0.1778)
						)
						(arc
							(start -0.1016 0.1778)
							(mid -0.137521 0.162921)
							(end -0.1524 0.127)
						)
						(arc
							(start -0.1524 -0.127)
							(mid -0.137521 -0.162921)
							(end -0.1016 -0.1778)
						)
						(arc
							(start 0.1016 -0.1778)
							(mid 0.137521 -0.162921)
							(end 0.1524 -0.127)
						)
					)
					(width 0)
					(fill yes)
				)
			)
		)
		(pad "2" smd custom
			(at 0 0.2794 180)
			(size 0.0762 0.0762)
			(layers "B.Cu" "B.Mask" "B.Paste")
			(net "GND")
			(options
				(clearance outline)
				(anchor circle)
			)
			(primitives
				(gr_poly
					(pts
						(arc
							(start 0.1524 0.127)
							(mid 0.137521 0.162921)
							(end 0.1016 0.1778)
						)
						(arc
							(start -0.1016 0.1778)
							(mid -0.137521 0.162921)
							(end -0.1524 0.127)
						)
						(arc
							(start -0.1524 -0.127)
							(mid -0.137521 -0.162921)
							(end -0.1016 -0.1778)
						)
						(arc
							(start 0.1016 -0.1778)
							(mid 0.137521 -0.162921)
							(end 0.1524 -0.127)
						)
					)
					(width 0)
					(fill yes)
				)
			)
		)
	)
	(footprint ""
		(layer "B.Cu")
		(at 221.7674 -7.366)
		(property "Reference" "R3714"
			(at 0 0 0)
			(layer "B.SilkS")
			(hide yes)
			(effects
				(font
					(size 1.27 1.27)
				)
				(justify mirror)
			)
		)
		(property "Value" "1KR2F-3-GP"
			(at -0.064008 -3.993896 0)
			(unlocked yes)
			(layer "B.Fab")
			(hide yes)
			(effects
				(font
					(size 1.016 1.016)
					(thickness 0.1524)
				)
				(justify mirror)
			)
		)
		(property "Device Type" "R402H16"
			(at -0.064008 -5.517896 0)
			(unlocked yes)
			(layer "B.Fab")
			(hide yes)
			(effects
				(font
					(size 1.016 1.016)
					(thickness 0.1524)
				)
				(justify mirror)
			)
		)
		(duplicate_pad_numbers_are_jumpers no)
		(fp_line
			(start -0.508 -0.9398)
			(end 0.508 -0.9398)
			(stroke
				(width 0.1524)
				(type default)
			)
			(layer "B.SilkS")
		)
		(fp_line
			(start 0.508 -0.9398)
			(end 0.508 0.9398)
			(stroke
				(width 0.1524)
				(type default)
			)
			(layer "B.SilkS")
		)
		(fp_rect
			(start 0.508 0.9398)
			(end -0.508 -0.9398)
			(stroke
				(width 0)
				(type default)
			)
			(fill no)
			(layer "B.CrtYd")
		)
		(fp_rect
			(start 0.508 0.9398)
			(end -0.508 -0.9398)
			(stroke
				(width 0)
				(type default)
			)
			(fill no)
			(layer "B.Fab")
		)
		(pad "1" smd custom
			(at 0 -0.4445 180)
			(size 0.1397 0.1397)
			(layers "B.Cu" "B.Mask" "B.Paste")
			(net "HOST1_RST_N")
			(options
				(clearance outline)
				(anchor circle)
			)
			(primitives
				(gr_poly
					(pts
						(arc
							(start -0.1778 0.2794)
							(mid -0.249642 0.249642)
							(end -0.2794 0.1778)
						)
						(arc
							(start -0.2794 -0.1778)
							(mid -0.249642 -0.249642)
							(end -0.1778 -0.2794)
						)
						(arc
							(start 0.1778 -0.2794)
							(mid 0.249642 -0.249642)
							(end 0.2794 -0.1778)
						)
						(arc
							(start 0.2794 0.1778)
							(mid 0.249642 0.249642)
							(end 0.1778 0.2794)
						)
					)
					(width 0)
					(fill yes)
				)
			)
		)
		(pad "2" smd custom
			(at 0 0.4445 180)
			(size 0.1397 0.1397)
			(layers "B.Cu" "B.Mask" "B.Paste")
			(net "P3V3_STBY")
			(options
				(clearance outline)
				(anchor circle)
			)
			(primitives
				(gr_poly
					(pts
						(arc
							(start -0.1778 0.2794)
							(mid -0.249642 0.249642)
							(end -0.2794 0.1778)
						)
						(arc
							(start -0.2794 -0.1778)
							(mid -0.249642 -0.249642)
							(end -0.1778 -0.2794)
						)
						(arc
							(start 0.1778 -0.2794)
							(mid 0.249642 -0.249642)
							(end 0.2794 -0.1778)
						)
						(arc
							(start 0.2794 0.1778)
							(mid 0.249642 0.249642)
							(end 0.1778 0.2794)
						)
					)
					(width 0)
					(fill yes)
				)
			)
		)
	)
	(footprint ""
		(layer "B.Cu")
		(at 245.5926 -56.9976 -90)
		(property "Reference" "C512"
			(at 0 0 90)
			(layer "B.SilkS")
			(hide yes)
			(effects
				(font
					(size 1.27 1.27)
				)
				(justify mirror)
			)
		)
		(property "Value" "SCD1U16V1KX-1-GP"
			(at 2.8321 -1.7399 270)
			(unlocked yes)
			(layer "B.Fab")
			(hide yes)
			(effects
				(font
					(size 1.016 1.016)
					(thickness 0.1524)
				)
				(justify mirror)
			)
		)
		(property "Device Type" "C0201H13"
			(at 2.8321 -3.2639 270)
			(unlocked yes)
			(layer "B.Fab")
			(hide yes)
			(effects
				(font
					(size 1.016 1.016)
					(thickness 0.1524)
				)
				(justify mirror)
			)
		)
		(duplicate_pad_numbers_are_jumpers no)
		(fp_rect
			(start 0.2794 0.6477)
			(end -0.2794 -0.6477)
			(stroke
				(width 0)
				(type default)
			)
			(fill no)
			(layer "B.CrtYd")
		)
		(fp_rect
			(start 0.2794 0.6477)
			(end -0.2794 -0.6477)
			(stroke
				(width 0)
				(type default)
			)
			(fill no)
			(layer "B.Fab")
		)
		(pad "1" smd custom
			(at 0 -0.2794 90)
			(size 0.0762 0.0762)
			(layers "B.Cu" "B.Mask" "B.Paste")
			(net "DUT_AVD_TX")
			(options
				(clearance outline)
				(anchor circle)
			)
			(primitives
				(gr_poly
					(pts
						(arc
							(start 0.1524 0.127)
							(mid 0.137521 0.162921)
							(end 0.1016 0.1778)
						)
						(arc
							(start -0.1016 0.1778)
							(mid -0.137521 0.162921)
							(end -0.1524 0.127)
						)
						(arc
							(start -0.1524 -0.127)
							(mid -0.137521 -0.162921)
							(end -0.1016 -0.1778)
						)
						(arc
							(start 0.1016 -0.1778)
							(mid 0.137521 -0.162921)
							(end 0.1524 -0.127)
						)
					)
					(width 0)
					(fill yes)
				)
			)
		)
		(pad "2" smd custom
			(at 0 0.2794 90)
			(size 0.0762 0.0762)
			(layers "B.Cu" "B.Mask" "B.Paste")
			(net "GND")
			(options
				(clearance outline)
				(anchor circle)
			)
			(primitives
				(gr_poly
					(pts
						(arc
							(start 0.1524 0.127)
							(mid 0.137521 0.162921)
							(end 0.1016 0.1778)
						)
						(arc
							(start -0.1016 0.1778)
							(mid -0.137521 0.162921)
							(end -0.1524 0.127)
						)
						(arc
							(start -0.1524 -0.127)
							(mid -0.137521 -0.162921)
							(end -0.1016 -0.1778)
						)
						(arc
							(start 0.1016 -0.1778)
							(mid 0.137521 -0.162921)
							(end 0.1524 -0.127)
						)
					)
					(width 0)
					(fill yes)
				)
			)
		)
	)
	(footprint ""
		(layer "B.Cu")
		(at 39.586154 -158.987744 180)
		(property "Reference" "C173"
			(at 0 0 0)
			(layer "B.SilkS")
			(hide yes)
			(effects
				(font
					(size 1.27 1.27)
				)
				(justify mirror)
			)
		)
		(property "Value" "SCD1U16V2KX-3GP"
			(at -1.1811 -2.7051 180)
			(unlocked yes)
			(layer "B.Fab")
			(hide yes)
			(effects
				(font
					(size 1.016 1.016)
					(thickness 0.1524)
				)
				(justify mirror)
			)
		)
		(property "Device Type" "C402H22"
			(at -1.1811 -4.2291 180)
			(unlocked yes)
			(layer "B.Fab")
			(hide yes)
			(effects
				(font
					(size 1.016 1.016)
					(thickness 0.1524)
				)
				(justify mirror)
			)
		)
		(duplicate_pad_numbers_are_jumpers no)
		(fp_rect
			(start 0.4318 0.9525)
			(end -0.4318 -0.9525)
			(stroke
				(width 0)
				(type default)
			)
			(fill no)
			(layer "B.CrtYd")
		)
		(fp_rect
			(start 0.4318 0.9525)
			(end -0.4318 -0.9525)
			(stroke
				(width 0)
				(type default)
			)
			(fill no)
			(layer "B.Fab")
		)
		(pad "1" smd custom
			(at 0 -0.4445)
			(size 0.1524 0.1524)
			(layers "B.Cu" "B.Mask" "B.Paste")
			(net "P1V53_STBY")
			(options
				(clearance outline)
				(anchor circle)
			)
			(primitives
				(gr_poly
					(pts
						(arc
							(start 0.3048 0.2032)
							(mid 0.275042 0.275042)
							(end 0.2032 0.3048)
						)
						(arc
							(start -0.2032 0.3048)
							(mid -0.275042 0.275042)
							(end -0.3048 0.2032)
						)
						(arc
							(start -0.3048 -0.2032)
							(mid -0.275042 -0.275042)
							(end -0.2032 -0.3048)
						)
						(arc
							(start 0.2032 -0.3048)
							(mid 0.275042 -0.275042)
							(end 0.3048 -0.2032)
						)
					)
					(width 0)
					(fill yes)
				)
			)
		)
		(pad "2" smd custom
			(at 0 0.4445)
			(size 0.1524 0.1524)
			(layers "B.Cu" "B.Mask" "B.Paste")
			(net "GND")
			(options
				(clearance outline)
				(anchor circle)
			)
			(primitives
				(gr_poly
					(pts
						(arc
							(start 0.3048 0.2032)
							(mid 0.275042 0.275042)
							(end 0.2032 0.3048)
						)
						(arc
							(start -0.2032 0.3048)
							(mid -0.275042 0.275042)
							(end -0.3048 0.2032)
						)
						(arc
							(start -0.3048 -0.2032)
							(mid -0.275042 -0.275042)
							(end -0.2032 -0.3048)
						)
						(arc
							(start 0.2032 -0.3048)
							(mid 0.275042 -0.275042)
							(end 0.3048 -0.2032)
						)
					)
					(width 0)
					(fill yes)
				)
			)
		)
	)
	(footprint ""
		(layer "B.Cu")
		(at 34.798 -116.713 180)
		(property "Reference" "R506"
			(at 0 0 0)
			(layer "B.SilkS")
			(hide yes)
			(effects
				(font
					(size 1.27 1.27)
				)
				(justify mirror)
			)
		)
		(property "Value" "0R2J-2-GP"
			(at -0.064008 -3.993896 180)
			(unlocked yes)
			(layer "B.Fab")
			(hide yes)
			(effects
				(font
					(size 1.016 1.016)
					(thickness 0.1524)
				)
				(justify mirror)
			)
		)
		(property "Device Type" "R402H16"
			(at -0.064008 -5.517896 180)
			(unlocked yes)
			(layer "B.Fab")
			(hide yes)
			(effects
				(font
					(size 1.016 1.016)
					(thickness 0.1524)
				)
				(justify mirror)
			)
		)
		(duplicate_pad_numbers_are_jumpers no)
		(fp_line
			(start 0.508 -0.9398)
			(end 0.508 0.9398)
			(stroke
				(width 0.1524)
				(type default)
			)
			(layer "B.SilkS")
		)
		(fp_line
			(start -0.508 -0.9398)
			(end 0.508 -0.9398)
			(stroke
				(width 0.1524)
				(type default)
			)
			(layer "B.SilkS")
		)
		(fp_rect
			(start 0.508 0.9398)
			(end -0.508 -0.9398)
			(stroke
				(width 0)
				(type default)
			)
			(fill no)
			(layer "B.CrtYd")
		)
		(fp_rect
			(start 0.508 0.9398)
			(end -0.508 -0.9398)
			(stroke
				(width 0)
				(type default)
			)
			(fill no)
			(layer "B.Fab")
		)
		(pad "1" smd custom
			(at 0 -0.4445)
			(size 0.1397 0.1397)
			(layers "B.Cu" "B.Mask" "B.Paste")
			(net "BMC_ADD2")
			(options
				(clearance outline)
				(anchor circle)
			)
			(primitives
				(gr_poly
					(pts
						(arc
							(start -0.1778 0.2794)
							(mid -0.249642 0.249642)
							(end -0.2794 0.1778)
						)
						(arc
							(start -0.2794 -0.1778)
							(mid -0.249642 -0.249642)
							(end -0.1778 -0.2794)
						)
						(arc
							(start 0.1778 -0.2794)
							(mid 0.249642 -0.249642)
							(end 0.2794 -0.1778)
						)
						(arc
							(start 0.2794 0.1778)
							(mid 0.249642 0.249642)
							(end 0.1778 0.2794)
						)
					)
					(width 0)
					(fill yes)
				)
			)
		)
		(pad "2" smd custom
			(at 0 0.4445)
			(size 0.1397 0.1397)
			(layers "B.Cu" "B.Mask" "B.Paste")
			(net "BMC_ADD2_R")
			(options
				(clearance outline)
				(anchor circle)
			)
			(primitives
				(gr_poly
					(pts
						(arc
							(start -0.1778 0.2794)
							(mid -0.249642 0.249642)
							(end -0.2794 0.1778)
						)
						(arc
							(start -0.2794 -0.1778)
							(mid -0.249642 -0.249642)
							(end -0.1778 -0.2794)
						)
						(arc
							(start 0.1778 -0.2794)
							(mid 0.249642 -0.249642)
							(end 0.2794 -0.1778)
						)
						(arc
							(start 0.2794 0.1778)
							(mid 0.249642 0.249642)
							(end 0.1778 0.2794)
						)
					)
					(width 0)
					(fill yes)
				)
			)
		)
	)
	(footprint ""
		(layer "B.Cu")
		(at 247.651016 -26.694638 90)
		(property "Reference" "TP304"
			(at 0 0 90)
			(layer "B.SilkS")
			(hide yes)
			(effects
				(font
					(size 1.27 1.27)
				)
				(justify mirror)
			)
		)
		(property "Value" "TPAD28-2-GP"
			(at 0.0127 -1.6637 90)
			(unlocked yes)
			(layer "B.Fab")
			(hide yes)
			(effects
				(font
					(size 1.016 1.016)
					(thickness 0.1524)
				)
				(justify mirror)
			)
		)
		(property "Device Type" "TPAD28"
			(at 0.0127 -3.1877 90)
			(unlocked yes)
			(layer "B.Fab")
			(hide yes)
			(effects
				(font
					(size 1.016 1.016)
					(thickness 0.1524)
				)
				(justify mirror)
			)
		)
		(duplicate_pad_numbers_are_jumpers no)
		(fp_poly
			(pts
				(arc
					(start 0 0.3556)
					(mid 0 -0.3556)
					(end 0 0.3556)
				)
			)
			(stroke
				(width 0)
				(type default)
			)
			(fill no)
			(layer "B.CrtYd")
		)
		(fp_poly
			(pts
				(arc
					(start 0 0.6096)
					(mid 0 -0.6096)
					(end 0 0.6096)
				)
			)
			(stroke
				(width 0)
				(type default)
			)
			(fill no)
			(layer "B.Fab")
		)
		(pad "1" smd circle
			(at 0 0 270)
			(size 0.7112 0.7112)
			(layers "B.Cu" "B.Mask" "B.Paste")
			(net "TWI_SDA10")
		)
	)
	(footprint ""
		(layer "B.Cu")
		(at 223.851724 -190.601092)
		(property "Reference" "R4139"
			(at 0 0 0)
			(layer "B.SilkS")
			(hide yes)
			(effects
				(font
					(size 1.27 1.27)
				)
				(justify mirror)
			)
		)
		(property "Value" "4K7R2F-GP"
			(at -0.064008 -3.993896 0)
			(unlocked yes)
			(layer "B.Fab")
			(hide yes)
			(effects
				(font
					(size 1.016 1.016)
					(thickness 0.1524)
				)
				(justify mirror)
			)
		)
		(property "Device Type" "R402H16"
			(at -0.064008 -5.517896 0)
			(unlocked yes)
			(layer "B.Fab")
			(hide yes)
			(effects
				(font
					(size 1.016 1.016)
					(thickness 0.1524)
				)
				(justify mirror)
			)
		)
		(duplicate_pad_numbers_are_jumpers no)
		(fp_line
			(start -0.508 -0.9398)
			(end 0.508 -0.9398)
			(stroke
				(width 0.1524)
				(type default)
			)
			(layer "B.SilkS")
		)
		(fp_line
			(start 0.508 -0.9398)
			(end 0.508 0.9398)
			(stroke
				(width 0.1524)
				(type default)
			)
			(layer "B.SilkS")
		)
		(fp_rect
			(start 0.508 0.9398)
			(end -0.508 -0.9398)
			(stroke
				(width 0)
				(type default)
			)
			(fill no)
			(layer "B.CrtYd")
		)
		(fp_rect
			(start 0.508 0.9398)
			(end -0.508 -0.9398)
			(stroke
				(width 0)
				(type default)
			)
			(fill no)
			(layer "B.Fab")
		)
		(pad "1" smd custom
			(at 0 -0.4445 180)
			(size 0.1397 0.1397)
			(layers "B.Cu" "B.Mask" "B.Paste")
			(net "SSD_PERST#3")
			(options
				(clearance outline)
				(anchor circle)
			)
			(primitives
				(gr_poly
					(pts
						(arc
							(start -0.1778 0.2794)
							(mid -0.249642 0.249642)
							(end -0.2794 0.1778)
						)
						(arc
							(start -0.2794 -0.1778)
							(mid -0.249642 -0.249642)
							(end -0.1778 -0.2794)
						)
						(arc
							(start 0.1778 -0.2794)
							(mid 0.249642 -0.249642)
							(end 0.2794 -0.1778)
						)
						(arc
							(start 0.2794 0.1778)
							(mid 0.249642 0.249642)
							(end 0.1778 0.2794)
						)
					)
					(width 0)
					(fill yes)
				)
			)
		)
		(pad "2" smd custom
			(at 0 0.4445 180)
			(size 0.1397 0.1397)
			(layers "B.Cu" "B.Mask" "B.Paste")
			(net "P3V3_STBY")
			(options
				(clearance outline)
				(anchor circle)
			)
			(primitives
				(gr_poly
					(pts
						(arc
							(start -0.1778 0.2794)
							(mid -0.249642 0.249642)
							(end -0.2794 0.1778)
						)
						(arc
							(start -0.2794 -0.1778)
							(mid -0.249642 -0.249642)
							(end -0.1778 -0.2794)
						)
						(arc
							(start 0.1778 -0.2794)
							(mid 0.249642 -0.249642)
							(end 0.2794 -0.1778)
						)
						(arc
							(start 0.2794 0.1778)
							(mid 0.249642 0.249642)
							(end 0.1778 0.2794)
						)
					)
					(width 0)
					(fill yes)
				)
			)
		)
	)
	(footprint ""
		(layer "B.Cu")
		(at 35.687 -114.55146 180)
		(property "Reference" "R620"
			(at 0 0 0)
			(layer "B.SilkS")
			(hide yes)
			(effects
				(font
					(size 1.27 1.27)
				)
				(justify mirror)
			)
		)
		(property "Value" "0R2J-2-GP"
			(at -0.064008 -3.993896 180)
			(unlocked yes)
			(layer "B.Fab")
			(hide yes)
			(effects
				(font
					(size 1.016 1.016)
					(thickness 0.1524)
				)
				(justify mirror)
			)
		)
		(property "Device Type" "R402H16"
			(at -0.064008 -5.517896 180)
			(unlocked yes)
			(layer "B.Fab")
			(hide yes)
			(effects
				(font
					(size 1.016 1.016)
					(thickness 0.1524)
				)
				(justify mirror)
			)
		)
		(duplicate_pad_numbers_are_jumpers no)
		(fp_line
			(start 0.508 -0.9398)
			(end 0.508 0.9398)
			(stroke
				(width 0.1524)
				(type default)
			)
			(layer "B.SilkS")
		)
		(fp_line
			(start -0.508 -0.9398)
			(end 0.508 -0.9398)
			(stroke
				(width 0.1524)
				(type default)
			)
			(layer "B.SilkS")
		)
		(fp_rect
			(start 0.508 0.9398)
			(end -0.508 -0.9398)
			(stroke
				(width 0)
				(type default)
			)
			(fill no)
			(layer "B.CrtYd")
		)
		(fp_rect
			(start 0.508 0.9398)
			(end -0.508 -0.9398)
			(stroke
				(width 0)
				(type default)
			)
			(fill no)
			(layer "B.Fab")
		)
		(pad "1" smd custom
			(at 0 -0.4445)
			(size 0.1397 0.1397)
			(layers "B.Cu" "B.Mask" "B.Paste")
			(net "GND")
			(options
				(clearance outline)
				(anchor circle)
			)
			(primitives
				(gr_poly
					(pts
						(arc
							(start -0.1778 0.2794)
							(mid -0.249642 0.249642)
							(end -0.2794 0.1778)
						)
						(arc
							(start -0.2794 -0.1778)
							(mid -0.249642 -0.249642)
							(end -0.1778 -0.2794)
						)
						(arc
							(start 0.1778 -0.2794)
							(mid 0.249642 -0.249642)
							(end 0.2794 -0.1778)
						)
						(arc
							(start 0.2794 0.1778)
							(mid 0.249642 0.249642)
							(end 0.1778 0.2794)
						)
					)
					(width 0)
					(fill yes)
				)
			)
		)
		(pad "2" smd custom
			(at 0 0.4445)
			(size 0.1397 0.1397)
			(layers "B.Cu" "B.Mask" "B.Paste")
			(net "RMII_BMC_PHY_TXD1")
			(options
				(clearance outline)
				(anchor circle)
			)
			(primitives
				(gr_poly
					(pts
						(arc
							(start -0.1778 0.2794)
							(mid -0.249642 0.249642)
							(end -0.2794 0.1778)
						)
						(arc
							(start -0.2794 -0.1778)
							(mid -0.249642 -0.249642)
							(end -0.1778 -0.2794)
						)
						(arc
							(start 0.1778 -0.2794)
							(mid 0.249642 -0.249642)
							(end 0.2794 -0.1778)
						)
						(arc
							(start 0.2794 0.1778)
							(mid 0.249642 0.249642)
							(end 0.1778 0.2794)
						)
					)
					(width 0)
					(fill yes)
				)
			)
		)
	)
	(footprint ""
		(layer "B.Cu")
		(at 178.0794 -69.215)
		(property "Reference" "PG17"
			(at 0 0 0)
			(layer "B.SilkS")
			(hide yes)
			(effects
				(font
					(size 1.27 1.27)
				)
				(justify mirror)
			)
		)
		(property "Value" "GAP-CLOSE-PWR-3-GP"
			(at -0.0254 -6.5786 0)
			(unlocked yes)
			(layer "B.Fab")
			(hide yes)
			(effects
				(font
					(size 1.016 1.016)
					(thickness 0.1524)
				)
				(justify mirror)
			)
		)
		(property "Device Type" "GAP-CLOSE-PWR-3"
			(at -0.0254 -8.255 0)
			(unlocked yes)
			(layer "B.Fab")
			(hide yes)
			(effects
				(font
					(size 1.016 1.016)
					(thickness 0.1524)
				)
				(justify mirror)
			)
		)
		(duplicate_pad_numbers_are_jumpers no)
		(fp_rect
			(start 0.7112 0.4572)
			(end -0.7112 -0.4572)
			(stroke
				(width 0)
				(type default)
			)
			(fill no)
			(layer "B.CrtYd")
		)
		(fp_poly
			(pts
				(xy 0.7112 -0.4572) (xy -0.7112 -0.4572) (xy -0.7112 0.4572) (xy 0.7112 0.4572)
			)
			(stroke
				(width 0)
				(type default)
			)
			(fill no)
			(layer "B.Fab")
		)
		(pad "1" smd rect
			(at 0.3048 0 180)
			(size 0.6604 0.762)
			(layers "B.Cu" "B.Mask" "B.Paste")
			(net "DUT_AVD_PCIE")
		)
		(pad "2" smd rect
			(at -0.3048 0 180)
			(size 0.6604 0.762)
			(layers "B.Cu" "B.Mask" "B.Paste")
			(net "P0V9")
		)
	)
	(footprint ""
		(layer "B.Cu")
		(at 252.603 -53.001672 -90)
		(property "Reference" "C582"
			(at 0 0 90)
			(layer "B.SilkS")
			(hide yes)
			(effects
				(font
					(size 1.27 1.27)
				)
				(justify mirror)
			)
		)
		(property "Value" "SCD1U16V1KX-1-GP"
			(at 2.8321 -1.7399 270)
			(unlocked yes)
			(layer "B.Fab")
			(hide yes)
			(effects
				(font
					(size 1.016 1.016)
					(thickness 0.1524)
				)
				(justify mirror)
			)
		)
		(property "Device Type" "C0201H13"
			(at 2.8321 -3.2639 270)
			(unlocked yes)
			(layer "B.Fab")
			(hide yes)
			(effects
				(font
					(size 1.016 1.016)
					(thickness 0.1524)
				)
				(justify mirror)
			)
		)
		(duplicate_pad_numbers_are_jumpers no)
		(fp_rect
			(start 0.2794 0.6477)
			(end -0.2794 -0.6477)
			(stroke
				(width 0)
				(type default)
			)
			(fill no)
			(layer "B.CrtYd")
		)
		(fp_rect
			(start 0.2794 0.6477)
			(end -0.2794 -0.6477)
			(stroke
				(width 0)
				(type default)
			)
			(fill no)
			(layer "B.Fab")
		)
		(pad "1" smd custom
			(at 0 -0.2794 90)
			(size 0.0762 0.0762)
			(layers "B.Cu" "B.Mask" "B.Paste")
			(net "DUT_AVD_PCIE")
			(options
				(clearance outline)
				(anchor circle)
			)
			(primitives
				(gr_poly
					(pts
						(arc
							(start 0.1524 0.127)
							(mid 0.137521 0.162921)
							(end 0.1016 0.1778)
						)
						(arc
							(start -0.1016 0.1778)
							(mid -0.137521 0.162921)
							(end -0.1524 0.127)
						)
						(arc
							(start -0.1524 -0.127)
							(mid -0.137521 -0.162921)
							(end -0.1016 -0.1778)
						)
						(arc
							(start 0.1016 -0.1778)
							(mid 0.137521 -0.162921)
							(end 0.1524 -0.127)
						)
					)
					(width 0)
					(fill yes)
				)
			)
		)
		(pad "2" smd custom
			(at 0 0.2794 90)
			(size 0.0762 0.0762)
			(layers "B.Cu" "B.Mask" "B.Paste")
			(net "GND")
			(options
				(clearance outline)
				(anchor circle)
			)
			(primitives
				(gr_poly
					(pts
						(arc
							(start 0.1524 0.127)
							(mid 0.137521 0.162921)
							(end 0.1016 0.1778)
						)
						(arc
							(start -0.1016 0.1778)
							(mid -0.137521 0.162921)
							(end -0.1524 0.127)
						)
						(arc
							(start -0.1524 -0.127)
							(mid -0.137521 -0.162921)
							(end -0.1016 -0.1778)
						)
						(arc
							(start 0.1016 -0.1778)
							(mid 0.137521 -0.162921)
							(end 0.1524 -0.127)
						)
					)
					(width 0)
					(fill yes)
				)
			)
		)
	)
	(footprint ""
		(layer "B.Cu")
		(at 254.7874 -26.1112 180)
		(property "Reference" "R772"
			(at 0 0 0)
			(layer "B.SilkS")
			(hide yes)
			(effects
				(font
					(size 1.27 1.27)
				)
				(justify mirror)
			)
		)
		(property "Value" "3K3R2F-2-GP"
			(at -0.064008 -3.993896 180)
			(unlocked yes)
			(layer "B.Fab")
			(hide yes)
			(effects
				(font
					(size 1.016 1.016)
					(thickness 0.1524)
				)
				(justify mirror)
			)
		)
		(property "Device Type" "R402H16"
			(at -0.064008 -5.517896 180)
			(unlocked yes)
			(layer "B.Fab")
			(hide yes)
			(effects
				(font
					(size 1.016 1.016)
					(thickness 0.1524)
				)
				(justify mirror)
			)
		)
		(duplicate_pad_numbers_are_jumpers no)
		(fp_line
			(start 0.508 -0.9398)
			(end 0.508 0.9398)
			(stroke
				(width 0.1524)
				(type default)
			)
			(layer "B.SilkS")
		)
		(fp_line
			(start -0.508 -0.9398)
			(end 0.508 -0.9398)
			(stroke
				(width 0.1524)
				(type default)
			)
			(layer "B.SilkS")
		)
		(fp_rect
			(start 0.508 0.9398)
			(end -0.508 -0.9398)
			(stroke
				(width 0)
				(type default)
			)
			(fill no)
			(layer "B.CrtYd")
		)
		(fp_rect
			(start 0.508 0.9398)
			(end -0.508 -0.9398)
			(stroke
				(width 0)
				(type default)
			)
			(fill no)
			(layer "B.Fab")
		)
		(pad "1" smd custom
			(at 0 -0.4445)
			(size 0.1397 0.1397)
			(layers "B.Cu" "B.Mask" "B.Paste")
			(net "P3V3_GPIO")
			(options
				(clearance outline)
				(anchor circle)
			)
			(primitives
				(gr_poly
					(pts
						(arc
							(start -0.1778 0.2794)
							(mid -0.249642 0.249642)
							(end -0.2794 0.1778)
						)
						(arc
							(start -0.2794 -0.1778)
							(mid -0.249642 -0.249642)
							(end -0.1778 -0.2794)
						)
						(arc
							(start 0.1778 -0.2794)
							(mid 0.249642 -0.249642)
							(end 0.2794 -0.1778)
						)
						(arc
							(start 0.2794 0.1778)
							(mid 0.249642 0.249642)
							(end 0.1778 0.2794)
						)
					)
					(width 0)
					(fill yes)
				)
			)
		)
		(pad "2" smd custom
			(at 0 0.4445)
			(size 0.1397 0.1397)
			(layers "B.Cu" "B.Mask" "B.Paste")
			(net "TWI_SCL0")
			(options
				(clearance outline)
				(anchor circle)
			)
			(primitives
				(gr_poly
					(pts
						(arc
							(start -0.1778 0.2794)
							(mid -0.249642 0.249642)
							(end -0.2794 0.1778)
						)
						(arc
							(start -0.2794 -0.1778)
							(mid -0.249642 -0.249642)
							(end -0.1778 -0.2794)
						)
						(arc
							(start 0.1778 -0.2794)
							(mid 0.249642 -0.249642)
							(end 0.2794 -0.1778)
						)
						(arc
							(start 0.2794 0.1778)
							(mid 0.249642 0.249642)
							(end 0.1778 0.2794)
						)
					)
					(width 0)
					(fill yes)
				)
			)
		)
	)
	(footprint ""
		(layer "B.Cu")
		(at 123.698 -199.7456)
		(property "Reference" "C3209"
			(at 0 0 0)
			(layer "B.SilkS")
			(hide yes)
			(effects
				(font
					(size 1.27 1.27)
				)
				(justify mirror)
			)
		)
		(property "Value" "SCD1U25V2KX-2-GP"
			(at -1.1811 -2.7051 0)
			(unlocked yes)
			(layer "B.Fab")
			(hide yes)
			(effects
				(font
					(size 1.016 1.016)
					(thickness 0.1524)
				)
				(justify mirror)
			)
		)
		(property "Device Type" "C402H22"
			(at -1.1811 -4.2291 0)
			(unlocked yes)
			(layer "B.Fab")
			(hide yes)
			(effects
				(font
					(size 1.016 1.016)
					(thickness 0.1524)
				)
				(justify mirror)
			)
		)
		(duplicate_pad_numbers_are_jumpers no)
		(fp_rect
			(start 0.4318 0.9525)
			(end -0.4318 -0.9525)
			(stroke
				(width 0)
				(type default)
			)
			(fill no)
			(layer "B.CrtYd")
		)
		(fp_rect
			(start 0.4318 0.9525)
			(end -0.4318 -0.9525)
			(stroke
				(width 0)
				(type default)
			)
			(fill no)
			(layer "B.Fab")
		)
		(pad "1" smd custom
			(at 0 -0.4445 180)
			(size 0.1524 0.1524)
			(layers "B.Cu" "B.Mask" "B.Paste")
			(net "P3V3_STBY")
			(options
				(clearance outline)
				(anchor circle)
			)
			(primitives
				(gr_poly
					(pts
						(arc
							(start 0.3048 0.2032)
							(mid 0.275042 0.275042)
							(end 0.2032 0.3048)
						)
						(arc
							(start -0.2032 0.3048)
							(mid -0.275042 0.275042)
							(end -0.3048 0.2032)
						)
						(arc
							(start -0.3048 -0.2032)
							(mid -0.275042 -0.275042)
							(end -0.2032 -0.3048)
						)
						(arc
							(start 0.2032 -0.3048)
							(mid 0.275042 -0.275042)
							(end 0.3048 -0.2032)
						)
					)
					(width 0)
					(fill yes)
				)
			)
		)
		(pad "2" smd custom
			(at 0 0.4445 180)
			(size 0.1524 0.1524)
			(layers "B.Cu" "B.Mask" "B.Paste")
			(net "GND")
			(options
				(clearance outline)
				(anchor circle)
			)
			(primitives
				(gr_poly
					(pts
						(arc
							(start 0.3048 0.2032)
							(mid 0.275042 0.275042)
							(end 0.2032 0.3048)
						)
						(arc
							(start -0.2032 0.3048)
							(mid -0.275042 0.275042)
							(end -0.3048 0.2032)
						)
						(arc
							(start -0.3048 -0.2032)
							(mid -0.275042 -0.275042)
							(end -0.2032 -0.3048)
						)
						(arc
							(start 0.2032 -0.3048)
							(mid 0.275042 -0.275042)
							(end 0.3048 -0.2032)
						)
					)
					(width 0)
					(fill yes)
				)
			)
		)
	)
	(footprint ""
		(layer "B.Cu")
		(at 46.863 -138.938)
		(property "Reference" "R308"
			(at 0 0 0)
			(layer "B.SilkS")
			(hide yes)
			(effects
				(font
					(size 1.27 1.27)
				)
				(justify mirror)
			)
		)
		(property "Value" "0R2J-2-GP"
			(at -0.064008 -3.993896 0)
			(unlocked yes)
			(layer "B.Fab")
			(hide yes)
			(effects
				(font
					(size 1.016 1.016)
					(thickness 0.1524)
				)
				(justify mirror)
			)
		)
		(property "Device Type" "R402H16"
			(at -0.064008 -5.517896 0)
			(unlocked yes)
			(layer "B.Fab")
			(hide yes)
			(effects
				(font
					(size 1.016 1.016)
					(thickness 0.1524)
				)
				(justify mirror)
			)
		)
		(duplicate_pad_numbers_are_jumpers no)
		(fp_line
			(start -0.508 -0.9398)
			(end 0.508 -0.9398)
			(stroke
				(width 0.1524)
				(type default)
			)
			(layer "B.SilkS")
		)
		(fp_line
			(start 0.508 -0.9398)
			(end 0.508 0.9398)
			(stroke
				(width 0.1524)
				(type default)
			)
			(layer "B.SilkS")
		)
		(fp_rect
			(start 0.508 0.9398)
			(end -0.508 -0.9398)
			(stroke
				(width 0)
				(type default)
			)
			(fill no)
			(layer "B.CrtYd")
		)
		(fp_rect
			(start 0.508 0.9398)
			(end -0.508 -0.9398)
			(stroke
				(width 0)
				(type default)
			)
			(fill no)
			(layer "B.Fab")
		)
		(pad "1" smd custom
			(at 0 -0.4445 180)
			(size 0.1397 0.1397)
			(layers "B.Cu" "B.Mask" "B.Paste")
			(net "PWM_EXP_A")
			(options
				(clearance outline)
				(anchor circle)
			)
			(primitives
				(gr_poly
					(pts
						(arc
							(start -0.1778 0.2794)
							(mid -0.249642 0.249642)
							(end -0.2794 0.1778)
						)
						(arc
							(start -0.2794 -0.1778)
							(mid -0.249642 -0.249642)
							(end -0.1778 -0.2794)
						)
						(arc
							(start 0.1778 -0.2794)
							(mid 0.249642 -0.249642)
							(end 0.2794 -0.1778)
						)
						(arc
							(start 0.2794 0.1778)
							(mid 0.249642 0.249642)
							(end 0.1778 0.2794)
						)
					)
					(width 0)
					(fill yes)
				)
			)
		)
		(pad "2" smd custom
			(at 0 0.4445 180)
			(size 0.1397 0.1397)
			(layers "B.Cu" "B.Mask" "B.Paste")
			(net "FAN_PWM_PCIE_BMC")
			(options
				(clearance outline)
				(anchor circle)
			)
			(primitives
				(gr_poly
					(pts
						(arc
							(start -0.1778 0.2794)
							(mid -0.249642 0.249642)
							(end -0.2794 0.1778)
						)
						(arc
							(start -0.2794 -0.1778)
							(mid -0.249642 -0.249642)
							(end -0.1778 -0.2794)
						)
						(arc
							(start 0.1778 -0.2794)
							(mid 0.249642 -0.249642)
							(end 0.2794 -0.1778)
						)
						(arc
							(start 0.2794 0.1778)
							(mid 0.249642 0.249642)
							(end 0.1778 0.2794)
						)
					)
					(width 0)
					(fill yes)
				)
			)
		)
	)
	(footprint ""
		(layer "B.Cu")
		(at 167.513 -33.528)
		(property "Reference" "R2930"
			(at 0 0 0)
			(layer "B.SilkS")
			(hide yes)
			(effects
				(font
					(size 1.27 1.27)
				)
				(justify mirror)
			)
		)
		(property "Value" "0R2J-2-GP"
			(at -0.064008 -3.993896 0)
			(unlocked yes)
			(layer "B.Fab")
			(hide yes)
			(effects
				(font
					(size 1.016 1.016)
					(thickness 0.1524)
				)
				(justify mirror)
			)
		)
		(property "Device Type" "R402H16"
			(at -0.064008 -5.517896 0)
			(unlocked yes)
			(layer "B.Fab")
			(hide yes)
			(effects
				(font
					(size 1.016 1.016)
					(thickness 0.1524)
				)
				(justify mirror)
			)
		)
		(duplicate_pad_numbers_are_jumpers no)
		(fp_line
			(start -0.508 -0.9398)
			(end 0.508 -0.9398)
			(stroke
				(width 0.1524)
				(type default)
			)
			(layer "B.SilkS")
		)
		(fp_line
			(start 0.508 -0.9398)
			(end 0.508 0.9398)
			(stroke
				(width 0.1524)
				(type default)
			)
			(layer "B.SilkS")
		)
		(fp_rect
			(start 0.508 0.9398)
			(end -0.508 -0.9398)
			(stroke
				(width 0)
				(type default)
			)
			(fill no)
			(layer "B.CrtYd")
		)
		(fp_rect
			(start 0.508 0.9398)
			(end -0.508 -0.9398)
			(stroke
				(width 0)
				(type default)
			)
			(fill no)
			(layer "B.Fab")
		)
		(pad "1" smd custom
			(at 0 -0.4445 180)
			(size 0.1397 0.1397)
			(layers "B.Cu" "B.Mask" "B.Paste")
			(net "BMC_I2C4_MINI4_SDA")
			(options
				(clearance outline)
				(anchor circle)
			)
			(primitives
				(gr_poly
					(pts
						(arc
							(start -0.1778 0.2794)
							(mid -0.249642 0.249642)
							(end -0.2794 0.1778)
						)
						(arc
							(start -0.2794 -0.1778)
							(mid -0.249642 -0.249642)
							(end -0.1778 -0.2794)
						)
						(arc
							(start 0.1778 -0.2794)
							(mid 0.249642 -0.249642)
							(end 0.2794 -0.1778)
						)
						(arc
							(start 0.2794 0.1778)
							(mid 0.249642 0.249642)
							(end 0.1778 0.2794)
						)
					)
					(width 0)
					(fill yes)
				)
			)
		)
		(pad "2" smd custom
			(at 0 0.4445 180)
			(size 0.1397 0.1397)
			(layers "B.Cu" "B.Mask" "B.Paste")
			(net "8644_CBL_PRSNT_R_4")
			(options
				(clearance outline)
				(anchor circle)
			)
			(primitives
				(gr_poly
					(pts
						(arc
							(start -0.1778 0.2794)
							(mid -0.249642 0.249642)
							(end -0.2794 0.1778)
						)
						(arc
							(start -0.2794 -0.1778)
							(mid -0.249642 -0.249642)
							(end -0.1778 -0.2794)
						)
						(arc
							(start 0.1778 -0.2794)
							(mid 0.249642 -0.249642)
							(end 0.2794 -0.1778)
						)
						(arc
							(start 0.2794 0.1778)
							(mid 0.249642 0.249642)
							(end 0.1778 0.2794)
						)
					)
					(width 0)
					(fill yes)
				)
			)
		)
	)
	(footprint ""
		(layer "B.Cu")
		(at 35.564064 -131.34848 90)
		(property "Reference" "C210"
			(at 0 0 90)
			(layer "B.SilkS")
			(hide yes)
			(effects
				(font
					(size 1.27 1.27)
				)
				(justify mirror)
			)
		)
		(property "Value" "SC1U10V2KX-4-GP"
			(at -1.1811 -2.7051 90)
			(unlocked yes)
			(layer "B.Fab")
			(hide yes)
			(effects
				(font
					(size 1.016 1.016)
					(thickness 0.1524)
				)
				(justify mirror)
			)
		)
		(property "Device Type" "C402H22"
			(at -1.1811 -4.2291 90)
			(unlocked yes)
			(layer "B.Fab")
			(hide yes)
			(effects
				(font
					(size 1.016 1.016)
					(thickness 0.1524)
				)
				(justify mirror)
			)
		)
		(duplicate_pad_numbers_are_jumpers no)
		(fp_rect
			(start 0.4318 0.9525)
			(end -0.4318 -0.9525)
			(stroke
				(width 0)
				(type default)
			)
			(fill no)
			(layer "B.CrtYd")
		)
		(fp_rect
			(start 0.4318 0.9525)
			(end -0.4318 -0.9525)
			(stroke
				(width 0)
				(type default)
			)
			(fill no)
			(layer "B.Fab")
		)
		(pad "1" smd custom
			(at 0 -0.4445 270)
			(size 0.1524 0.1524)
			(layers "B.Cu" "B.Mask" "B.Paste")
			(net "P3V3_STBY")
			(options
				(clearance outline)
				(anchor circle)
			)
			(primitives
				(gr_poly
					(pts
						(arc
							(start 0.3048 0.2032)
							(mid 0.275042 0.275042)
							(end 0.2032 0.3048)
						)
						(arc
							(start -0.2032 0.3048)
							(mid -0.275042 0.275042)
							(end -0.3048 0.2032)
						)
						(arc
							(start -0.3048 -0.2032)
							(mid -0.275042 -0.275042)
							(end -0.2032 -0.3048)
						)
						(arc
							(start 0.2032 -0.3048)
							(mid 0.275042 -0.275042)
							(end 0.3048 -0.2032)
						)
					)
					(width 0)
					(fill yes)
				)
			)
		)
		(pad "2" smd custom
			(at 0 0.4445 270)
			(size 0.1524 0.1524)
			(layers "B.Cu" "B.Mask" "B.Paste")
			(net "GND")
			(options
				(clearance outline)
				(anchor circle)
			)
			(primitives
				(gr_poly
					(pts
						(arc
							(start 0.3048 0.2032)
							(mid 0.275042 0.275042)
							(end 0.2032 0.3048)
						)
						(arc
							(start -0.2032 0.3048)
							(mid -0.275042 0.275042)
							(end -0.3048 0.2032)
						)
						(arc
							(start -0.3048 -0.2032)
							(mid -0.275042 -0.275042)
							(end -0.2032 -0.3048)
						)
						(arc
							(start 0.2032 -0.3048)
							(mid 0.275042 -0.275042)
							(end 0.3048 -0.2032)
						)
					)
					(width 0)
					(fill yes)
				)
			)
		)
	)
	(footprint ""
		(layer "B.Cu")
		(at 329.692 -180.086)
		(property "Reference" "R3214"
			(at 0 0 0)
			(layer "B.SilkS")
			(hide yes)
			(effects
				(font
					(size 1.27 1.27)
				)
				(justify mirror)
			)
		)
		(property "Value" "0R2J-2-GP"
			(at -0.064008 -3.993896 0)
			(unlocked yes)
			(layer "B.Fab")
			(hide yes)
			(effects
				(font
					(size 1.016 1.016)
					(thickness 0.1524)
				)
				(justify mirror)
			)
		)
		(property "Device Type" "R402H16"
			(at -0.064008 -5.517896 0)
			(unlocked yes)
			(layer "B.Fab")
			(hide yes)
			(effects
				(font
					(size 1.016 1.016)
					(thickness 0.1524)
				)
				(justify mirror)
			)
		)
		(duplicate_pad_numbers_are_jumpers no)
		(fp_line
			(start -0.508 -0.9398)
			(end 0.508 -0.9398)
			(stroke
				(width 0.1524)
				(type default)
			)
			(layer "B.SilkS")
		)
		(fp_line
			(start 0.508 -0.9398)
			(end 0.508 0.9398)
			(stroke
				(width 0.1524)
				(type default)
			)
			(layer "B.SilkS")
		)
		(fp_rect
			(start 0.508 0.9398)
			(end -0.508 -0.9398)
			(stroke
				(width 0)
				(type default)
			)
			(fill no)
			(layer "B.CrtYd")
		)
		(fp_rect
			(start 0.508 0.9398)
			(end -0.508 -0.9398)
			(stroke
				(width 0)
				(type default)
			)
			(fill no)
			(layer "B.Fab")
		)
		(pad "1" smd custom
			(at 0 -0.4445 180)
			(size 0.1397 0.1397)
			(layers "B.Cu" "B.Mask" "B.Paste")
			(net "BMC_SSD_RST#4")
			(options
				(clearance outline)
				(anchor circle)
			)
			(primitives
				(gr_poly
					(pts
						(arc
							(start -0.1778 0.2794)
							(mid -0.249642 0.249642)
							(end -0.2794 0.1778)
						)
						(arc
							(start -0.2794 -0.1778)
							(mid -0.249642 -0.249642)
							(end -0.1778 -0.2794)
						)
						(arc
							(start 0.1778 -0.2794)
							(mid 0.249642 -0.249642)
							(end 0.2794 -0.1778)
						)
						(arc
							(start 0.2794 0.1778)
							(mid 0.249642 0.249642)
							(end 0.1778 0.2794)
						)
					)
					(width 0)
					(fill yes)
				)
			)
		)
		(pad "2" smd custom
			(at 0 0.4445 180)
			(size 0.1397 0.1397)
			(layers "B.Cu" "B.Mask" "B.Paste")
			(net "BMC_SSD_RST#0_A4")
			(options
				(clearance outline)
				(anchor circle)
			)
			(primitives
				(gr_poly
					(pts
						(arc
							(start -0.1778 0.2794)
							(mid -0.249642 0.249642)
							(end -0.2794 0.1778)
						)
						(arc
							(start -0.2794 -0.1778)
							(mid -0.249642 -0.249642)
							(end -0.1778 -0.2794)
						)
						(arc
							(start 0.1778 -0.2794)
							(mid 0.249642 -0.249642)
							(end 0.2794 -0.1778)
						)
						(arc
							(start 0.2794 0.1778)
							(mid 0.249642 0.249642)
							(end 0.1778 0.2794)
						)
					)
					(width 0)
					(fill yes)
				)
			)
		)
	)
	(footprint ""
		(layer "B.Cu")
		(at 50.76952 -126.529846)
		(property "Reference" "TP179"
			(at 0 0 0)
			(layer "B.SilkS")
			(hide yes)
			(effects
				(font
					(size 1.27 1.27)
				)
				(justify mirror)
			)
		)
		(property "Value" "TPAD28-2-GP"
			(at 0.0127 -1.6637 0)
			(unlocked yes)
			(layer "B.Fab")
			(hide yes)
			(effects
				(font
					(size 1.016 1.016)
					(thickness 0.1524)
				)
				(justify mirror)
			)
		)
		(property "Device Type" "TPAD28"
			(at 0.0127 -3.1877 0)
			(unlocked yes)
			(layer "B.Fab")
			(hide yes)
			(effects
				(font
					(size 1.016 1.016)
					(thickness 0.1524)
				)
				(justify mirror)
			)
		)
		(duplicate_pad_numbers_are_jumpers no)
		(fp_poly
			(pts
				(arc
					(start 0.3556 0)
					(mid -0.3556 0)
					(end 0.3556 0)
				)
			)
			(stroke
				(width 0)
				(type default)
			)
			(fill no)
			(layer "B.CrtYd")
		)
		(fp_poly
			(pts
				(arc
					(start 0.6096 0)
					(mid -0.6096 0)
					(end 0.6096 0)
				)
			)
			(stroke
				(width 0)
				(type default)
			)
			(fill no)
			(layer "B.Fab")
		)
		(pad "1" smd circle
			(at 0 0 180)
			(size 0.7112 0.7112)
			(layers "B.Cu" "B.Mask" "B.Paste")
			(net "BMC0_JTAG_RTCK")
		)
	)
	(footprint ""
		(layer "B.Cu")
		(at 141.358874 -92.22232)
		(property "Reference" "PC86"
			(at 0 0 0)
			(layer "B.SilkS")
			(hide yes)
			(effects
				(font
					(size 1.27 1.27)
				)
				(justify mirror)
			)
		)
		(property "Value" "SCD01U25V2KX-3GP"
			(at -1.1811 -2.7051 0)
			(unlocked yes)
			(layer "B.Fab")
			(hide yes)
			(effects
				(font
					(size 1.016 1.016)
					(thickness 0.1524)
				)
				(justify mirror)
			)
		)
		(property "Device Type" "C402H22"
			(at -1.1811 -4.2291 0)
			(unlocked yes)
			(layer "B.Fab")
			(hide yes)
			(effects
				(font
					(size 1.016 1.016)
					(thickness 0.1524)
				)
				(justify mirror)
			)
		)
		(duplicate_pad_numbers_are_jumpers no)
		(fp_rect
			(start 0.4318 0.9525)
			(end -0.4318 -0.9525)
			(stroke
				(width 0)
				(type default)
			)
			(fill no)
			(layer "B.CrtYd")
		)
		(fp_rect
			(start 0.4318 0.9525)
			(end -0.4318 -0.9525)
			(stroke
				(width 0)
				(type default)
			)
			(fill no)
			(layer "B.Fab")
		)
		(pad "1" smd custom
			(at 0 -0.4445 180)
			(size 0.1524 0.1524)
			(layers "B.Cu" "B.Mask" "B.Paste")
			(net "VR_P1V8_STBY_EN_R")
			(options
				(clearance outline)
				(anchor circle)
			)
			(primitives
				(gr_poly
					(pts
						(arc
							(start 0.3048 0.2032)
							(mid 0.275042 0.275042)
							(end 0.2032 0.3048)
						)
						(arc
							(start -0.2032 0.3048)
							(mid -0.275042 0.275042)
							(end -0.3048 0.2032)
						)
						(arc
							(start -0.3048 -0.2032)
							(mid -0.275042 -0.275042)
							(end -0.2032 -0.3048)
						)
						(arc
							(start 0.2032 -0.3048)
							(mid 0.275042 -0.275042)
							(end 0.3048 -0.2032)
						)
					)
					(width 0)
					(fill yes)
				)
			)
		)
		(pad "2" smd custom
			(at 0 0.4445 180)
			(size 0.1524 0.1524)
			(layers "B.Cu" "B.Mask" "B.Paste")
			(net "GND")
			(options
				(clearance outline)
				(anchor circle)
			)
			(primitives
				(gr_poly
					(pts
						(arc
							(start 0.3048 0.2032)
							(mid 0.275042 0.275042)
							(end 0.2032 0.3048)
						)
						(arc
							(start -0.2032 0.3048)
							(mid -0.275042 0.275042)
							(end -0.3048 0.2032)
						)
						(arc
							(start -0.3048 -0.2032)
							(mid -0.275042 -0.275042)
							(end -0.2032 -0.3048)
						)
						(arc
							(start 0.2032 -0.3048)
							(mid 0.275042 -0.275042)
							(end 0.3048 -0.2032)
						)
					)
					(width 0)
					(fill yes)
				)
			)
		)
	)
	(footprint ""
		(layer "B.Cu")
		(at 142.136114 -34.44113 180)
		(property "Reference" "C223"
			(at 0 0 0)
			(layer "B.SilkS")
			(hide yes)
			(effects
				(font
					(size 1.27 1.27)
				)
				(justify mirror)
			)
		)
		(property "Value" "SCD1U10V2KX-5GP"
			(at -1.1811 -2.7051 180)
			(unlocked yes)
			(layer "B.Fab")
			(hide yes)
			(effects
				(font
					(size 1.016 1.016)
					(thickness 0.1524)
				)
				(justify mirror)
			)
		)
		(property "Device Type" "C402H22"
			(at -1.1811 -4.2291 180)
			(unlocked yes)
			(layer "B.Fab")
			(hide yes)
			(effects
				(font
					(size 1.016 1.016)
					(thickness 0.1524)
				)
				(justify mirror)
			)
		)
		(duplicate_pad_numbers_are_jumpers no)
		(fp_rect
			(start 0.4318 0.9525)
			(end -0.4318 -0.9525)
			(stroke
				(width 0)
				(type default)
			)
			(fill no)
			(layer "B.CrtYd")
		)
		(fp_rect
			(start 0.4318 0.9525)
			(end -0.4318 -0.9525)
			(stroke
				(width 0)
				(type default)
			)
			(fill no)
			(layer "B.Fab")
		)
		(pad "1" smd custom
			(at 0 -0.4445)
			(size 0.1524 0.1524)
			(layers "B.Cu" "B.Mask" "B.Paste")
			(net "GND")
			(options
				(clearance outline)
				(anchor circle)
			)
			(primitives
				(gr_poly
					(pts
						(arc
							(start 0.3048 0.2032)
							(mid 0.275042 0.275042)
							(end 0.2032 0.3048)
						)
						(arc
							(start -0.2032 0.3048)
							(mid -0.275042 0.275042)
							(end -0.3048 0.2032)
						)
						(arc
							(start -0.3048 -0.2032)
							(mid -0.275042 -0.275042)
							(end -0.2032 -0.3048)
						)
						(arc
							(start 0.2032 -0.3048)
							(mid 0.275042 -0.275042)
							(end 0.3048 -0.2032)
						)
					)
					(width 0)
					(fill yes)
				)
			)
		)
		(pad "2" smd custom
			(at 0 0.4445)
			(size 0.1524 0.1524)
			(layers "B.Cu" "B.Mask" "B.Paste")
			(net "P3V3_STBY")
			(options
				(clearance outline)
				(anchor circle)
			)
			(primitives
				(gr_poly
					(pts
						(arc
							(start 0.3048 0.2032)
							(mid 0.275042 0.275042)
							(end 0.2032 0.3048)
						)
						(arc
							(start -0.2032 0.3048)
							(mid -0.275042 0.275042)
							(end -0.3048 0.2032)
						)
						(arc
							(start -0.3048 -0.2032)
							(mid -0.275042 -0.275042)
							(end -0.2032 -0.3048)
						)
						(arc
							(start 0.2032 -0.3048)
							(mid 0.275042 -0.275042)
							(end 0.3048 -0.2032)
						)
					)
					(width 0)
					(fill yes)
				)
			)
		)
	)
	(footprint ""
		(layer "B.Cu")
		(at 54.4322 -115.7732)
		(property "Reference" "R490"
			(at 0 0 0)
			(layer "B.SilkS")
			(hide yes)
			(effects
				(font
					(size 1.27 1.27)
				)
				(justify mirror)
			)
		)
		(property "Value" "0R2J-2-GP"
			(at -0.064008 -3.993896 0)
			(unlocked yes)
			(layer "B.Fab")
			(hide yes)
			(effects
				(font
					(size 1.016 1.016)
					(thickness 0.1524)
				)
				(justify mirror)
			)
		)
		(property "Device Type" "R402H16"
			(at -0.064008 -5.517896 0)
			(unlocked yes)
			(layer "B.Fab")
			(hide yes)
			(effects
				(font
					(size 1.016 1.016)
					(thickness 0.1524)
				)
				(justify mirror)
			)
		)
		(duplicate_pad_numbers_are_jumpers no)
		(fp_line
			(start -0.508 -0.9398)
			(end 0.508 -0.9398)
			(stroke
				(width 0.1524)
				(type default)
			)
			(layer "B.SilkS")
		)
		(fp_line
			(start 0.508 -0.9398)
			(end 0.508 0.9398)
			(stroke
				(width 0.1524)
				(type default)
			)
			(layer "B.SilkS")
		)
		(fp_rect
			(start 0.508 0.9398)
			(end -0.508 -0.9398)
			(stroke
				(width 0)
				(type default)
			)
			(fill no)
			(layer "B.CrtYd")
		)
		(fp_rect
			(start 0.508 0.9398)
			(end -0.508 -0.9398)
			(stroke
				(width 0)
				(type default)
			)
			(fill no)
			(layer "B.Fab")
		)
		(pad "1" smd custom
			(at 0 -0.4445 180)
			(size 0.1397 0.1397)
			(layers "B.Cu" "B.Mask" "B.Paste")
			(net "BMC0_SDA12_R")
			(options
				(clearance outline)
				(anchor circle)
			)
			(primitives
				(gr_poly
					(pts
						(arc
							(start -0.1778 0.2794)
							(mid -0.249642 0.249642)
							(end -0.2794 0.1778)
						)
						(arc
							(start -0.2794 -0.1778)
							(mid -0.249642 -0.249642)
							(end -0.1778 -0.2794)
						)
						(arc
							(start 0.1778 -0.2794)
							(mid 0.249642 -0.249642)
							(end 0.2794 -0.1778)
						)
						(arc
							(start 0.2794 0.1778)
							(mid 0.249642 0.249642)
							(end 0.1778 0.2794)
						)
					)
					(width 0)
					(fill yes)
				)
			)
		)
		(pad "2" smd custom
			(at 0 0.4445 180)
			(size 0.1397 0.1397)
			(layers "B.Cu" "B.Mask" "B.Paste")
			(net "BMC_I2C12_MINI6_SDA_S")
			(options
				(clearance outline)
				(anchor circle)
			)
			(primitives
				(gr_poly
					(pts
						(arc
							(start -0.1778 0.2794)
							(mid -0.249642 0.249642)
							(end -0.2794 0.1778)
						)
						(arc
							(start -0.2794 -0.1778)
							(mid -0.249642 -0.249642)
							(end -0.1778 -0.2794)
						)
						(arc
							(start 0.1778 -0.2794)
							(mid 0.249642 -0.249642)
							(end 0.2794 -0.1778)
						)
						(arc
							(start 0.2794 0.1778)
							(mid 0.249642 0.249642)
							(end 0.1778 0.2794)
						)
					)
					(width 0)
					(fill yes)
				)
			)
		)
	)
	(footprint ""
		(layer "B.Cu")
		(at 235.585 -56.9976 90)
		(property "Reference" "C519"
			(at 0 0 90)
			(layer "B.SilkS")
			(hide yes)
			(effects
				(font
					(size 1.27 1.27)
				)
				(justify mirror)
			)
		)
		(property "Value" "SCD1U16V1KX-1-GP"
			(at 2.8321 -1.7399 90)
			(unlocked yes)
			(layer "B.Fab")
			(hide yes)
			(effects
				(font
					(size 1.016 1.016)
					(thickness 0.1524)
				)
				(justify mirror)
			)
		)
		(property "Device Type" "C0201H13"
			(at 2.8321 -3.2639 90)
			(unlocked yes)
			(layer "B.Fab")
			(hide yes)
			(effects
				(font
					(size 1.016 1.016)
					(thickness 0.1524)
				)
				(justify mirror)
			)
		)
		(duplicate_pad_numbers_are_jumpers no)
		(fp_rect
			(start 0.2794 0.6477)
			(end -0.2794 -0.6477)
			(stroke
				(width 0)
				(type default)
			)
			(fill no)
			(layer "B.CrtYd")
		)
		(fp_rect
			(start 0.2794 0.6477)
			(end -0.2794 -0.6477)
			(stroke
				(width 0)
				(type default)
			)
			(fill no)
			(layer "B.Fab")
		)
		(pad "1" smd custom
			(at 0 -0.2794 270)
			(size 0.0762 0.0762)
			(layers "B.Cu" "B.Mask" "B.Paste")
			(net "DUT_AVD_TX")
			(options
				(clearance outline)
				(anchor circle)
			)
			(primitives
				(gr_poly
					(pts
						(arc
							(start 0.1524 0.127)
							(mid 0.137521 0.162921)
							(end 0.1016 0.1778)
						)
						(arc
							(start -0.1016 0.1778)
							(mid -0.137521 0.162921)
							(end -0.1524 0.127)
						)
						(arc
							(start -0.1524 -0.127)
							(mid -0.137521 -0.162921)
							(end -0.1016 -0.1778)
						)
						(arc
							(start 0.1016 -0.1778)
							(mid 0.137521 -0.162921)
							(end 0.1524 -0.127)
						)
					)
					(width 0)
					(fill yes)
				)
			)
		)
		(pad "2" smd custom
			(at 0 0.2794 270)
			(size 0.0762 0.0762)
			(layers "B.Cu" "B.Mask" "B.Paste")
			(net "GND")
			(options
				(clearance outline)
				(anchor circle)
			)
			(primitives
				(gr_poly
					(pts
						(arc
							(start 0.1524 0.127)
							(mid 0.137521 0.162921)
							(end 0.1016 0.1778)
						)
						(arc
							(start -0.1016 0.1778)
							(mid -0.137521 0.162921)
							(end -0.1524 0.127)
						)
						(arc
							(start -0.1524 -0.127)
							(mid -0.137521 -0.162921)
							(end -0.1016 -0.1778)
						)
						(arc
							(start 0.1016 -0.1778)
							(mid 0.137521 -0.162921)
							(end 0.1524 -0.127)
						)
					)
					(width 0)
					(fill yes)
				)
			)
		)
	)
	(footprint ""
		(layer "B.Cu")
		(at 243.586 -59.99734 90)
		(property "Reference" "C505"
			(at 0 0 90)
			(layer "B.SilkS")
			(hide yes)
			(effects
				(font
					(size 1.27 1.27)
				)
				(justify mirror)
			)
		)
		(property "Value" "SCD1U16V1KX-1-GP"
			(at 2.8321 -1.7399 90)
			(unlocked yes)
			(layer "B.Fab")
			(hide yes)
			(effects
				(font
					(size 1.016 1.016)
					(thickness 0.1524)
				)
				(justify mirror)
			)
		)
		(property "Device Type" "C0201H13"
			(at 2.8321 -3.2639 90)
			(unlocked yes)
			(layer "B.Fab")
			(hide yes)
			(effects
				(font
					(size 1.016 1.016)
					(thickness 0.1524)
				)
				(justify mirror)
			)
		)
		(duplicate_pad_numbers_are_jumpers no)
		(fp_rect
			(start 0.2794 0.6477)
			(end -0.2794 -0.6477)
			(stroke
				(width 0)
				(type default)
			)
			(fill no)
			(layer "B.CrtYd")
		)
		(fp_rect
			(start 0.2794 0.6477)
			(end -0.2794 -0.6477)
			(stroke
				(width 0)
				(type default)
			)
			(fill no)
			(layer "B.Fab")
		)
		(pad "1" smd custom
			(at 0 -0.2794 270)
			(size 0.0762 0.0762)
			(layers "B.Cu" "B.Mask" "B.Paste")
			(net "DUT_AVD_TX")
			(options
				(clearance outline)
				(anchor circle)
			)
			(primitives
				(gr_poly
					(pts
						(arc
							(start 0.1524 0.127)
							(mid 0.137521 0.162921)
							(end 0.1016 0.1778)
						)
						(arc
							(start -0.1016 0.1778)
							(mid -0.137521 0.162921)
							(end -0.1524 0.127)
						)
						(arc
							(start -0.1524 -0.127)
							(mid -0.137521 -0.162921)
							(end -0.1016 -0.1778)
						)
						(arc
							(start 0.1016 -0.1778)
							(mid 0.137521 -0.162921)
							(end 0.1524 -0.127)
						)
					)
					(width 0)
					(fill yes)
				)
			)
		)
		(pad "2" smd custom
			(at 0 0.2794 270)
			(size 0.0762 0.0762)
			(layers "B.Cu" "B.Mask" "B.Paste")
			(net "GND")
			(options
				(clearance outline)
				(anchor circle)
			)
			(primitives
				(gr_poly
					(pts
						(arc
							(start 0.1524 0.127)
							(mid 0.137521 0.162921)
							(end 0.1016 0.1778)
						)
						(arc
							(start -0.1016 0.1778)
							(mid -0.137521 0.162921)
							(end -0.1524 0.127)
						)
						(arc
							(start -0.1524 -0.127)
							(mid -0.137521 -0.162921)
							(end -0.1016 -0.1778)
						)
						(arc
							(start 0.1016 -0.1778)
							(mid 0.137521 -0.162921)
							(end 0.1524 -0.127)
						)
					)
					(width 0)
					(fill yes)
				)
			)
		)
	)
	(footprint ""
		(layer "B.Cu")
		(at 310.007 -64.643 180)
		(property "Reference" "PG36"
			(at 0 0 0)
			(layer "B.SilkS")
			(hide yes)
			(effects
				(font
					(size 1.27 1.27)
				)
				(justify mirror)
			)
		)
		(property "Value" "GAP-CLOSE-PWR-3-GP"
			(at -0.0254 -6.5786 180)
			(unlocked yes)
			(layer "B.Fab")
			(hide yes)
			(effects
				(font
					(size 1.016 1.016)
					(thickness 0.1524)
				)
				(justify mirror)
			)
		)
		(property "Device Type" "GAP-CLOSE-PWR-3"
			(at -0.0254 -8.255 180)
			(unlocked yes)
			(layer "B.Fab")
			(hide yes)
			(effects
				(font
					(size 1.016 1.016)
					(thickness 0.1524)
				)
				(justify mirror)
			)
		)
		(duplicate_pad_numbers_are_jumpers no)
		(fp_rect
			(start 0.7112 0.4572)
			(end -0.7112 -0.4572)
			(stroke
				(width 0)
				(type default)
			)
			(fill no)
			(layer "B.CrtYd")
		)
		(fp_poly
			(pts
				(xy 0.7112 -0.4572) (xy -0.7112 -0.4572) (xy -0.7112 0.4572) (xy 0.7112 0.4572)
			)
			(stroke
				(width 0)
				(type default)
			)
			(fill no)
			(layer "B.Fab")
		)
		(pad "1" smd rect
			(at 0.3048 0)
			(size 0.6604 0.762)
			(layers "B.Cu" "B.Mask" "B.Paste")
			(net "DUT_VDD")
		)
		(pad "2" smd rect
			(at -0.3048 0)
			(size 0.6604 0.762)
			(layers "B.Cu" "B.Mask" "B.Paste")
			(net "P0V9_E")
		)
	)
	(footprint ""
		(layer "B.Cu")
		(at 243.1288 -43.997372 -90)
		(property "Reference" "C451"
			(at 0 0 90)
			(layer "B.SilkS")
			(hide yes)
			(effects
				(font
					(size 1.27 1.27)
				)
				(justify mirror)
			)
		)
		(property "Value" "SCD1U16V1KX-1-GP"
			(at 2.8321 -1.7399 270)
			(unlocked yes)
			(layer "B.Fab")
			(hide yes)
			(effects
				(font
					(size 1.016 1.016)
					(thickness 0.1524)
				)
				(justify mirror)
			)
		)
		(property "Device Type" "C0201H13"
			(at 2.8321 -3.2639 270)
			(unlocked yes)
			(layer "B.Fab")
			(hide yes)
			(effects
				(font
					(size 1.016 1.016)
					(thickness 0.1524)
				)
				(justify mirror)
			)
		)
		(duplicate_pad_numbers_are_jumpers no)
		(fp_rect
			(start 0.2794 0.6477)
			(end -0.2794 -0.6477)
			(stroke
				(width 0)
				(type default)
			)
			(fill no)
			(layer "B.CrtYd")
		)
		(fp_rect
			(start 0.2794 0.6477)
			(end -0.2794 -0.6477)
			(stroke
				(width 0)
				(type default)
			)
			(fill no)
			(layer "B.Fab")
		)
		(pad "1" smd custom
			(at 0 -0.2794 90)
			(size 0.0762 0.0762)
			(layers "B.Cu" "B.Mask" "B.Paste")
			(net "DUT_VDD")
			(options
				(clearance outline)
				(anchor circle)
			)
			(primitives
				(gr_poly
					(pts
						(arc
							(start 0.1524 0.127)
							(mid 0.137521 0.162921)
							(end 0.1016 0.1778)
						)
						(arc
							(start -0.1016 0.1778)
							(mid -0.137521 0.162921)
							(end -0.1524 0.127)
						)
						(arc
							(start -0.1524 -0.127)
							(mid -0.137521 -0.162921)
							(end -0.1016 -0.1778)
						)
						(arc
							(start 0.1016 -0.1778)
							(mid 0.137521 -0.162921)
							(end 0.1524 -0.127)
						)
					)
					(width 0)
					(fill yes)
				)
			)
		)
		(pad "2" smd custom
			(at 0 0.2794 90)
			(size 0.0762 0.0762)
			(layers "B.Cu" "B.Mask" "B.Paste")
			(net "GND")
			(options
				(clearance outline)
				(anchor circle)
			)
			(primitives
				(gr_poly
					(pts
						(arc
							(start 0.1524 0.127)
							(mid 0.137521 0.162921)
							(end 0.1016 0.1778)
						)
						(arc
							(start -0.1016 0.1778)
							(mid -0.137521 0.162921)
							(end -0.1524 0.127)
						)
						(arc
							(start -0.1524 -0.127)
							(mid -0.137521 -0.162921)
							(end -0.1016 -0.1778)
						)
						(arc
							(start 0.1016 -0.1778)
							(mid 0.137521 -0.162921)
							(end 0.1524 -0.127)
						)
					)
					(width 0)
					(fill yes)
				)
			)
		)
	)
	(footprint ""
		(layer "B.Cu")
		(at 245.1354 -43.997372 -90)
		(property "Reference" "C450"
			(at 0 0 90)
			(layer "B.SilkS")
			(hide yes)
			(effects
				(font
					(size 1.27 1.27)
				)
				(justify mirror)
			)
		)
		(property "Value" "SCD1U16V1KX-1-GP"
			(at 2.8321 -1.7399 270)
			(unlocked yes)
			(layer "B.Fab")
			(hide yes)
			(effects
				(font
					(size 1.016 1.016)
					(thickness 0.1524)
				)
				(justify mirror)
			)
		)
		(property "Device Type" "C0201H13"
			(at 2.8321 -3.2639 270)
			(unlocked yes)
			(layer "B.Fab")
			(hide yes)
			(effects
				(font
					(size 1.016 1.016)
					(thickness 0.1524)
				)
				(justify mirror)
			)
		)
		(duplicate_pad_numbers_are_jumpers no)
		(fp_rect
			(start 0.2794 0.6477)
			(end -0.2794 -0.6477)
			(stroke
				(width 0)
				(type default)
			)
			(fill no)
			(layer "B.CrtYd")
		)
		(fp_rect
			(start 0.2794 0.6477)
			(end -0.2794 -0.6477)
			(stroke
				(width 0)
				(type default)
			)
			(fill no)
			(layer "B.Fab")
		)
		(pad "1" smd custom
			(at 0 -0.2794 90)
			(size 0.0762 0.0762)
			(layers "B.Cu" "B.Mask" "B.Paste")
			(net "DUT_VDD")
			(options
				(clearance outline)
				(anchor circle)
			)
			(primitives
				(gr_poly
					(pts
						(arc
							(start 0.1524 0.127)
							(mid 0.137521 0.162921)
							(end 0.1016 0.1778)
						)
						(arc
							(start -0.1016 0.1778)
							(mid -0.137521 0.162921)
							(end -0.1524 0.127)
						)
						(arc
							(start -0.1524 -0.127)
							(mid -0.137521 -0.162921)
							(end -0.1016 -0.1778)
						)
						(arc
							(start 0.1016 -0.1778)
							(mid 0.137521 -0.162921)
							(end 0.1524 -0.127)
						)
					)
					(width 0)
					(fill yes)
				)
			)
		)
		(pad "2" smd custom
			(at 0 0.2794 90)
			(size 0.0762 0.0762)
			(layers "B.Cu" "B.Mask" "B.Paste")
			(net "GND")
			(options
				(clearance outline)
				(anchor circle)
			)
			(primitives
				(gr_poly
					(pts
						(arc
							(start 0.1524 0.127)
							(mid 0.137521 0.162921)
							(end 0.1016 0.1778)
						)
						(arc
							(start -0.1016 0.1778)
							(mid -0.137521 0.162921)
							(end -0.1524 0.127)
						)
						(arc
							(start -0.1524 -0.127)
							(mid -0.137521 -0.162921)
							(end -0.1016 -0.1778)
						)
						(arc
							(start 0.1016 -0.1778)
							(mid 0.137521 -0.162921)
							(end 0.1524 -0.127)
						)
					)
					(width 0)
					(fill yes)
				)
			)
		)
	)
	(footprint ""
		(layer "B.Cu")
		(at 58.166 -133.985 180)
		(property "Reference" "R434"
			(at 0 0 0)
			(layer "B.SilkS")
			(hide yes)
			(effects
				(font
					(size 1.27 1.27)
				)
				(justify mirror)
			)
		)
		(property "Value" "3K3R2F-2-GP"
			(at -0.064008 -3.993896 180)
			(unlocked yes)
			(layer "B.Fab")
			(hide yes)
			(effects
				(font
					(size 1.016 1.016)
					(thickness 0.1524)
				)
				(justify mirror)
			)
		)
		(property "Device Type" "R402H16"
			(at -0.064008 -5.517896 180)
			(unlocked yes)
			(layer "B.Fab")
			(hide yes)
			(effects
				(font
					(size 1.016 1.016)
					(thickness 0.1524)
				)
				(justify mirror)
			)
		)
		(duplicate_pad_numbers_are_jumpers no)
		(fp_line
			(start 0.508 -0.9398)
			(end 0.508 0.9398)
			(stroke
				(width 0.1524)
				(type default)
			)
			(layer "B.SilkS")
		)
		(fp_line
			(start -0.508 -0.9398)
			(end 0.508 -0.9398)
			(stroke
				(width 0.1524)
				(type default)
			)
			(layer "B.SilkS")
		)
		(fp_rect
			(start 0.508 0.9398)
			(end -0.508 -0.9398)
			(stroke
				(width 0)
				(type default)
			)
			(fill no)
			(layer "B.CrtYd")
		)
		(fp_rect
			(start 0.508 0.9398)
			(end -0.508 -0.9398)
			(stroke
				(width 0)
				(type default)
			)
			(fill no)
			(layer "B.Fab")
		)
		(pad "1" smd custom
			(at 0 -0.4445)
			(size 0.1397 0.1397)
			(layers "B.Cu" "B.Mask" "B.Paste")
			(net "ADC_P5V_STBY")
			(options
				(clearance outline)
				(anchor circle)
			)
			(primitives
				(gr_poly
					(pts
						(arc
							(start -0.1778 0.2794)
							(mid -0.249642 0.249642)
							(end -0.2794 0.1778)
						)
						(arc
							(start -0.2794 -0.1778)
							(mid -0.249642 -0.249642)
							(end -0.1778 -0.2794)
						)
						(arc
							(start 0.1778 -0.2794)
							(mid 0.249642 -0.249642)
							(end 0.2794 -0.1778)
						)
						(arc
							(start 0.2794 0.1778)
							(mid 0.249642 0.249642)
							(end 0.1778 0.2794)
						)
					)
					(width 0)
					(fill yes)
				)
			)
		)
		(pad "2" smd custom
			(at 0 0.4445)
			(size 0.1397 0.1397)
			(layers "B.Cu" "B.Mask" "B.Paste")
			(net "P5V_STBY")
			(options
				(clearance outline)
				(anchor circle)
			)
			(primitives
				(gr_poly
					(pts
						(arc
							(start -0.1778 0.2794)
							(mid -0.249642 0.249642)
							(end -0.2794 0.1778)
						)
						(arc
							(start -0.2794 -0.1778)
							(mid -0.249642 -0.249642)
							(end -0.1778 -0.2794)
						)
						(arc
							(start 0.1778 -0.2794)
							(mid 0.249642 -0.249642)
							(end 0.2794 -0.1778)
						)
						(arc
							(start 0.2794 0.1778)
							(mid 0.249642 0.249642)
							(end 0.1778 0.2794)
						)
					)
					(width 0)
					(fill yes)
				)
			)
		)
	)
	(footprint ""
		(layer "B.Cu")
		(at 238.9124 -59.0042 -90)
		(property "Reference" "C530"
			(at 0 0 90)
			(layer "B.SilkS")
			(hide yes)
			(effects
				(font
					(size 1.27 1.27)
				)
				(justify mirror)
			)
		)
		(property "Value" "SCD1U16V1KX-1-GP"
			(at 2.8321 -1.7399 270)
			(unlocked yes)
			(layer "B.Fab")
			(hide yes)
			(effects
				(font
					(size 1.016 1.016)
					(thickness 0.1524)
				)
				(justify mirror)
			)
		)
		(property "Device Type" "C0201H13"
			(at 2.8321 -3.2639 270)
			(unlocked yes)
			(layer "B.Fab")
			(hide yes)
			(effects
				(font
					(size 1.016 1.016)
					(thickness 0.1524)
				)
				(justify mirror)
			)
		)
		(duplicate_pad_numbers_are_jumpers no)
		(fp_rect
			(start 0.2794 0.6477)
			(end -0.2794 -0.6477)
			(stroke
				(width 0)
				(type default)
			)
			(fill no)
			(layer "B.CrtYd")
		)
		(fp_rect
			(start 0.2794 0.6477)
			(end -0.2794 -0.6477)
			(stroke
				(width 0)
				(type default)
			)
			(fill no)
			(layer "B.Fab")
		)
		(pad "1" smd custom
			(at 0 -0.2794 90)
			(size 0.0762 0.0762)
			(layers "B.Cu" "B.Mask" "B.Paste")
			(net "DUT_AVD_TX")
			(options
				(clearance outline)
				(anchor circle)
			)
			(primitives
				(gr_poly
					(pts
						(arc
							(start 0.1524 0.127)
							(mid 0.137521 0.162921)
							(end 0.1016 0.1778)
						)
						(arc
							(start -0.1016 0.1778)
							(mid -0.137521 0.162921)
							(end -0.1524 0.127)
						)
						(arc
							(start -0.1524 -0.127)
							(mid -0.137521 -0.162921)
							(end -0.1016 -0.1778)
						)
						(arc
							(start 0.1016 -0.1778)
							(mid 0.137521 -0.162921)
							(end 0.1524 -0.127)
						)
					)
					(width 0)
					(fill yes)
				)
			)
		)
		(pad "2" smd custom
			(at 0 0.2794 90)
			(size 0.0762 0.0762)
			(layers "B.Cu" "B.Mask" "B.Paste")
			(net "GND")
			(options
				(clearance outline)
				(anchor circle)
			)
			(primitives
				(gr_poly
					(pts
						(arc
							(start 0.1524 0.127)
							(mid 0.137521 0.162921)
							(end 0.1016 0.1778)
						)
						(arc
							(start -0.1016 0.1778)
							(mid -0.137521 0.162921)
							(end -0.1524 0.127)
						)
						(arc
							(start -0.1524 -0.127)
							(mid -0.137521 -0.162921)
							(end -0.1016 -0.1778)
						)
						(arc
							(start 0.1016 -0.1778)
							(mid 0.137521 -0.162921)
							(end 0.1524 -0.127)
						)
					)
					(width 0)
					(fill yes)
				)
			)
		)
	)
	(footprint ""
		(layer "B.Cu")
		(at 130.220466 -208.8769 180)
		(property "Reference" "R4128"
			(at 0 0 0)
			(layer "B.SilkS")
			(hide yes)
			(effects
				(font
					(size 1.27 1.27)
				)
				(justify mirror)
			)
		)
		(property "Value" "4K7R2F-GP"
			(at -0.064008 -3.993896 180)
			(unlocked yes)
			(layer "B.Fab")
			(hide yes)
			(effects
				(font
					(size 1.016 1.016)
					(thickness 0.1524)
				)
				(justify mirror)
			)
		)
		(property "Device Type" "R402H16"
			(at -0.064008 -5.517896 180)
			(unlocked yes)
			(layer "B.Fab")
			(hide yes)
			(effects
				(font
					(size 1.016 1.016)
					(thickness 0.1524)
				)
				(justify mirror)
			)
		)
		(duplicate_pad_numbers_are_jumpers no)
		(fp_line
			(start 0.508 -0.9398)
			(end 0.508 0.9398)
			(stroke
				(width 0.1524)
				(type default)
			)
			(layer "B.SilkS")
		)
		(fp_line
			(start -0.508 -0.9398)
			(end 0.508 -0.9398)
			(stroke
				(width 0.1524)
				(type default)
			)
			(layer "B.SilkS")
		)
		(fp_rect
			(start 0.508 0.9398)
			(end -0.508 -0.9398)
			(stroke
				(width 0)
				(type default)
			)
			(fill no)
			(layer "B.CrtYd")
		)
		(fp_rect
			(start 0.508 0.9398)
			(end -0.508 -0.9398)
			(stroke
				(width 0)
				(type default)
			)
			(fill no)
			(layer "B.Fab")
		)
		(pad "1" smd custom
			(at 0 -0.4445)
			(size 0.1397 0.1397)
			(layers "B.Cu" "B.Mask" "B.Paste")
			(net "SSD_PRSNT#7")
			(options
				(clearance outline)
				(anchor circle)
			)
			(primitives
				(gr_poly
					(pts
						(arc
							(start -0.1778 0.2794)
							(mid -0.249642 0.249642)
							(end -0.2794 0.1778)
						)
						(arc
							(start -0.2794 -0.1778)
							(mid -0.249642 -0.249642)
							(end -0.1778 -0.2794)
						)
						(arc
							(start 0.1778 -0.2794)
							(mid 0.249642 -0.249642)
							(end 0.2794 -0.1778)
						)
						(arc
							(start 0.2794 0.1778)
							(mid 0.249642 0.249642)
							(end 0.1778 0.2794)
						)
					)
					(width 0)
					(fill yes)
				)
			)
		)
		(pad "2" smd custom
			(at 0 0.4445)
			(size 0.1397 0.1397)
			(layers "B.Cu" "B.Mask" "B.Paste")
			(net "P3V3_STBY")
			(options
				(clearance outline)
				(anchor circle)
			)
			(primitives
				(gr_poly
					(pts
						(arc
							(start -0.1778 0.2794)
							(mid -0.249642 0.249642)
							(end -0.2794 0.1778)
						)
						(arc
							(start -0.2794 -0.1778)
							(mid -0.249642 -0.249642)
							(end -0.1778 -0.2794)
						)
						(arc
							(start 0.1778 -0.2794)
							(mid 0.249642 -0.249642)
							(end 0.2794 -0.1778)
						)
						(arc
							(start 0.2794 0.1778)
							(mid 0.249642 0.249642)
							(end 0.1778 0.2794)
						)
					)
					(width 0)
					(fill yes)
				)
			)
		)
	)
	(footprint ""
		(layer "B.Cu")
		(at 227.6856 -39.004748 -90)
		(property "Reference" "C571"
			(at 0 0 90)
			(layer "B.SilkS")
			(hide yes)
			(effects
				(font
					(size 1.27 1.27)
				)
				(justify mirror)
			)
		)
		(property "Value" "SCD1U16V1KX-1-GP"
			(at 2.8321 -1.7399 270)
			(unlocked yes)
			(layer "B.Fab")
			(hide yes)
			(effects
				(font
					(size 1.016 1.016)
					(thickness 0.1524)
				)
				(justify mirror)
			)
		)
		(property "Device Type" "C0201H13"
			(at 2.8321 -3.2639 270)
			(unlocked yes)
			(layer "B.Fab")
			(hide yes)
			(effects
				(font
					(size 1.016 1.016)
					(thickness 0.1524)
				)
				(justify mirror)
			)
		)
		(duplicate_pad_numbers_are_jumpers no)
		(fp_rect
			(start 0.2794 0.6477)
			(end -0.2794 -0.6477)
			(stroke
				(width 0)
				(type default)
			)
			(fill no)
			(layer "B.CrtYd")
		)
		(fp_rect
			(start 0.2794 0.6477)
			(end -0.2794 -0.6477)
			(stroke
				(width 0)
				(type default)
			)
			(fill no)
			(layer "B.Fab")
		)
		(pad "1" smd custom
			(at 0 -0.2794 90)
			(size 0.0762 0.0762)
			(layers "B.Cu" "B.Mask" "B.Paste")
			(net "DUT_AVD_PCIE")
			(options
				(clearance outline)
				(anchor circle)
			)
			(primitives
				(gr_poly
					(pts
						(arc
							(start 0.1524 0.127)
							(mid 0.137521 0.162921)
							(end 0.1016 0.1778)
						)
						(arc
							(start -0.1016 0.1778)
							(mid -0.137521 0.162921)
							(end -0.1524 0.127)
						)
						(arc
							(start -0.1524 -0.127)
							(mid -0.137521 -0.162921)
							(end -0.1016 -0.1778)
						)
						(arc
							(start 0.1016 -0.1778)
							(mid 0.137521 -0.162921)
							(end 0.1524 -0.127)
						)
					)
					(width 0)
					(fill yes)
				)
			)
		)
		(pad "2" smd custom
			(at 0 0.2794 90)
			(size 0.0762 0.0762)
			(layers "B.Cu" "B.Mask" "B.Paste")
			(net "GND")
			(options
				(clearance outline)
				(anchor circle)
			)
			(primitives
				(gr_poly
					(pts
						(arc
							(start 0.1524 0.127)
							(mid 0.137521 0.162921)
							(end 0.1016 0.1778)
						)
						(arc
							(start -0.1016 0.1778)
							(mid -0.137521 0.162921)
							(end -0.1524 0.127)
						)
						(arc
							(start -0.1524 -0.127)
							(mid -0.137521 -0.162921)
							(end -0.1016 -0.1778)
						)
						(arc
							(start 0.1016 -0.1778)
							(mid 0.137521 -0.162921)
							(end 0.1524 -0.127)
						)
					)
					(width 0)
					(fill yes)
				)
			)
		)
	)
	(footprint ""
		(layer "B.Cu")
		(at 252.603 -58.996072 -90)
		(property "Reference" "C548"
			(at 0 0 90)
			(layer "B.SilkS")
			(hide yes)
			(effects
				(font
					(size 1.27 1.27)
				)
				(justify mirror)
			)
		)
		(property "Value" "SCD1U16V1KX-1-GP"
			(at 2.8321 -1.7399 270)
			(unlocked yes)
			(layer "B.Fab")
			(hide yes)
			(effects
				(font
					(size 1.016 1.016)
					(thickness 0.1524)
				)
				(justify mirror)
			)
		)
		(property "Device Type" "C0201H13"
			(at 2.8321 -3.2639 270)
			(unlocked yes)
			(layer "B.Fab")
			(hide yes)
			(effects
				(font
					(size 1.016 1.016)
					(thickness 0.1524)
				)
				(justify mirror)
			)
		)
		(duplicate_pad_numbers_are_jumpers no)
		(fp_rect
			(start 0.2794 0.6477)
			(end -0.2794 -0.6477)
			(stroke
				(width 0)
				(type default)
			)
			(fill no)
			(layer "B.CrtYd")
		)
		(fp_rect
			(start 0.2794 0.6477)
			(end -0.2794 -0.6477)
			(stroke
				(width 0)
				(type default)
			)
			(fill no)
			(layer "B.Fab")
		)
		(pad "1" smd custom
			(at 0 -0.2794 90)
			(size 0.0762 0.0762)
			(layers "B.Cu" "B.Mask" "B.Paste")
			(net "DUT_AVD_PCIE")
			(options
				(clearance outline)
				(anchor circle)
			)
			(primitives
				(gr_poly
					(pts
						(arc
							(start 0.1524 0.127)
							(mid 0.137521 0.162921)
							(end 0.1016 0.1778)
						)
						(arc
							(start -0.1016 0.1778)
							(mid -0.137521 0.162921)
							(end -0.1524 0.127)
						)
						(arc
							(start -0.1524 -0.127)
							(mid -0.137521 -0.162921)
							(end -0.1016 -0.1778)
						)
						(arc
							(start 0.1016 -0.1778)
							(mid 0.137521 -0.162921)
							(end 0.1524 -0.127)
						)
					)
					(width 0)
					(fill yes)
				)
			)
		)
		(pad "2" smd custom
			(at 0 0.2794 90)
			(size 0.0762 0.0762)
			(layers "B.Cu" "B.Mask" "B.Paste")
			(net "GND")
			(options
				(clearance outline)
				(anchor circle)
			)
			(primitives
				(gr_poly
					(pts
						(arc
							(start 0.1524 0.127)
							(mid 0.137521 0.162921)
							(end 0.1016 0.1778)
						)
						(arc
							(start -0.1016 0.1778)
							(mid -0.137521 0.162921)
							(end -0.1524 0.127)
						)
						(arc
							(start -0.1524 -0.127)
							(mid -0.137521 -0.162921)
							(end -0.1016 -0.1778)
						)
						(arc
							(start 0.1016 -0.1778)
							(mid 0.137521 -0.162921)
							(end 0.1524 -0.127)
						)
					)
					(width 0)
					(fill yes)
				)
			)
		)
	)
	(footprint ""
		(layer "B.Cu")
		(at 45.212 -137.668)
		(property "Reference" "TP319"
			(at 0 0 0)
			(layer "B.SilkS")
			(hide yes)
			(effects
				(font
					(size 1.27 1.27)
				)
				(justify mirror)
			)
		)
		(property "Value" "TPAD28-2-GP"
			(at 0.0127 -1.6637 0)
			(unlocked yes)
			(layer "B.Fab")
			(hide yes)
			(effects
				(font
					(size 1.016 1.016)
					(thickness 0.1524)
				)
				(justify mirror)
			)
		)
		(property "Device Type" "TPAD28"
			(at 0.0127 -3.1877 0)
			(unlocked yes)
			(layer "B.Fab")
			(hide yes)
			(effects
				(font
					(size 1.016 1.016)
					(thickness 0.1524)
				)
				(justify mirror)
			)
		)
		(duplicate_pad_numbers_are_jumpers no)
		(fp_poly
			(pts
				(arc
					(start 0.3556 0)
					(mid -0.3556 0)
					(end 0.3556 0)
				)
			)
			(stroke
				(width 0)
				(type default)
			)
			(fill no)
			(layer "B.CrtYd")
		)
		(fp_poly
			(pts
				(arc
					(start 0.6096 0)
					(mid -0.6096 0)
					(end 0.6096 0)
				)
			)
			(stroke
				(width 0)
				(type default)
			)
			(fill no)
			(layer "B.Fab")
		)
		(pad "1" smd circle
			(at 0 0 180)
			(size 0.7112 0.7112)
			(layers "B.Cu" "B.Mask" "B.Paste")
			(net "TP_GPIOO1")
		)
	)
	(footprint ""
		(layer "B.Cu")
		(at 245.684802 -26.67)
		(property "Reference" "TP285"
			(at 0 0 0)
			(layer "B.SilkS")
			(hide yes)
			(effects
				(font
					(size 1.27 1.27)
				)
				(justify mirror)
			)
		)
		(property "Value" "TPAD28-2-GP"
			(at 0.0127 -1.6637 0)
			(unlocked yes)
			(layer "B.Fab")
			(hide yes)
			(effects
				(font
					(size 1.016 1.016)
					(thickness 0.1524)
				)
				(justify mirror)
			)
		)
		(property "Device Type" "TPAD28"
			(at 0.0127 -3.1877 0)
			(unlocked yes)
			(layer "B.Fab")
			(hide yes)
			(effects
				(font
					(size 1.016 1.016)
					(thickness 0.1524)
				)
				(justify mirror)
			)
		)
		(duplicate_pad_numbers_are_jumpers no)
		(fp_poly
			(pts
				(arc
					(start 0.3556 0)
					(mid -0.3556 0)
					(end 0.3556 0)
				)
			)
			(stroke
				(width 0)
				(type default)
			)
			(fill no)
			(layer "B.CrtYd")
		)
		(fp_poly
			(pts
				(arc
					(start 0.6096 0)
					(mid -0.6096 0)
					(end 0.6096 0)
				)
			)
			(stroke
				(width 0)
				(type default)
			)
			(fill no)
			(layer "B.Fab")
		)
		(pad "1" smd circle
			(at 0 0 180)
			(size 0.7112 0.7112)
			(layers "B.Cu" "B.Mask" "B.Paste")
			(net "TWI_SDA4")
		)
	)
	(footprint ""
		(layer "B.Cu")
		(at 186.0804 -61.595)
		(property "Reference" "C583"
			(at 0 0 0)
			(layer "B.SilkS")
			(hide yes)
			(effects
				(font
					(size 1.27 1.27)
				)
				(justify mirror)
			)
		)
		(property "Value" "SC4D7U16V5KX-1-GP"
			(at 0.0762 -6.1214 0)
			(unlocked yes)
			(layer "B.Fab")
			(hide yes)
			(effects
				(font
					(size 1.016 1.016)
					(thickness 0.1524)
				)
				(justify mirror)
			)
		)
		(property "Device Type" "C805H56"
			(at 0.0762 -8.1534 0)
			(unlocked yes)
			(layer "B.Fab")
			(hide yes)
			(effects
				(font
					(size 1.016 1.016)
					(thickness 0.1524)
				)
				(justify mirror)
			)
		)
		(duplicate_pad_numbers_are_jumpers no)
		(fp_line
			(start -0.635 0)
			(end 0.635 0)
			(stroke
				(width 0.508)
				(type default)
			)
			(layer "B.SilkS")
		)
		(fp_rect
			(start 0.9652 1.778)
			(end -0.9652 -1.778)
			(stroke
				(width 0)
				(type default)
			)
			(fill no)
			(layer "B.CrtYd")
		)
		(fp_poly
			(pts
				(xy 0.9652 -1.778) (xy -0.9652 -1.778) (xy -0.9652 1.778) (xy 0.9652 1.778)
			)
			(stroke
				(width 0)
				(type default)
			)
			(fill no)
			(layer "B.Fab")
		)
		(pad "1" smd rect
			(at 0 -0.9652 180)
			(size 1.397 1.143)
			(layers "B.Cu" "B.Mask" "B.Paste")
			(net "DUT_AVD_PCIE")
		)
		(pad "2" smd rect
			(at 0 0.9652 180)
			(size 1.397 1.143)
			(layers "B.Cu" "B.Mask" "B.Paste")
			(net "GND")
		)
	)
	(footprint ""
		(layer "B.Cu")
		(at 337.9216 -175.7426)
		(property "Reference" "R3230"
			(at 0 0 0)
			(layer "B.SilkS")
			(hide yes)
			(effects
				(font
					(size 1.27 1.27)
				)
				(justify mirror)
			)
		)
		(property "Value" "0R2J-2-GP"
			(at -0.064008 -3.993896 0)
			(unlocked yes)
			(layer "B.Fab")
			(hide yes)
			(effects
				(font
					(size 1.016 1.016)
					(thickness 0.1524)
				)
				(justify mirror)
			)
		)
		(property "Device Type" "R402H16"
			(at -0.064008 -5.517896 0)
			(unlocked yes)
			(layer "B.Fab")
			(hide yes)
			(effects
				(font
					(size 1.016 1.016)
					(thickness 0.1524)
				)
				(justify mirror)
			)
		)
		(duplicate_pad_numbers_are_jumpers no)
		(fp_line
			(start -0.508 -0.9398)
			(end 0.508 -0.9398)
			(stroke
				(width 0.1524)
				(type default)
			)
			(layer "B.SilkS")
		)
		(fp_line
			(start 0.508 -0.9398)
			(end 0.508 0.9398)
			(stroke
				(width 0.1524)
				(type default)
			)
			(layer "B.SilkS")
		)
		(fp_rect
			(start 0.508 0.9398)
			(end -0.508 -0.9398)
			(stroke
				(width 0)
				(type default)
			)
			(fill no)
			(layer "B.CrtYd")
		)
		(fp_rect
			(start 0.508 0.9398)
			(end -0.508 -0.9398)
			(stroke
				(width 0)
				(type default)
			)
			(fill no)
			(layer "B.Fab")
		)
		(pad "1" smd custom
			(at 0 -0.4445 180)
			(size 0.1397 0.1397)
			(layers "B.Cu" "B.Mask" "B.Paste")
			(net "SSD_PERST_Y9")
			(options
				(clearance outline)
				(anchor circle)
			)
			(primitives
				(gr_poly
					(pts
						(arc
							(start -0.1778 0.2794)
							(mid -0.249642 0.249642)
							(end -0.2794 0.1778)
						)
						(arc
							(start -0.2794 -0.1778)
							(mid -0.249642 -0.249642)
							(end -0.1778 -0.2794)
						)
						(arc
							(start 0.1778 -0.2794)
							(mid 0.249642 -0.249642)
							(end 0.2794 -0.1778)
						)
						(arc
							(start 0.2794 0.1778)
							(mid 0.249642 0.249642)
							(end 0.1778 0.2794)
						)
					)
					(width 0)
					(fill yes)
				)
			)
		)
		(pad "2" smd custom
			(at 0 0.4445 180)
			(size 0.1397 0.1397)
			(layers "B.Cu" "B.Mask" "B.Paste")
			(net "SSD_PERST#9_R")
			(options
				(clearance outline)
				(anchor circle)
			)
			(primitives
				(gr_poly
					(pts
						(arc
							(start -0.1778 0.2794)
							(mid -0.249642 0.249642)
							(end -0.2794 0.1778)
						)
						(arc
							(start -0.2794 -0.1778)
							(mid -0.249642 -0.249642)
							(end -0.1778 -0.2794)
						)
						(arc
							(start 0.1778 -0.2794)
							(mid 0.249642 -0.249642)
							(end 0.2794 -0.1778)
						)
						(arc
							(start 0.2794 0.1778)
							(mid 0.249642 0.249642)
							(end 0.1778 0.2794)
						)
					)
					(width 0)
					(fill yes)
				)
			)
		)
	)
	(footprint ""
		(layer "B.Cu")
		(at 228.1682 -194.4116 90)
		(property "Reference" "R3239"
			(at 0 0 90)
			(layer "B.SilkS")
			(hide yes)
			(effects
				(font
					(size 1.27 1.27)
				)
				(justify mirror)
			)
		)
		(property "Value" "0R2J-2-GP"
			(at -0.064008 -3.993896 90)
			(unlocked yes)
			(layer "B.Fab")
			(hide yes)
			(effects
				(font
					(size 1.016 1.016)
					(thickness 0.1524)
				)
				(justify mirror)
			)
		)
		(property "Device Type" "R402H16"
			(at -0.064008 -5.517896 90)
			(unlocked yes)
			(layer "B.Fab")
			(hide yes)
			(effects
				(font
					(size 1.016 1.016)
					(thickness 0.1524)
				)
				(justify mirror)
			)
		)
		(duplicate_pad_numbers_are_jumpers no)
		(fp_line
			(start 0.508 -0.9398)
			(end 0.508 0.9398)
			(stroke
				(width 0.1524)
				(type default)
			)
			(layer "B.SilkS")
		)
		(fp_line
			(start -0.508 -0.9398)
			(end 0.508 -0.9398)
			(stroke
				(width 0.1524)
				(type default)
			)
			(layer "B.SilkS")
		)
		(fp_rect
			(start 0.508 0.9398)
			(end -0.508 -0.9398)
			(stroke
				(width 0)
				(type default)
			)
			(fill no)
			(layer "B.CrtYd")
		)
		(fp_rect
			(start 0.508 0.9398)
			(end -0.508 -0.9398)
			(stroke
				(width 0)
				(type default)
			)
			(fill no)
			(layer "B.Fab")
		)
		(pad "1" smd custom
			(at 0 -0.4445 270)
			(size 0.1397 0.1397)
			(layers "B.Cu" "B.Mask" "B.Paste")
			(net "SSD_PERST_Y12")
			(options
				(clearance outline)
				(anchor circle)
			)
			(primitives
				(gr_poly
					(pts
						(arc
							(start -0.1778 0.2794)
							(mid -0.249642 0.249642)
							(end -0.2794 0.1778)
						)
						(arc
							(start -0.2794 -0.1778)
							(mid -0.249642 -0.249642)
							(end -0.1778 -0.2794)
						)
						(arc
							(start 0.1778 -0.2794)
							(mid 0.249642 -0.249642)
							(end 0.2794 -0.1778)
						)
						(arc
							(start 0.2794 0.1778)
							(mid 0.249642 0.249642)
							(end 0.1778 0.2794)
						)
					)
					(width 0)
					(fill yes)
				)
			)
		)
		(pad "2" smd custom
			(at 0 0.4445 270)
			(size 0.1397 0.1397)
			(layers "B.Cu" "B.Mask" "B.Paste")
			(net "SSD_PERST#12_R")
			(options
				(clearance outline)
				(anchor circle)
			)
			(primitives
				(gr_poly
					(pts
						(arc
							(start -0.1778 0.2794)
							(mid -0.249642 0.249642)
							(end -0.2794 0.1778)
						)
						(arc
							(start -0.2794 -0.1778)
							(mid -0.249642 -0.249642)
							(end -0.1778 -0.2794)
						)
						(arc
							(start 0.1778 -0.2794)
							(mid 0.249642 -0.249642)
							(end 0.2794 -0.1778)
						)
						(arc
							(start 0.2794 0.1778)
							(mid 0.249642 0.249642)
							(end 0.1778 0.2794)
						)
					)
					(width 0)
					(fill yes)
				)
			)
		)
	)
	(footprint ""
		(layer "B.Cu")
		(at 228.6254 -57.992772 90)
		(property "Reference" "C534"
			(at 0 0 90)
			(layer "B.SilkS")
			(hide yes)
			(effects
				(font
					(size 1.27 1.27)
				)
				(justify mirror)
			)
		)
		(property "Value" "SCD1U16V1KX-1-GP"
			(at 2.8321 -1.7399 90)
			(unlocked yes)
			(layer "B.Fab")
			(hide yes)
			(effects
				(font
					(size 1.016 1.016)
					(thickness 0.1524)
				)
				(justify mirror)
			)
		)
		(property "Device Type" "C0201H13"
			(at 2.8321 -3.2639 90)
			(unlocked yes)
			(layer "B.Fab")
			(hide yes)
			(effects
				(font
					(size 1.016 1.016)
					(thickness 0.1524)
				)
				(justify mirror)
			)
		)
		(duplicate_pad_numbers_are_jumpers no)
		(fp_rect
			(start 0.2794 0.6477)
			(end -0.2794 -0.6477)
			(stroke
				(width 0)
				(type default)
			)
			(fill no)
			(layer "B.CrtYd")
		)
		(fp_rect
			(start 0.2794 0.6477)
			(end -0.2794 -0.6477)
			(stroke
				(width 0)
				(type default)
			)
			(fill no)
			(layer "B.Fab")
		)
		(pad "1" smd custom
			(at 0 -0.2794 270)
			(size 0.0762 0.0762)
			(layers "B.Cu" "B.Mask" "B.Paste")
			(net "DUT_AVD_PCIE")
			(options
				(clearance outline)
				(anchor circle)
			)
			(primitives
				(gr_poly
					(pts
						(arc
							(start 0.1524 0.127)
							(mid 0.137521 0.162921)
							(end 0.1016 0.1778)
						)
						(arc
							(start -0.1016 0.1778)
							(mid -0.137521 0.162921)
							(end -0.1524 0.127)
						)
						(arc
							(start -0.1524 -0.127)
							(mid -0.137521 -0.162921)
							(end -0.1016 -0.1778)
						)
						(arc
							(start 0.1016 -0.1778)
							(mid 0.137521 -0.162921)
							(end 0.1524 -0.127)
						)
					)
					(width 0)
					(fill yes)
				)
			)
		)
		(pad "2" smd custom
			(at 0 0.2794 270)
			(size 0.0762 0.0762)
			(layers "B.Cu" "B.Mask" "B.Paste")
			(net "GND")
			(options
				(clearance outline)
				(anchor circle)
			)
			(primitives
				(gr_poly
					(pts
						(arc
							(start 0.1524 0.127)
							(mid 0.137521 0.162921)
							(end 0.1016 0.1778)
						)
						(arc
							(start -0.1016 0.1778)
							(mid -0.137521 0.162921)
							(end -0.1524 0.127)
						)
						(arc
							(start -0.1524 -0.127)
							(mid -0.137521 -0.162921)
							(end -0.1016 -0.1778)
						)
						(arc
							(start 0.1016 -0.1778)
							(mid 0.137521 -0.162921)
							(end 0.1524 -0.127)
						)
					)
					(width 0)
					(fill yes)
				)
			)
		)
	)
	(footprint ""
		(layer "B.Cu")
		(at 249.5423 -47.0027 90)
		(property "Reference" "C497"
			(at 0 0 90)
			(layer "B.SilkS")
			(hide yes)
			(effects
				(font
					(size 1.27 1.27)
				)
				(justify mirror)
			)
		)
		(property "Value" "SCD1U16V1KX-1-GP"
			(at 2.8321 -1.7399 90)
			(unlocked yes)
			(layer "B.Fab")
			(hide yes)
			(effects
				(font
					(size 1.016 1.016)
					(thickness 0.1524)
				)
				(justify mirror)
			)
		)
		(property "Device Type" "C0201H13"
			(at 2.8321 -3.2639 90)
			(unlocked yes)
			(layer "B.Fab")
			(hide yes)
			(effects
				(font
					(size 1.016 1.016)
					(thickness 0.1524)
				)
				(justify mirror)
			)
		)
		(duplicate_pad_numbers_are_jumpers no)
		(fp_rect
			(start 0.2794 0.6477)
			(end -0.2794 -0.6477)
			(stroke
				(width 0)
				(type default)
			)
			(fill no)
			(layer "B.CrtYd")
		)
		(fp_rect
			(start 0.2794 0.6477)
			(end -0.2794 -0.6477)
			(stroke
				(width 0)
				(type default)
			)
			(fill no)
			(layer "B.Fab")
		)
		(pad "1" smd custom
			(at 0 -0.2794 270)
			(size 0.0762 0.0762)
			(layers "B.Cu" "B.Mask" "B.Paste")
			(net "DUT_AVD_PCIE_Q")
			(options
				(clearance outline)
				(anchor circle)
			)
			(primitives
				(gr_poly
					(pts
						(arc
							(start 0.1524 0.127)
							(mid 0.137521 0.162921)
							(end 0.1016 0.1778)
						)
						(arc
							(start -0.1016 0.1778)
							(mid -0.137521 0.162921)
							(end -0.1524 0.127)
						)
						(arc
							(start -0.1524 -0.127)
							(mid -0.137521 -0.162921)
							(end -0.1016 -0.1778)
						)
						(arc
							(start 0.1016 -0.1778)
							(mid 0.137521 -0.162921)
							(end 0.1524 -0.127)
						)
					)
					(width 0)
					(fill yes)
				)
			)
		)
		(pad "2" smd custom
			(at 0 0.2794 270)
			(size 0.0762 0.0762)
			(layers "B.Cu" "B.Mask" "B.Paste")
			(net "GND")
			(options
				(clearance outline)
				(anchor circle)
			)
			(primitives
				(gr_poly
					(pts
						(arc
							(start 0.1524 0.127)
							(mid 0.137521 0.162921)
							(end 0.1016 0.1778)
						)
						(arc
							(start -0.1016 0.1778)
							(mid -0.137521 0.162921)
							(end -0.1524 0.127)
						)
						(arc
							(start -0.1524 -0.127)
							(mid -0.137521 -0.162921)
							(end -0.1016 -0.1778)
						)
						(arc
							(start 0.1016 -0.1778)
							(mid 0.137521 -0.162921)
							(end 0.1524 -0.127)
						)
					)
					(width 0)
					(fill yes)
				)
			)
		)
	)
	(footprint ""
		(layer "B.Cu")
		(at 235.585 -57.995058 -90)
		(property "Reference" "C503"
			(at 0 0 90)
			(layer "B.SilkS")
			(hide yes)
			(effects
				(font
					(size 1.27 1.27)
				)
				(justify mirror)
			)
		)
		(property "Value" "SCD1U16V1KX-1-GP"
			(at 2.8321 -1.7399 270)
			(unlocked yes)
			(layer "B.Fab")
			(hide yes)
			(effects
				(font
					(size 1.016 1.016)
					(thickness 0.1524)
				)
				(justify mirror)
			)
		)
		(property "Device Type" "C0201H13"
			(at 2.8321 -3.2639 270)
			(unlocked yes)
			(layer "B.Fab")
			(hide yes)
			(effects
				(font
					(size 1.016 1.016)
					(thickness 0.1524)
				)
				(justify mirror)
			)
		)
		(duplicate_pad_numbers_are_jumpers no)
		(fp_rect
			(start 0.2794 0.6477)
			(end -0.2794 -0.6477)
			(stroke
				(width 0)
				(type default)
			)
			(fill no)
			(layer "B.CrtYd")
		)
		(fp_rect
			(start 0.2794 0.6477)
			(end -0.2794 -0.6477)
			(stroke
				(width 0)
				(type default)
			)
			(fill no)
			(layer "B.Fab")
		)
		(pad "1" smd custom
			(at 0 -0.2794 90)
			(size 0.0762 0.0762)
			(layers "B.Cu" "B.Mask" "B.Paste")
			(net "DUT_AVD_TX")
			(options
				(clearance outline)
				(anchor circle)
			)
			(primitives
				(gr_poly
					(pts
						(arc
							(start 0.1524 0.127)
							(mid 0.137521 0.162921)
							(end 0.1016 0.1778)
						)
						(arc
							(start -0.1016 0.1778)
							(mid -0.137521 0.162921)
							(end -0.1524 0.127)
						)
						(arc
							(start -0.1524 -0.127)
							(mid -0.137521 -0.162921)
							(end -0.1016 -0.1778)
						)
						(arc
							(start 0.1016 -0.1778)
							(mid 0.137521 -0.162921)
							(end 0.1524 -0.127)
						)
					)
					(width 0)
					(fill yes)
				)
			)
		)
		(pad "2" smd custom
			(at 0 0.2794 90)
			(size 0.0762 0.0762)
			(layers "B.Cu" "B.Mask" "B.Paste")
			(net "GND")
			(options
				(clearance outline)
				(anchor circle)
			)
			(primitives
				(gr_poly
					(pts
						(arc
							(start 0.1524 0.127)
							(mid 0.137521 0.162921)
							(end 0.1016 0.1778)
						)
						(arc
							(start -0.1016 0.1778)
							(mid -0.137521 0.162921)
							(end -0.1524 0.127)
						)
						(arc
							(start -0.1524 -0.127)
							(mid -0.137521 -0.162921)
							(end -0.1016 -0.1778)
						)
						(arc
							(start 0.1016 -0.1778)
							(mid 0.137521 -0.162921)
							(end 0.1524 -0.127)
						)
					)
					(width 0)
					(fill yes)
				)
			)
		)
	)
	(footprint ""
		(layer "B.Cu")
		(at 245.1354 -54.0004 90)
		(property "Reference" "C44"
			(at 0 0 90)
			(layer "B.SilkS")
			(hide yes)
			(effects
				(font
					(size 1.27 1.27)
				)
				(justify mirror)
			)
		)
		(property "Value" "SCD1U16V1KX-1-GP"
			(at 2.8321 -1.7399 90)
			(unlocked yes)
			(layer "B.Fab")
			(hide yes)
			(effects
				(font
					(size 1.016 1.016)
					(thickness 0.1524)
				)
				(justify mirror)
			)
		)
		(property "Device Type" "C0201H13"
			(at 2.8321 -3.2639 90)
			(unlocked yes)
			(layer "B.Fab")
			(hide yes)
			(effects
				(font
					(size 1.016 1.016)
					(thickness 0.1524)
				)
				(justify mirror)
			)
		)
		(duplicate_pad_numbers_are_jumpers no)
		(fp_rect
			(start 0.2794 0.6477)
			(end -0.2794 -0.6477)
			(stroke
				(width 0)
				(type default)
			)
			(fill no)
			(layer "B.CrtYd")
		)
		(fp_rect
			(start 0.2794 0.6477)
			(end -0.2794 -0.6477)
			(stroke
				(width 0)
				(type default)
			)
			(fill no)
			(layer "B.Fab")
		)
		(pad "1" smd custom
			(at 0 -0.2794 270)
			(size 0.0762 0.0762)
			(layers "B.Cu" "B.Mask" "B.Paste")
			(net "DUT_VDD")
			(options
				(clearance outline)
				(anchor circle)
			)
			(primitives
				(gr_poly
					(pts
						(arc
							(start 0.1524 0.127)
							(mid 0.137521 0.162921)
							(end 0.1016 0.1778)
						)
						(arc
							(start -0.1016 0.1778)
							(mid -0.137521 0.162921)
							(end -0.1524 0.127)
						)
						(arc
							(start -0.1524 -0.127)
							(mid -0.137521 -0.162921)
							(end -0.1016 -0.1778)
						)
						(arc
							(start 0.1016 -0.1778)
							(mid 0.137521 -0.162921)
							(end 0.1524 -0.127)
						)
					)
					(width 0)
					(fill yes)
				)
			)
		)
		(pad "2" smd custom
			(at 0 0.2794 270)
			(size 0.0762 0.0762)
			(layers "B.Cu" "B.Mask" "B.Paste")
			(net "GND")
			(options
				(clearance outline)
				(anchor circle)
			)
			(primitives
				(gr_poly
					(pts
						(arc
							(start 0.1524 0.127)
							(mid 0.137521 0.162921)
							(end 0.1016 0.1778)
						)
						(arc
							(start -0.1016 0.1778)
							(mid -0.137521 0.162921)
							(end -0.1524 0.127)
						)
						(arc
							(start -0.1524 -0.127)
							(mid -0.137521 -0.162921)
							(end -0.1016 -0.1778)
						)
						(arc
							(start 0.1016 -0.1778)
							(mid 0.137521 -0.162921)
							(end 0.1524 -0.127)
						)
					)
					(width 0)
					(fill yes)
				)
			)
		)
	)
	(footprint ""
		(layer "B.Cu")
		(at 233.68 -23.241 180)
		(property "Reference" "R788"
			(at 0 0 0)
			(layer "B.SilkS")
			(hide yes)
			(effects
				(font
					(size 1.27 1.27)
				)
				(justify mirror)
			)
		)
		(property "Value" "4K7R2F-GP"
			(at -0.064008 -3.993896 180)
			(unlocked yes)
			(layer "B.Fab")
			(hide yes)
			(effects
				(font
					(size 1.016 1.016)
					(thickness 0.1524)
				)
				(justify mirror)
			)
		)
		(property "Device Type" "R402H16"
			(at -0.064008 -5.517896 180)
			(unlocked yes)
			(layer "B.Fab")
			(hide yes)
			(effects
				(font
					(size 1.016 1.016)
					(thickness 0.1524)
				)
				(justify mirror)
			)
		)
		(duplicate_pad_numbers_are_jumpers no)
		(fp_line
			(start 0.508 -0.9398)
			(end 0.508 0.9398)
			(stroke
				(width 0.1524)
				(type default)
			)
			(layer "B.SilkS")
		)
		(fp_line
			(start -0.508 -0.9398)
			(end 0.508 -0.9398)
			(stroke
				(width 0.1524)
				(type default)
			)
			(layer "B.SilkS")
		)
		(fp_rect
			(start 0.508 0.9398)
			(end -0.508 -0.9398)
			(stroke
				(width 0)
				(type default)
			)
			(fill no)
			(layer "B.CrtYd")
		)
		(fp_rect
			(start 0.508 0.9398)
			(end -0.508 -0.9398)
			(stroke
				(width 0)
				(type default)
			)
			(fill no)
			(layer "B.Fab")
		)
		(pad "1" smd custom
			(at 0 -0.4445)
			(size 0.1397 0.1397)
			(layers "B.Cu" "B.Mask" "B.Paste")
			(net "BOOTSTRAP8")
			(options
				(clearance outline)
				(anchor circle)
			)
			(primitives
				(gr_poly
					(pts
						(arc
							(start -0.1778 0.2794)
							(mid -0.249642 0.249642)
							(end -0.2794 0.1778)
						)
						(arc
							(start -0.2794 -0.1778)
							(mid -0.249642 -0.249642)
							(end -0.1778 -0.2794)
						)
						(arc
							(start 0.1778 -0.2794)
							(mid 0.249642 -0.249642)
							(end 0.2794 -0.1778)
						)
						(arc
							(start 0.2794 0.1778)
							(mid 0.249642 0.249642)
							(end 0.1778 0.2794)
						)
					)
					(width 0)
					(fill yes)
				)
			)
		)
		(pad "2" smd custom
			(at 0 0.4445)
			(size 0.1397 0.1397)
			(layers "B.Cu" "B.Mask" "B.Paste")
			(net "BOOTSTRAP_R_8")
			(options
				(clearance outline)
				(anchor circle)
			)
			(primitives
				(gr_poly
					(pts
						(arc
							(start -0.1778 0.2794)
							(mid -0.249642 0.249642)
							(end -0.2794 0.1778)
						)
						(arc
							(start -0.2794 -0.1778)
							(mid -0.249642 -0.249642)
							(end -0.1778 -0.2794)
						)
						(arc
							(start 0.1778 -0.2794)
							(mid 0.249642 -0.249642)
							(end 0.2794 -0.1778)
						)
						(arc
							(start 0.2794 0.1778)
							(mid 0.249642 0.249642)
							(end 0.1778 0.2794)
						)
					)
					(width 0)
					(fill yes)
				)
			)
		)
	)
	(footprint ""
		(layer "B.Cu")
		(at 46.179994 -133.344412)
		(property "Reference" "TP318"
			(at 0 0 0)
			(layer "B.SilkS")
			(hide yes)
			(effects
				(font
					(size 1.27 1.27)
				)
				(justify mirror)
			)
		)
		(property "Value" "TPAD28-2-GP"
			(at 0.0127 -1.6637 0)
			(unlocked yes)
			(layer "B.Fab")
			(hide yes)
			(effects
				(font
					(size 1.016 1.016)
					(thickness 0.1524)
				)
				(justify mirror)
			)
		)
		(property "Device Type" "TPAD28"
			(at 0.0127 -3.1877 0)
			(unlocked yes)
			(layer "B.Fab")
			(hide yes)
			(effects
				(font
					(size 1.016 1.016)
					(thickness 0.1524)
				)
				(justify mirror)
			)
		)
		(duplicate_pad_numbers_are_jumpers no)
		(fp_poly
			(pts
				(arc
					(start 0.3556 0)
					(mid -0.3556 0)
					(end 0.3556 0)
				)
			)
			(stroke
				(width 0)
				(type default)
			)
			(fill no)
			(layer "B.CrtYd")
		)
		(fp_poly
			(pts
				(arc
					(start 0.6096 0)
					(mid -0.6096 0)
					(end 0.6096 0)
				)
			)
			(stroke
				(width 0)
				(type default)
			)
			(fill no)
			(layer "B.Fab")
		)
		(pad "1" smd circle
			(at 0 0 180)
			(size 0.7112 0.7112)
			(layers "B.Cu" "B.Mask" "B.Paste")
			(net "DACG")
		)
	)
	(footprint ""
		(layer "B.Cu")
		(at 32.58312 -120.93448)
		(property "Reference" "TP307"
			(at 0 0 0)
			(layer "B.SilkS")
			(hide yes)
			(effects
				(font
					(size 1.27 1.27)
				)
				(justify mirror)
			)
		)
		(property "Value" "TPAD28-2-GP"
			(at 0.0127 -1.6637 0)
			(unlocked yes)
			(layer "B.Fab")
			(hide yes)
			(effects
				(font
					(size 1.016 1.016)
					(thickness 0.1524)
				)
				(justify mirror)
			)
		)
		(property "Device Type" "TPAD28"
			(at 0.0127 -3.1877 0)
			(unlocked yes)
			(layer "B.Fab")
			(hide yes)
			(effects
				(font
					(size 1.016 1.016)
					(thickness 0.1524)
				)
				(justify mirror)
			)
		)
		(duplicate_pad_numbers_are_jumpers no)
		(fp_poly
			(pts
				(arc
					(start 0.3556 0)
					(mid -0.3556 0)
					(end 0.3556 0)
				)
			)
			(stroke
				(width 0)
				(type default)
			)
			(fill no)
			(layer "B.CrtYd")
		)
		(fp_poly
			(pts
				(arc
					(start 0.6096 0)
					(mid -0.6096 0)
					(end 0.6096 0)
				)
			)
			(stroke
				(width 0)
				(type default)
			)
			(fill no)
			(layer "B.Fab")
		)
		(pad "1" smd circle
			(at 0 0 180)
			(size 0.7112 0.7112)
			(layers "B.Cu" "B.Mask" "B.Paste")
			(net "TP_GPIOD4")
		)
	)
	(footprint ""
		(layer "B.Cu")
		(at 263.139174 -0.721868 90)
		(property "Reference" "R203"
			(at 0 0 90)
			(layer "B.SilkS")
			(hide yes)
			(effects
				(font
					(size 1.27 1.27)
				)
				(justify mirror)
			)
		)
		(property "Value" "0R2J-2-GP"
			(at -0.064008 -3.993896 90)
			(unlocked yes)
			(layer "B.Fab")
			(hide yes)
			(effects
				(font
					(size 1.016 1.016)
					(thickness 0.1524)
				)
				(justify mirror)
			)
		)
		(property "Device Type" "R402H16"
			(at -0.064008 -5.517896 90)
			(unlocked yes)
			(layer "B.Fab")
			(hide yes)
			(effects
				(font
					(size 1.016 1.016)
					(thickness 0.1524)
				)
				(justify mirror)
			)
		)
		(duplicate_pad_numbers_are_jumpers no)
		(fp_line
			(start 0.508 -0.9398)
			(end 0.508 0.9398)
			(stroke
				(width 0.1524)
				(type default)
			)
			(layer "B.SilkS")
		)
		(fp_line
			(start -0.508 -0.9398)
			(end 0.508 -0.9398)
			(stroke
				(width 0.1524)
				(type default)
			)
			(layer "B.SilkS")
		)
		(fp_rect
			(start 0.508 0.9398)
			(end -0.508 -0.9398)
			(stroke
				(width 0)
				(type default)
			)
			(fill no)
			(layer "B.CrtYd")
		)
		(fp_rect
			(start 0.508 0.9398)
			(end -0.508 -0.9398)
			(stroke
				(width 0)
				(type default)
			)
			(fill no)
			(layer "B.Fab")
		)
		(pad "1" smd custom
			(at 0 -0.4445 270)
			(size 0.1397 0.1397)
			(layers "B.Cu" "B.Mask" "B.Paste")
			(net "GND")
			(options
				(clearance outline)
				(anchor circle)
			)
			(primitives
				(gr_poly
					(pts
						(arc
							(start -0.1778 0.2794)
							(mid -0.249642 0.249642)
							(end -0.2794 0.1778)
						)
						(arc
							(start -0.2794 -0.1778)
							(mid -0.249642 -0.249642)
							(end -0.1778 -0.2794)
						)
						(arc
							(start 0.1778 -0.2794)
							(mid 0.249642 -0.249642)
							(end 0.2794 -0.1778)
						)
						(arc
							(start 0.2794 0.1778)
							(mid 0.249642 0.249642)
							(end 0.1778 0.2794)
						)
					)
					(width 0)
					(fill yes)
				)
			)
		)
		(pad "2" smd custom
			(at 0 0.4445 270)
			(size 0.1397 0.1397)
			(layers "B.Cu" "B.Mask" "B.Paste")
			(net "TEMP_SENSOR_C")
			(options
				(clearance outline)
				(anchor circle)
			)
			(primitives
				(gr_poly
					(pts
						(arc
							(start -0.1778 0.2794)
							(mid -0.249642 0.249642)
							(end -0.2794 0.1778)
						)
						(arc
							(start -0.2794 -0.1778)
							(mid -0.249642 -0.249642)
							(end -0.1778 -0.2794)
						)
						(arc
							(start 0.1778 -0.2794)
							(mid 0.249642 -0.249642)
							(end 0.2794 -0.1778)
						)
						(arc
							(start 0.2794 0.1778)
							(mid 0.249642 0.249642)
							(end 0.1778 0.2794)
						)
					)
					(width 0)
					(fill yes)
				)
			)
		)
	)
	(footprint ""
		(layer "B.Cu")
		(at 238.6076 -36.9824 180)
		(property "Reference" "R8"
			(at 0 0 0)
			(layer "B.SilkS")
			(hide yes)
			(effects
				(font
					(size 1.27 1.27)
				)
				(justify mirror)
			)
		)
		(property "Value" "33R1J-GP"
			(at 3.3274 -1.3335 180)
			(unlocked yes)
			(layer "B.Fab")
			(hide yes)
			(effects
				(font
					(size 1.016 1.016)
					(thickness 0.1524)
				)
				(justify mirror)
			)
		)
		(property "Device Type" "R0201H12"
			(at 3.3274 -2.8575 180)
			(unlocked yes)
			(layer "B.Fab")
			(hide yes)
			(effects
				(font
					(size 1.016 1.016)
					(thickness 0.1524)
				)
				(justify mirror)
			)
		)
		(duplicate_pad_numbers_are_jumpers no)
		(fp_rect
			(start 0.2794 0.6477)
			(end -0.2794 -0.6477)
			(stroke
				(width 0)
				(type default)
			)
			(fill no)
			(layer "B.CrtYd")
		)
		(fp_rect
			(start 0.2794 0.6477)
			(end -0.2794 -0.6477)
			(stroke
				(width 0)
				(type default)
			)
			(fill no)
			(layer "B.Fab")
		)
		(pad "1" smd custom
			(at 0 -0.2794)
			(size 0.0762 0.0762)
			(layers "B.Cu" "B.Mask" "B.Paste")
			(net "PCIE_REFCLK_H2_N")
			(options
				(clearance outline)
				(anchor circle)
			)
			(primitives
				(gr_poly
					(pts
						(arc
							(start 0.1524 0.127)
							(mid 0.137521 0.162921)
							(end 0.1016 0.1778)
						)
						(arc
							(start -0.1016 0.1778)
							(mid -0.137521 0.162921)
							(end -0.1524 0.127)
						)
						(arc
							(start -0.1524 -0.127)
							(mid -0.137521 -0.162921)
							(end -0.1016 -0.1778)
						)
						(arc
							(start 0.1016 -0.1778)
							(mid 0.137521 -0.162921)
							(end 0.1524 -0.127)
						)
					)
					(width 0)
					(fill yes)
				)
			)
		)
		(pad "2" smd custom
			(at 0 0.2794)
			(size 0.0762 0.0762)
			(layers "B.Cu" "B.Mask" "B.Paste")
			(net "PCIE_REFCLK_H2_P")
			(options
				(clearance outline)
				(anchor circle)
			)
			(primitives
				(gr_poly
					(pts
						(arc
							(start 0.1524 0.127)
							(mid 0.137521 0.162921)
							(end 0.1016 0.1778)
						)
						(arc
							(start -0.1016 0.1778)
							(mid -0.137521 0.162921)
							(end -0.1524 0.127)
						)
						(arc
							(start -0.1524 -0.127)
							(mid -0.137521 -0.162921)
							(end -0.1016 -0.1778)
						)
						(arc
							(start 0.1016 -0.1778)
							(mid 0.137521 -0.162921)
							(end 0.1524 -0.127)
						)
					)
					(width 0)
					(fill yes)
				)
			)
		)
	)
	(footprint ""
		(layer "B.Cu")
		(at 247.1166 -47.032672 -90)
		(property "Reference" "C452"
			(at 0 0 90)
			(layer "B.SilkS")
			(hide yes)
			(effects
				(font
					(size 1.27 1.27)
				)
				(justify mirror)
			)
		)
		(property "Value" "SCD1U16V1KX-1-GP"
			(at 2.8321 -1.7399 270)
			(unlocked yes)
			(layer "B.Fab")
			(hide yes)
			(effects
				(font
					(size 1.016 1.016)
					(thickness 0.1524)
				)
				(justify mirror)
			)
		)
		(property "Device Type" "C0201H13"
			(at 2.8321 -3.2639 270)
			(unlocked yes)
			(layer "B.Fab")
			(hide yes)
			(effects
				(font
					(size 1.016 1.016)
					(thickness 0.1524)
				)
				(justify mirror)
			)
		)
		(duplicate_pad_numbers_are_jumpers no)
		(fp_rect
			(start 0.2794 0.6477)
			(end -0.2794 -0.6477)
			(stroke
				(width 0)
				(type default)
			)
			(fill no)
			(layer "B.CrtYd")
		)
		(fp_rect
			(start 0.2794 0.6477)
			(end -0.2794 -0.6477)
			(stroke
				(width 0)
				(type default)
			)
			(fill no)
			(layer "B.Fab")
		)
		(pad "1" smd custom
			(at 0 -0.2794 90)
			(size 0.0762 0.0762)
			(layers "B.Cu" "B.Mask" "B.Paste")
			(net "DUT_VDD")
			(options
				(clearance outline)
				(anchor circle)
			)
			(primitives
				(gr_poly
					(pts
						(arc
							(start 0.1524 0.127)
							(mid 0.137521 0.162921)
							(end 0.1016 0.1778)
						)
						(arc
							(start -0.1016 0.1778)
							(mid -0.137521 0.162921)
							(end -0.1524 0.127)
						)
						(arc
							(start -0.1524 -0.127)
							(mid -0.137521 -0.162921)
							(end -0.1016 -0.1778)
						)
						(arc
							(start 0.1016 -0.1778)
							(mid 0.137521 -0.162921)
							(end 0.1524 -0.127)
						)
					)
					(width 0)
					(fill yes)
				)
			)
		)
		(pad "2" smd custom
			(at 0 0.2794 90)
			(size 0.0762 0.0762)
			(layers "B.Cu" "B.Mask" "B.Paste")
			(net "GND")
			(options
				(clearance outline)
				(anchor circle)
			)
			(primitives
				(gr_poly
					(pts
						(arc
							(start 0.1524 0.127)
							(mid 0.137521 0.162921)
							(end 0.1016 0.1778)
						)
						(arc
							(start -0.1016 0.1778)
							(mid -0.137521 0.162921)
							(end -0.1524 0.127)
						)
						(arc
							(start -0.1524 -0.127)
							(mid -0.137521 -0.162921)
							(end -0.1016 -0.1778)
						)
						(arc
							(start 0.1016 -0.1778)
							(mid 0.137521 -0.162921)
							(end 0.1524 -0.127)
						)
					)
					(width 0)
					(fill yes)
				)
			)
		)
	)
	(footprint ""
		(layer "B.Cu")
		(at 313.436 -55.372)
		(property "Reference" "PC178"
			(at 0 0 0)
			(layer "B.SilkS")
			(hide yes)
			(effects
				(font
					(size 1.27 1.27)
				)
				(justify mirror)
			)
		)
		(property "Value" "SC22U6D3V5MX-5-GP"
			(at 0.0762 -6.1214 0)
			(unlocked yes)
			(layer "B.Fab")
			(hide yes)
			(effects
				(font
					(size 1.016 1.016)
					(thickness 0.1524)
				)
				(justify mirror)
			)
		)
		(property "Device Type" "C805H56"
			(at 0.0762 -8.1534 0)
			(unlocked yes)
			(layer "B.Fab")
			(hide yes)
			(effects
				(font
					(size 1.016 1.016)
					(thickness 0.1524)
				)
				(justify mirror)
			)
		)
		(duplicate_pad_numbers_are_jumpers no)
		(fp_line
			(start -0.635 0)
			(end 0.635 0)
			(stroke
				(width 0.508)
				(type default)
			)
			(layer "B.SilkS")
		)
		(fp_rect
			(start 0.9652 1.778)
			(end -0.9652 -1.778)
			(stroke
				(width 0)
				(type default)
			)
			(fill no)
			(layer "B.CrtYd")
		)
		(fp_poly
			(pts
				(xy 0.9652 -1.778) (xy -0.9652 -1.778) (xy -0.9652 1.778) (xy 0.9652 1.778)
			)
			(stroke
				(width 0)
				(type default)
			)
			(fill no)
			(layer "B.Fab")
		)
		(pad "1" smd rect
			(at 0 -0.9652 180)
			(size 1.397 1.143)
			(layers "B.Cu" "B.Mask" "B.Paste")
			(net "P0V9_E")
		)
		(pad "2" smd rect
			(at 0 0.9652 180)
			(size 1.397 1.143)
			(layers "B.Cu" "B.Mask" "B.Paste")
			(net "GND")
		)
	)
	(footprint ""
		(layer "B.Cu")
		(at 220.956124 -203.047092 180)
		(property "Reference" "R4149"
			(at 0 0 0)
			(layer "B.SilkS")
			(hide yes)
			(effects
				(font
					(size 1.27 1.27)
				)
				(justify mirror)
			)
		)
		(property "Value" "4K7R2F-GP"
			(at -0.064008 -3.993896 180)
			(unlocked yes)
			(layer "B.Fab")
			(hide yes)
			(effects
				(font
					(size 1.016 1.016)
					(thickness 0.1524)
				)
				(justify mirror)
			)
		)
		(property "Device Type" "R402H16"
			(at -0.064008 -5.517896 180)
			(unlocked yes)
			(layer "B.Fab")
			(hide yes)
			(effects
				(font
					(size 1.016 1.016)
					(thickness 0.1524)
				)
				(justify mirror)
			)
		)
		(duplicate_pad_numbers_are_jumpers no)
		(fp_line
			(start 0.508 -0.9398)
			(end 0.508 0.9398)
			(stroke
				(width 0.1524)
				(type default)
			)
			(layer "B.SilkS")
		)
		(fp_line
			(start -0.508 -0.9398)
			(end 0.508 -0.9398)
			(stroke
				(width 0.1524)
				(type default)
			)
			(layer "B.SilkS")
		)
		(fp_rect
			(start 0.508 0.9398)
			(end -0.508 -0.9398)
			(stroke
				(width 0)
				(type default)
			)
			(fill no)
			(layer "B.CrtYd")
		)
		(fp_rect
			(start 0.508 0.9398)
			(end -0.508 -0.9398)
			(stroke
				(width 0)
				(type default)
			)
			(fill no)
			(layer "B.Fab")
		)
		(pad "1" smd custom
			(at 0 -0.4445)
			(size 0.1397 0.1397)
			(layers "B.Cu" "B.Mask" "B.Paste")
			(net "SSD_PERST#13")
			(options
				(clearance outline)
				(anchor circle)
			)
			(primitives
				(gr_poly
					(pts
						(arc
							(start -0.1778 0.2794)
							(mid -0.249642 0.249642)
							(end -0.2794 0.1778)
						)
						(arc
							(start -0.2794 -0.1778)
							(mid -0.249642 -0.249642)
							(end -0.1778 -0.2794)
						)
						(arc
							(start 0.1778 -0.2794)
							(mid 0.249642 -0.249642)
							(end 0.2794 -0.1778)
						)
						(arc
							(start 0.2794 0.1778)
							(mid 0.249642 0.249642)
							(end 0.1778 0.2794)
						)
					)
					(width 0)
					(fill yes)
				)
			)
		)
		(pad "2" smd custom
			(at 0 0.4445)
			(size 0.1397 0.1397)
			(layers "B.Cu" "B.Mask" "B.Paste")
			(net "P3V3_STBY")
			(options
				(clearance outline)
				(anchor circle)
			)
			(primitives
				(gr_poly
					(pts
						(arc
							(start -0.1778 0.2794)
							(mid -0.249642 0.249642)
							(end -0.2794 0.1778)
						)
						(arc
							(start -0.2794 -0.1778)
							(mid -0.249642 -0.249642)
							(end -0.1778 -0.2794)
						)
						(arc
							(start 0.1778 -0.2794)
							(mid 0.249642 -0.249642)
							(end 0.2794 -0.1778)
						)
						(arc
							(start 0.2794 0.1778)
							(mid 0.249642 0.249642)
							(end 0.1778 0.2794)
						)
					)
					(width 0)
					(fill yes)
				)
			)
		)
	)
	(footprint ""
		(layer "B.Cu")
		(at 272.6055 -9.7155)
		(property "Reference" "R388"
			(at 0 0 0)
			(layer "B.SilkS")
			(hide yes)
			(effects
				(font
					(size 1.27 1.27)
				)
				(justify mirror)
			)
		)
		(property "Value" "0R2J-2-GP"
			(at -0.064008 -3.993896 0)
			(unlocked yes)
			(layer "B.Fab")
			(hide yes)
			(effects
				(font
					(size 1.016 1.016)
					(thickness 0.1524)
				)
				(justify mirror)
			)
		)
		(property "Device Type" "R402H16"
			(at -0.064008 -5.517896 0)
			(unlocked yes)
			(layer "B.Fab")
			(hide yes)
			(effects
				(font
					(size 1.016 1.016)
					(thickness 0.1524)
				)
				(justify mirror)
			)
		)
		(duplicate_pad_numbers_are_jumpers no)
		(fp_line
			(start -0.508 -0.9398)
			(end 0.508 -0.9398)
			(stroke
				(width 0.1524)
				(type default)
			)
			(layer "B.SilkS")
		)
		(fp_line
			(start 0.508 -0.9398)
			(end 0.508 0.9398)
			(stroke
				(width 0.1524)
				(type default)
			)
			(layer "B.SilkS")
		)
		(fp_rect
			(start 0.508 0.9398)
			(end -0.508 -0.9398)
			(stroke
				(width 0)
				(type default)
			)
			(fill no)
			(layer "B.CrtYd")
		)
		(fp_rect
			(start 0.508 0.9398)
			(end -0.508 -0.9398)
			(stroke
				(width 0)
				(type default)
			)
			(fill no)
			(layer "B.Fab")
		)
		(pad "1" smd custom
			(at 0 -0.4445 180)
			(size 0.1397 0.1397)
			(layers "B.Cu" "B.Mask" "B.Paste")
			(net "CLK_P_5_R")
			(options
				(clearance outline)
				(anchor circle)
			)
			(primitives
				(gr_poly
					(pts
						(arc
							(start -0.1778 0.2794)
							(mid -0.249642 0.249642)
							(end -0.2794 0.1778)
						)
						(arc
							(start -0.2794 -0.1778)
							(mid -0.249642 -0.249642)
							(end -0.1778 -0.2794)
						)
						(arc
							(start 0.1778 -0.2794)
							(mid 0.249642 -0.249642)
							(end 0.2794 -0.1778)
						)
						(arc
							(start 0.2794 0.1778)
							(mid 0.249642 0.249642)
							(end 0.1778 0.2794)
						)
					)
					(width 0)
					(fill yes)
				)
			)
		)
		(pad "2" smd custom
			(at 0 0.4445 180)
			(size 0.1397 0.1397)
			(layers "B.Cu" "B.Mask" "B.Paste")
			(net "PCIE_REFCLK_H0_P_R")
			(options
				(clearance outline)
				(anchor circle)
			)
			(primitives
				(gr_poly
					(pts
						(arc
							(start -0.1778 0.2794)
							(mid -0.249642 0.249642)
							(end -0.2794 0.1778)
						)
						(arc
							(start -0.2794 -0.1778)
							(mid -0.249642 -0.249642)
							(end -0.1778 -0.2794)
						)
						(arc
							(start 0.1778 -0.2794)
							(mid 0.249642 -0.249642)
							(end 0.2794 -0.1778)
						)
						(arc
							(start 0.2794 0.1778)
							(mid 0.249642 0.249642)
							(end 0.1778 0.2794)
						)
					)
					(width 0)
					(fill yes)
				)
			)
		)
	)
	(footprint ""
		(layer "B.Cu")
		(at 247.1166 -51.9938 90)
		(property "Reference" "C442"
			(at 0 0 90)
			(layer "B.SilkS")
			(hide yes)
			(effects
				(font
					(size 1.27 1.27)
				)
				(justify mirror)
			)
		)
		(property "Value" "SCD1U16V1KX-1-GP"
			(at 2.8321 -1.7399 90)
			(unlocked yes)
			(layer "B.Fab")
			(hide yes)
			(effects
				(font
					(size 1.016 1.016)
					(thickness 0.1524)
				)
				(justify mirror)
			)
		)
		(property "Device Type" "C0201H13"
			(at 2.8321 -3.2639 90)
			(unlocked yes)
			(layer "B.Fab")
			(hide yes)
			(effects
				(font
					(size 1.016 1.016)
					(thickness 0.1524)
				)
				(justify mirror)
			)
		)
		(duplicate_pad_numbers_are_jumpers no)
		(fp_rect
			(start 0.2794 0.6477)
			(end -0.2794 -0.6477)
			(stroke
				(width 0)
				(type default)
			)
			(fill no)
			(layer "B.CrtYd")
		)
		(fp_rect
			(start 0.2794 0.6477)
			(end -0.2794 -0.6477)
			(stroke
				(width 0)
				(type default)
			)
			(fill no)
			(layer "B.Fab")
		)
		(pad "1" smd custom
			(at 0 -0.2794 270)
			(size 0.0762 0.0762)
			(layers "B.Cu" "B.Mask" "B.Paste")
			(net "DUT_VDD")
			(options
				(clearance outline)
				(anchor circle)
			)
			(primitives
				(gr_poly
					(pts
						(arc
							(start 0.1524 0.127)
							(mid 0.137521 0.162921)
							(end 0.1016 0.1778)
						)
						(arc
							(start -0.1016 0.1778)
							(mid -0.137521 0.162921)
							(end -0.1524 0.127)
						)
						(arc
							(start -0.1524 -0.127)
							(mid -0.137521 -0.162921)
							(end -0.1016 -0.1778)
						)
						(arc
							(start 0.1016 -0.1778)
							(mid 0.137521 -0.162921)
							(end 0.1524 -0.127)
						)
					)
					(width 0)
					(fill yes)
				)
			)
		)
		(pad "2" smd custom
			(at 0 0.2794 270)
			(size 0.0762 0.0762)
			(layers "B.Cu" "B.Mask" "B.Paste")
			(net "GND")
			(options
				(clearance outline)
				(anchor circle)
			)
			(primitives
				(gr_poly
					(pts
						(arc
							(start 0.1524 0.127)
							(mid 0.137521 0.162921)
							(end 0.1016 0.1778)
						)
						(arc
							(start -0.1016 0.1778)
							(mid -0.137521 0.162921)
							(end -0.1524 0.127)
						)
						(arc
							(start -0.1524 -0.127)
							(mid -0.137521 -0.162921)
							(end -0.1016 -0.1778)
						)
						(arc
							(start 0.1016 -0.1778)
							(mid 0.137521 -0.162921)
							(end 0.1524 -0.127)
						)
					)
					(width 0)
					(fill yes)
				)
			)
		)
	)
	(footprint ""
		(layer "B.Cu")
		(at 241.6048 -56.9976 -90)
		(property "Reference" "C513"
			(at 0 0 90)
			(layer "B.SilkS")
			(hide yes)
			(effects
				(font
					(size 1.27 1.27)
				)
				(justify mirror)
			)
		)
		(property "Value" "SCD1U16V1KX-1-GP"
			(at 2.8321 -1.7399 270)
			(unlocked yes)
			(layer "B.Fab")
			(hide yes)
			(effects
				(font
					(size 1.016 1.016)
					(thickness 0.1524)
				)
				(justify mirror)
			)
		)
		(property "Device Type" "C0201H13"
			(at 2.8321 -3.2639 270)
			(unlocked yes)
			(layer "B.Fab")
			(hide yes)
			(effects
				(font
					(size 1.016 1.016)
					(thickness 0.1524)
				)
				(justify mirror)
			)
		)
		(duplicate_pad_numbers_are_jumpers no)
		(fp_rect
			(start 0.2794 0.6477)
			(end -0.2794 -0.6477)
			(stroke
				(width 0)
				(type default)
			)
			(fill no)
			(layer "B.CrtYd")
		)
		(fp_rect
			(start 0.2794 0.6477)
			(end -0.2794 -0.6477)
			(stroke
				(width 0)
				(type default)
			)
			(fill no)
			(layer "B.Fab")
		)
		(pad "1" smd custom
			(at 0 -0.2794 90)
			(size 0.0762 0.0762)
			(layers "B.Cu" "B.Mask" "B.Paste")
			(net "DUT_AVD_TX")
			(options
				(clearance outline)
				(anchor circle)
			)
			(primitives
				(gr_poly
					(pts
						(arc
							(start 0.1524 0.127)
							(mid 0.137521 0.162921)
							(end 0.1016 0.1778)
						)
						(arc
							(start -0.1016 0.1778)
							(mid -0.137521 0.162921)
							(end -0.1524 0.127)
						)
						(arc
							(start -0.1524 -0.127)
							(mid -0.137521 -0.162921)
							(end -0.1016 -0.1778)
						)
						(arc
							(start 0.1016 -0.1778)
							(mid 0.137521 -0.162921)
							(end 0.1524 -0.127)
						)
					)
					(width 0)
					(fill yes)
				)
			)
		)
		(pad "2" smd custom
			(at 0 0.2794 90)
			(size 0.0762 0.0762)
			(layers "B.Cu" "B.Mask" "B.Paste")
			(net "GND")
			(options
				(clearance outline)
				(anchor circle)
			)
			(primitives
				(gr_poly
					(pts
						(arc
							(start 0.1524 0.127)
							(mid 0.137521 0.162921)
							(end 0.1016 0.1778)
						)
						(arc
							(start -0.1016 0.1778)
							(mid -0.137521 0.162921)
							(end -0.1524 0.127)
						)
						(arc
							(start -0.1524 -0.127)
							(mid -0.137521 -0.162921)
							(end -0.1016 -0.1778)
						)
						(arc
							(start 0.1016 -0.1778)
							(mid 0.137521 -0.162921)
							(end 0.1524 -0.127)
						)
					)
					(width 0)
					(fill yes)
				)
			)
		)
	)
	(footprint ""
		(layer "B.Cu")
		(at 332.613 -68.9356 90)
		(property "Reference" "PR21"
			(at 0 0 90)
			(layer "B.SilkS")
			(hide yes)
			(effects
				(font
					(size 1.27 1.27)
				)
				(justify mirror)
			)
		)
		(property "Value" "0R3J-0-U-GP"
			(at 0.0254 -2.5146 90)
			(unlocked yes)
			(layer "B.Fab")
			(hide yes)
			(effects
				(font
					(size 1.016 1.016)
					(thickness 0.1524)
				)
				(justify mirror)
			)
		)
		(property "Device Type" "R603H22"
			(at 0.0254 -4.0386 90)
			(unlocked yes)
			(layer "B.Fab")
			(hide yes)
			(effects
				(font
					(size 1.016 1.016)
					(thickness 0.1524)
				)
				(justify mirror)
			)
		)
		(duplicate_pad_numbers_are_jumpers no)
		(fp_line
			(start 0.4826 0)
			(end 0.2032 0)
			(stroke
				(width 0.2032)
				(type default)
			)
			(layer "B.SilkS")
		)
		(fp_line
			(start -0.2032 0)
			(end -0.4826 0)
			(stroke
				(width 0.2032)
				(type default)
			)
			(layer "B.SilkS")
		)
		(fp_rect
			(start 0.5842 1.3335)
			(end -0.5842 -1.3335)
			(stroke
				(width 0)
				(type default)
			)
			(fill no)
			(layer "B.CrtYd")
		)
		(fp_rect
			(start 0.5842 1.3335)
			(end -0.5842 -1.3335)
			(stroke
				(width 0)
				(type default)
			)
			(fill no)
			(layer "B.Fab")
		)
		(pad "1" smd custom
			(at 0 -0.762 270)
			(size 0.2159 0.2159)
			(layers "B.Cu" "B.Mask" "B.Paste")
			(net "P0V9_E_LX")
			(options
				(clearance outline)
				(anchor circle)
			)
			(primitives
				(gr_poly
					(pts
						(arc
							(start -0.3302 0.4318)
							(mid -0.402042 0.402042)
							(end -0.4318 0.3302)
						)
						(arc
							(start -0.4318 -0.3302)
							(mid -0.402042 -0.402042)
							(end -0.3302 -0.4318)
						)
						(arc
							(start 0.3302 -0.4318)
							(mid 0.402042 -0.402042)
							(end 0.4318 -0.3302)
						)
						(arc
							(start 0.4318 0.3302)
							(mid 0.402042 0.402042)
							(end 0.3302 0.4318)
						)
					)
					(width 0)
					(fill yes)
				)
			)
		)
		(pad "2" smd custom
			(at 0 0.762 270)
			(size 0.2159 0.2159)
			(layers "B.Cu" "B.Mask" "B.Paste")
			(net "P0V9_E_VBST_RC")
			(options
				(clearance outline)
				(anchor circle)
			)
			(primitives
				(gr_poly
					(pts
						(arc
							(start -0.3302 0.4318)
							(mid -0.402042 0.402042)
							(end -0.4318 0.3302)
						)
						(arc
							(start -0.4318 -0.3302)
							(mid -0.402042 -0.402042)
							(end -0.3302 -0.4318)
						)
						(arc
							(start 0.3302 -0.4318)
							(mid 0.402042 -0.402042)
							(end 0.4318 -0.3302)
						)
						(arc
							(start 0.4318 0.3302)
							(mid 0.402042 0.402042)
							(end 0.3302 0.4318)
						)
					)
					(width 0)
					(fill yes)
				)
			)
		)
	)
	(footprint ""
		(layer "B.Cu")
		(at 147.946618 -33.53562)
		(property "Reference" "R2920"
			(at 0 0 0)
			(layer "B.SilkS")
			(hide yes)
			(effects
				(font
					(size 1.27 1.27)
				)
				(justify mirror)
			)
		)
		(property "Value" "0R2J-2-GP"
			(at -0.064008 -3.993896 0)
			(unlocked yes)
			(layer "B.Fab")
			(hide yes)
			(effects
				(font
					(size 1.016 1.016)
					(thickness 0.1524)
				)
				(justify mirror)
			)
		)
		(property "Device Type" "R402H16"
			(at -0.064008 -5.517896 0)
			(unlocked yes)
			(layer "B.Fab")
			(hide yes)
			(effects
				(font
					(size 1.016 1.016)
					(thickness 0.1524)
				)
				(justify mirror)
			)
		)
		(duplicate_pad_numbers_are_jumpers no)
		(fp_line
			(start -0.508 -0.9398)
			(end 0.508 -0.9398)
			(stroke
				(width 0.1524)
				(type default)
			)
			(layer "B.SilkS")
		)
		(fp_line
			(start 0.508 -0.9398)
			(end 0.508 0.9398)
			(stroke
				(width 0.1524)
				(type default)
			)
			(layer "B.SilkS")
		)
		(fp_rect
			(start 0.508 0.9398)
			(end -0.508 -0.9398)
			(stroke
				(width 0)
				(type default)
			)
			(fill no)
			(layer "B.CrtYd")
		)
		(fp_rect
			(start 0.508 0.9398)
			(end -0.508 -0.9398)
			(stroke
				(width 0)
				(type default)
			)
			(fill no)
			(layer "B.Fab")
		)
		(pad "1" smd custom
			(at 0 -0.4445 180)
			(size 0.1397 0.1397)
			(layers "B.Cu" "B.Mask" "B.Paste")
			(net "CBL_PRSNT_N_2")
			(options
				(clearance outline)
				(anchor circle)
			)
			(primitives
				(gr_poly
					(pts
						(arc
							(start -0.1778 0.2794)
							(mid -0.249642 0.249642)
							(end -0.2794 0.1778)
						)
						(arc
							(start -0.2794 -0.1778)
							(mid -0.249642 -0.249642)
							(end -0.1778 -0.2794)
						)
						(arc
							(start 0.1778 -0.2794)
							(mid 0.249642 -0.249642)
							(end 0.2794 -0.1778)
						)
						(arc
							(start 0.2794 0.1778)
							(mid 0.249642 0.249642)
							(end 0.1778 0.2794)
						)
					)
					(width 0)
					(fill yes)
				)
			)
		)
		(pad "2" smd custom
			(at 0 0.4445 180)
			(size 0.1397 0.1397)
			(layers "B.Cu" "B.Mask" "B.Paste")
			(net "8644_CBL_PRSNT_R_2")
			(options
				(clearance outline)
				(anchor circle)
			)
			(primitives
				(gr_poly
					(pts
						(arc
							(start -0.1778 0.2794)
							(mid -0.249642 0.249642)
							(end -0.2794 0.1778)
						)
						(arc
							(start -0.2794 -0.1778)
							(mid -0.249642 -0.249642)
							(end -0.1778 -0.2794)
						)
						(arc
							(start 0.1778 -0.2794)
							(mid 0.249642 -0.249642)
							(end 0.2794 -0.1778)
						)
						(arc
							(start 0.2794 0.1778)
							(mid 0.249642 0.249642)
							(end 0.1778 0.2794)
						)
					)
					(width 0)
					(fill yes)
				)
			)
		)
	)
	(footprint ""
		(layer "B.Cu")
		(at 230.604822 -60.1218)
		(property "Reference" "C543"
			(at 0 0 0)
			(layer "B.SilkS")
			(hide yes)
			(effects
				(font
					(size 1.27 1.27)
				)
				(justify mirror)
			)
		)
		(property "Value" "SCD1U16V1KX-1-GP"
			(at 2.8321 -1.7399 0)
			(unlocked yes)
			(layer "B.Fab")
			(hide yes)
			(effects
				(font
					(size 1.016 1.016)
					(thickness 0.1524)
				)
				(justify mirror)
			)
		)
		(property "Device Type" "C0201H13"
			(at 2.8321 -3.2639 0)
			(unlocked yes)
			(layer "B.Fab")
			(hide yes)
			(effects
				(font
					(size 1.016 1.016)
					(thickness 0.1524)
				)
				(justify mirror)
			)
		)
		(duplicate_pad_numbers_are_jumpers no)
		(fp_rect
			(start 0.2794 0.6477)
			(end -0.2794 -0.6477)
			(stroke
				(width 0)
				(type default)
			)
			(fill no)
			(layer "B.CrtYd")
		)
		(fp_rect
			(start 0.2794 0.6477)
			(end -0.2794 -0.6477)
			(stroke
				(width 0)
				(type default)
			)
			(fill no)
			(layer "B.Fab")
		)
		(pad "1" smd custom
			(at 0 -0.2794 180)
			(size 0.0762 0.0762)
			(layers "B.Cu" "B.Mask" "B.Paste")
			(net "DUT_AVD_PCIE")
			(options
				(clearance outline)
				(anchor circle)
			)
			(primitives
				(gr_poly
					(pts
						(arc
							(start 0.1524 0.127)
							(mid 0.137521 0.162921)
							(end 0.1016 0.1778)
						)
						(arc
							(start -0.1016 0.1778)
							(mid -0.137521 0.162921)
							(end -0.1524 0.127)
						)
						(arc
							(start -0.1524 -0.127)
							(mid -0.137521 -0.162921)
							(end -0.1016 -0.1778)
						)
						(arc
							(start 0.1016 -0.1778)
							(mid 0.137521 -0.162921)
							(end 0.1524 -0.127)
						)
					)
					(width 0)
					(fill yes)
				)
			)
		)
		(pad "2" smd custom
			(at 0 0.2794 180)
			(size 0.0762 0.0762)
			(layers "B.Cu" "B.Mask" "B.Paste")
			(net "GND")
			(options
				(clearance outline)
				(anchor circle)
			)
			(primitives
				(gr_poly
					(pts
						(arc
							(start 0.1524 0.127)
							(mid 0.137521 0.162921)
							(end 0.1016 0.1778)
						)
						(arc
							(start -0.1016 0.1778)
							(mid -0.137521 0.162921)
							(end -0.1524 0.127)
						)
						(arc
							(start -0.1524 -0.127)
							(mid -0.137521 -0.162921)
							(end -0.1016 -0.1778)
						)
						(arc
							(start 0.1016 -0.1778)
							(mid 0.137521 -0.162921)
							(end 0.1524 -0.127)
						)
					)
					(width 0)
					(fill yes)
				)
			)
		)
	)
	(footprint ""
		(layer "B.Cu")
		(at 252.603 -55.998872 -90)
		(property "Reference" "C579"
			(at 0 0 90)
			(layer "B.SilkS")
			(hide yes)
			(effects
				(font
					(size 1.27 1.27)
				)
				(justify mirror)
			)
		)
		(property "Value" "SCD1U16V1KX-1-GP"
			(at 2.8321 -1.7399 270)
			(unlocked yes)
			(layer "B.Fab")
			(hide yes)
			(effects
				(font
					(size 1.016 1.016)
					(thickness 0.1524)
				)
				(justify mirror)
			)
		)
		(property "Device Type" "C0201H13"
			(at 2.8321 -3.2639 270)
			(unlocked yes)
			(layer "B.Fab")
			(hide yes)
			(effects
				(font
					(size 1.016 1.016)
					(thickness 0.1524)
				)
				(justify mirror)
			)
		)
		(duplicate_pad_numbers_are_jumpers no)
		(fp_rect
			(start 0.2794 0.6477)
			(end -0.2794 -0.6477)
			(stroke
				(width 0)
				(type default)
			)
			(fill no)
			(layer "B.CrtYd")
		)
		(fp_rect
			(start 0.2794 0.6477)
			(end -0.2794 -0.6477)
			(stroke
				(width 0)
				(type default)
			)
			(fill no)
			(layer "B.Fab")
		)
		(pad "1" smd custom
			(at 0 -0.2794 90)
			(size 0.0762 0.0762)
			(layers "B.Cu" "B.Mask" "B.Paste")
			(net "DUT_AVD_PCIE")
			(options
				(clearance outline)
				(anchor circle)
			)
			(primitives
				(gr_poly
					(pts
						(arc
							(start 0.1524 0.127)
							(mid 0.137521 0.162921)
							(end 0.1016 0.1778)
						)
						(arc
							(start -0.1016 0.1778)
							(mid -0.137521 0.162921)
							(end -0.1524 0.127)
						)
						(arc
							(start -0.1524 -0.127)
							(mid -0.137521 -0.162921)
							(end -0.1016 -0.1778)
						)
						(arc
							(start 0.1016 -0.1778)
							(mid 0.137521 -0.162921)
							(end 0.1524 -0.127)
						)
					)
					(width 0)
					(fill yes)
				)
			)
		)
		(pad "2" smd custom
			(at 0 0.2794 90)
			(size 0.0762 0.0762)
			(layers "B.Cu" "B.Mask" "B.Paste")
			(net "GND")
			(options
				(clearance outline)
				(anchor circle)
			)
			(primitives
				(gr_poly
					(pts
						(arc
							(start 0.1524 0.127)
							(mid 0.137521 0.162921)
							(end 0.1016 0.1778)
						)
						(arc
							(start -0.1016 0.1778)
							(mid -0.137521 0.162921)
							(end -0.1524 0.127)
						)
						(arc
							(start -0.1524 -0.127)
							(mid -0.137521 -0.162921)
							(end -0.1016 -0.1778)
						)
						(arc
							(start 0.1016 -0.1778)
							(mid 0.137521 -0.162921)
							(end 0.1524 -0.127)
						)
					)
					(width 0)
					(fill yes)
				)
			)
		)
	)
	(footprint ""
		(layer "B.Cu")
		(at 249.428 -25.4 -90)
		(property "Reference" "TP287"
			(at 0 0 90)
			(layer "B.SilkS")
			(hide yes)
			(effects
				(font
					(size 1.27 1.27)
				)
				(justify mirror)
			)
		)
		(property "Value" "TPAD28-2-GP"
			(at 0.0127 -1.6637 270)
			(unlocked yes)
			(layer "B.Fab")
			(hide yes)
			(effects
				(font
					(size 1.016 1.016)
					(thickness 0.1524)
				)
				(justify mirror)
			)
		)
		(property "Device Type" "TPAD28"
			(at 0.0127 -3.1877 270)
			(unlocked yes)
			(layer "B.Fab")
			(hide yes)
			(effects
				(font
					(size 1.016 1.016)
					(thickness 0.1524)
				)
				(justify mirror)
			)
		)
		(duplicate_pad_numbers_are_jumpers no)
		(fp_poly
			(pts
				(arc
					(start 0 -0.3556)
					(mid 0 0.3556)
					(end 0 -0.3556)
				)
			)
			(stroke
				(width 0)
				(type default)
			)
			(fill no)
			(layer "B.CrtYd")
		)
		(fp_poly
			(pts
				(arc
					(start 0 -0.6096)
					(mid 0 0.6096)
					(end 0 -0.6096)
				)
			)
			(stroke
				(width 0)
				(type default)
			)
			(fill no)
			(layer "B.Fab")
		)
		(pad "1" smd circle
			(at 0 0 90)
			(size 0.7112 0.7112)
			(layers "B.Cu" "B.Mask" "B.Paste")
			(net "TWI_SDA5")
		)
	)
	(footprint ""
		(layer "B.Cu")
		(at 242.0366 -25.1206)
		(property "Reference" "TP211"
			(at 0 0 0)
			(layer "B.SilkS")
			(hide yes)
			(effects
				(font
					(size 1.27 1.27)
				)
				(justify mirror)
			)
		)
		(property "Value" "TPAD28-2-GP"
			(at 0.0127 -1.6637 0)
			(unlocked yes)
			(layer "B.Fab")
			(hide yes)
			(effects
				(font
					(size 1.016 1.016)
					(thickness 0.1524)
				)
				(justify mirror)
			)
		)
		(property "Device Type" "TPAD28"
			(at 0.0127 -3.1877 0)
			(unlocked yes)
			(layer "B.Fab")
			(hide yes)
			(effects
				(font
					(size 1.016 1.016)
					(thickness 0.1524)
				)
				(justify mirror)
			)
		)
		(duplicate_pad_numbers_are_jumpers no)
		(fp_poly
			(pts
				(arc
					(start 0.3556 0)
					(mid -0.3556 0)
					(end 0.3556 0)
				)
			)
			(stroke
				(width 0)
				(type default)
			)
			(fill no)
			(layer "B.CrtYd")
		)
		(fp_poly
			(pts
				(arc
					(start 0.6096 0)
					(mid -0.6096 0)
					(end 0.6096 0)
				)
			)
			(stroke
				(width 0)
				(type default)
			)
			(fill no)
			(layer "B.Fab")
		)
		(pad "1" smd circle
			(at 0 0 180)
			(size 0.7112 0.7112)
			(layers "B.Cu" "B.Mask" "B.Paste")
			(net "LBI_DATA_2")
		)
	)
	(footprint ""
		(layer "B.Cu")
		(at 312.039 -68.58 180)
		(property "Reference" "PC180"
			(at 0 0 0)
			(layer "B.SilkS")
			(hide yes)
			(effects
				(font
					(size 1.27 1.27)
				)
				(justify mirror)
			)
		)
		(property "Value" "SC22U6D3V5MX-5-GP"
			(at 0.0762 -6.1214 180)
			(unlocked yes)
			(layer "B.Fab")
			(hide yes)
			(effects
				(font
					(size 1.016 1.016)
					(thickness 0.1524)
				)
				(justify mirror)
			)
		)
		(property "Device Type" "C805H56"
			(at 0.0762 -8.1534 180)
			(unlocked yes)
			(layer "B.Fab")
			(hide yes)
			(effects
				(font
					(size 1.016 1.016)
					(thickness 0.1524)
				)
				(justify mirror)
			)
		)
		(duplicate_pad_numbers_are_jumpers no)
		(fp_line
			(start -0.635 0)
			(end 0.635 0)
			(stroke
				(width 0.508)
				(type default)
			)
			(layer "B.SilkS")
		)
		(fp_rect
			(start 0.9652 1.778)
			(end -0.9652 -1.778)
			(stroke
				(width 0)
				(type default)
			)
			(fill no)
			(layer "B.CrtYd")
		)
		(fp_poly
			(pts
				(xy 0.9652 -1.778) (xy -0.9652 -1.778) (xy -0.9652 1.778) (xy 0.9652 1.778)
			)
			(stroke
				(width 0)
				(type default)
			)
			(fill no)
			(layer "B.Fab")
		)
		(pad "1" smd rect
			(at 0 -0.9652)
			(size 1.397 1.143)
			(layers "B.Cu" "B.Mask" "B.Paste")
			(net "P0V9_E")
		)
		(pad "2" smd rect
			(at 0 0.9652)
			(size 1.397 1.143)
			(layers "B.Cu" "B.Mask" "B.Paste")
			(net "GND")
		)
	)
	(footprint ""
		(layer "B.Cu")
		(at 226.822 -20.447)
		(property "Reference" "R3704"
			(at 0 0 0)
			(layer "B.SilkS")
			(hide yes)
			(effects
				(font
					(size 1.27 1.27)
				)
				(justify mirror)
			)
		)
		(property "Value" "4K7R2F-GP"
			(at -0.064008 -3.993896 0)
			(unlocked yes)
			(layer "B.Fab")
			(hide yes)
			(effects
				(font
					(size 1.016 1.016)
					(thickness 0.1524)
				)
				(justify mirror)
			)
		)
		(property "Device Type" "R402H16"
			(at -0.064008 -5.517896 0)
			(unlocked yes)
			(layer "B.Fab")
			(hide yes)
			(effects
				(font
					(size 1.016 1.016)
					(thickness 0.1524)
				)
				(justify mirror)
			)
		)
		(duplicate_pad_numbers_are_jumpers no)
		(fp_line
			(start -0.508 -0.9398)
			(end 0.508 -0.9398)
			(stroke
				(width 0.1524)
				(type default)
			)
			(layer "B.SilkS")
		)
		(fp_line
			(start 0.508 -0.9398)
			(end 0.508 0.9398)
			(stroke
				(width 0.1524)
				(type default)
			)
			(layer "B.SilkS")
		)
		(fp_rect
			(start 0.508 0.9398)
			(end -0.508 -0.9398)
			(stroke
				(width 0)
				(type default)
			)
			(fill no)
			(layer "B.CrtYd")
		)
		(fp_rect
			(start 0.508 0.9398)
			(end -0.508 -0.9398)
			(stroke
				(width 0)
				(type default)
			)
			(fill no)
			(layer "B.Fab")
		)
		(pad "1" smd custom
			(at 0 -0.4445 180)
			(size 0.1397 0.1397)
			(layers "B.Cu" "B.Mask" "B.Paste")
			(net "HOST4_RST_N_LS")
			(options
				(clearance outline)
				(anchor circle)
			)
			(primitives
				(gr_poly
					(pts
						(arc
							(start -0.1778 0.2794)
							(mid -0.249642 0.249642)
							(end -0.2794 0.1778)
						)
						(arc
							(start -0.2794 -0.1778)
							(mid -0.249642 -0.249642)
							(end -0.1778 -0.2794)
						)
						(arc
							(start 0.1778 -0.2794)
							(mid 0.249642 -0.249642)
							(end 0.2794 -0.1778)
						)
						(arc
							(start 0.2794 0.1778)
							(mid 0.249642 0.249642)
							(end 0.1778 0.2794)
						)
					)
					(width 0)
					(fill yes)
				)
			)
		)
		(pad "2" smd custom
			(at 0 0.4445 180)
			(size 0.1397 0.1397)
			(layers "B.Cu" "B.Mask" "B.Paste")
			(net "DUT_VDDO")
			(options
				(clearance outline)
				(anchor circle)
			)
			(primitives
				(gr_poly
					(pts
						(arc
							(start -0.1778 0.2794)
							(mid -0.249642 0.249642)
							(end -0.2794 0.1778)
						)
						(arc
							(start -0.2794 -0.1778)
							(mid -0.249642 -0.249642)
							(end -0.1778 -0.2794)
						)
						(arc
							(start 0.1778 -0.2794)
							(mid 0.249642 -0.249642)
							(end 0.2794 -0.1778)
						)
						(arc
							(start 0.2794 0.1778)
							(mid 0.249642 0.249642)
							(end 0.1778 0.2794)
						)
					)
					(width 0)
					(fill yes)
				)
			)
		)
	)
	(footprint ""
		(layer "B.Cu")
		(at 238.252 -20.447)
		(property "Reference" "R797"
			(at 0 0 0)
			(layer "B.SilkS")
			(hide yes)
			(effects
				(font
					(size 1.27 1.27)
				)
				(justify mirror)
			)
		)
		(property "Value" "4K7R2F-GP"
			(at -0.064008 -3.993896 0)
			(unlocked yes)
			(layer "B.Fab")
			(hide yes)
			(effects
				(font
					(size 1.016 1.016)
					(thickness 0.1524)
				)
				(justify mirror)
			)
		)
		(property "Device Type" "R402H16"
			(at -0.064008 -5.517896 0)
			(unlocked yes)
			(layer "B.Fab")
			(hide yes)
			(effects
				(font
					(size 1.016 1.016)
					(thickness 0.1524)
				)
				(justify mirror)
			)
		)
		(duplicate_pad_numbers_are_jumpers no)
		(fp_line
			(start -0.508 -0.9398)
			(end 0.508 -0.9398)
			(stroke
				(width 0.1524)
				(type default)
			)
			(layer "B.SilkS")
		)
		(fp_line
			(start 0.508 -0.9398)
			(end 0.508 0.9398)
			(stroke
				(width 0.1524)
				(type default)
			)
			(layer "B.SilkS")
		)
		(fp_rect
			(start 0.508 0.9398)
			(end -0.508 -0.9398)
			(stroke
				(width 0)
				(type default)
			)
			(fill no)
			(layer "B.CrtYd")
		)
		(fp_rect
			(start 0.508 0.9398)
			(end -0.508 -0.9398)
			(stroke
				(width 0)
				(type default)
			)
			(fill no)
			(layer "B.Fab")
		)
		(pad "1" smd custom
			(at 0 -0.4445 180)
			(size 0.1397 0.1397)
			(layers "B.Cu" "B.Mask" "B.Paste")
			(net "BOOTSTRAP2")
			(options
				(clearance outline)
				(anchor circle)
			)
			(primitives
				(gr_poly
					(pts
						(arc
							(start -0.1778 0.2794)
							(mid -0.249642 0.249642)
							(end -0.2794 0.1778)
						)
						(arc
							(start -0.2794 -0.1778)
							(mid -0.249642 -0.249642)
							(end -0.1778 -0.2794)
						)
						(arc
							(start 0.1778 -0.2794)
							(mid 0.249642 -0.249642)
							(end 0.2794 -0.1778)
						)
						(arc
							(start 0.2794 0.1778)
							(mid 0.249642 0.249642)
							(end 0.1778 0.2794)
						)
					)
					(width 0)
					(fill yes)
				)
			)
		)
		(pad "2" smd custom
			(at 0 0.4445 180)
			(size 0.1397 0.1397)
			(layers "B.Cu" "B.Mask" "B.Paste")
			(net "DUT_VDDO")
			(options
				(clearance outline)
				(anchor circle)
			)
			(primitives
				(gr_poly
					(pts
						(arc
							(start -0.1778 0.2794)
							(mid -0.249642 0.249642)
							(end -0.2794 0.1778)
						)
						(arc
							(start -0.2794 -0.1778)
							(mid -0.249642 -0.249642)
							(end -0.1778 -0.2794)
						)
						(arc
							(start 0.1778 -0.2794)
							(mid 0.249642 -0.249642)
							(end 0.2794 -0.1778)
						)
						(arc
							(start 0.2794 0.1778)
							(mid 0.249642 0.249642)
							(end 0.1778 0.2794)
						)
					)
					(width 0)
					(fill yes)
				)
			)
		)
	)
	(footprint ""
		(layer "B.Cu")
		(at 53.4162 -115.7732)
		(property "Reference" "R531"
			(at 0 0 0)
			(layer "B.SilkS")
			(hide yes)
			(effects
				(font
					(size 1.27 1.27)
				)
				(justify mirror)
			)
		)
		(property "Value" "0R2J-2-GP"
			(at -0.064008 -3.993896 0)
			(unlocked yes)
			(layer "B.Fab")
			(hide yes)
			(effects
				(font
					(size 1.016 1.016)
					(thickness 0.1524)
				)
				(justify mirror)
			)
		)
		(property "Device Type" "R402H16"
			(at -0.064008 -5.517896 0)
			(unlocked yes)
			(layer "B.Fab")
			(hide yes)
			(effects
				(font
					(size 1.016 1.016)
					(thickness 0.1524)
				)
				(justify mirror)
			)
		)
		(duplicate_pad_numbers_are_jumpers no)
		(fp_line
			(start -0.508 -0.9398)
			(end 0.508 -0.9398)
			(stroke
				(width 0.1524)
				(type default)
			)
			(layer "B.SilkS")
		)
		(fp_line
			(start 0.508 -0.9398)
			(end 0.508 0.9398)
			(stroke
				(width 0.1524)
				(type default)
			)
			(layer "B.SilkS")
		)
		(fp_rect
			(start 0.508 0.9398)
			(end -0.508 -0.9398)
			(stroke
				(width 0)
				(type default)
			)
			(fill no)
			(layer "B.CrtYd")
		)
		(fp_rect
			(start 0.508 0.9398)
			(end -0.508 -0.9398)
			(stroke
				(width 0)
				(type default)
			)
			(fill no)
			(layer "B.Fab")
		)
		(pad "1" smd custom
			(at 0 -0.4445 180)
			(size 0.1397 0.1397)
			(layers "B.Cu" "B.Mask" "B.Paste")
			(net "BMC0_SCL12_R")
			(options
				(clearance outline)
				(anchor circle)
			)
			(primitives
				(gr_poly
					(pts
						(arc
							(start -0.1778 0.2794)
							(mid -0.249642 0.249642)
							(end -0.2794 0.1778)
						)
						(arc
							(start -0.2794 -0.1778)
							(mid -0.249642 -0.249642)
							(end -0.1778 -0.2794)
						)
						(arc
							(start 0.1778 -0.2794)
							(mid 0.249642 -0.249642)
							(end 0.2794 -0.1778)
						)
						(arc
							(start 0.2794 0.1778)
							(mid 0.249642 0.249642)
							(end 0.1778 0.2794)
						)
					)
					(width 0)
					(fill yes)
				)
			)
		)
		(pad "2" smd custom
			(at 0 0.4445 180)
			(size 0.1397 0.1397)
			(layers "B.Cu" "B.Mask" "B.Paste")
			(net "BMC_I2C12_MINI6_SCL_S")
			(options
				(clearance outline)
				(anchor circle)
			)
			(primitives
				(gr_poly
					(pts
						(arc
							(start -0.1778 0.2794)
							(mid -0.249642 0.249642)
							(end -0.2794 0.1778)
						)
						(arc
							(start -0.2794 -0.1778)
							(mid -0.249642 -0.249642)
							(end -0.1778 -0.2794)
						)
						(arc
							(start 0.1778 -0.2794)
							(mid 0.249642 -0.249642)
							(end 0.2794 -0.1778)
						)
						(arc
							(start 0.2794 0.1778)
							(mid 0.249642 0.249642)
							(end 0.1778 0.2794)
						)
					)
					(width 0)
					(fill yes)
				)
			)
		)
	)
	(footprint ""
		(layer "B.Cu")
		(at 341.6046 -181.8386)
		(property "Reference" "R3243"
			(at 0 0 0)
			(layer "B.SilkS")
			(hide yes)
			(effects
				(font
					(size 1.27 1.27)
				)
				(justify mirror)
			)
		)
		(property "Value" "0R2J-2-GP"
			(at -0.064008 -3.993896 0)
			(unlocked yes)
			(layer "B.Fab")
			(hide yes)
			(effects
				(font
					(size 1.016 1.016)
					(thickness 0.1524)
				)
				(justify mirror)
			)
		)
		(property "Device Type" "R402H16"
			(at -0.064008 -5.517896 0)
			(unlocked yes)
			(layer "B.Fab")
			(hide yes)
			(effects
				(font
					(size 1.016 1.016)
					(thickness 0.1524)
				)
				(justify mirror)
			)
		)
		(duplicate_pad_numbers_are_jumpers no)
		(fp_line
			(start -0.508 -0.9398)
			(end 0.508 -0.9398)
			(stroke
				(width 0.1524)
				(type default)
			)
			(layer "B.SilkS")
		)
		(fp_line
			(start 0.508 -0.9398)
			(end 0.508 0.9398)
			(stroke
				(width 0.1524)
				(type default)
			)
			(layer "B.SilkS")
		)
		(fp_rect
			(start 0.508 0.9398)
			(end -0.508 -0.9398)
			(stroke
				(width 0)
				(type default)
			)
			(fill no)
			(layer "B.CrtYd")
		)
		(fp_rect
			(start 0.508 0.9398)
			(end -0.508 -0.9398)
			(stroke
				(width 0)
				(type default)
			)
			(fill no)
			(layer "B.Fab")
		)
		(pad "1" smd custom
			(at 0 -0.4445 180)
			(size 0.1397 0.1397)
			(layers "B.Cu" "B.Mask" "B.Paste")
			(net "SSD_PERST#14")
			(options
				(clearance outline)
				(anchor circle)
			)
			(primitives
				(gr_poly
					(pts
						(arc
							(start -0.1778 0.2794)
							(mid -0.249642 0.249642)
							(end -0.2794 0.1778)
						)
						(arc
							(start -0.2794 -0.1778)
							(mid -0.249642 -0.249642)
							(end -0.1778 -0.2794)
						)
						(arc
							(start 0.1778 -0.2794)
							(mid 0.249642 -0.249642)
							(end 0.2794 -0.1778)
						)
						(arc
							(start 0.2794 0.1778)
							(mid 0.249642 0.249642)
							(end 0.1778 0.2794)
						)
					)
					(width 0)
					(fill yes)
				)
			)
		)
		(pad "2" smd custom
			(at 0 0.4445 180)
			(size 0.1397 0.1397)
			(layers "B.Cu" "B.Mask" "B.Paste")
			(net "SSD_PERST#0_B14")
			(options
				(clearance outline)
				(anchor circle)
			)
			(primitives
				(gr_poly
					(pts
						(arc
							(start -0.1778 0.2794)
							(mid -0.249642 0.249642)
							(end -0.2794 0.1778)
						)
						(arc
							(start -0.2794 -0.1778)
							(mid -0.249642 -0.249642)
							(end -0.1778 -0.2794)
						)
						(arc
							(start 0.1778 -0.2794)
							(mid 0.249642 -0.249642)
							(end 0.2794 -0.1778)
						)
						(arc
							(start 0.2794 0.1778)
							(mid 0.249642 0.249642)
							(end 0.1778 0.2794)
						)
					)
					(width 0)
					(fill yes)
				)
			)
		)
	)
	(footprint ""
		(layer "B.Cu")
		(at 310.007 -66.929 180)
		(property "Reference" "PG56"
			(at 0 0 0)
			(layer "B.SilkS")
			(hide yes)
			(effects
				(font
					(size 1.27 1.27)
				)
				(justify mirror)
			)
		)
		(property "Value" "GAP-CLOSE-PWR-3-GP"
			(at -0.0254 -6.5786 180)
			(unlocked yes)
			(layer "B.Fab")
			(hide yes)
			(effects
				(font
					(size 1.016 1.016)
					(thickness 0.1524)
				)
				(justify mirror)
			)
		)
		(property "Device Type" "GAP-CLOSE-PWR-3"
			(at -0.0254 -8.255 180)
			(unlocked yes)
			(layer "B.Fab")
			(hide yes)
			(effects
				(font
					(size 1.016 1.016)
					(thickness 0.1524)
				)
				(justify mirror)
			)
		)
		(duplicate_pad_numbers_are_jumpers no)
		(fp_rect
			(start 0.7112 0.4572)
			(end -0.7112 -0.4572)
			(stroke
				(width 0)
				(type default)
			)
			(fill no)
			(layer "B.CrtYd")
		)
		(fp_poly
			(pts
				(xy 0.7112 -0.4572) (xy -0.7112 -0.4572) (xy -0.7112 0.4572) (xy 0.7112 0.4572)
			)
			(stroke
				(width 0)
				(type default)
			)
			(fill no)
			(layer "B.Fab")
		)
		(pad "1" smd rect
			(at 0.3048 0)
			(size 0.6604 0.762)
			(layers "B.Cu" "B.Mask" "B.Paste")
			(net "DUT_VDD")
		)
		(pad "2" smd rect
			(at -0.3048 0)
			(size 0.6604 0.762)
			(layers "B.Cu" "B.Mask" "B.Paste")
			(net "P0V9_E")
		)
	)
	(footprint ""
		(layer "B.Cu")
		(at 252.603 -51.985672 -90)
		(property "Reference" "C550"
			(at 0 0 90)
			(layer "B.SilkS")
			(hide yes)
			(effects
				(font
					(size 1.27 1.27)
				)
				(justify mirror)
			)
		)
		(property "Value" "SCD1U16V1KX-1-GP"
			(at 2.8321 -1.7399 270)
			(unlocked yes)
			(layer "B.Fab")
			(hide yes)
			(effects
				(font
					(size 1.016 1.016)
					(thickness 0.1524)
				)
				(justify mirror)
			)
		)
		(property "Device Type" "C0201H13"
			(at 2.8321 -3.2639 270)
			(unlocked yes)
			(layer "B.Fab")
			(hide yes)
			(effects
				(font
					(size 1.016 1.016)
					(thickness 0.1524)
				)
				(justify mirror)
			)
		)
		(duplicate_pad_numbers_are_jumpers no)
		(fp_rect
			(start 0.2794 0.6477)
			(end -0.2794 -0.6477)
			(stroke
				(width 0)
				(type default)
			)
			(fill no)
			(layer "B.CrtYd")
		)
		(fp_rect
			(start 0.2794 0.6477)
			(end -0.2794 -0.6477)
			(stroke
				(width 0)
				(type default)
			)
			(fill no)
			(layer "B.Fab")
		)
		(pad "1" smd custom
			(at 0 -0.2794 90)
			(size 0.0762 0.0762)
			(layers "B.Cu" "B.Mask" "B.Paste")
			(net "DUT_AVD_PCIE")
			(options
				(clearance outline)
				(anchor circle)
			)
			(primitives
				(gr_poly
					(pts
						(arc
							(start 0.1524 0.127)
							(mid 0.137521 0.162921)
							(end 0.1016 0.1778)
						)
						(arc
							(start -0.1016 0.1778)
							(mid -0.137521 0.162921)
							(end -0.1524 0.127)
						)
						(arc
							(start -0.1524 -0.127)
							(mid -0.137521 -0.162921)
							(end -0.1016 -0.1778)
						)
						(arc
							(start 0.1016 -0.1778)
							(mid 0.137521 -0.162921)
							(end 0.1524 -0.127)
						)
					)
					(width 0)
					(fill yes)
				)
			)
		)
		(pad "2" smd custom
			(at 0 0.2794 90)
			(size 0.0762 0.0762)
			(layers "B.Cu" "B.Mask" "B.Paste")
			(net "GND")
			(options
				(clearance outline)
				(anchor circle)
			)
			(primitives
				(gr_poly
					(pts
						(arc
							(start 0.1524 0.127)
							(mid 0.137521 0.162921)
							(end 0.1016 0.1778)
						)
						(arc
							(start -0.1016 0.1778)
							(mid -0.137521 0.162921)
							(end -0.1524 0.127)
						)
						(arc
							(start -0.1524 -0.127)
							(mid -0.137521 -0.162921)
							(end -0.1016 -0.1778)
						)
						(arc
							(start 0.1016 -0.1778)
							(mid 0.137521 -0.162921)
							(end 0.1524 -0.127)
						)
					)
					(width 0)
					(fill yes)
				)
			)
		)
	)
	(footprint ""
		(layer "B.Cu")
		(at 330.708 -179.07)
		(property "Reference" "R141"
			(at 0 0 0)
			(layer "B.SilkS")
			(hide yes)
			(effects
				(font
					(size 1.27 1.27)
				)
				(justify mirror)
			)
		)
		(property "Value" "4K7R2F-GP"
			(at -0.064008 -3.993896 0)
			(unlocked yes)
			(layer "B.Fab")
			(hide yes)
			(effects
				(font
					(size 1.016 1.016)
					(thickness 0.1524)
				)
				(justify mirror)
			)
		)
		(property "Device Type" "R402H16"
			(at -0.064008 -5.517896 0)
			(unlocked yes)
			(layer "B.Fab")
			(hide yes)
			(effects
				(font
					(size 1.016 1.016)
					(thickness 0.1524)
				)
				(justify mirror)
			)
		)
		(duplicate_pad_numbers_are_jumpers no)
		(fp_line
			(start -0.508 -0.9398)
			(end 0.508 -0.9398)
			(stroke
				(width 0.1524)
				(type default)
			)
			(layer "B.SilkS")
		)
		(fp_line
			(start 0.508 -0.9398)
			(end 0.508 0.9398)
			(stroke
				(width 0.1524)
				(type default)
			)
			(layer "B.SilkS")
		)
		(fp_rect
			(start 0.508 0.9398)
			(end -0.508 -0.9398)
			(stroke
				(width 0)
				(type default)
			)
			(fill no)
			(layer "B.CrtYd")
		)
		(fp_rect
			(start 0.508 0.9398)
			(end -0.508 -0.9398)
			(stroke
				(width 0)
				(type default)
			)
			(fill no)
			(layer "B.Fab")
		)
		(pad "1" smd custom
			(at 0 -0.4445 180)
			(size 0.1397 0.1397)
			(layers "B.Cu" "B.Mask" "B.Paste")
			(net "BMC_SSD_RST#0_A4")
			(options
				(clearance outline)
				(anchor circle)
			)
			(primitives
				(gr_poly
					(pts
						(arc
							(start -0.1778 0.2794)
							(mid -0.249642 0.249642)
							(end -0.2794 0.1778)
						)
						(arc
							(start -0.2794 -0.1778)
							(mid -0.249642 -0.249642)
							(end -0.1778 -0.2794)
						)
						(arc
							(start 0.1778 -0.2794)
							(mid 0.249642 -0.249642)
							(end 0.2794 -0.1778)
						)
						(arc
							(start 0.2794 0.1778)
							(mid 0.249642 0.249642)
							(end 0.1778 0.2794)
						)
					)
					(width 0)
					(fill yes)
				)
			)
		)
		(pad "2" smd custom
			(at 0 0.4445 180)
			(size 0.1397 0.1397)
			(layers "B.Cu" "B.Mask" "B.Paste")
			(net "P3V3_STBY")
			(options
				(clearance outline)
				(anchor circle)
			)
			(primitives
				(gr_poly
					(pts
						(arc
							(start -0.1778 0.2794)
							(mid -0.249642 0.249642)
							(end -0.2794 0.1778)
						)
						(arc
							(start -0.2794 -0.1778)
							(mid -0.249642 -0.249642)
							(end -0.1778 -0.2794)
						)
						(arc
							(start 0.1778 -0.2794)
							(mid 0.249642 -0.249642)
							(end 0.2794 -0.1778)
						)
						(arc
							(start 0.2794 0.1778)
							(mid 0.249642 0.249642)
							(end 0.1778 0.2794)
						)
					)
					(width 0)
					(fill yes)
				)
			)
		)
	)
	(footprint ""
		(layer "B.Cu")
		(at 245.5926 -59.0042 -90)
		(property "Reference" "C506"
			(at 0 0 90)
			(layer "B.SilkS")
			(hide yes)
			(effects
				(font
					(size 1.27 1.27)
				)
				(justify mirror)
			)
		)
		(property "Value" "SCD1U16V1KX-1-GP"
			(at 2.8321 -1.7399 270)
			(unlocked yes)
			(layer "B.Fab")
			(hide yes)
			(effects
				(font
					(size 1.016 1.016)
					(thickness 0.1524)
				)
				(justify mirror)
			)
		)
		(property "Device Type" "C0201H13"
			(at 2.8321 -3.2639 270)
			(unlocked yes)
			(layer "B.Fab")
			(hide yes)
			(effects
				(font
					(size 1.016 1.016)
					(thickness 0.1524)
				)
				(justify mirror)
			)
		)
		(duplicate_pad_numbers_are_jumpers no)
		(fp_rect
			(start 0.2794 0.6477)
			(end -0.2794 -0.6477)
			(stroke
				(width 0)
				(type default)
			)
			(fill no)
			(layer "B.CrtYd")
		)
		(fp_rect
			(start 0.2794 0.6477)
			(end -0.2794 -0.6477)
			(stroke
				(width 0)
				(type default)
			)
			(fill no)
			(layer "B.Fab")
		)
		(pad "1" smd custom
			(at 0 -0.2794 90)
			(size 0.0762 0.0762)
			(layers "B.Cu" "B.Mask" "B.Paste")
			(net "DUT_AVD_TX")
			(options
				(clearance outline)
				(anchor circle)
			)
			(primitives
				(gr_poly
					(pts
						(arc
							(start 0.1524 0.127)
							(mid 0.137521 0.162921)
							(end 0.1016 0.1778)
						)
						(arc
							(start -0.1016 0.1778)
							(mid -0.137521 0.162921)
							(end -0.1524 0.127)
						)
						(arc
							(start -0.1524 -0.127)
							(mid -0.137521 -0.162921)
							(end -0.1016 -0.1778)
						)
						(arc
							(start 0.1016 -0.1778)
							(mid 0.137521 -0.162921)
							(end 0.1524 -0.127)
						)
					)
					(width 0)
					(fill yes)
				)
			)
		)
		(pad "2" smd custom
			(at 0 0.2794 90)
			(size 0.0762 0.0762)
			(layers "B.Cu" "B.Mask" "B.Paste")
			(net "GND")
			(options
				(clearance outline)
				(anchor circle)
			)
			(primitives
				(gr_poly
					(pts
						(arc
							(start 0.1524 0.127)
							(mid 0.137521 0.162921)
							(end 0.1016 0.1778)
						)
						(arc
							(start -0.1016 0.1778)
							(mid -0.137521 0.162921)
							(end -0.1524 0.127)
						)
						(arc
							(start -0.1524 -0.127)
							(mid -0.137521 -0.162921)
							(end -0.1016 -0.1778)
						)
						(arc
							(start 0.1016 -0.1778)
							(mid 0.137521 -0.162921)
							(end 0.1524 -0.127)
						)
					)
					(width 0)
					(fill yes)
				)
			)
		)
	)
	(footprint ""
		(layer "B.Cu")
		(at 235.599986 -38.999922)
		(property "Reference" "TP135"
			(at 0 0 0)
			(layer "B.SilkS")
			(hide yes)
			(effects
				(font
					(size 1.27 1.27)
				)
				(justify mirror)
			)
		)
		(property "Value" "TPAD28-2-GP"
			(at 0.0127 -1.6637 0)
			(unlocked yes)
			(layer "B.Fab")
			(hide yes)
			(effects
				(font
					(size 1.016 1.016)
					(thickness 0.1524)
				)
				(justify mirror)
			)
		)
		(property "Device Type" "TPAD28"
			(at 0.0127 -3.1877 0)
			(unlocked yes)
			(layer "B.Fab")
			(hide yes)
			(effects
				(font
					(size 1.016 1.016)
					(thickness 0.1524)
				)
				(justify mirror)
			)
		)
		(duplicate_pad_numbers_are_jumpers no)
		(fp_poly
			(pts
				(arc
					(start 0.3556 0)
					(mid -0.3556 0)
					(end 0.3556 0)
				)
			)
			(stroke
				(width 0)
				(type default)
			)
			(fill no)
			(layer "B.CrtYd")
		)
		(fp_poly
			(pts
				(arc
					(start 0.6096 0)
					(mid -0.6096 0)
					(end 0.6096 0)
				)
			)
			(stroke
				(width 0)
				(type default)
			)
			(fill no)
			(layer "B.Fab")
		)
		(pad "1" smd circle
			(at 0 0 180)
			(size 0.7112 0.7112)
			(layers "B.Cu" "B.Mask" "B.Paste")
			(net "LBI_ADDR_12_R")
		)
	)
	(footprint ""
		(layer "B.Cu")
		(at 336.677 -184.912 180)
		(property "Reference" "R4154"
			(at 0 0 0)
			(layer "B.SilkS")
			(hide yes)
			(effects
				(font
					(size 1.27 1.27)
				)
				(justify mirror)
			)
		)
		(property "Value" "4K7R2F-GP"
			(at -0.064008 -3.993896 180)
			(unlocked yes)
			(layer "B.Fab")
			(hide yes)
			(effects
				(font
					(size 1.016 1.016)
					(thickness 0.1524)
				)
				(justify mirror)
			)
		)
		(property "Device Type" "R402H16"
			(at -0.064008 -5.517896 180)
			(unlocked yes)
			(layer "B.Fab")
			(hide yes)
			(effects
				(font
					(size 1.016 1.016)
					(thickness 0.1524)
				)
				(justify mirror)
			)
		)
		(duplicate_pad_numbers_are_jumpers no)
		(fp_line
			(start 0.508 -0.9398)
			(end 0.508 0.9398)
			(stroke
				(width 0.1524)
				(type default)
			)
			(layer "B.SilkS")
		)
		(fp_line
			(start -0.508 -0.9398)
			(end 0.508 -0.9398)
			(stroke
				(width 0.1524)
				(type default)
			)
			(layer "B.SilkS")
		)
		(fp_rect
			(start 0.508 0.9398)
			(end -0.508 -0.9398)
			(stroke
				(width 0)
				(type default)
			)
			(fill no)
			(layer "B.CrtYd")
		)
		(fp_rect
			(start 0.508 0.9398)
			(end -0.508 -0.9398)
			(stroke
				(width 0)
				(type default)
			)
			(fill no)
			(layer "B.Fab")
		)
		(pad "1" smd custom
			(at 0 -0.4445)
			(size 0.1397 0.1397)
			(layers "B.Cu" "B.Mask" "B.Paste")
			(net "SSD_PERST#14")
			(options
				(clearance outline)
				(anchor circle)
			)
			(primitives
				(gr_poly
					(pts
						(arc
							(start -0.1778 0.2794)
							(mid -0.249642 0.249642)
							(end -0.2794 0.1778)
						)
						(arc
							(start -0.2794 -0.1778)
							(mid -0.249642 -0.249642)
							(end -0.1778 -0.2794)
						)
						(arc
							(start 0.1778 -0.2794)
							(mid 0.249642 -0.249642)
							(end 0.2794 -0.1778)
						)
						(arc
							(start 0.2794 0.1778)
							(mid 0.249642 0.249642)
							(end 0.1778 0.2794)
						)
					)
					(width 0)
					(fill yes)
				)
			)
		)
		(pad "2" smd custom
			(at 0 0.4445)
			(size 0.1397 0.1397)
			(layers "B.Cu" "B.Mask" "B.Paste")
			(net "P3V3_STBY")
			(options
				(clearance outline)
				(anchor circle)
			)
			(primitives
				(gr_poly
					(pts
						(arc
							(start -0.1778 0.2794)
							(mid -0.249642 0.249642)
							(end -0.2794 0.1778)
						)
						(arc
							(start -0.2794 -0.1778)
							(mid -0.249642 -0.249642)
							(end -0.1778 -0.2794)
						)
						(arc
							(start 0.1778 -0.2794)
							(mid 0.249642 -0.249642)
							(end 0.2794 -0.1778)
						)
						(arc
							(start 0.2794 0.1778)
							(mid 0.249642 0.249642)
							(end 0.1778 0.2794)
						)
					)
					(width 0)
					(fill yes)
				)
			)
		)
	)
	(footprint ""
		(layer "B.Cu")
		(at 48.1711 -116.032788 180)
		(property "Reference" "R465"
			(at 0 0 0)
			(layer "B.SilkS")
			(hide yes)
			(effects
				(font
					(size 1.27 1.27)
				)
				(justify mirror)
			)
		)
		(property "Value" "0R2J-2-GP"
			(at -0.064008 -3.993896 180)
			(unlocked yes)
			(layer "B.Fab")
			(hide yes)
			(effects
				(font
					(size 1.016 1.016)
					(thickness 0.1524)
				)
				(justify mirror)
			)
		)
		(property "Device Type" "R402H16"
			(at -0.064008 -5.517896 180)
			(unlocked yes)
			(layer "B.Fab")
			(hide yes)
			(effects
				(font
					(size 1.016 1.016)
					(thickness 0.1524)
				)
				(justify mirror)
			)
		)
		(duplicate_pad_numbers_are_jumpers no)
		(fp_line
			(start 0.508 -0.9398)
			(end 0.508 0.9398)
			(stroke
				(width 0.1524)
				(type default)
			)
			(layer "B.SilkS")
		)
		(fp_line
			(start -0.508 -0.9398)
			(end 0.508 -0.9398)
			(stroke
				(width 0.1524)
				(type default)
			)
			(layer "B.SilkS")
		)
		(fp_rect
			(start 0.508 0.9398)
			(end -0.508 -0.9398)
			(stroke
				(width 0)
				(type default)
			)
			(fill no)
			(layer "B.CrtYd")
		)
		(fp_rect
			(start 0.508 0.9398)
			(end -0.508 -0.9398)
			(stroke
				(width 0)
				(type default)
			)
			(fill no)
			(layer "B.Fab")
		)
		(pad "1" smd custom
			(at 0 -0.4445)
			(size 0.1397 0.1397)
			(layers "B.Cu" "B.Mask" "B.Paste")
			(net "BMC_I2C9_CLKBUF2_SCL")
			(options
				(clearance outline)
				(anchor circle)
			)
			(primitives
				(gr_poly
					(pts
						(arc
							(start -0.1778 0.2794)
							(mid -0.249642 0.249642)
							(end -0.2794 0.1778)
						)
						(arc
							(start -0.2794 -0.1778)
							(mid -0.249642 -0.249642)
							(end -0.1778 -0.2794)
						)
						(arc
							(start 0.1778 -0.2794)
							(mid 0.249642 -0.249642)
							(end 0.2794 -0.1778)
						)
						(arc
							(start 0.2794 0.1778)
							(mid 0.249642 0.249642)
							(end 0.1778 0.2794)
						)
					)
					(width 0)
					(fill yes)
				)
			)
		)
		(pad "2" smd custom
			(at 0 0.4445)
			(size 0.1397 0.1397)
			(layers "B.Cu" "B.Mask" "B.Paste")
			(net "BMC0_SMB9_CLK")
			(options
				(clearance outline)
				(anchor circle)
			)
			(primitives
				(gr_poly
					(pts
						(arc
							(start -0.1778 0.2794)
							(mid -0.249642 0.249642)
							(end -0.2794 0.1778)
						)
						(arc
							(start -0.2794 -0.1778)
							(mid -0.249642 -0.249642)
							(end -0.1778 -0.2794)
						)
						(arc
							(start 0.1778 -0.2794)
							(mid 0.249642 -0.249642)
							(end 0.2794 -0.1778)
						)
						(arc
							(start 0.2794 0.1778)
							(mid 0.249642 0.249642)
							(end 0.1778 0.2794)
						)
					)
					(width 0)
					(fill yes)
				)
			)
		)
	)
	(footprint ""
		(layer "B.Cu")
		(at 271.4625 -6.6675)
		(property "Reference" "R371"
			(at 0 0 0)
			(layer "B.SilkS")
			(hide yes)
			(effects
				(font
					(size 1.27 1.27)
				)
				(justify mirror)
			)
		)
		(property "Value" "0R2J-2-GP"
			(at -0.064008 -3.993896 0)
			(unlocked yes)
			(layer "B.Fab")
			(hide yes)
			(effects
				(font
					(size 1.016 1.016)
					(thickness 0.1524)
				)
				(justify mirror)
			)
		)
		(property "Device Type" "R402H16"
			(at -0.064008 -5.517896 0)
			(unlocked yes)
			(layer "B.Fab")
			(hide yes)
			(effects
				(font
					(size 1.016 1.016)
					(thickness 0.1524)
				)
				(justify mirror)
			)
		)
		(duplicate_pad_numbers_are_jumpers no)
		(fp_line
			(start -0.508 -0.9398)
			(end 0.508 -0.9398)
			(stroke
				(width 0.1524)
				(type default)
			)
			(layer "B.SilkS")
		)
		(fp_line
			(start 0.508 -0.9398)
			(end 0.508 0.9398)
			(stroke
				(width 0.1524)
				(type default)
			)
			(layer "B.SilkS")
		)
		(fp_rect
			(start 0.508 0.9398)
			(end -0.508 -0.9398)
			(stroke
				(width 0)
				(type default)
			)
			(fill no)
			(layer "B.CrtYd")
		)
		(fp_rect
			(start 0.508 0.9398)
			(end -0.508 -0.9398)
			(stroke
				(width 0)
				(type default)
			)
			(fill no)
			(layer "B.Fab")
		)
		(pad "1" smd custom
			(at 0 -0.4445 180)
			(size 0.1397 0.1397)
			(layers "B.Cu" "B.Mask" "B.Paste")
			(net "CLK_P_7_R")
			(options
				(clearance outline)
				(anchor circle)
			)
			(primitives
				(gr_poly
					(pts
						(arc
							(start -0.1778 0.2794)
							(mid -0.249642 0.249642)
							(end -0.2794 0.1778)
						)
						(arc
							(start -0.2794 -0.1778)
							(mid -0.249642 -0.249642)
							(end -0.1778 -0.2794)
						)
						(arc
							(start 0.1778 -0.2794)
							(mid 0.249642 -0.249642)
							(end 0.2794 -0.1778)
						)
						(arc
							(start 0.2794 0.1778)
							(mid 0.249642 0.249642)
							(end 0.1778 0.2794)
						)
					)
					(width 0)
					(fill yes)
				)
			)
		)
		(pad "2" smd custom
			(at 0 0.4445 180)
			(size 0.1397 0.1397)
			(layers "B.Cu" "B.Mask" "B.Paste")
			(net "PCIE_REFCLK_H1_P_R")
			(options
				(clearance outline)
				(anchor circle)
			)
			(primitives
				(gr_poly
					(pts
						(arc
							(start -0.1778 0.2794)
							(mid -0.249642 0.249642)
							(end -0.2794 0.1778)
						)
						(arc
							(start -0.2794 -0.1778)
							(mid -0.249642 -0.249642)
							(end -0.1778 -0.2794)
						)
						(arc
							(start 0.1778 -0.2794)
							(mid 0.249642 -0.249642)
							(end 0.2794 -0.1778)
						)
						(arc
							(start 0.2794 0.1778)
							(mid 0.249642 0.249642)
							(end 0.1778 0.2794)
						)
					)
					(width 0)
					(fill yes)
				)
			)
		)
	)
	(footprint ""
		(layer "B.Cu")
		(at 41.660826 -132.51688 -90)
		(property "Reference" "C205"
			(at 0 0 90)
			(layer "B.SilkS")
			(hide yes)
			(effects
				(font
					(size 1.27 1.27)
				)
				(justify mirror)
			)
		)
		(property "Value" "SC1U10V2KX-4-GP"
			(at -1.1811 -2.7051 270)
			(unlocked yes)
			(layer "B.Fab")
			(hide yes)
			(effects
				(font
					(size 1.016 1.016)
					(thickness 0.1524)
				)
				(justify mirror)
			)
		)
		(property "Device Type" "C402H22"
			(at -1.1811 -4.2291 270)
			(unlocked yes)
			(layer "B.Fab")
			(hide yes)
			(effects
				(font
					(size 1.016 1.016)
					(thickness 0.1524)
				)
				(justify mirror)
			)
		)
		(duplicate_pad_numbers_are_jumpers no)
		(fp_rect
			(start 0.4318 0.9525)
			(end -0.4318 -0.9525)
			(stroke
				(width 0)
				(type default)
			)
			(fill no)
			(layer "B.CrtYd")
		)
		(fp_rect
			(start 0.4318 0.9525)
			(end -0.4318 -0.9525)
			(stroke
				(width 0)
				(type default)
			)
			(fill no)
			(layer "B.Fab")
		)
		(pad "1" smd custom
			(at 0 -0.4445 90)
			(size 0.1524 0.1524)
			(layers "B.Cu" "B.Mask" "B.Paste")
			(net "P1V26_STBY")
			(options
				(clearance outline)
				(anchor circle)
			)
			(primitives
				(gr_poly
					(pts
						(arc
							(start 0.3048 0.2032)
							(mid 0.275042 0.275042)
							(end 0.2032 0.3048)
						)
						(arc
							(start -0.2032 0.3048)
							(mid -0.275042 0.275042)
							(end -0.3048 0.2032)
						)
						(arc
							(start -0.3048 -0.2032)
							(mid -0.275042 -0.275042)
							(end -0.2032 -0.3048)
						)
						(arc
							(start 0.2032 -0.3048)
							(mid 0.275042 -0.275042)
							(end 0.3048 -0.2032)
						)
					)
					(width 0)
					(fill yes)
				)
			)
		)
		(pad "2" smd custom
			(at 0 0.4445 90)
			(size 0.1524 0.1524)
			(layers "B.Cu" "B.Mask" "B.Paste")
			(net "GND")
			(options
				(clearance outline)
				(anchor circle)
			)
			(primitives
				(gr_poly
					(pts
						(arc
							(start 0.3048 0.2032)
							(mid 0.275042 0.275042)
							(end 0.2032 0.3048)
						)
						(arc
							(start -0.2032 0.3048)
							(mid -0.275042 0.275042)
							(end -0.3048 0.2032)
						)
						(arc
							(start -0.3048 -0.2032)
							(mid -0.275042 -0.275042)
							(end -0.2032 -0.3048)
						)
						(arc
							(start 0.2032 -0.3048)
							(mid 0.275042 -0.275042)
							(end 0.3048 -0.2032)
						)
					)
					(width 0)
					(fill yes)
				)
			)
		)
	)
	(footprint ""
		(layer "B.Cu")
		(at 254.5588 -59.9948 90)
		(property "Reference" "C597"
			(at 0 0 90)
			(layer "B.SilkS")
			(hide yes)
			(effects
				(font
					(size 1.27 1.27)
				)
				(justify mirror)
			)
		)
		(property "Value" "SCD1U16V1KX-1-GP"
			(at 2.8321 -1.7399 90)
			(unlocked yes)
			(layer "B.Fab")
			(hide yes)
			(effects
				(font
					(size 1.016 1.016)
					(thickness 0.1524)
				)
				(justify mirror)
			)
		)
		(property "Device Type" "C0201H13"
			(at 2.8321 -3.2639 90)
			(unlocked yes)
			(layer "B.Fab")
			(hide yes)
			(effects
				(font
					(size 1.016 1.016)
					(thickness 0.1524)
				)
				(justify mirror)
			)
		)
		(duplicate_pad_numbers_are_jumpers no)
		(fp_rect
			(start 0.2794 0.6477)
			(end -0.2794 -0.6477)
			(stroke
				(width 0)
				(type default)
			)
			(fill no)
			(layer "B.CrtYd")
		)
		(fp_rect
			(start 0.2794 0.6477)
			(end -0.2794 -0.6477)
			(stroke
				(width 0)
				(type default)
			)
			(fill no)
			(layer "B.Fab")
		)
		(pad "1" smd custom
			(at 0 -0.2794 270)
			(size 0.0762 0.0762)
			(layers "B.Cu" "B.Mask" "B.Paste")
			(net "DUT_AVD_PCIE")
			(options
				(clearance outline)
				(anchor circle)
			)
			(primitives
				(gr_poly
					(pts
						(arc
							(start 0.1524 0.127)
							(mid 0.137521 0.162921)
							(end 0.1016 0.1778)
						)
						(arc
							(start -0.1016 0.1778)
							(mid -0.137521 0.162921)
							(end -0.1524 0.127)
						)
						(arc
							(start -0.1524 -0.127)
							(mid -0.137521 -0.162921)
							(end -0.1016 -0.1778)
						)
						(arc
							(start 0.1016 -0.1778)
							(mid 0.137521 -0.162921)
							(end 0.1524 -0.127)
						)
					)
					(width 0)
					(fill yes)
				)
			)
		)
		(pad "2" smd custom
			(at 0 0.2794 270)
			(size 0.0762 0.0762)
			(layers "B.Cu" "B.Mask" "B.Paste")
			(net "GND")
			(options
				(clearance outline)
				(anchor circle)
			)
			(primitives
				(gr_poly
					(pts
						(arc
							(start 0.1524 0.127)
							(mid 0.137521 0.162921)
							(end 0.1016 0.1778)
						)
						(arc
							(start -0.1016 0.1778)
							(mid -0.137521 0.162921)
							(end -0.1524 0.127)
						)
						(arc
							(start -0.1524 -0.127)
							(mid -0.137521 -0.162921)
							(end -0.1016 -0.1778)
						)
						(arc
							(start 0.1016 -0.1778)
							(mid 0.137521 -0.162921)
							(end 0.1524 -0.127)
						)
					)
					(width 0)
					(fill yes)
				)
			)
		)
	)
	(footprint ""
		(layer "B.Cu")
		(at 71.9074 -37.8206 90)
		(property "Reference" "PC27"
			(at 0 0 90)
			(layer "B.SilkS")
			(hide yes)
			(effects
				(font
					(size 1.27 1.27)
				)
				(justify mirror)
			)
		)
		(property "Value" "SCD1U50V3KX-GP"
			(at 0 -2.8194 90)
			(unlocked yes)
			(layer "B.Fab")
			(hide yes)
			(effects
				(font
					(size 1.016 1.016)
					(thickness 0.1524)
				)
				(justify mirror)
			)
		)
		(property "Device Type" "C603H36"
			(at 0 -4.3434 90)
			(unlocked yes)
			(layer "B.Fab")
			(hide yes)
			(effects
				(font
					(size 1.016 1.016)
					(thickness 0.1524)
				)
				(justify mirror)
			)
		)
		(duplicate_pad_numbers_are_jumpers no)
		(fp_line
			(start -0.508 0)
			(end 0.508 0)
			(stroke
				(width 0.2032)
				(type default)
			)
			(layer "B.SilkS")
		)
		(fp_rect
			(start 0.5842 1.3335)
			(end -0.5842 -1.3335)
			(stroke
				(width 0)
				(type default)
			)
			(fill no)
			(layer "B.CrtYd")
		)
		(fp_rect
			(start 0.5842 1.3335)
			(end -0.5842 -1.3335)
			(stroke
				(width 0)
				(type default)
			)
			(fill no)
			(layer "B.Fab")
		)
		(pad "1" smd custom
			(at 0 -0.762 270)
			(size 0.2159 0.2159)
			(layers "B.Cu" "B.Mask" "B.Paste")
			(net "P3V3_STBY_VBST_RC")
			(options
				(clearance outline)
				(anchor circle)
			)
			(primitives
				(gr_poly
					(pts
						(arc
							(start -0.3302 0.4318)
							(mid -0.402042 0.402042)
							(end -0.4318 0.3302)
						)
						(arc
							(start -0.4318 -0.3302)
							(mid -0.402042 -0.402042)
							(end -0.3302 -0.4318)
						)
						(arc
							(start 0.3302 -0.4318)
							(mid 0.402042 -0.402042)
							(end 0.4318 -0.3302)
						)
						(arc
							(start 0.4318 0.3302)
							(mid 0.402042 0.402042)
							(end 0.3302 0.4318)
						)
					)
					(width 0)
					(fill yes)
				)
			)
		)
		(pad "2" smd custom
			(at 0 0.762 270)
			(size 0.2159 0.2159)
			(layers "B.Cu" "B.Mask" "B.Paste")
			(net "P3V3_STBY_LL")
			(options
				(clearance outline)
				(anchor circle)
			)
			(primitives
				(gr_poly
					(pts
						(arc
							(start -0.3302 0.4318)
							(mid -0.402042 0.402042)
							(end -0.4318 0.3302)
						)
						(arc
							(start -0.4318 -0.3302)
							(mid -0.402042 -0.402042)
							(end -0.3302 -0.4318)
						)
						(arc
							(start 0.3302 -0.4318)
							(mid 0.402042 -0.402042)
							(end 0.4318 -0.3302)
						)
						(arc
							(start 0.4318 0.3302)
							(mid 0.402042 0.402042)
							(end 0.3302 0.4318)
						)
					)
					(width 0)
					(fill yes)
				)
			)
		)
	)
	(footprint ""
		(layer "B.Cu")
		(at 226.8474 -9.2456 180)
		(property "Reference" "R713"
			(at 0 0 0)
			(layer "B.SilkS")
			(hide yes)
			(effects
				(font
					(size 1.27 1.27)
				)
				(justify mirror)
			)
		)
		(property "Value" "4K7R2F-GP"
			(at -0.064008 -3.993896 180)
			(unlocked yes)
			(layer "B.Fab")
			(hide yes)
			(effects
				(font
					(size 1.016 1.016)
					(thickness 0.1524)
				)
				(justify mirror)
			)
		)
		(property "Device Type" "R402H16"
			(at -0.064008 -5.517896 180)
			(unlocked yes)
			(layer "B.Fab")
			(hide yes)
			(effects
				(font
					(size 1.016 1.016)
					(thickness 0.1524)
				)
				(justify mirror)
			)
		)
		(duplicate_pad_numbers_are_jumpers no)
		(fp_line
			(start 0.508 -0.9398)
			(end 0.508 0.9398)
			(stroke
				(width 0.1524)
				(type default)
			)
			(layer "B.SilkS")
		)
		(fp_line
			(start -0.508 -0.9398)
			(end 0.508 -0.9398)
			(stroke
				(width 0.1524)
				(type default)
			)
			(layer "B.SilkS")
		)
		(fp_rect
			(start 0.508 0.9398)
			(end -0.508 -0.9398)
			(stroke
				(width 0)
				(type default)
			)
			(fill no)
			(layer "B.CrtYd")
		)
		(fp_rect
			(start 0.508 0.9398)
			(end -0.508 -0.9398)
			(stroke
				(width 0)
				(type default)
			)
			(fill no)
			(layer "B.Fab")
		)
		(pad "1" smd custom
			(at 0 -0.4445)
			(size 0.1397 0.1397)
			(layers "B.Cu" "B.Mask" "B.Paste")
			(net "U81_B")
			(options
				(clearance outline)
				(anchor circle)
			)
			(primitives
				(gr_poly
					(pts
						(arc
							(start -0.1778 0.2794)
							(mid -0.249642 0.249642)
							(end -0.2794 0.1778)
						)
						(arc
							(start -0.2794 -0.1778)
							(mid -0.249642 -0.249642)
							(end -0.1778 -0.2794)
						)
						(arc
							(start 0.1778 -0.2794)
							(mid 0.249642 -0.249642)
							(end 0.2794 -0.1778)
						)
						(arc
							(start 0.2794 0.1778)
							(mid 0.249642 0.249642)
							(end 0.1778 0.2794)
						)
					)
					(width 0)
					(fill yes)
				)
			)
		)
		(pad "2" smd custom
			(at 0 0.4445)
			(size 0.1397 0.1397)
			(layers "B.Cu" "B.Mask" "B.Paste")
			(net "P3V3_STBY")
			(options
				(clearance outline)
				(anchor circle)
			)
			(primitives
				(gr_poly
					(pts
						(arc
							(start -0.1778 0.2794)
							(mid -0.249642 0.249642)
							(end -0.2794 0.1778)
						)
						(arc
							(start -0.2794 -0.1778)
							(mid -0.249642 -0.249642)
							(end -0.1778 -0.2794)
						)
						(arc
							(start 0.1778 -0.2794)
							(mid 0.249642 -0.249642)
							(end 0.2794 -0.1778)
						)
						(arc
							(start 0.2794 0.1778)
							(mid 0.249642 0.249642)
							(end 0.1778 0.2794)
						)
					)
					(width 0)
					(fill yes)
				)
			)
		)
	)
	(footprint ""
		(layer "B.Cu")
		(at 63.881 -123.444 90)
		(property "Reference" "R249"
			(at 0 0 90)
			(layer "B.SilkS")
			(hide yes)
			(effects
				(font
					(size 1.27 1.27)
				)
				(justify mirror)
			)
		)
		(property "Value" "0R2J-2-GP"
			(at -0.064008 -3.993896 90)
			(unlocked yes)
			(layer "B.Fab")
			(hide yes)
			(effects
				(font
					(size 1.016 1.016)
					(thickness 0.1524)
				)
				(justify mirror)
			)
		)
		(property "Device Type" "R402H16"
			(at -0.064008 -5.517896 90)
			(unlocked yes)
			(layer "B.Fab")
			(hide yes)
			(effects
				(font
					(size 1.016 1.016)
					(thickness 0.1524)
				)
				(justify mirror)
			)
		)
		(duplicate_pad_numbers_are_jumpers no)
		(fp_line
			(start 0.508 -0.9398)
			(end 0.508 0.9398)
			(stroke
				(width 0.1524)
				(type default)
			)
			(layer "B.SilkS")
		)
		(fp_line
			(start -0.508 -0.9398)
			(end 0.508 -0.9398)
			(stroke
				(width 0.1524)
				(type default)
			)
			(layer "B.SilkS")
		)
		(fp_rect
			(start 0.508 0.9398)
			(end -0.508 -0.9398)
			(stroke
				(width 0)
				(type default)
			)
			(fill no)
			(layer "B.CrtYd")
		)
		(fp_rect
			(start 0.508 0.9398)
			(end -0.508 -0.9398)
			(stroke
				(width 0)
				(type default)
			)
			(fill no)
			(layer "B.Fab")
		)
		(pad "1" smd custom
			(at 0 -0.4445 270)
			(size 0.1397 0.1397)
			(layers "B.Cu" "B.Mask" "B.Paste")
			(net "BMC_I2C6_C_FCB_SCL")
			(options
				(clearance outline)
				(anchor circle)
			)
			(primitives
				(gr_poly
					(pts
						(arc
							(start -0.1778 0.2794)
							(mid -0.249642 0.249642)
							(end -0.2794 0.1778)
						)
						(arc
							(start -0.2794 -0.1778)
							(mid -0.249642 -0.249642)
							(end -0.1778 -0.2794)
						)
						(arc
							(start 0.1778 -0.2794)
							(mid 0.249642 -0.249642)
							(end 0.2794 -0.1778)
						)
						(arc
							(start 0.2794 0.1778)
							(mid 0.249642 0.249642)
							(end 0.1778 0.2794)
						)
					)
					(width 0)
					(fill yes)
				)
			)
		)
		(pad "2" smd custom
			(at 0 0.4445 270)
			(size 0.1397 0.1397)
			(layers "B.Cu" "B.Mask" "B.Paste")
			(net "BMC0_SMB6_CLK")
			(options
				(clearance outline)
				(anchor circle)
			)
			(primitives
				(gr_poly
					(pts
						(arc
							(start -0.1778 0.2794)
							(mid -0.249642 0.249642)
							(end -0.2794 0.1778)
						)
						(arc
							(start -0.2794 -0.1778)
							(mid -0.249642 -0.249642)
							(end -0.1778 -0.2794)
						)
						(arc
							(start 0.1778 -0.2794)
							(mid 0.249642 -0.249642)
							(end 0.2794 -0.1778)
						)
						(arc
							(start 0.2794 0.1778)
							(mid 0.249642 0.249642)
							(end 0.1778 0.2794)
						)
					)
					(width 0)
					(fill yes)
				)
			)
		)
	)
	(footprint ""
		(layer "B.Cu")
		(at 328.549 -70.104 180)
		(property "Reference" "PR155"
			(at 0 0 0)
			(layer "B.SilkS")
			(hide yes)
			(effects
				(font
					(size 1.27 1.27)
				)
				(justify mirror)
			)
		)
		(property "Value" "2K21R2F-GP"
			(at -0.064008 -3.993896 180)
			(unlocked yes)
			(layer "B.Fab")
			(hide yes)
			(effects
				(font
					(size 1.016 1.016)
					(thickness 0.1524)
				)
				(justify mirror)
			)
		)
		(property "Device Type" "R402H16"
			(at -0.064008 -5.517896 180)
			(unlocked yes)
			(layer "B.Fab")
			(hide yes)
			(effects
				(font
					(size 1.016 1.016)
					(thickness 0.1524)
				)
				(justify mirror)
			)
		)
		(duplicate_pad_numbers_are_jumpers no)
		(fp_line
			(start 0.508 -0.9398)
			(end 0.508 0.9398)
			(stroke
				(width 0.1524)
				(type default)
			)
			(layer "B.SilkS")
		)
		(fp_line
			(start -0.508 -0.9398)
			(end 0.508 -0.9398)
			(stroke
				(width 0.1524)
				(type default)
			)
			(layer "B.SilkS")
		)
		(fp_rect
			(start 0.508 0.9398)
			(end -0.508 -0.9398)
			(stroke
				(width 0)
				(type default)
			)
			(fill no)
			(layer "B.CrtYd")
		)
		(fp_rect
			(start 0.508 0.9398)
			(end -0.508 -0.9398)
			(stroke
				(width 0)
				(type default)
			)
			(fill no)
			(layer "B.Fab")
		)
		(pad "1" smd custom
			(at 0 -0.4445)
			(size 0.1397 0.1397)
			(layers "B.Cu" "B.Mask" "B.Paste")
			(net "P0V9_E_LX")
			(options
				(clearance outline)
				(anchor circle)
			)
			(primitives
				(gr_poly
					(pts
						(arc
							(start -0.1778 0.2794)
							(mid -0.249642 0.249642)
							(end -0.2794 0.1778)
						)
						(arc
							(start -0.2794 -0.1778)
							(mid -0.249642 -0.249642)
							(end -0.1778 -0.2794)
						)
						(arc
							(start 0.1778 -0.2794)
							(mid 0.249642 -0.249642)
							(end 0.2794 -0.1778)
						)
						(arc
							(start 0.2794 0.1778)
							(mid 0.249642 0.249642)
							(end 0.1778 0.2794)
						)
					)
					(width 0)
					(fill yes)
				)
			)
		)
		(pad "2" smd custom
			(at 0 0.4445)
			(size 0.1397 0.1397)
			(layers "B.Cu" "B.Mask" "B.Paste")
			(net "P0V9_E_SW_R")
			(options
				(clearance outline)
				(anchor circle)
			)
			(primitives
				(gr_poly
					(pts
						(arc
							(start -0.1778 0.2794)
							(mid -0.249642 0.249642)
							(end -0.2794 0.1778)
						)
						(arc
							(start -0.2794 -0.1778)
							(mid -0.249642 -0.249642)
							(end -0.1778 -0.2794)
						)
						(arc
							(start 0.1778 -0.2794)
							(mid 0.249642 -0.249642)
							(end 0.2794 -0.1778)
						)
						(arc
							(start 0.2794 0.1778)
							(mid 0.249642 0.249642)
							(end 0.1778 0.2794)
						)
					)
					(width 0)
					(fill yes)
				)
			)
		)
	)
	(footprint ""
		(layer "B.Cu")
		(at 9.144 -78.3082 -90)
		(property "Reference" "C430"
			(at 0 0 90)
			(layer "B.SilkS")
			(hide yes)
			(effects
				(font
					(size 1.27 1.27)
				)
				(justify mirror)
			)
		)
		(property "Value" "SC10U6D3V5KX-4GP"
			(at 0.0762 -6.1214 270)
			(unlocked yes)
			(layer "B.Fab")
			(hide yes)
			(effects
				(font
					(size 1.016 1.016)
					(thickness 0.1524)
				)
				(justify mirror)
			)
		)
		(property "Device Type" "C805H58"
			(at 0.0762 -8.1534 270)
			(unlocked yes)
			(layer "B.Fab")
			(hide yes)
			(effects
				(font
					(size 1.016 1.016)
					(thickness 0.1524)
				)
				(justify mirror)
			)
		)
		(duplicate_pad_numbers_are_jumpers no)
		(fp_line
			(start -0.635 0)
			(end 0.635 0)
			(stroke
				(width 0.508)
				(type default)
			)
			(layer "B.SilkS")
		)
		(fp_rect
			(start 0.9652 1.778)
			(end -0.9652 -1.778)
			(stroke
				(width 0)
				(type default)
			)
			(fill no)
			(layer "B.CrtYd")
		)
		(fp_poly
			(pts
				(xy 0.9652 -1.778) (xy -0.9652 -1.778) (xy -0.9652 1.778) (xy 0.9652 1.778)
			)
			(stroke
				(width 0)
				(type default)
			)
			(fill no)
			(layer "B.Fab")
		)
		(pad "1" smd rect
			(at 0 -0.9652 90)
			(size 1.397 1.143)
			(layers "B.Cu" "B.Mask" "B.Paste")
			(net "P1V5_I210")
		)
		(pad "2" smd rect
			(at 0 0.9652 90)
			(size 1.397 1.143)
			(layers "B.Cu" "B.Mask" "B.Paste")
			(net "GND")
		)
	)
	(footprint ""
		(layer "B.Cu")
		(at 249.612912 -32.004)
		(property "Reference" "C469"
			(at 0 0 0)
			(layer "B.SilkS")
			(hide yes)
			(effects
				(font
					(size 1.27 1.27)
				)
				(justify mirror)
			)
		)
		(property "Value" "SCD1U16V1KX-1-GP"
			(at 2.8321 -1.7399 0)
			(unlocked yes)
			(layer "B.Fab")
			(hide yes)
			(effects
				(font
					(size 1.016 1.016)
					(thickness 0.1524)
				)
				(justify mirror)
			)
		)
		(property "Device Type" "C0201H13"
			(at 2.8321 -3.2639 0)
			(unlocked yes)
			(layer "B.Fab")
			(hide yes)
			(effects
				(font
					(size 1.016 1.016)
					(thickness 0.1524)
				)
				(justify mirror)
			)
		)
		(duplicate_pad_numbers_are_jumpers no)
		(fp_rect
			(start 0.2794 0.6477)
			(end -0.2794 -0.6477)
			(stroke
				(width 0)
				(type default)
			)
			(fill no)
			(layer "B.CrtYd")
		)
		(fp_rect
			(start 0.2794 0.6477)
			(end -0.2794 -0.6477)
			(stroke
				(width 0)
				(type default)
			)
			(fill no)
			(layer "B.Fab")
		)
		(pad "1" smd custom
			(at 0 -0.2794 180)
			(size 0.0762 0.0762)
			(layers "B.Cu" "B.Mask" "B.Paste")
			(net "DUT_VDDO")
			(options
				(clearance outline)
				(anchor circle)
			)
			(primitives
				(gr_poly
					(pts
						(arc
							(start 0.1524 0.127)
							(mid 0.137521 0.162921)
							(end 0.1016 0.1778)
						)
						(arc
							(start -0.1016 0.1778)
							(mid -0.137521 0.162921)
							(end -0.1524 0.127)
						)
						(arc
							(start -0.1524 -0.127)
							(mid -0.137521 -0.162921)
							(end -0.1016 -0.1778)
						)
						(arc
							(start 0.1016 -0.1778)
							(mid 0.137521 -0.162921)
							(end 0.1524 -0.127)
						)
					)
					(width 0)
					(fill yes)
				)
			)
		)
		(pad "2" smd custom
			(at 0 0.2794 180)
			(size 0.0762 0.0762)
			(layers "B.Cu" "B.Mask" "B.Paste")
			(net "GND")
			(options
				(clearance outline)
				(anchor circle)
			)
			(primitives
				(gr_poly
					(pts
						(arc
							(start 0.1524 0.127)
							(mid 0.137521 0.162921)
							(end 0.1016 0.1778)
						)
						(arc
							(start -0.1016 0.1778)
							(mid -0.137521 0.162921)
							(end -0.1524 0.127)
						)
						(arc
							(start -0.1524 -0.127)
							(mid -0.137521 -0.162921)
							(end -0.1016 -0.1778)
						)
						(arc
							(start 0.1016 -0.1778)
							(mid 0.137521 -0.162921)
							(end 0.1524 -0.127)
						)
					)
					(width 0)
					(fill yes)
				)
			)
		)
	)
	(footprint ""
		(layer "B.Cu")
		(at 219.686124 -190.601092)
		(property "Reference" "R4146"
			(at 0 0 0)
			(layer "B.SilkS")
			(hide yes)
			(effects
				(font
					(size 1.27 1.27)
				)
				(justify mirror)
			)
		)
		(property "Value" "4K7R2F-GP"
			(at -0.064008 -3.993896 0)
			(unlocked yes)
			(layer "B.Fab")
			(hide yes)
			(effects
				(font
					(size 1.016 1.016)
					(thickness 0.1524)
				)
				(justify mirror)
			)
		)
		(property "Device Type" "R402H16"
			(at -0.064008 -5.517896 0)
			(unlocked yes)
			(layer "B.Fab")
			(hide yes)
			(effects
				(font
					(size 1.016 1.016)
					(thickness 0.1524)
				)
				(justify mirror)
			)
		)
		(duplicate_pad_numbers_are_jumpers no)
		(fp_line
			(start -0.508 -0.9398)
			(end 0.508 -0.9398)
			(stroke
				(width 0.1524)
				(type default)
			)
			(layer "B.SilkS")
		)
		(fp_line
			(start 0.508 -0.9398)
			(end 0.508 0.9398)
			(stroke
				(width 0.1524)
				(type default)
			)
			(layer "B.SilkS")
		)
		(fp_rect
			(start 0.508 0.9398)
			(end -0.508 -0.9398)
			(stroke
				(width 0)
				(type default)
			)
			(fill no)
			(layer "B.CrtYd")
		)
		(fp_rect
			(start 0.508 0.9398)
			(end -0.508 -0.9398)
			(stroke
				(width 0)
				(type default)
			)
			(fill no)
			(layer "B.Fab")
		)
		(pad "1" smd custom
			(at 0 -0.4445 180)
			(size 0.1397 0.1397)
			(layers "B.Cu" "B.Mask" "B.Paste")
			(net "SSD_PRSNT#3")
			(options
				(clearance outline)
				(anchor circle)
			)
			(primitives
				(gr_poly
					(pts
						(arc
							(start -0.1778 0.2794)
							(mid -0.249642 0.249642)
							(end -0.2794 0.1778)
						)
						(arc
							(start -0.2794 -0.1778)
							(mid -0.249642 -0.249642)
							(end -0.1778 -0.2794)
						)
						(arc
							(start 0.1778 -0.2794)
							(mid 0.249642 -0.249642)
							(end 0.2794 -0.1778)
						)
						(arc
							(start 0.2794 0.1778)
							(mid 0.249642 0.249642)
							(end 0.1778 0.2794)
						)
					)
					(width 0)
					(fill yes)
				)
			)
		)
		(pad "2" smd custom
			(at 0 0.4445 180)
			(size 0.1397 0.1397)
			(layers "B.Cu" "B.Mask" "B.Paste")
			(net "P3V3_STBY")
			(options
				(clearance outline)
				(anchor circle)
			)
			(primitives
				(gr_poly
					(pts
						(arc
							(start -0.1778 0.2794)
							(mid -0.249642 0.249642)
							(end -0.2794 0.1778)
						)
						(arc
							(start -0.2794 -0.1778)
							(mid -0.249642 -0.249642)
							(end -0.1778 -0.2794)
						)
						(arc
							(start 0.1778 -0.2794)
							(mid 0.249642 -0.249642)
							(end 0.2794 -0.1778)
						)
						(arc
							(start 0.2794 0.1778)
							(mid 0.249642 0.249642)
							(end 0.1778 0.2794)
						)
					)
					(width 0)
					(fill yes)
				)
			)
		)
	)
	(footprint ""
		(layer "B.Cu")
		(at 332.796388 -178.681126)
		(property "Reference" "U68"
			(at 0 0 0)
			(layer "B.SilkS")
			(hide yes)
			(effects
				(font
					(size 1.27 1.27)
				)
				(justify mirror)
			)
		)
		(property "Value" "SN74LVC1G08DCKR-GP"
			(at 2.3368 -8.6868 0)
			(unlocked yes)
			(layer "B.Fab")
			(hide yes)
			(effects
				(font
					(size 1.016 1.016)
					(thickness 0.1524)
				)
				(justify mirror)
			)
		)
		(property "Device Type" "SC70-5H44"
			(at 2.3114 -10.414 0)
			(unlocked yes)
			(layer "B.Fab")
			(hide yes)
			(effects
				(font
					(size 1.016 1.016)
					(thickness 0.1524)
				)
				(justify mirror)
			)
		)
		(duplicate_pad_numbers_are_jumpers no)
		(fp_line
			(start -1.3843 -1.8034)
			(end -1.3843 -1.1176)
			(stroke
				(width 0.3302)
				(type default)
			)
			(layer "B.SilkS")
		)
		(fp_line
			(start -1.27 -1.7018)
			(end -1.27 1.7018)
			(stroke
				(width 0.1524)
				(type default)
			)
			(layer "B.SilkS")
		)
		(fp_line
			(start -1.27 1.7018)
			(end 1.27 1.7018)
			(stroke
				(width 0.1524)
				(type default)
			)
			(layer "B.SilkS")
		)
		(fp_line
			(start -0.6604 -1.8034)
			(end -1.3843 -1.8034)
			(stroke
				(width 0.3302)
				(type default)
			)
			(layer "B.SilkS")
		)
		(fp_line
			(start 1.27 -1.7018)
			(end -1.27 -1.7018)
			(stroke
				(width 0.1524)
				(type default)
			)
			(layer "B.SilkS")
		)
		(fp_line
			(start 1.27 1.7018)
			(end 1.27 -1.7018)
			(stroke
				(width 0.1524)
				(type default)
			)
			(layer "B.SilkS")
		)
		(fp_rect
			(start 1.524 1.9558)
			(end -1.524 -1.9558)
			(stroke
				(width 0)
				(type default)
			)
			(fill no)
			(layer "B.CrtYd")
		)
		(fp_poly
			(pts
				(xy 1.524 -1.9558) (xy -1.524 -1.9558) (xy -1.524 1.9558) (xy 1.524 1.9558)
			)
			(stroke
				(width 0)
				(type default)
			)
			(fill no)
			(layer "B.Fab")
		)
		(pad "1" smd rect
			(at -0.65024 -0.8255 180)
			(size 0.4064 1.2192)
			(layers "B.Cu" "B.Mask" "B.Paste")
			(net "BMC_SSD_RST#0_A4")
		)
		(pad "2" smd rect
			(at 0 -0.8255 180)
			(size 0.4064 1.2192)
			(layers "B.Cu" "B.Mask" "B.Paste")
			(net "SSD_PERST#0_B4")
		)
		(pad "3" smd rect
			(at 0.65024 -0.8255 180)
			(size 0.4064 1.2192)
			(layers "B.Cu" "B.Mask" "B.Paste")
			(net "GND")
		)
		(pad "4" smd rect
			(at 0.65024 0.8255 180)
			(size 0.4064 1.2192)
			(layers "B.Cu" "B.Mask" "B.Paste")
			(net "SSD_PERST_Y4")
		)
		(pad "5" smd rect
			(at -0.65024 0.8255 180)
			(size 0.4064 1.2192)
			(layers "B.Cu" "B.Mask" "B.Paste")
			(net "P3V3_STBY")
		)
	)
	(footprint ""
		(layer "B.Cu")
		(at 246.126 -72.009 90)
		(property "Reference" "C517"
			(at 0 0 90)
			(layer "B.SilkS")
			(hide yes)
			(effects
				(font
					(size 1.27 1.27)
				)
				(justify mirror)
			)
		)
		(property "Value" "SC4D7U16V5KX-1-GP"
			(at 0.0762 -6.1214 90)
			(unlocked yes)
			(layer "B.Fab")
			(hide yes)
			(effects
				(font
					(size 1.016 1.016)
					(thickness 0.1524)
				)
				(justify mirror)
			)
		)
		(property "Device Type" "C805H56"
			(at 0.0762 -8.1534 90)
			(unlocked yes)
			(layer "B.Fab")
			(hide yes)
			(effects
				(font
					(size 1.016 1.016)
					(thickness 0.1524)
				)
				(justify mirror)
			)
		)
		(duplicate_pad_numbers_are_jumpers no)
		(fp_line
			(start -0.635 0)
			(end 0.635 0)
			(stroke
				(width 0.508)
				(type default)
			)
			(layer "B.SilkS")
		)
		(fp_rect
			(start 0.9652 1.778)
			(end -0.9652 -1.778)
			(stroke
				(width 0)
				(type default)
			)
			(fill no)
			(layer "B.CrtYd")
		)
		(fp_poly
			(pts
				(xy 0.9652 -1.778) (xy -0.9652 -1.778) (xy -0.9652 1.778) (xy 0.9652 1.778)
			)
			(stroke
				(width 0)
				(type default)
			)
			(fill no)
			(layer "B.Fab")
		)
		(pad "1" smd rect
			(at 0 -0.9652 270)
			(size 1.397 1.143)
			(layers "B.Cu" "B.Mask" "B.Paste")
			(net "DUT_AVD_TX")
		)
		(pad "2" smd rect
			(at 0 0.9652 270)
			(size 1.397 1.143)
			(layers "B.Cu" "B.Mask" "B.Paste")
			(net "GND")
		)
	)
	(footprint ""
		(layer "B.Cu")
		(at 53.721 -132.461 -90)
		(property "Reference" "R318"
			(at 0 0 90)
			(layer "B.SilkS")
			(hide yes)
			(effects
				(font
					(size 1.27 1.27)
				)
				(justify mirror)
			)
		)
		(property "Value" "0R2J-2-GP"
			(at -0.064008 -3.993896 270)
			(unlocked yes)
			(layer "B.Fab")
			(hide yes)
			(effects
				(font
					(size 1.016 1.016)
					(thickness 0.1524)
				)
				(justify mirror)
			)
		)
		(property "Device Type" "R402H16"
			(at -0.064008 -5.517896 270)
			(unlocked yes)
			(layer "B.Fab")
			(hide yes)
			(effects
				(font
					(size 1.016 1.016)
					(thickness 0.1524)
				)
				(justify mirror)
			)
		)
		(duplicate_pad_numbers_are_jumpers no)
		(fp_line
			(start -0.508 -0.9398)
			(end 0.508 -0.9398)
			(stroke
				(width 0.1524)
				(type default)
			)
			(layer "B.SilkS")
		)
		(fp_line
			(start 0.508 -0.9398)
			(end 0.508 0.9398)
			(stroke
				(width 0.1524)
				(type default)
			)
			(layer "B.SilkS")
		)
		(fp_rect
			(start 0.508 0.9398)
			(end -0.508 -0.9398)
			(stroke
				(width 0)
				(type default)
			)
			(fill no)
			(layer "B.CrtYd")
		)
		(fp_rect
			(start 0.508 0.9398)
			(end -0.508 -0.9398)
			(stroke
				(width 0)
				(type default)
			)
			(fill no)
			(layer "B.Fab")
		)
		(pad "1" smd custom
			(at 0 -0.4445 90)
			(size 0.1397 0.1397)
			(layers "B.Cu" "B.Mask" "B.Paste")
			(net "ADC_P3V3_STBY")
			(options
				(clearance outline)
				(anchor circle)
			)
			(primitives
				(gr_poly
					(pts
						(arc
							(start -0.1778 0.2794)
							(mid -0.249642 0.249642)
							(end -0.2794 0.1778)
						)
						(arc
							(start -0.2794 -0.1778)
							(mid -0.249642 -0.249642)
							(end -0.1778 -0.2794)
						)
						(arc
							(start 0.1778 -0.2794)
							(mid 0.249642 -0.249642)
							(end 0.2794 -0.1778)
						)
						(arc
							(start 0.2794 0.1778)
							(mid 0.249642 0.249642)
							(end 0.1778 0.2794)
						)
					)
					(width 0)
					(fill yes)
				)
			)
		)
		(pad "2" smd custom
			(at 0 0.4445 90)
			(size 0.1397 0.1397)
			(layers "B.Cu" "B.Mask" "B.Paste")
			(net "ADC_P3V3_STBY_BMC")
			(options
				(clearance outline)
				(anchor circle)
			)
			(primitives
				(gr_poly
					(pts
						(arc
							(start -0.1778 0.2794)
							(mid -0.249642 0.249642)
							(end -0.2794 0.1778)
						)
						(arc
							(start -0.2794 -0.1778)
							(mid -0.249642 -0.249642)
							(end -0.1778 -0.2794)
						)
						(arc
							(start 0.1778 -0.2794)
							(mid 0.249642 -0.249642)
							(end 0.2794 -0.1778)
						)
						(arc
							(start 0.2794 0.1778)
							(mid 0.249642 0.249642)
							(end 0.1778 0.2794)
						)
					)
					(width 0)
					(fill yes)
				)
			)
		)
	)
	(footprint ""
		(layer "B.Cu")
		(at 332.7654 -184.8866)
		(property "Reference" "R573"
			(at 0 0 0)
			(layer "B.SilkS")
			(hide yes)
			(effects
				(font
					(size 1.27 1.27)
				)
				(justify mirror)
			)
		)
		(property "Value" "10KR2F-2-GP"
			(at -0.064008 -3.993896 0)
			(unlocked yes)
			(layer "B.Fab")
			(hide yes)
			(effects
				(font
					(size 1.016 1.016)
					(thickness 0.1524)
				)
				(justify mirror)
			)
		)
		(property "Device Type" "R402H16"
			(at -0.064008 -5.517896 0)
			(unlocked yes)
			(layer "B.Fab")
			(hide yes)
			(effects
				(font
					(size 1.016 1.016)
					(thickness 0.1524)
				)
				(justify mirror)
			)
		)
		(duplicate_pad_numbers_are_jumpers no)
		(fp_line
			(start -0.508 -0.9398)
			(end 0.508 -0.9398)
			(stroke
				(width 0.1524)
				(type default)
			)
			(layer "B.SilkS")
		)
		(fp_line
			(start 0.508 -0.9398)
			(end 0.508 0.9398)
			(stroke
				(width 0.1524)
				(type default)
			)
			(layer "B.SilkS")
		)
		(fp_rect
			(start 0.508 0.9398)
			(end -0.508 -0.9398)
			(stroke
				(width 0)
				(type default)
			)
			(fill no)
			(layer "B.CrtYd")
		)
		(fp_rect
			(start 0.508 0.9398)
			(end -0.508 -0.9398)
			(stroke
				(width 0)
				(type default)
			)
			(fill no)
			(layer "B.Fab")
		)
		(pad "1" smd custom
			(at 0 -0.4445 180)
			(size 0.1397 0.1397)
			(layers "B.Cu" "B.Mask" "B.Paste")
			(net "P3V3_STBY")
			(options
				(clearance outline)
				(anchor circle)
			)
			(primitives
				(gr_poly
					(pts
						(arc
							(start -0.1778 0.2794)
							(mid -0.249642 0.249642)
							(end -0.2794 0.1778)
						)
						(arc
							(start -0.2794 -0.1778)
							(mid -0.249642 -0.249642)
							(end -0.1778 -0.2794)
						)
						(arc
							(start 0.1778 -0.2794)
							(mid 0.249642 -0.249642)
							(end 0.2794 -0.1778)
						)
						(arc
							(start 0.2794 0.1778)
							(mid 0.249642 0.249642)
							(end 0.1778 0.2794)
						)
					)
					(width 0)
					(fill yes)
				)
			)
		)
		(pad "2" smd custom
			(at 0 0.4445 180)
			(size 0.1397 0.1397)
			(layers "B.Cu" "B.Mask" "B.Paste")
			(net "IOEXP4_AD0")
			(options
				(clearance outline)
				(anchor circle)
			)
			(primitives
				(gr_poly
					(pts
						(arc
							(start -0.1778 0.2794)
							(mid -0.249642 0.249642)
							(end -0.2794 0.1778)
						)
						(arc
							(start -0.2794 -0.1778)
							(mid -0.249642 -0.249642)
							(end -0.1778 -0.2794)
						)
						(arc
							(start 0.1778 -0.2794)
							(mid 0.249642 -0.249642)
							(end 0.2794 -0.1778)
						)
						(arc
							(start 0.2794 0.1778)
							(mid 0.249642 0.249642)
							(end 0.1778 0.2794)
						)
					)
					(width 0)
					(fill yes)
				)
			)
		)
	)
	(footprint ""
		(layer "B.Cu")
		(at 137.8712 -205.9432)
		(property "Reference" "R9035"
			(at 0 0 0)
			(layer "B.SilkS")
			(hide yes)
			(effects
				(font
					(size 1.27 1.27)
				)
				(justify mirror)
			)
		)
		(property "Value" "4K7R2F-GP"
			(at -0.064008 -3.993896 0)
			(unlocked yes)
			(layer "B.Fab")
			(hide yes)
			(effects
				(font
					(size 1.016 1.016)
					(thickness 0.1524)
				)
				(justify mirror)
			)
		)
		(property "Device Type" "R402H16"
			(at -0.064008 -5.517896 0)
			(unlocked yes)
			(layer "B.Fab")
			(hide yes)
			(effects
				(font
					(size 1.016 1.016)
					(thickness 0.1524)
				)
				(justify mirror)
			)
		)
		(duplicate_pad_numbers_are_jumpers no)
		(fp_line
			(start -0.508 -0.9398)
			(end 0.508 -0.9398)
			(stroke
				(width 0.1524)
				(type default)
			)
			(layer "B.SilkS")
		)
		(fp_line
			(start 0.508 -0.9398)
			(end 0.508 0.9398)
			(stroke
				(width 0.1524)
				(type default)
			)
			(layer "B.SilkS")
		)
		(fp_rect
			(start 0.508 0.9398)
			(end -0.508 -0.9398)
			(stroke
				(width 0)
				(type default)
			)
			(fill no)
			(layer "B.CrtYd")
		)
		(fp_rect
			(start 0.508 0.9398)
			(end -0.508 -0.9398)
			(stroke
				(width 0)
				(type default)
			)
			(fill no)
			(layer "B.Fab")
		)
		(pad "1" smd custom
			(at 0 -0.4445 180)
			(size 0.1397 0.1397)
			(layers "B.Cu" "B.Mask" "B.Paste")
			(net "SSD_PERST#6")
			(options
				(clearance outline)
				(anchor circle)
			)
			(primitives
				(gr_poly
					(pts
						(arc
							(start -0.1778 0.2794)
							(mid -0.249642 0.249642)
							(end -0.2794 0.1778)
						)
						(arc
							(start -0.2794 -0.1778)
							(mid -0.249642 -0.249642)
							(end -0.1778 -0.2794)
						)
						(arc
							(start 0.1778 -0.2794)
							(mid 0.249642 -0.249642)
							(end 0.2794 -0.1778)
						)
						(arc
							(start 0.2794 0.1778)
							(mid 0.249642 0.249642)
							(end 0.1778 0.2794)
						)
					)
					(width 0)
					(fill yes)
				)
			)
		)
		(pad "2" smd custom
			(at 0 0.4445 180)
			(size 0.1397 0.1397)
			(layers "B.Cu" "B.Mask" "B.Paste")
			(net "GND")
			(options
				(clearance outline)
				(anchor circle)
			)
			(primitives
				(gr_poly
					(pts
						(arc
							(start -0.1778 0.2794)
							(mid -0.249642 0.249642)
							(end -0.2794 0.1778)
						)
						(arc
							(start -0.2794 -0.1778)
							(mid -0.249642 -0.249642)
							(end -0.1778 -0.2794)
						)
						(arc
							(start 0.1778 -0.2794)
							(mid 0.249642 -0.249642)
							(end 0.2794 -0.1778)
						)
						(arc
							(start 0.2794 0.1778)
							(mid 0.249642 0.249642)
							(end 0.1778 0.2794)
						)
					)
					(width 0)
					(fill yes)
				)
			)
		)
	)
	(footprint ""
		(layer "B.Cu")
		(at 53.222652 -108.06303 90)
		(property "Reference" "R52"
			(at 0 0 90)
			(layer "B.SilkS")
			(hide yes)
			(effects
				(font
					(size 1.27 1.27)
				)
				(justify mirror)
			)
		)
		(property "Value" "0R2J-2-GP"
			(at -0.064008 -3.993896 90)
			(unlocked yes)
			(layer "B.Fab")
			(hide yes)
			(effects
				(font
					(size 1.016 1.016)
					(thickness 0.1524)
				)
				(justify mirror)
			)
		)
		(property "Device Type" "R402H16"
			(at -0.064008 -5.517896 90)
			(unlocked yes)
			(layer "B.Fab")
			(hide yes)
			(effects
				(font
					(size 1.016 1.016)
					(thickness 0.1524)
				)
				(justify mirror)
			)
		)
		(duplicate_pad_numbers_are_jumpers no)
		(fp_line
			(start 0.508 -0.9398)
			(end 0.508 0.9398)
			(stroke
				(width 0.1524)
				(type default)
			)
			(layer "B.SilkS")
		)
		(fp_line
			(start -0.508 -0.9398)
			(end 0.508 -0.9398)
			(stroke
				(width 0.1524)
				(type default)
			)
			(layer "B.SilkS")
		)
		(fp_rect
			(start 0.508 0.9398)
			(end -0.508 -0.9398)
			(stroke
				(width 0)
				(type default)
			)
			(fill no)
			(layer "B.CrtYd")
		)
		(fp_rect
			(start 0.508 0.9398)
			(end -0.508 -0.9398)
			(stroke
				(width 0)
				(type default)
			)
			(fill no)
			(layer "B.Fab")
		)
		(pad "1" smd custom
			(at 0 -0.4445 270)
			(size 0.1397 0.1397)
			(layers "B.Cu" "B.Mask" "B.Paste")
			(net "BMC_I2C12_MINI6_SCL_S")
			(options
				(clearance outline)
				(anchor circle)
			)
			(primitives
				(gr_poly
					(pts
						(arc
							(start -0.1778 0.2794)
							(mid -0.249642 0.249642)
							(end -0.2794 0.1778)
						)
						(arc
							(start -0.2794 -0.1778)
							(mid -0.249642 -0.249642)
							(end -0.1778 -0.2794)
						)
						(arc
							(start 0.1778 -0.2794)
							(mid 0.249642 -0.249642)
							(end 0.2794 -0.1778)
						)
						(arc
							(start 0.2794 0.1778)
							(mid 0.249642 0.249642)
							(end 0.1778 0.2794)
						)
					)
					(width 0)
					(fill yes)
				)
			)
		)
		(pad "2" smd custom
			(at 0 0.4445 270)
			(size 0.1397 0.1397)
			(layers "B.Cu" "B.Mask" "B.Paste")
			(net "BMC_I2C12_MINI6_SCL")
			(options
				(clearance outline)
				(anchor circle)
			)
			(primitives
				(gr_poly
					(pts
						(arc
							(start -0.1778 0.2794)
							(mid -0.249642 0.249642)
							(end -0.2794 0.1778)
						)
						(arc
							(start -0.2794 -0.1778)
							(mid -0.249642 -0.249642)
							(end -0.1778 -0.2794)
						)
						(arc
							(start 0.1778 -0.2794)
							(mid 0.249642 -0.249642)
							(end 0.2794 -0.1778)
						)
						(arc
							(start 0.2794 0.1778)
							(mid 0.249642 0.249642)
							(end 0.1778 0.2794)
						)
					)
					(width 0)
					(fill yes)
				)
			)
		)
	)
	(footprint ""
		(layer "B.Cu")
		(at 29.913834 -126.973584)
		(property "Reference" "TP221"
			(at 0 0 0)
			(layer "B.SilkS")
			(hide yes)
			(effects
				(font
					(size 1.27 1.27)
				)
				(justify mirror)
			)
		)
		(property "Value" "TPAD28-2-GP"
			(at 0.0127 -1.6637 0)
			(unlocked yes)
			(layer "B.Fab")
			(hide yes)
			(effects
				(font
					(size 1.016 1.016)
					(thickness 0.1524)
				)
				(justify mirror)
			)
		)
		(property "Device Type" "TPAD28"
			(at 0.0127 -3.1877 0)
			(unlocked yes)
			(layer "B.Fab")
			(hide yes)
			(effects
				(font
					(size 1.016 1.016)
					(thickness 0.1524)
				)
				(justify mirror)
			)
		)
		(duplicate_pad_numbers_are_jumpers no)
		(fp_poly
			(pts
				(arc
					(start 0.3556 0)
					(mid -0.3556 0)
					(end 0.3556 0)
				)
			)
			(stroke
				(width 0)
				(type default)
			)
			(fill no)
			(layer "B.CrtYd")
		)
		(fp_poly
			(pts
				(arc
					(start 0.6096 0)
					(mid -0.6096 0)
					(end 0.6096 0)
				)
			)
			(stroke
				(width 0)
				(type default)
			)
			(fill no)
			(layer "B.Fab")
		)
		(pad "1" smd circle
			(at 0 0 180)
			(size 0.7112 0.7112)
			(layers "B.Cu" "B.Mask" "B.Paste")
			(net "TP_GPIOB6")
		)
	)
	(footprint ""
		(layer "B.Cu")
		(at 73.705212 -186.545474)
		(property "Reference" "C3201"
			(at 0 0 0)
			(layer "B.SilkS")
			(hide yes)
			(effects
				(font
					(size 1.27 1.27)
				)
				(justify mirror)
			)
		)
		(property "Value" "SCD1U25V2KX-2-GP"
			(at -1.1811 -2.7051 0)
			(unlocked yes)
			(layer "B.Fab")
			(hide yes)
			(effects
				(font
					(size 1.016 1.016)
					(thickness 0.1524)
				)
				(justify mirror)
			)
		)
		(property "Device Type" "C402H22"
			(at -1.1811 -4.2291 0)
			(unlocked yes)
			(layer "B.Fab")
			(hide yes)
			(effects
				(font
					(size 1.016 1.016)
					(thickness 0.1524)
				)
				(justify mirror)
			)
		)
		(duplicate_pad_numbers_are_jumpers no)
		(fp_rect
			(start 0.4318 0.9525)
			(end -0.4318 -0.9525)
			(stroke
				(width 0)
				(type default)
			)
			(fill no)
			(layer "B.CrtYd")
		)
		(fp_rect
			(start 0.4318 0.9525)
			(end -0.4318 -0.9525)
			(stroke
				(width 0)
				(type default)
			)
			(fill no)
			(layer "B.Fab")
		)
		(pad "1" smd custom
			(at 0 -0.4445 180)
			(size 0.1524 0.1524)
			(layers "B.Cu" "B.Mask" "B.Paste")
			(net "P3V3_STBY")
			(options
				(clearance outline)
				(anchor circle)
			)
			(primitives
				(gr_poly
					(pts
						(arc
							(start 0.3048 0.2032)
							(mid 0.275042 0.275042)
							(end 0.2032 0.3048)
						)
						(arc
							(start -0.2032 0.3048)
							(mid -0.275042 0.275042)
							(end -0.3048 0.2032)
						)
						(arc
							(start -0.3048 -0.2032)
							(mid -0.275042 -0.275042)
							(end -0.2032 -0.3048)
						)
						(arc
							(start 0.2032 -0.3048)
							(mid 0.275042 -0.275042)
							(end 0.3048 -0.2032)
						)
					)
					(width 0)
					(fill yes)
				)
			)
		)
		(pad "2" smd custom
			(at 0 0.4445 180)
			(size 0.1524 0.1524)
			(layers "B.Cu" "B.Mask" "B.Paste")
			(net "GND")
			(options
				(clearance outline)
				(anchor circle)
			)
			(primitives
				(gr_poly
					(pts
						(arc
							(start 0.3048 0.2032)
							(mid 0.275042 0.275042)
							(end 0.2032 0.3048)
						)
						(arc
							(start -0.2032 0.3048)
							(mid -0.275042 0.275042)
							(end -0.3048 0.2032)
						)
						(arc
							(start -0.3048 -0.2032)
							(mid -0.275042 -0.275042)
							(end -0.2032 -0.3048)
						)
						(arc
							(start 0.2032 -0.3048)
							(mid 0.275042 -0.275042)
							(end 0.3048 -0.2032)
						)
					)
					(width 0)
					(fill yes)
				)
			)
		)
	)
	(footprint ""
		(layer "B.Cu")
		(at 229.9208 -47.0408 90)
		(property "Reference" "C491"
			(at 0 0 90)
			(layer "B.SilkS")
			(hide yes)
			(effects
				(font
					(size 1.27 1.27)
				)
				(justify mirror)
			)
		)
		(property "Value" "SCD1U16V1KX-1-GP"
			(at 2.8321 -1.7399 90)
			(unlocked yes)
			(layer "B.Fab")
			(hide yes)
			(effects
				(font
					(size 1.016 1.016)
					(thickness 0.1524)
				)
				(justify mirror)
			)
		)
		(property "Device Type" "C0201H13"
			(at 2.8321 -3.2639 90)
			(unlocked yes)
			(layer "B.Fab")
			(hide yes)
			(effects
				(font
					(size 1.016 1.016)
					(thickness 0.1524)
				)
				(justify mirror)
			)
		)
		(duplicate_pad_numbers_are_jumpers no)
		(fp_rect
			(start 0.2794 0.6477)
			(end -0.2794 -0.6477)
			(stroke
				(width 0)
				(type default)
			)
			(fill no)
			(layer "B.CrtYd")
		)
		(fp_rect
			(start 0.2794 0.6477)
			(end -0.2794 -0.6477)
			(stroke
				(width 0)
				(type default)
			)
			(fill no)
			(layer "B.Fab")
		)
		(pad "1" smd custom
			(at 0 -0.2794 270)
			(size 0.0762 0.0762)
			(layers "B.Cu" "B.Mask" "B.Paste")
			(net "DUT_AVD_PCIE")
			(options
				(clearance outline)
				(anchor circle)
			)
			(primitives
				(gr_poly
					(pts
						(arc
							(start 0.1524 0.127)
							(mid 0.137521 0.162921)
							(end 0.1016 0.1778)
						)
						(arc
							(start -0.1016 0.1778)
							(mid -0.137521 0.162921)
							(end -0.1524 0.127)
						)
						(arc
							(start -0.1524 -0.127)
							(mid -0.137521 -0.162921)
							(end -0.1016 -0.1778)
						)
						(arc
							(start 0.1016 -0.1778)
							(mid 0.137521 -0.162921)
							(end 0.1524 -0.127)
						)
					)
					(width 0)
					(fill yes)
				)
			)
		)
		(pad "2" smd custom
			(at 0 0.2794 270)
			(size 0.0762 0.0762)
			(layers "B.Cu" "B.Mask" "B.Paste")
			(net "GND")
			(options
				(clearance outline)
				(anchor circle)
			)
			(primitives
				(gr_poly
					(pts
						(arc
							(start 0.1524 0.127)
							(mid 0.137521 0.162921)
							(end 0.1016 0.1778)
						)
						(arc
							(start -0.1016 0.1778)
							(mid -0.137521 0.162921)
							(end -0.1524 0.127)
						)
						(arc
							(start -0.1524 -0.127)
							(mid -0.137521 -0.162921)
							(end -0.1016 -0.1778)
						)
						(arc
							(start 0.1016 -0.1778)
							(mid 0.137521 -0.162921)
							(end 0.1524 -0.127)
						)
					)
					(width 0)
					(fill yes)
				)
			)
		)
	)
	(footprint ""
		(layer "B.Cu")
		(at 327.533 -70.104 180)
		(property "Reference" "PC186"
			(at 0 0 0)
			(layer "B.SilkS")
			(hide yes)
			(effects
				(font
					(size 1.27 1.27)
				)
				(justify mirror)
			)
		)
		(property "Value" "SCD1U16V2KX-3GP"
			(at -1.1811 -2.7051 180)
			(unlocked yes)
			(layer "B.Fab")
			(hide yes)
			(effects
				(font
					(size 1.016 1.016)
					(thickness 0.1524)
				)
				(justify mirror)
			)
		)
		(property "Device Type" "C402H22"
			(at -1.1811 -4.2291 180)
			(unlocked yes)
			(layer "B.Fab")
			(hide yes)
			(effects
				(font
					(size 1.016 1.016)
					(thickness 0.1524)
				)
				(justify mirror)
			)
		)
		(duplicate_pad_numbers_are_jumpers no)
		(fp_rect
			(start 0.4318 0.9525)
			(end -0.4318 -0.9525)
			(stroke
				(width 0)
				(type default)
			)
			(fill no)
			(layer "B.CrtYd")
		)
		(fp_rect
			(start 0.4318 0.9525)
			(end -0.4318 -0.9525)
			(stroke
				(width 0)
				(type default)
			)
			(fill no)
			(layer "B.Fab")
		)
		(pad "1" smd custom
			(at 0 -0.4445)
			(size 0.1524 0.1524)
			(layers "B.Cu" "B.Mask" "B.Paste")
			(net "P0V9_E")
			(options
				(clearance outline)
				(anchor circle)
			)
			(primitives
				(gr_poly
					(pts
						(arc
							(start 0.3048 0.2032)
							(mid 0.275042 0.275042)
							(end 0.2032 0.3048)
						)
						(arc
							(start -0.2032 0.3048)
							(mid -0.275042 0.275042)
							(end -0.3048 0.2032)
						)
						(arc
							(start -0.3048 -0.2032)
							(mid -0.275042 -0.275042)
							(end -0.2032 -0.3048)
						)
						(arc
							(start 0.2032 -0.3048)
							(mid 0.275042 -0.275042)
							(end 0.3048 -0.2032)
						)
					)
					(width 0)
					(fill yes)
				)
			)
		)
		(pad "2" smd custom
			(at 0 0.4445)
			(size 0.1524 0.1524)
			(layers "B.Cu" "B.Mask" "B.Paste")
			(net "P0V9_E_SW_R")
			(options
				(clearance outline)
				(anchor circle)
			)
			(primitives
				(gr_poly
					(pts
						(arc
							(start 0.3048 0.2032)
							(mid 0.275042 0.275042)
							(end 0.2032 0.3048)
						)
						(arc
							(start -0.2032 0.3048)
							(mid -0.275042 0.275042)
							(end -0.3048 0.2032)
						)
						(arc
							(start -0.3048 -0.2032)
							(mid -0.275042 -0.275042)
							(end -0.2032 -0.3048)
						)
						(arc
							(start 0.2032 -0.3048)
							(mid 0.275042 -0.275042)
							(end 0.3048 -0.2032)
						)
					)
					(width 0)
					(fill yes)
				)
			)
		)
	)
	(footprint ""
		(layer "B.Cu")
		(at 238.9124 -56.9976 -90)
		(property "Reference" "C531"
			(at 0 0 90)
			(layer "B.SilkS")
			(hide yes)
			(effects
				(font
					(size 1.27 1.27)
				)
				(justify mirror)
			)
		)
		(property "Value" "SCD1U16V1KX-1-GP"
			(at 2.8321 -1.7399 270)
			(unlocked yes)
			(layer "B.Fab")
			(hide yes)
			(effects
				(font
					(size 1.016 1.016)
					(thickness 0.1524)
				)
				(justify mirror)
			)
		)
		(property "Device Type" "C0201H13"
			(at 2.8321 -3.2639 270)
			(unlocked yes)
			(layer "B.Fab")
			(hide yes)
			(effects
				(font
					(size 1.016 1.016)
					(thickness 0.1524)
				)
				(justify mirror)
			)
		)
		(duplicate_pad_numbers_are_jumpers no)
		(fp_rect
			(start 0.2794 0.6477)
			(end -0.2794 -0.6477)
			(stroke
				(width 0)
				(type default)
			)
			(fill no)
			(layer "B.CrtYd")
		)
		(fp_rect
			(start 0.2794 0.6477)
			(end -0.2794 -0.6477)
			(stroke
				(width 0)
				(type default)
			)
			(fill no)
			(layer "B.Fab")
		)
		(pad "1" smd custom
			(at 0 -0.2794 90)
			(size 0.0762 0.0762)
			(layers "B.Cu" "B.Mask" "B.Paste")
			(net "DUT_AVD_TX")
			(options
				(clearance outline)
				(anchor circle)
			)
			(primitives
				(gr_poly
					(pts
						(arc
							(start 0.1524 0.127)
							(mid 0.137521 0.162921)
							(end 0.1016 0.1778)
						)
						(arc
							(start -0.1016 0.1778)
							(mid -0.137521 0.162921)
							(end -0.1524 0.127)
						)
						(arc
							(start -0.1524 -0.127)
							(mid -0.137521 -0.162921)
							(end -0.1016 -0.1778)
						)
						(arc
							(start 0.1016 -0.1778)
							(mid 0.137521 -0.162921)
							(end 0.1524 -0.127)
						)
					)
					(width 0)
					(fill yes)
				)
			)
		)
		(pad "2" smd custom
			(at 0 0.2794 90)
			(size 0.0762 0.0762)
			(layers "B.Cu" "B.Mask" "B.Paste")
			(net "GND")
			(options
				(clearance outline)
				(anchor circle)
			)
			(primitives
				(gr_poly
					(pts
						(arc
							(start 0.1524 0.127)
							(mid 0.137521 0.162921)
							(end 0.1016 0.1778)
						)
						(arc
							(start -0.1016 0.1778)
							(mid -0.137521 0.162921)
							(end -0.1524 0.127)
						)
						(arc
							(start -0.1524 -0.127)
							(mid -0.137521 -0.162921)
							(end -0.1016 -0.1778)
						)
						(arc
							(start 0.1016 -0.1778)
							(mid 0.137521 -0.162921)
							(end 0.1524 -0.127)
						)
					)
					(width 0)
					(fill yes)
				)
			)
		)
	)
	(footprint ""
		(layer "B.Cu")
		(at 223.393 -196.977)
		(property "Reference" "U72"
			(at 0 0 0)
			(layer "B.SilkS")
			(hide yes)
			(effects
				(font
					(size 1.27 1.27)
				)
				(justify mirror)
			)
		)
		(property "Value" "SN74LVC1G08DCKR-GP"
			(at 2.3368 -8.6868 0)
			(unlocked yes)
			(layer "B.Fab")
			(hide yes)
			(effects
				(font
					(size 1.016 1.016)
					(thickness 0.1524)
				)
				(justify mirror)
			)
		)
		(property "Device Type" "SC70-5H44"
			(at 2.3114 -10.414 0)
			(unlocked yes)
			(layer "B.Fab")
			(hide yes)
			(effects
				(font
					(size 1.016 1.016)
					(thickness 0.1524)
				)
				(justify mirror)
			)
		)
		(duplicate_pad_numbers_are_jumpers no)
		(fp_line
			(start -1.3843 -1.8034)
			(end -1.3843 -1.1176)
			(stroke
				(width 0.3302)
				(type default)
			)
			(layer "B.SilkS")
		)
		(fp_line
			(start -1.27 -1.7018)
			(end -1.27 1.7018)
			(stroke
				(width 0.1524)
				(type default)
			)
			(layer "B.SilkS")
		)
		(fp_line
			(start -1.27 1.7018)
			(end 1.27 1.7018)
			(stroke
				(width 0.1524)
				(type default)
			)
			(layer "B.SilkS")
		)
		(fp_line
			(start -0.6604 -1.8034)
			(end -1.3843 -1.8034)
			(stroke
				(width 0.3302)
				(type default)
			)
			(layer "B.SilkS")
		)
		(fp_line
			(start 1.27 -1.7018)
			(end -1.27 -1.7018)
			(stroke
				(width 0.1524)
				(type default)
			)
			(layer "B.SilkS")
		)
		(fp_line
			(start 1.27 1.7018)
			(end 1.27 -1.7018)
			(stroke
				(width 0.1524)
				(type default)
			)
			(layer "B.SilkS")
		)
		(fp_rect
			(start 1.524 1.9558)
			(end -1.524 -1.9558)
			(stroke
				(width 0)
				(type default)
			)
			(fill no)
			(layer "B.CrtYd")
		)
		(fp_poly
			(pts
				(xy 1.524 -1.9558) (xy -1.524 -1.9558) (xy -1.524 1.9558) (xy 1.524 1.9558)
			)
			(stroke
				(width 0)
				(type default)
			)
			(fill no)
			(layer "B.Fab")
		)
		(pad "1" smd rect
			(at -0.65024 -0.8255 180)
			(size 0.4064 1.2192)
			(layers "B.Cu" "B.Mask" "B.Paste")
			(net "BMC_SSD_RST#0_A8")
		)
		(pad "2" smd rect
			(at 0 -0.8255 180)
			(size 0.4064 1.2192)
			(layers "B.Cu" "B.Mask" "B.Paste")
			(net "SSD_PERST#0_B8")
		)
		(pad "3" smd rect
			(at 0.65024 -0.8255 180)
			(size 0.4064 1.2192)
			(layers "B.Cu" "B.Mask" "B.Paste")
			(net "GND")
		)
		(pad "4" smd rect
			(at 0.65024 0.8255 180)
			(size 0.4064 1.2192)
			(layers "B.Cu" "B.Mask" "B.Paste")
			(net "SSD_PERST_Y8")
		)
		(pad "5" smd rect
			(at -0.65024 0.8255 180)
			(size 0.4064 1.2192)
			(layers "B.Cu" "B.Mask" "B.Paste")
			(net "P3V3_STBY")
		)
	)
	(footprint ""
		(layer "B.Cu")
		(at 240.538 -18.161)
		(property "Reference" "TP193"
			(at 0 0 0)
			(layer "B.SilkS")
			(hide yes)
			(effects
				(font
					(size 1.27 1.27)
				)
				(justify mirror)
			)
		)
		(property "Value" "TPAD28-2-GP"
			(at 0.0127 -1.6637 0)
			(unlocked yes)
			(layer "B.Fab")
			(hide yes)
			(effects
				(font
					(size 1.016 1.016)
					(thickness 0.1524)
				)
				(justify mirror)
			)
		)
		(property "Device Type" "TPAD28"
			(at 0.0127 -3.1877 0)
			(unlocked yes)
			(layer "B.Fab")
			(hide yes)
			(effects
				(font
					(size 1.016 1.016)
					(thickness 0.1524)
				)
				(justify mirror)
			)
		)
		(duplicate_pad_numbers_are_jumpers no)
		(fp_poly
			(pts
				(arc
					(start 0.3556 0)
					(mid -0.3556 0)
					(end 0.3556 0)
				)
			)
			(stroke
				(width 0)
				(type default)
			)
			(fill no)
			(layer "B.CrtYd")
		)
		(fp_poly
			(pts
				(arc
					(start 0.6096 0)
					(mid -0.6096 0)
					(end 0.6096 0)
				)
			)
			(stroke
				(width 0)
				(type default)
			)
			(fill no)
			(layer "B.Fab")
		)
		(pad "1" smd circle
			(at 0 0 180)
			(size 0.7112 0.7112)
			(layers "B.Cu" "B.Mask" "B.Paste")
			(net "LBI_DATA_0")
		)
	)
	(footprint ""
		(layer "B.Cu")
		(at 239.1664 -47.032672 90)
		(property "Reference" "C38"
			(at 0 0 90)
			(layer "B.SilkS")
			(hide yes)
			(effects
				(font
					(size 1.27 1.27)
				)
				(justify mirror)
			)
		)
		(property "Value" "SCD1U16V1KX-1-GP"
			(at 2.8321 -1.7399 90)
			(unlocked yes)
			(layer "B.Fab")
			(hide yes)
			(effects
				(font
					(size 1.016 1.016)
					(thickness 0.1524)
				)
				(justify mirror)
			)
		)
		(property "Device Type" "C0201H13"
			(at 2.8321 -3.2639 90)
			(unlocked yes)
			(layer "B.Fab")
			(hide yes)
			(effects
				(font
					(size 1.016 1.016)
					(thickness 0.1524)
				)
				(justify mirror)
			)
		)
		(duplicate_pad_numbers_are_jumpers no)
		(fp_rect
			(start 0.2794 0.6477)
			(end -0.2794 -0.6477)
			(stroke
				(width 0)
				(type default)
			)
			(fill no)
			(layer "B.CrtYd")
		)
		(fp_rect
			(start 0.2794 0.6477)
			(end -0.2794 -0.6477)
			(stroke
				(width 0)
				(type default)
			)
			(fill no)
			(layer "B.Fab")
		)
		(pad "1" smd custom
			(at 0 -0.2794 270)
			(size 0.0762 0.0762)
			(layers "B.Cu" "B.Mask" "B.Paste")
			(net "DUT_VDD")
			(options
				(clearance outline)
				(anchor circle)
			)
			(primitives
				(gr_poly
					(pts
						(arc
							(start 0.1524 0.127)
							(mid 0.137521 0.162921)
							(end 0.1016 0.1778)
						)
						(arc
							(start -0.1016 0.1778)
							(mid -0.137521 0.162921)
							(end -0.1524 0.127)
						)
						(arc
							(start -0.1524 -0.127)
							(mid -0.137521 -0.162921)
							(end -0.1016 -0.1778)
						)
						(arc
							(start 0.1016 -0.1778)
							(mid 0.137521 -0.162921)
							(end 0.1524 -0.127)
						)
					)
					(width 0)
					(fill yes)
				)
			)
		)
		(pad "2" smd custom
			(at 0 0.2794 270)
			(size 0.0762 0.0762)
			(layers "B.Cu" "B.Mask" "B.Paste")
			(net "GND")
			(options
				(clearance outline)
				(anchor circle)
			)
			(primitives
				(gr_poly
					(pts
						(arc
							(start 0.1524 0.127)
							(mid 0.137521 0.162921)
							(end 0.1016 0.1778)
						)
						(arc
							(start -0.1016 0.1778)
							(mid -0.137521 0.162921)
							(end -0.1524 0.127)
						)
						(arc
							(start -0.1524 -0.127)
							(mid -0.137521 -0.162921)
							(end -0.1016 -0.1778)
						)
						(arc
							(start 0.1016 -0.1778)
							(mid 0.137521 -0.162921)
							(end 0.1524 -0.127)
						)
					)
					(width 0)
					(fill yes)
				)
			)
		)
	)
	(footprint ""
		(layer "B.Cu")
		(at 242.443 -17.2466 -90)
		(property "Reference" "R4177"
			(at 0 0 90)
			(layer "B.SilkS")
			(hide yes)
			(effects
				(font
					(size 1.27 1.27)
				)
				(justify mirror)
			)
		)
		(property "Value" "4K7R2F-GP"
			(at -0.064008 -3.993896 270)
			(unlocked yes)
			(layer "B.Fab")
			(hide yes)
			(effects
				(font
					(size 1.016 1.016)
					(thickness 0.1524)
				)
				(justify mirror)
			)
		)
		(property "Device Type" "R402H16"
			(at -0.064008 -5.517896 270)
			(unlocked yes)
			(layer "B.Fab")
			(hide yes)
			(effects
				(font
					(size 1.016 1.016)
					(thickness 0.1524)
				)
				(justify mirror)
			)
		)
		(duplicate_pad_numbers_are_jumpers no)
		(fp_line
			(start -0.508 -0.9398)
			(end 0.508 -0.9398)
			(stroke
				(width 0.1524)
				(type default)
			)
			(layer "B.SilkS")
		)
		(fp_line
			(start 0.508 -0.9398)
			(end 0.508 0.9398)
			(stroke
				(width 0.1524)
				(type default)
			)
			(layer "B.SilkS")
		)
		(fp_rect
			(start 0.508 0.9398)
			(end -0.508 -0.9398)
			(stroke
				(width 0)
				(type default)
			)
			(fill no)
			(layer "B.CrtYd")
		)
		(fp_rect
			(start 0.508 0.9398)
			(end -0.508 -0.9398)
			(stroke
				(width 0)
				(type default)
			)
			(fill no)
			(layer "B.Fab")
		)
		(pad "1" smd custom
			(at 0 -0.4445 90)
			(size 0.1397 0.1397)
			(layers "B.Cu" "B.Mask" "B.Paste")
			(net "PM8536_HB")
			(options
				(clearance outline)
				(anchor circle)
			)
			(primitives
				(gr_poly
					(pts
						(arc
							(start -0.1778 0.2794)
							(mid -0.249642 0.249642)
							(end -0.2794 0.1778)
						)
						(arc
							(start -0.2794 -0.1778)
							(mid -0.249642 -0.249642)
							(end -0.1778 -0.2794)
						)
						(arc
							(start 0.1778 -0.2794)
							(mid 0.249642 -0.249642)
							(end 0.2794 -0.1778)
						)
						(arc
							(start 0.2794 0.1778)
							(mid 0.249642 0.249642)
							(end 0.1778 0.2794)
						)
					)
					(width 0)
					(fill yes)
				)
			)
		)
		(pad "2" smd custom
			(at 0 0.4445 90)
			(size 0.1397 0.1397)
			(layers "B.Cu" "B.Mask" "B.Paste")
			(net "P3V3_STBY")
			(options
				(clearance outline)
				(anchor circle)
			)
			(primitives
				(gr_poly
					(pts
						(arc
							(start -0.1778 0.2794)
							(mid -0.249642 0.249642)
							(end -0.2794 0.1778)
						)
						(arc
							(start -0.2794 -0.1778)
							(mid -0.249642 -0.249642)
							(end -0.1778 -0.2794)
						)
						(arc
							(start 0.1778 -0.2794)
							(mid 0.249642 -0.249642)
							(end 0.2794 -0.1778)
						)
						(arc
							(start 0.2794 0.1778)
							(mid 0.249642 0.249642)
							(end 0.1778 0.2794)
						)
					)
					(width 0)
					(fill yes)
				)
			)
		)
	)
	(footprint ""
		(layer "B.Cu")
		(at 24.13 -121.0056 -90)
		(property "Reference" "R554"
			(at 0 0 90)
			(layer "B.SilkS")
			(hide yes)
			(effects
				(font
					(size 1.27 1.27)
				)
				(justify mirror)
			)
		)
		(property "Value" "0R2J-2-GP"
			(at -0.064008 -3.993896 270)
			(unlocked yes)
			(layer "B.Fab")
			(hide yes)
			(effects
				(font
					(size 1.016 1.016)
					(thickness 0.1524)
				)
				(justify mirror)
			)
		)
		(property "Device Type" "R402H16"
			(at -0.064008 -5.517896 270)
			(unlocked yes)
			(layer "B.Fab")
			(hide yes)
			(effects
				(font
					(size 1.016 1.016)
					(thickness 0.1524)
				)
				(justify mirror)
			)
		)
		(duplicate_pad_numbers_are_jumpers no)
		(fp_line
			(start -0.508 -0.9398)
			(end 0.508 -0.9398)
			(stroke
				(width 0.1524)
				(type default)
			)
			(layer "B.SilkS")
		)
		(fp_line
			(start 0.508 -0.9398)
			(end 0.508 0.9398)
			(stroke
				(width 0.1524)
				(type default)
			)
			(layer "B.SilkS")
		)
		(fp_rect
			(start 0.508 0.9398)
			(end -0.508 -0.9398)
			(stroke
				(width 0)
				(type default)
			)
			(fill no)
			(layer "B.CrtYd")
		)
		(fp_rect
			(start 0.508 0.9398)
			(end -0.508 -0.9398)
			(stroke
				(width 0)
				(type default)
			)
			(fill no)
			(layer "B.Fab")
		)
		(pad "1" smd custom
			(at 0 -0.4445 90)
			(size 0.1397 0.1397)
			(layers "B.Cu" "B.Mask" "B.Paste")
			(net "FM_PCH_LAN1_DISABLE_N_R")
			(options
				(clearance outline)
				(anchor circle)
			)
			(primitives
				(gr_poly
					(pts
						(arc
							(start -0.1778 0.2794)
							(mid -0.249642 0.249642)
							(end -0.2794 0.1778)
						)
						(arc
							(start -0.2794 -0.1778)
							(mid -0.249642 -0.249642)
							(end -0.1778 -0.2794)
						)
						(arc
							(start 0.1778 -0.2794)
							(mid 0.249642 -0.249642)
							(end 0.2794 -0.1778)
						)
						(arc
							(start 0.2794 0.1778)
							(mid 0.249642 0.249642)
							(end 0.1778 0.2794)
						)
					)
					(width 0)
					(fill yes)
				)
			)
		)
		(pad "2" smd custom
			(at 0 0.4445 90)
			(size 0.1397 0.1397)
			(layers "B.Cu" "B.Mask" "B.Paste")
			(net "FM_PCH_LAN1_DISABLE_N")
			(options
				(clearance outline)
				(anchor circle)
			)
			(primitives
				(gr_poly
					(pts
						(arc
							(start -0.1778 0.2794)
							(mid -0.249642 0.249642)
							(end -0.2794 0.1778)
						)
						(arc
							(start -0.2794 -0.1778)
							(mid -0.249642 -0.249642)
							(end -0.1778 -0.2794)
						)
						(arc
							(start 0.1778 -0.2794)
							(mid 0.249642 -0.249642)
							(end 0.2794 -0.1778)
						)
						(arc
							(start 0.2794 0.1778)
							(mid 0.249642 0.249642)
							(end 0.1778 0.2794)
						)
					)
					(width 0)
					(fill yes)
				)
			)
		)
	)
	(footprint ""
		(layer "B.Cu")
		(at 269.150084 -17.37106 90)
		(property "Reference" "R2976"
			(at 0 0 90)
			(layer "B.SilkS")
			(hide yes)
			(effects
				(font
					(size 1.27 1.27)
				)
				(justify mirror)
			)
		)
		(property "Value" "0R2J-2-GP"
			(at -0.064008 -3.993896 90)
			(unlocked yes)
			(layer "B.Fab")
			(hide yes)
			(effects
				(font
					(size 1.016 1.016)
					(thickness 0.1524)
				)
				(justify mirror)
			)
		)
		(property "Device Type" "R402H16"
			(at -0.064008 -5.517896 90)
			(unlocked yes)
			(layer "B.Fab")
			(hide yes)
			(effects
				(font
					(size 1.016 1.016)
					(thickness 0.1524)
				)
				(justify mirror)
			)
		)
		(duplicate_pad_numbers_are_jumpers no)
		(fp_line
			(start 0.508 -0.9398)
			(end 0.508 0.9398)
			(stroke
				(width 0.1524)
				(type default)
			)
			(layer "B.SilkS")
		)
		(fp_line
			(start -0.508 -0.9398)
			(end 0.508 -0.9398)
			(stroke
				(width 0.1524)
				(type default)
			)
			(layer "B.SilkS")
		)
		(fp_rect
			(start 0.508 0.9398)
			(end -0.508 -0.9398)
			(stroke
				(width 0)
				(type default)
			)
			(fill no)
			(layer "B.CrtYd")
		)
		(fp_rect
			(start 0.508 0.9398)
			(end -0.508 -0.9398)
			(stroke
				(width 0)
				(type default)
			)
			(fill no)
			(layer "B.Fab")
		)
		(pad "1" smd custom
			(at 0 -0.4445 270)
			(size 0.1397 0.1397)
			(layers "B.Cu" "B.Mask" "B.Paste")
			(net "USB_P4_DP_BMC")
			(options
				(clearance outline)
				(anchor circle)
			)
			(primitives
				(gr_poly
					(pts
						(arc
							(start -0.1778 0.2794)
							(mid -0.249642 0.249642)
							(end -0.2794 0.1778)
						)
						(arc
							(start -0.2794 -0.1778)
							(mid -0.249642 -0.249642)
							(end -0.1778 -0.2794)
						)
						(arc
							(start 0.1778 -0.2794)
							(mid 0.249642 -0.249642)
							(end 0.2794 -0.1778)
						)
						(arc
							(start 0.2794 0.1778)
							(mid 0.249642 0.249642)
							(end 0.1778 0.2794)
						)
					)
					(width 0)
					(fill yes)
				)
			)
		)
		(pad "2" smd custom
			(at 0 0.4445 270)
			(size 0.1397 0.1397)
			(layers "B.Cu" "B.Mask" "B.Paste")
			(net "8644_USB_DP5")
			(options
				(clearance outline)
				(anchor circle)
			)
			(primitives
				(gr_poly
					(pts
						(arc
							(start -0.1778 0.2794)
							(mid -0.249642 0.249642)
							(end -0.2794 0.1778)
						)
						(arc
							(start -0.2794 -0.1778)
							(mid -0.249642 -0.249642)
							(end -0.1778 -0.2794)
						)
						(arc
							(start 0.1778 -0.2794)
							(mid 0.249642 -0.249642)
							(end 0.2794 -0.1778)
						)
						(arc
							(start 0.2794 0.1778)
							(mid 0.249642 0.249642)
							(end 0.1778 0.2794)
						)
					)
					(width 0)
					(fill yes)
				)
			)
		)
	)
	(footprint ""
		(layer "B.Cu")
		(at 35.687 -132.588 90)
		(property "Reference" "C207"
			(at 0 0 90)
			(layer "B.SilkS")
			(hide yes)
			(effects
				(font
					(size 1.27 1.27)
				)
				(justify mirror)
			)
		)
		(property "Value" "SC1U10V2KX-4-GP"
			(at -1.1811 -2.7051 90)
			(unlocked yes)
			(layer "B.Fab")
			(hide yes)
			(effects
				(font
					(size 1.016 1.016)
					(thickness 0.1524)
				)
				(justify mirror)
			)
		)
		(property "Device Type" "C402H22"
			(at -1.1811 -4.2291 90)
			(unlocked yes)
			(layer "B.Fab")
			(hide yes)
			(effects
				(font
					(size 1.016 1.016)
					(thickness 0.1524)
				)
				(justify mirror)
			)
		)
		(duplicate_pad_numbers_are_jumpers no)
		(fp_rect
			(start 0.4318 0.9525)
			(end -0.4318 -0.9525)
			(stroke
				(width 0)
				(type default)
			)
			(fill no)
			(layer "B.CrtYd")
		)
		(fp_rect
			(start 0.4318 0.9525)
			(end -0.4318 -0.9525)
			(stroke
				(width 0)
				(type default)
			)
			(fill no)
			(layer "B.Fab")
		)
		(pad "1" smd custom
			(at 0 -0.4445 270)
			(size 0.1524 0.1524)
			(layers "B.Cu" "B.Mask" "B.Paste")
			(net "P1V26_STBY")
			(options
				(clearance outline)
				(anchor circle)
			)
			(primitives
				(gr_poly
					(pts
						(arc
							(start 0.3048 0.2032)
							(mid 0.275042 0.275042)
							(end 0.2032 0.3048)
						)
						(arc
							(start -0.2032 0.3048)
							(mid -0.275042 0.275042)
							(end -0.3048 0.2032)
						)
						(arc
							(start -0.3048 -0.2032)
							(mid -0.275042 -0.275042)
							(end -0.2032 -0.3048)
						)
						(arc
							(start 0.2032 -0.3048)
							(mid 0.275042 -0.275042)
							(end 0.3048 -0.2032)
						)
					)
					(width 0)
					(fill yes)
				)
			)
		)
		(pad "2" smd custom
			(at 0 0.4445 270)
			(size 0.1524 0.1524)
			(layers "B.Cu" "B.Mask" "B.Paste")
			(net "GND")
			(options
				(clearance outline)
				(anchor circle)
			)
			(primitives
				(gr_poly
					(pts
						(arc
							(start 0.3048 0.2032)
							(mid 0.275042 0.275042)
							(end 0.2032 0.3048)
						)
						(arc
							(start -0.2032 0.3048)
							(mid -0.275042 0.275042)
							(end -0.3048 0.2032)
						)
						(arc
							(start -0.3048 -0.2032)
							(mid -0.275042 -0.275042)
							(end -0.2032 -0.3048)
						)
						(arc
							(start 0.2032 -0.3048)
							(mid 0.275042 -0.275042)
							(end 0.3048 -0.2032)
						)
					)
					(width 0)
					(fill yes)
				)
			)
		)
	)
	(footprint ""
		(layer "B.Cu")
		(at 126.492 -203.835)
		(property "Reference" "R144"
			(at 0 0 0)
			(layer "B.SilkS")
			(hide yes)
			(effects
				(font
					(size 1.27 1.27)
				)
				(justify mirror)
			)
		)
		(property "Value" "4K7R2F-GP"
			(at -0.064008 -3.993896 0)
			(unlocked yes)
			(layer "B.Fab")
			(hide yes)
			(effects
				(font
					(size 1.016 1.016)
					(thickness 0.1524)
				)
				(justify mirror)
			)
		)
		(property "Device Type" "R402H16"
			(at -0.064008 -5.517896 0)
			(unlocked yes)
			(layer "B.Fab")
			(hide yes)
			(effects
				(font
					(size 1.016 1.016)
					(thickness 0.1524)
				)
				(justify mirror)
			)
		)
		(duplicate_pad_numbers_are_jumpers no)
		(fp_line
			(start -0.508 -0.9398)
			(end 0.508 -0.9398)
			(stroke
				(width 0.1524)
				(type default)
			)
			(layer "B.SilkS")
		)
		(fp_line
			(start 0.508 -0.9398)
			(end 0.508 0.9398)
			(stroke
				(width 0.1524)
				(type default)
			)
			(layer "B.SilkS")
		)
		(fp_rect
			(start 0.508 0.9398)
			(end -0.508 -0.9398)
			(stroke
				(width 0)
				(type default)
			)
			(fill no)
			(layer "B.CrtYd")
		)
		(fp_rect
			(start 0.508 0.9398)
			(end -0.508 -0.9398)
			(stroke
				(width 0)
				(type default)
			)
			(fill no)
			(layer "B.Fab")
		)
		(pad "1" smd custom
			(at 0 -0.4445 180)
			(size 0.1397 0.1397)
			(layers "B.Cu" "B.Mask" "B.Paste")
			(net "BMC_SSD_RST#0_A1")
			(options
				(clearance outline)
				(anchor circle)
			)
			(primitives
				(gr_poly
					(pts
						(arc
							(start -0.1778 0.2794)
							(mid -0.249642 0.249642)
							(end -0.2794 0.1778)
						)
						(arc
							(start -0.2794 -0.1778)
							(mid -0.249642 -0.249642)
							(end -0.1778 -0.2794)
						)
						(arc
							(start 0.1778 -0.2794)
							(mid 0.249642 -0.249642)
							(end 0.2794 -0.1778)
						)
						(arc
							(start 0.2794 0.1778)
							(mid 0.249642 0.249642)
							(end 0.1778 0.2794)
						)
					)
					(width 0)
					(fill yes)
				)
			)
		)
		(pad "2" smd custom
			(at 0 0.4445 180)
			(size 0.1397 0.1397)
			(layers "B.Cu" "B.Mask" "B.Paste")
			(net "P3V3_STBY")
			(options
				(clearance outline)
				(anchor circle)
			)
			(primitives
				(gr_poly
					(pts
						(arc
							(start -0.1778 0.2794)
							(mid -0.249642 0.249642)
							(end -0.2794 0.1778)
						)
						(arc
							(start -0.2794 -0.1778)
							(mid -0.249642 -0.249642)
							(end -0.1778 -0.2794)
						)
						(arc
							(start 0.1778 -0.2794)
							(mid 0.249642 -0.249642)
							(end 0.2794 -0.1778)
						)
						(arc
							(start 0.2794 0.1778)
							(mid 0.249642 0.249642)
							(end 0.1778 0.2794)
						)
					)
					(width 0)
					(fill yes)
				)
			)
		)
	)
	(footprint ""
		(layer "B.Cu")
		(at 252.603 -50.004472 -90)
		(property "Reference" "C608"
			(at 0 0 90)
			(layer "B.SilkS")
			(hide yes)
			(effects
				(font
					(size 1.27 1.27)
				)
				(justify mirror)
			)
		)
		(property "Value" "SCD1U16V1KX-1-GP"
			(at 2.8321 -1.7399 270)
			(unlocked yes)
			(layer "B.Fab")
			(hide yes)
			(effects
				(font
					(size 1.016 1.016)
					(thickness 0.1524)
				)
				(justify mirror)
			)
		)
		(property "Device Type" "C0201H13"
			(at 2.8321 -3.2639 270)
			(unlocked yes)
			(layer "B.Fab")
			(hide yes)
			(effects
				(font
					(size 1.016 1.016)
					(thickness 0.1524)
				)
				(justify mirror)
			)
		)
		(duplicate_pad_numbers_are_jumpers no)
		(fp_rect
			(start 0.2794 0.6477)
			(end -0.2794 -0.6477)
			(stroke
				(width 0)
				(type default)
			)
			(fill no)
			(layer "B.CrtYd")
		)
		(fp_rect
			(start 0.2794 0.6477)
			(end -0.2794 -0.6477)
			(stroke
				(width 0)
				(type default)
			)
			(fill no)
			(layer "B.Fab")
		)
		(pad "1" smd custom
			(at 0 -0.2794 90)
			(size 0.0762 0.0762)
			(layers "B.Cu" "B.Mask" "B.Paste")
			(net "DUT_AVD_PCIE")
			(options
				(clearance outline)
				(anchor circle)
			)
			(primitives
				(gr_poly
					(pts
						(arc
							(start 0.1524 0.127)
							(mid 0.137521 0.162921)
							(end 0.1016 0.1778)
						)
						(arc
							(start -0.1016 0.1778)
							(mid -0.137521 0.162921)
							(end -0.1524 0.127)
						)
						(arc
							(start -0.1524 -0.127)
							(mid -0.137521 -0.162921)
							(end -0.1016 -0.1778)
						)
						(arc
							(start 0.1016 -0.1778)
							(mid 0.137521 -0.162921)
							(end 0.1524 -0.127)
						)
					)
					(width 0)
					(fill yes)
				)
			)
		)
		(pad "2" smd custom
			(at 0 0.2794 90)
			(size 0.0762 0.0762)
			(layers "B.Cu" "B.Mask" "B.Paste")
			(net "GND")
			(options
				(clearance outline)
				(anchor circle)
			)
			(primitives
				(gr_poly
					(pts
						(arc
							(start 0.1524 0.127)
							(mid 0.137521 0.162921)
							(end 0.1016 0.1778)
						)
						(arc
							(start -0.1016 0.1778)
							(mid -0.137521 0.162921)
							(end -0.1524 0.127)
						)
						(arc
							(start -0.1524 -0.127)
							(mid -0.137521 -0.162921)
							(end -0.1016 -0.1778)
						)
						(arc
							(start 0.1016 -0.1778)
							(mid 0.137521 -0.162921)
							(end 0.1524 -0.127)
						)
					)
					(width 0)
					(fill yes)
				)
			)
		)
	)
	(footprint ""
		(layer "B.Cu")
		(at 74.950066 -195.6689 180)
		(property "Reference" "R4114"
			(at 0 0 0)
			(layer "B.SilkS")
			(hide yes)
			(effects
				(font
					(size 1.27 1.27)
				)
				(justify mirror)
			)
		)
		(property "Value" "4K7R2F-GP"
			(at -0.064008 -3.993896 180)
			(unlocked yes)
			(layer "B.Fab")
			(hide yes)
			(effects
				(font
					(size 1.016 1.016)
					(thickness 0.1524)
				)
				(justify mirror)
			)
		)
		(property "Device Type" "R402H16"
			(at -0.064008 -5.517896 180)
			(unlocked yes)
			(layer "B.Fab")
			(hide yes)
			(effects
				(font
					(size 1.016 1.016)
					(thickness 0.1524)
				)
				(justify mirror)
			)
		)
		(duplicate_pad_numbers_are_jumpers no)
		(fp_line
			(start 0.508 -0.9398)
			(end 0.508 0.9398)
			(stroke
				(width 0.1524)
				(type default)
			)
			(layer "B.SilkS")
		)
		(fp_line
			(start -0.508 -0.9398)
			(end 0.508 -0.9398)
			(stroke
				(width 0.1524)
				(type default)
			)
			(layer "B.SilkS")
		)
		(fp_rect
			(start 0.508 0.9398)
			(end -0.508 -0.9398)
			(stroke
				(width 0)
				(type default)
			)
			(fill no)
			(layer "B.CrtYd")
		)
		(fp_rect
			(start 0.508 0.9398)
			(end -0.508 -0.9398)
			(stroke
				(width 0)
				(type default)
			)
			(fill no)
			(layer "B.Fab")
		)
		(pad "1" smd custom
			(at 0 -0.4445)
			(size 0.1397 0.1397)
			(layers "B.Cu" "B.Mask" "B.Paste")
			(net "SSD_ATNLED#11")
			(options
				(clearance outline)
				(anchor circle)
			)
			(primitives
				(gr_poly
					(pts
						(arc
							(start -0.1778 0.2794)
							(mid -0.249642 0.249642)
							(end -0.2794 0.1778)
						)
						(arc
							(start -0.2794 -0.1778)
							(mid -0.249642 -0.249642)
							(end -0.1778 -0.2794)
						)
						(arc
							(start 0.1778 -0.2794)
							(mid 0.249642 -0.249642)
							(end 0.2794 -0.1778)
						)
						(arc
							(start 0.2794 0.1778)
							(mid 0.249642 0.249642)
							(end 0.1778 0.2794)
						)
					)
					(width 0)
					(fill yes)
				)
			)
		)
		(pad "2" smd custom
			(at 0 0.4445)
			(size 0.1397 0.1397)
			(layers "B.Cu" "B.Mask" "B.Paste")
			(net "P3V3_STBY")
			(options
				(clearance outline)
				(anchor circle)
			)
			(primitives
				(gr_poly
					(pts
						(arc
							(start -0.1778 0.2794)
							(mid -0.249642 0.249642)
							(end -0.2794 0.1778)
						)
						(arc
							(start -0.2794 -0.1778)
							(mid -0.249642 -0.249642)
							(end -0.1778 -0.2794)
						)
						(arc
							(start 0.1778 -0.2794)
							(mid 0.249642 -0.249642)
							(end 0.2794 -0.1778)
						)
						(arc
							(start 0.2794 0.1778)
							(mid 0.249642 0.249642)
							(end 0.1778 0.2794)
						)
					)
					(width 0)
					(fill yes)
				)
			)
		)
	)
	(footprint ""
		(layer "B.Cu")
		(at 221.107 -10.3124 180)
		(property "Reference" "U81"
			(at 0 0 0)
			(layer "B.SilkS")
			(hide yes)
			(effects
				(font
					(size 1.27 1.27)
				)
				(justify mirror)
			)
		)
		(property "Value" "SN74LVC1G08DCKR-GP"
			(at 2.3368 -8.6868 180)
			(unlocked yes)
			(layer "B.Fab")
			(hide yes)
			(effects
				(font
					(size 1.016 1.016)
					(thickness 0.1524)
				)
				(justify mirror)
			)
		)
		(property "Device Type" "SC70-5H44"
			(at 2.3114 -10.414 180)
			(unlocked yes)
			(layer "B.Fab")
			(hide yes)
			(effects
				(font
					(size 1.016 1.016)
					(thickness 0.1524)
				)
				(justify mirror)
			)
		)
		(duplicate_pad_numbers_are_jumpers no)
		(fp_line
			(start 1.27 1.7018)
			(end 1.27 -1.7018)
			(stroke
				(width 0.1524)
				(type default)
			)
			(layer "B.SilkS")
		)
		(fp_line
			(start 1.27 -1.7018)
			(end -1.27 -1.7018)
			(stroke
				(width 0.1524)
				(type default)
			)
			(layer "B.SilkS")
		)
		(fp_line
			(start -0.6604 -1.8034)
			(end -1.3843 -1.8034)
			(stroke
				(width 0.3302)
				(type default)
			)
			(layer "B.SilkS")
		)
		(fp_line
			(start -1.27 1.7018)
			(end 1.27 1.7018)
			(stroke
				(width 0.1524)
				(type default)
			)
			(layer "B.SilkS")
		)
		(fp_line
			(start -1.27 -1.7018)
			(end -1.27 1.7018)
			(stroke
				(width 0.1524)
				(type default)
			)
			(layer "B.SilkS")
		)
		(fp_line
			(start -1.3843 -1.8034)
			(end -1.3843 -1.1176)
			(stroke
				(width 0.3302)
				(type default)
			)
			(layer "B.SilkS")
		)
		(fp_rect
			(start 1.524 1.9558)
			(end -1.524 -1.9558)
			(stroke
				(width 0)
				(type default)
			)
			(fill no)
			(layer "B.CrtYd")
		)
		(fp_poly
			(pts
				(xy 1.524 -1.9558) (xy -1.524 -1.9558) (xy -1.524 1.9558) (xy 1.524 1.9558)
			)
			(stroke
				(width 0)
				(type default)
			)
			(fill no)
			(layer "B.Fab")
		)
		(pad "1" smd rect
			(at -0.65024 -0.8255)
			(size 0.4064 1.2192)
			(layers "B.Cu" "B.Mask" "B.Paste")
			(net "HOST1_RST_N")
		)
		(pad "2" smd rect
			(at 0 -0.8255)
			(size 0.4064 1.2192)
			(layers "B.Cu" "B.Mask" "B.Paste")
			(net "U81_B")
		)
		(pad "3" smd rect
			(at 0.65024 -0.8255)
			(size 0.4064 1.2192)
			(layers "B.Cu" "B.Mask" "B.Paste")
			(net "GND")
		)
		(pad "4" smd rect
			(at 0.65024 0.8255)
			(size 0.4064 1.2192)
			(layers "B.Cu" "B.Mask" "B.Paste")
			(net "U81_Y")
		)
		(pad "5" smd rect
			(at -0.65024 0.8255)
			(size 0.4064 1.2192)
			(layers "B.Cu" "B.Mask" "B.Paste")
			(net "P3V3_STBY")
		)
	)
	(footprint ""
		(layer "B.Cu")
		(at 241.0968 -43.997372 -90)
		(property "Reference" "C428"
			(at 0 0 90)
			(layer "B.SilkS")
			(hide yes)
			(effects
				(font
					(size 1.27 1.27)
				)
				(justify mirror)
			)
		)
		(property "Value" "SCD1U16V1KX-1-GP"
			(at 2.8321 -1.7399 270)
			(unlocked yes)
			(layer "B.Fab")
			(hide yes)
			(effects
				(font
					(size 1.016 1.016)
					(thickness 0.1524)
				)
				(justify mirror)
			)
		)
		(property "Device Type" "C0201H13"
			(at 2.8321 -3.2639 270)
			(unlocked yes)
			(layer "B.Fab")
			(hide yes)
			(effects
				(font
					(size 1.016 1.016)
					(thickness 0.1524)
				)
				(justify mirror)
			)
		)
		(duplicate_pad_numbers_are_jumpers no)
		(fp_rect
			(start 0.2794 0.6477)
			(end -0.2794 -0.6477)
			(stroke
				(width 0)
				(type default)
			)
			(fill no)
			(layer "B.CrtYd")
		)
		(fp_rect
			(start 0.2794 0.6477)
			(end -0.2794 -0.6477)
			(stroke
				(width 0)
				(type default)
			)
			(fill no)
			(layer "B.Fab")
		)
		(pad "1" smd custom
			(at 0 -0.2794 90)
			(size 0.0762 0.0762)
			(layers "B.Cu" "B.Mask" "B.Paste")
			(net "DUT_VDD")
			(options
				(clearance outline)
				(anchor circle)
			)
			(primitives
				(gr_poly
					(pts
						(arc
							(start 0.1524 0.127)
							(mid 0.137521 0.162921)
							(end 0.1016 0.1778)
						)
						(arc
							(start -0.1016 0.1778)
							(mid -0.137521 0.162921)
							(end -0.1524 0.127)
						)
						(arc
							(start -0.1524 -0.127)
							(mid -0.137521 -0.162921)
							(end -0.1016 -0.1778)
						)
						(arc
							(start 0.1016 -0.1778)
							(mid 0.137521 -0.162921)
							(end 0.1524 -0.127)
						)
					)
					(width 0)
					(fill yes)
				)
			)
		)
		(pad "2" smd custom
			(at 0 0.2794 90)
			(size 0.0762 0.0762)
			(layers "B.Cu" "B.Mask" "B.Paste")
			(net "GND")
			(options
				(clearance outline)
				(anchor circle)
			)
			(primitives
				(gr_poly
					(pts
						(arc
							(start 0.1524 0.127)
							(mid 0.137521 0.162921)
							(end 0.1016 0.1778)
						)
						(arc
							(start -0.1016 0.1778)
							(mid -0.137521 0.162921)
							(end -0.1524 0.127)
						)
						(arc
							(start -0.1524 -0.127)
							(mid -0.137521 -0.162921)
							(end -0.1016 -0.1778)
						)
						(arc
							(start 0.1016 -0.1778)
							(mid 0.137521 -0.162921)
							(end 0.1524 -0.127)
						)
					)
					(width 0)
					(fill yes)
				)
			)
		)
	)
	(footprint ""
		(layer "B.Cu")
		(at 310.007 -58.547 180)
		(property "Reference" "PG40"
			(at 0 0 0)
			(layer "B.SilkS")
			(hide yes)
			(effects
				(font
					(size 1.27 1.27)
				)
				(justify mirror)
			)
		)
		(property "Value" "GAP-CLOSE-PWR-3-GP"
			(at -0.0254 -6.5786 180)
			(unlocked yes)
			(layer "B.Fab")
			(hide yes)
			(effects
				(font
					(size 1.016 1.016)
					(thickness 0.1524)
				)
				(justify mirror)
			)
		)
		(property "Device Type" "GAP-CLOSE-PWR-3"
			(at -0.0254 -8.255 180)
			(unlocked yes)
			(layer "B.Fab")
			(hide yes)
			(effects
				(font
					(size 1.016 1.016)
					(thickness 0.1524)
				)
				(justify mirror)
			)
		)
		(duplicate_pad_numbers_are_jumpers no)
		(fp_rect
			(start 0.7112 0.4572)
			(end -0.7112 -0.4572)
			(stroke
				(width 0)
				(type default)
			)
			(fill no)
			(layer "B.CrtYd")
		)
		(fp_poly
			(pts
				(xy 0.7112 -0.4572) (xy -0.7112 -0.4572) (xy -0.7112 0.4572) (xy 0.7112 0.4572)
			)
			(stroke
				(width 0)
				(type default)
			)
			(fill no)
			(layer "B.Fab")
		)
		(pad "1" smd rect
			(at 0.3048 0)
			(size 0.6604 0.762)
			(layers "B.Cu" "B.Mask" "B.Paste")
			(net "DUT_VDD")
		)
		(pad "2" smd rect
			(at -0.3048 0)
			(size 0.6604 0.762)
			(layers "B.Cu" "B.Mask" "B.Paste")
			(net "P0V9_E")
		)
	)
	(footprint ""
		(layer "B.Cu")
		(at 34.613088 -126.105412)
		(property "Reference" "TP245"
			(at 0 0 0)
			(layer "B.SilkS")
			(hide yes)
			(effects
				(font
					(size 1.27 1.27)
				)
				(justify mirror)
			)
		)
		(property "Value" "TPAD28-2-GP"
			(at 0.0127 -1.6637 0)
			(unlocked yes)
			(layer "B.Fab")
			(hide yes)
			(effects
				(font
					(size 1.016 1.016)
					(thickness 0.1524)
				)
				(justify mirror)
			)
		)
		(property "Device Type" "TPAD28"
			(at 0.0127 -3.1877 0)
			(unlocked yes)
			(layer "B.Fab")
			(hide yes)
			(effects
				(font
					(size 1.016 1.016)
					(thickness 0.1524)
				)
				(justify mirror)
			)
		)
		(duplicate_pad_numbers_are_jumpers no)
		(fp_poly
			(pts
				(arc
					(start 0.3556 0)
					(mid -0.3556 0)
					(end 0.3556 0)
				)
			)
			(stroke
				(width 0)
				(type default)
			)
			(fill no)
			(layer "B.CrtYd")
		)
		(fp_poly
			(pts
				(arc
					(start 0.6096 0)
					(mid -0.6096 0)
					(end 0.6096 0)
				)
			)
			(stroke
				(width 0)
				(type default)
			)
			(fill no)
			(layer "B.Fab")
		)
		(pad "1" smd circle
			(at 0 0 180)
			(size 0.7112 0.7112)
			(layers "B.Cu" "B.Mask" "B.Paste")
			(net "TP_GPIOB5")
		)
	)
	(footprint ""
		(layer "B.Cu")
		(at 23.941786 -131.462018 90)
		(property "Reference" "R355"
			(at 0 0 90)
			(layer "B.SilkS")
			(hide yes)
			(effects
				(font
					(size 1.27 1.27)
				)
				(justify mirror)
			)
		)
		(property "Value" "3K3R2F-2-GP"
			(at -0.064008 -3.993896 90)
			(unlocked yes)
			(layer "B.Fab")
			(hide yes)
			(effects
				(font
					(size 1.016 1.016)
					(thickness 0.1524)
				)
				(justify mirror)
			)
		)
		(property "Device Type" "R402H16"
			(at -0.064008 -5.517896 90)
			(unlocked yes)
			(layer "B.Fab")
			(hide yes)
			(effects
				(font
					(size 1.016 1.016)
					(thickness 0.1524)
				)
				(justify mirror)
			)
		)
		(duplicate_pad_numbers_are_jumpers no)
		(fp_line
			(start 0.508 -0.9398)
			(end 0.508 0.9398)
			(stroke
				(width 0.1524)
				(type default)
			)
			(layer "B.SilkS")
		)
		(fp_line
			(start -0.508 -0.9398)
			(end 0.508 -0.9398)
			(stroke
				(width 0.1524)
				(type default)
			)
			(layer "B.SilkS")
		)
		(fp_rect
			(start 0.508 0.9398)
			(end -0.508 -0.9398)
			(stroke
				(width 0)
				(type default)
			)
			(fill no)
			(layer "B.CrtYd")
		)
		(fp_rect
			(start 0.508 0.9398)
			(end -0.508 -0.9398)
			(stroke
				(width 0)
				(type default)
			)
			(fill no)
			(layer "B.Fab")
		)
		(pad "1" smd custom
			(at 0 -0.4445 270)
			(size 0.1397 0.1397)
			(layers "B.Cu" "B.Mask" "B.Paste")
			(net "P3V3_STBY")
			(options
				(clearance outline)
				(anchor circle)
			)
			(primitives
				(gr_poly
					(pts
						(arc
							(start -0.1778 0.2794)
							(mid -0.249642 0.249642)
							(end -0.2794 0.1778)
						)
						(arc
							(start -0.2794 -0.1778)
							(mid -0.249642 -0.249642)
							(end -0.1778 -0.2794)
						)
						(arc
							(start 0.1778 -0.2794)
							(mid 0.249642 -0.249642)
							(end 0.2794 -0.1778)
						)
						(arc
							(start 0.2794 0.1778)
							(mid 0.249642 0.249642)
							(end 0.1778 0.2794)
						)
					)
					(width 0)
					(fill yes)
				)
			)
		)
		(pad "2" smd custom
			(at 0 0.4445 270)
			(size 0.1397 0.1397)
			(layers "B.Cu" "B.Mask" "B.Paste")
			(net "ROMA4")
			(options
				(clearance outline)
				(anchor circle)
			)
			(primitives
				(gr_poly
					(pts
						(arc
							(start -0.1778 0.2794)
							(mid -0.249642 0.249642)
							(end -0.2794 0.1778)
						)
						(arc
							(start -0.2794 -0.1778)
							(mid -0.249642 -0.249642)
							(end -0.1778 -0.2794)
						)
						(arc
							(start 0.1778 -0.2794)
							(mid 0.249642 -0.249642)
							(end 0.2794 -0.1778)
						)
						(arc
							(start 0.2794 0.1778)
							(mid 0.249642 0.249642)
							(end 0.1778 0.2794)
						)
					)
					(width 0)
					(fill yes)
				)
			)
		)
	)
	(footprint ""
		(layer "B.Cu")
		(at 53.7845 -124.902976 -90)
		(property "Reference" "R799"
			(at 0 0 90)
			(layer "B.SilkS")
			(hide yes)
			(effects
				(font
					(size 1.27 1.27)
				)
				(justify mirror)
			)
		)
		(property "Value" "4K7R2F-GP"
			(at -0.064008 -3.993896 270)
			(unlocked yes)
			(layer "B.Fab")
			(hide yes)
			(effects
				(font
					(size 1.016 1.016)
					(thickness 0.1524)
				)
				(justify mirror)
			)
		)
		(property "Device Type" "R402H16"
			(at -0.064008 -5.517896 270)
			(unlocked yes)
			(layer "B.Fab")
			(hide yes)
			(effects
				(font
					(size 1.016 1.016)
					(thickness 0.1524)
				)
				(justify mirror)
			)
		)
		(duplicate_pad_numbers_are_jumpers no)
		(fp_line
			(start -0.508 -0.9398)
			(end 0.508 -0.9398)
			(stroke
				(width 0.1524)
				(type default)
			)
			(layer "B.SilkS")
		)
		(fp_line
			(start 0.508 -0.9398)
			(end 0.508 0.9398)
			(stroke
				(width 0.1524)
				(type default)
			)
			(layer "B.SilkS")
		)
		(fp_rect
			(start 0.508 0.9398)
			(end -0.508 -0.9398)
			(stroke
				(width 0)
				(type default)
			)
			(fill no)
			(layer "B.CrtYd")
		)
		(fp_rect
			(start 0.508 0.9398)
			(end -0.508 -0.9398)
			(stroke
				(width 0)
				(type default)
			)
			(fill no)
			(layer "B.Fab")
		)
		(pad "1" smd custom
			(at 0 -0.4445 90)
			(size 0.1397 0.1397)
			(layers "B.Cu" "B.Mask" "B.Paste")
			(net "P3V3_STBY")
			(options
				(clearance outline)
				(anchor circle)
			)
			(primitives
				(gr_poly
					(pts
						(arc
							(start -0.1778 0.2794)
							(mid -0.249642 0.249642)
							(end -0.2794 0.1778)
						)
						(arc
							(start -0.2794 -0.1778)
							(mid -0.249642 -0.249642)
							(end -0.1778 -0.2794)
						)
						(arc
							(start 0.1778 -0.2794)
							(mid 0.249642 -0.249642)
							(end 0.2794 -0.1778)
						)
						(arc
							(start 0.2794 0.1778)
							(mid 0.249642 0.249642)
							(end 0.1778 0.2794)
						)
					)
					(width 0)
					(fill yes)
				)
			)
		)
		(pad "2" smd custom
			(at 0 0.4445 90)
			(size 0.1397 0.1397)
			(layers "B.Cu" "B.Mask" "B.Paste")
			(net "JTAG_BMC_TDO")
			(options
				(clearance outline)
				(anchor circle)
			)
			(primitives
				(gr_poly
					(pts
						(arc
							(start -0.1778 0.2794)
							(mid -0.249642 0.249642)
							(end -0.2794 0.1778)
						)
						(arc
							(start -0.2794 -0.1778)
							(mid -0.249642 -0.249642)
							(end -0.1778 -0.2794)
						)
						(arc
							(start 0.1778 -0.2794)
							(mid 0.249642 -0.249642)
							(end 0.2794 -0.1778)
						)
						(arc
							(start 0.2794 0.1778)
							(mid 0.249642 0.249642)
							(end 0.1778 0.2794)
						)
					)
					(width 0)
					(fill yes)
				)
			)
		)
	)
	(footprint ""
		(layer "B.Cu")
		(at 252.603 -47.997872 -90)
		(property "Reference" "C610"
			(at 0 0 90)
			(layer "B.SilkS")
			(hide yes)
			(effects
				(font
					(size 1.27 1.27)
				)
				(justify mirror)
			)
		)
		(property "Value" "SCD1U16V1KX-1-GP"
			(at 2.8321 -1.7399 270)
			(unlocked yes)
			(layer "B.Fab")
			(hide yes)
			(effects
				(font
					(size 1.016 1.016)
					(thickness 0.1524)
				)
				(justify mirror)
			)
		)
		(property "Device Type" "C0201H13"
			(at 2.8321 -3.2639 270)
			(unlocked yes)
			(layer "B.Fab")
			(hide yes)
			(effects
				(font
					(size 1.016 1.016)
					(thickness 0.1524)
				)
				(justify mirror)
			)
		)
		(duplicate_pad_numbers_are_jumpers no)
		(fp_rect
			(start 0.2794 0.6477)
			(end -0.2794 -0.6477)
			(stroke
				(width 0)
				(type default)
			)
			(fill no)
			(layer "B.CrtYd")
		)
		(fp_rect
			(start 0.2794 0.6477)
			(end -0.2794 -0.6477)
			(stroke
				(width 0)
				(type default)
			)
			(fill no)
			(layer "B.Fab")
		)
		(pad "1" smd custom
			(at 0 -0.2794 90)
			(size 0.0762 0.0762)
			(layers "B.Cu" "B.Mask" "B.Paste")
			(net "DUT_AVD_PCIE")
			(options
				(clearance outline)
				(anchor circle)
			)
			(primitives
				(gr_poly
					(pts
						(arc
							(start 0.1524 0.127)
							(mid 0.137521 0.162921)
							(end 0.1016 0.1778)
						)
						(arc
							(start -0.1016 0.1778)
							(mid -0.137521 0.162921)
							(end -0.1524 0.127)
						)
						(arc
							(start -0.1524 -0.127)
							(mid -0.137521 -0.162921)
							(end -0.1016 -0.1778)
						)
						(arc
							(start 0.1016 -0.1778)
							(mid 0.137521 -0.162921)
							(end 0.1524 -0.127)
						)
					)
					(width 0)
					(fill yes)
				)
			)
		)
		(pad "2" smd custom
			(at 0 0.2794 90)
			(size 0.0762 0.0762)
			(layers "B.Cu" "B.Mask" "B.Paste")
			(net "GND")
			(options
				(clearance outline)
				(anchor circle)
			)
			(primitives
				(gr_poly
					(pts
						(arc
							(start 0.1524 0.127)
							(mid 0.137521 0.162921)
							(end 0.1016 0.1778)
						)
						(arc
							(start -0.1016 0.1778)
							(mid -0.137521 0.162921)
							(end -0.1524 0.127)
						)
						(arc
							(start -0.1524 -0.127)
							(mid -0.137521 -0.162921)
							(end -0.1016 -0.1778)
						)
						(arc
							(start 0.1016 -0.1778)
							(mid 0.137521 -0.162921)
							(end 0.1524 -0.127)
						)
					)
					(width 0)
					(fill yes)
				)
			)
		)
	)
	(footprint ""
		(layer "B.Cu")
		(at 83.230212 -186.545474)
		(property "Reference" "R3233"
			(at 0 0 0)
			(layer "B.SilkS")
			(hide yes)
			(effects
				(font
					(size 1.27 1.27)
				)
				(justify mirror)
			)
		)
		(property "Value" "0R2J-2-GP"
			(at -0.064008 -3.993896 0)
			(unlocked yes)
			(layer "B.Fab")
			(hide yes)
			(effects
				(font
					(size 1.016 1.016)
					(thickness 0.1524)
				)
				(justify mirror)
			)
		)
		(property "Device Type" "R402H16"
			(at -0.064008 -5.517896 0)
			(unlocked yes)
			(layer "B.Fab")
			(hide yes)
			(effects
				(font
					(size 1.016 1.016)
					(thickness 0.1524)
				)
				(justify mirror)
			)
		)
		(duplicate_pad_numbers_are_jumpers no)
		(fp_line
			(start -0.508 -0.9398)
			(end 0.508 -0.9398)
			(stroke
				(width 0.1524)
				(type default)
			)
			(layer "B.SilkS")
		)
		(fp_line
			(start 0.508 -0.9398)
			(end 0.508 0.9398)
			(stroke
				(width 0.1524)
				(type default)
			)
			(layer "B.SilkS")
		)
		(fp_rect
			(start 0.508 0.9398)
			(end -0.508 -0.9398)
			(stroke
				(width 0)
				(type default)
			)
			(fill no)
			(layer "B.CrtYd")
		)
		(fp_rect
			(start 0.508 0.9398)
			(end -0.508 -0.9398)
			(stroke
				(width 0)
				(type default)
			)
			(fill no)
			(layer "B.Fab")
		)
		(pad "1" smd custom
			(at 0 -0.4445 180)
			(size 0.1397 0.1397)
			(layers "B.Cu" "B.Mask" "B.Paste")
			(net "SSD_PERST_Y10")
			(options
				(clearance outline)
				(anchor circle)
			)
			(primitives
				(gr_poly
					(pts
						(arc
							(start -0.1778 0.2794)
							(mid -0.249642 0.249642)
							(end -0.2794 0.1778)
						)
						(arc
							(start -0.2794 -0.1778)
							(mid -0.249642 -0.249642)
							(end -0.1778 -0.2794)
						)
						(arc
							(start 0.1778 -0.2794)
							(mid 0.249642 -0.249642)
							(end 0.2794 -0.1778)
						)
						(arc
							(start 0.2794 0.1778)
							(mid 0.249642 0.249642)
							(end 0.1778 0.2794)
						)
					)
					(width 0)
					(fill yes)
				)
			)
		)
		(pad "2" smd custom
			(at 0 0.4445 180)
			(size 0.1397 0.1397)
			(layers "B.Cu" "B.Mask" "B.Paste")
			(net "SSD_PERST#10_R")
			(options
				(clearance outline)
				(anchor circle)
			)
			(primitives
				(gr_poly
					(pts
						(arc
							(start -0.1778 0.2794)
							(mid -0.249642 0.249642)
							(end -0.2794 0.1778)
						)
						(arc
							(start -0.2794 -0.1778)
							(mid -0.249642 -0.249642)
							(end -0.1778 -0.2794)
						)
						(arc
							(start 0.1778 -0.2794)
							(mid 0.249642 -0.249642)
							(end 0.2794 -0.1778)
						)
						(arc
							(start 0.2794 0.1778)
							(mid 0.249642 0.249642)
							(end 0.1778 0.2794)
						)
					)
					(width 0)
					(fill yes)
				)
			)
		)
	)
	(footprint ""
		(layer "B.Cu")
		(at 68.961 -42.164 -90)
		(property "Reference" "PR28"
			(at 0 0 90)
			(layer "B.SilkS")
			(hide yes)
			(effects
				(font
					(size 1.27 1.27)
				)
				(justify mirror)
			)
		)
		(property "Value" "3D01R5F-GP"
			(at 0 -8.9535 270)
			(unlocked yes)
			(layer "B.Fab")
			(hide yes)
			(effects
				(font
					(size 1.27 1.016)
					(thickness 0.1524)
				)
				(justify mirror)
			)
		)
		(property "Device Type" "R805H24"
			(at 0 -10.6299 270)
			(unlocked yes)
			(layer "B.Fab")
			(hide yes)
			(effects
				(font
					(size 1.27 1.016)
					(thickness 0.1524)
				)
				(justify mirror)
			)
		)
		(duplicate_pad_numbers_are_jumpers no)
		(fp_line
			(start -0.889 1.7018)
			(end -0.889 -0.508)
			(stroke
				(width 0.1524)
				(type default)
			)
			(layer "B.SilkS")
		)
		(fp_line
			(start 0.889 1.7018)
			(end -0.889 1.7018)
			(stroke
				(width 0.1524)
				(type default)
			)
			(layer "B.SilkS")
		)
		(fp_line
			(start 0.889 0.0762)
			(end 0.889 1.7018)
			(stroke
				(width 0.1524)
				(type default)
			)
			(layer "B.SilkS")
		)
		(fp_line
			(start -0.889 -1.7018)
			(end -0.889 -0.381)
			(stroke
				(width 0.1524)
				(type default)
			)
			(layer "B.SilkS")
		)
		(fp_line
			(start -0.889 -1.7018)
			(end 0.889 -1.7018)
			(stroke
				(width 0.1524)
				(type default)
			)
			(layer "B.SilkS")
		)
		(fp_line
			(start 0.889 -1.7018)
			(end 0.889 0.2794)
			(stroke
				(width 0.1524)
				(type default)
			)
			(layer "B.SilkS")
		)
		(fp_poly
			(pts
				(xy -0.9652 -1.778) (xy -0.9652 1.778) (xy 0.9652 1.778) (xy 0.9652 -1.778)
			)
			(stroke
				(width 0)
				(type default)
			)
			(fill no)
			(layer "B.CrtYd")
		)
		(fp_rect
			(start 0.9652 1.778)
			(end -0.9652 -1.778)
			(stroke
				(width 0)
				(type default)
			)
			(fill no)
			(layer "B.Fab")
		)
		(pad "1" smd rect
			(at 0 -0.9652 90)
			(size 1.397 1.143)
			(layers "B.Cu" "B.Mask" "B.Paste")
			(net "P3V3_STBY_SNB")
		)
		(pad "2" smd rect
			(at 0 0.9652 90)
			(size 1.397 1.143)
			(layers "B.Cu" "B.Mask" "B.Paste")
			(net "GND")
		)
	)
	(footprint ""
		(layer "B.Cu")
		(at 336.836512 -172.432218)
		(property "Reference" "R4156"
			(at 0 0 0)
			(layer "B.SilkS")
			(hide yes)
			(effects
				(font
					(size 1.27 1.27)
				)
				(justify mirror)
			)
		)
		(property "Value" "4K7R2F-GP"
			(at -0.064008 -3.993896 0)
			(unlocked yes)
			(layer "B.Fab")
			(hide yes)
			(effects
				(font
					(size 1.016 1.016)
					(thickness 0.1524)
				)
				(justify mirror)
			)
		)
		(property "Device Type" "R402H16"
			(at -0.064008 -5.517896 0)
			(unlocked yes)
			(layer "B.Fab")
			(hide yes)
			(effects
				(font
					(size 1.016 1.016)
					(thickness 0.1524)
				)
				(justify mirror)
			)
		)
		(duplicate_pad_numbers_are_jumpers no)
		(fp_line
			(start -0.508 -0.9398)
			(end 0.508 -0.9398)
			(stroke
				(width 0.1524)
				(type default)
			)
			(layer "B.SilkS")
		)
		(fp_line
			(start 0.508 -0.9398)
			(end 0.508 0.9398)
			(stroke
				(width 0.1524)
				(type default)
			)
			(layer "B.SilkS")
		)
		(fp_rect
			(start 0.508 0.9398)
			(end -0.508 -0.9398)
			(stroke
				(width 0)
				(type default)
			)
			(fill no)
			(layer "B.CrtYd")
		)
		(fp_rect
			(start 0.508 0.9398)
			(end -0.508 -0.9398)
			(stroke
				(width 0)
				(type default)
			)
			(fill no)
			(layer "B.Fab")
		)
		(pad "1" smd custom
			(at 0 -0.4445 180)
			(size 0.1397 0.1397)
			(layers "B.Cu" "B.Mask" "B.Paste")
			(net "SSD_PRSNT#9")
			(options
				(clearance outline)
				(anchor circle)
			)
			(primitives
				(gr_poly
					(pts
						(arc
							(start -0.1778 0.2794)
							(mid -0.249642 0.249642)
							(end -0.2794 0.1778)
						)
						(arc
							(start -0.2794 -0.1778)
							(mid -0.249642 -0.249642)
							(end -0.1778 -0.2794)
						)
						(arc
							(start 0.1778 -0.2794)
							(mid 0.249642 -0.249642)
							(end 0.2794 -0.1778)
						)
						(arc
							(start 0.2794 0.1778)
							(mid 0.249642 0.249642)
							(end 0.1778 0.2794)
						)
					)
					(width 0)
					(fill yes)
				)
			)
		)
		(pad "2" smd custom
			(at 0 0.4445 180)
			(size 0.1397 0.1397)
			(layers "B.Cu" "B.Mask" "B.Paste")
			(net "P3V3_STBY")
			(options
				(clearance outline)
				(anchor circle)
			)
			(primitives
				(gr_poly
					(pts
						(arc
							(start -0.1778 0.2794)
							(mid -0.249642 0.249642)
							(end -0.2794 0.1778)
						)
						(arc
							(start -0.2794 -0.1778)
							(mid -0.249642 -0.249642)
							(end -0.1778 -0.2794)
						)
						(arc
							(start 0.1778 -0.2794)
							(mid 0.249642 -0.249642)
							(end 0.2794 -0.1778)
						)
						(arc
							(start 0.2794 0.1778)
							(mid 0.249642 0.249642)
							(end 0.1778 0.2794)
						)
					)
					(width 0)
					(fill yes)
				)
			)
		)
	)
	(footprint ""
		(layer "B.Cu")
		(at 212.598 -197.231 180)
		(property "Reference" "R3241"
			(at 0 0 0)
			(layer "B.SilkS")
			(hide yes)
			(effects
				(font
					(size 1.27 1.27)
				)
				(justify mirror)
			)
		)
		(property "Value" "0R2J-2-GP"
			(at -0.064008 -3.993896 180)
			(unlocked yes)
			(layer "B.Fab")
			(hide yes)
			(effects
				(font
					(size 1.016 1.016)
					(thickness 0.1524)
				)
				(justify mirror)
			)
		)
		(property "Device Type" "R402H16"
			(at -0.064008 -5.517896 180)
			(unlocked yes)
			(layer "B.Fab")
			(hide yes)
			(effects
				(font
					(size 1.016 1.016)
					(thickness 0.1524)
				)
				(justify mirror)
			)
		)
		(duplicate_pad_numbers_are_jumpers no)
		(fp_line
			(start 0.508 -0.9398)
			(end 0.508 0.9398)
			(stroke
				(width 0.1524)
				(type default)
			)
			(layer "B.SilkS")
		)
		(fp_line
			(start -0.508 -0.9398)
			(end 0.508 -0.9398)
			(stroke
				(width 0.1524)
				(type default)
			)
			(layer "B.SilkS")
		)
		(fp_rect
			(start 0.508 0.9398)
			(end -0.508 -0.9398)
			(stroke
				(width 0)
				(type default)
			)
			(fill no)
			(layer "B.CrtYd")
		)
		(fp_rect
			(start 0.508 0.9398)
			(end -0.508 -0.9398)
			(stroke
				(width 0)
				(type default)
			)
			(fill no)
			(layer "B.Fab")
		)
		(pad "1" smd custom
			(at 0 -0.4445)
			(size 0.1397 0.1397)
			(layers "B.Cu" "B.Mask" "B.Paste")
			(net "BMC_SSD_RST#13")
			(options
				(clearance outline)
				(anchor circle)
			)
			(primitives
				(gr_poly
					(pts
						(arc
							(start -0.1778 0.2794)
							(mid -0.249642 0.249642)
							(end -0.2794 0.1778)
						)
						(arc
							(start -0.2794 -0.1778)
							(mid -0.249642 -0.249642)
							(end -0.1778 -0.2794)
						)
						(arc
							(start 0.1778 -0.2794)
							(mid 0.249642 -0.249642)
							(end 0.2794 -0.1778)
						)
						(arc
							(start 0.2794 0.1778)
							(mid 0.249642 0.249642)
							(end 0.1778 0.2794)
						)
					)
					(width 0)
					(fill yes)
				)
			)
		)
		(pad "2" smd custom
			(at 0 0.4445)
			(size 0.1397 0.1397)
			(layers "B.Cu" "B.Mask" "B.Paste")
			(net "BMC_SSD_RST#0_A13")
			(options
				(clearance outline)
				(anchor circle)
			)
			(primitives
				(gr_poly
					(pts
						(arc
							(start -0.1778 0.2794)
							(mid -0.249642 0.249642)
							(end -0.2794 0.1778)
						)
						(arc
							(start -0.2794 -0.1778)
							(mid -0.249642 -0.249642)
							(end -0.1778 -0.2794)
						)
						(arc
							(start 0.1778 -0.2794)
							(mid 0.249642 -0.249642)
							(end 0.2794 -0.1778)
						)
						(arc
							(start 0.2794 0.1778)
							(mid 0.249642 0.249642)
							(end 0.1778 0.2794)
						)
					)
					(width 0)
					(fill yes)
				)
			)
		)
	)
	(footprint ""
		(layer "B.Cu")
		(at 25.4508 -69.96684 90)
		(property "Reference" "R459"
			(at 0 0 90)
			(layer "B.SilkS")
			(hide yes)
			(effects
				(font
					(size 1.27 1.27)
				)
				(justify mirror)
			)
		)
		(property "Value" "10KR2F-2-GP"
			(at -0.064008 -3.993896 90)
			(unlocked yes)
			(layer "B.Fab")
			(hide yes)
			(effects
				(font
					(size 1.016 1.016)
					(thickness 0.1524)
				)
				(justify mirror)
			)
		)
		(property "Device Type" "R402H16"
			(at -0.064008 -5.517896 90)
			(unlocked yes)
			(layer "B.Fab")
			(hide yes)
			(effects
				(font
					(size 1.016 1.016)
					(thickness 0.1524)
				)
				(justify mirror)
			)
		)
		(duplicate_pad_numbers_are_jumpers no)
		(fp_line
			(start 0.508 -0.9398)
			(end 0.508 0.9398)
			(stroke
				(width 0.1524)
				(type default)
			)
			(layer "B.SilkS")
		)
		(fp_line
			(start -0.508 -0.9398)
			(end 0.508 -0.9398)
			(stroke
				(width 0.1524)
				(type default)
			)
			(layer "B.SilkS")
		)
		(fp_rect
			(start 0.508 0.9398)
			(end -0.508 -0.9398)
			(stroke
				(width 0)
				(type default)
			)
			(fill no)
			(layer "B.CrtYd")
		)
		(fp_rect
			(start 0.508 0.9398)
			(end -0.508 -0.9398)
			(stroke
				(width 0)
				(type default)
			)
			(fill no)
			(layer "B.Fab")
		)
		(pad "1" smd custom
			(at 0 -0.4445 270)
			(size 0.1397 0.1397)
			(layers "B.Cu" "B.Mask" "B.Paste")
			(net "GND")
			(options
				(clearance outline)
				(anchor circle)
			)
			(primitives
				(gr_poly
					(pts
						(arc
							(start -0.1778 0.2794)
							(mid -0.249642 0.249642)
							(end -0.2794 0.1778)
						)
						(arc
							(start -0.2794 -0.1778)
							(mid -0.249642 -0.249642)
							(end -0.1778 -0.2794)
						)
						(arc
							(start 0.1778 -0.2794)
							(mid 0.249642 -0.249642)
							(end 0.2794 -0.1778)
						)
						(arc
							(start 0.2794 0.1778)
							(mid 0.249642 0.249642)
							(end 0.1778 0.2794)
						)
					)
					(width 0)
					(fill yes)
				)
			)
		)
		(pad "2" smd custom
			(at 0 0.4445 270)
			(size 0.1397 0.1397)
			(layers "B.Cu" "B.Mask" "B.Paste")
			(net "RMII_BMC_TX_EN")
			(options
				(clearance outline)
				(anchor circle)
			)
			(primitives
				(gr_poly
					(pts
						(arc
							(start -0.1778 0.2794)
							(mid -0.249642 0.249642)
							(end -0.2794 0.1778)
						)
						(arc
							(start -0.2794 -0.1778)
							(mid -0.249642 -0.249642)
							(end -0.1778 -0.2794)
						)
						(arc
							(start 0.1778 -0.2794)
							(mid 0.249642 -0.249642)
							(end 0.2794 -0.1778)
						)
						(arc
							(start 0.2794 0.1778)
							(mid 0.249642 0.249642)
							(end 0.1778 0.2794)
						)
					)
					(width 0)
					(fill yes)
				)
			)
		)
	)
	(footprint ""
		(layer "B.Cu")
		(at 227.457 -196.977)
		(property "Reference" "U76"
			(at 0 0 0)
			(layer "B.SilkS")
			(hide yes)
			(effects
				(font
					(size 1.27 1.27)
				)
				(justify mirror)
			)
		)
		(property "Value" "SN74LVC1G08DCKR-GP"
			(at 2.3368 -8.6868 0)
			(unlocked yes)
			(layer "B.Fab")
			(hide yes)
			(effects
				(font
					(size 1.016 1.016)
					(thickness 0.1524)
				)
				(justify mirror)
			)
		)
		(property "Device Type" "SC70-5H44"
			(at 2.3114 -10.414 0)
			(unlocked yes)
			(layer "B.Fab")
			(hide yes)
			(effects
				(font
					(size 1.016 1.016)
					(thickness 0.1524)
				)
				(justify mirror)
			)
		)
		(duplicate_pad_numbers_are_jumpers no)
		(fp_line
			(start -1.3843 -1.8034)
			(end -1.3843 -1.1176)
			(stroke
				(width 0.3302)
				(type default)
			)
			(layer "B.SilkS")
		)
		(fp_line
			(start -1.27 -1.7018)
			(end -1.27 1.7018)
			(stroke
				(width 0.1524)
				(type default)
			)
			(layer "B.SilkS")
		)
		(fp_line
			(start -1.27 1.7018)
			(end 1.27 1.7018)
			(stroke
				(width 0.1524)
				(type default)
			)
			(layer "B.SilkS")
		)
		(fp_line
			(start -0.6604 -1.8034)
			(end -1.3843 -1.8034)
			(stroke
				(width 0.3302)
				(type default)
			)
			(layer "B.SilkS")
		)
		(fp_line
			(start 1.27 -1.7018)
			(end -1.27 -1.7018)
			(stroke
				(width 0.1524)
				(type default)
			)
			(layer "B.SilkS")
		)
		(fp_line
			(start 1.27 1.7018)
			(end 1.27 -1.7018)
			(stroke
				(width 0.1524)
				(type default)
			)
			(layer "B.SilkS")
		)
		(fp_rect
			(start 1.524 1.9558)
			(end -1.524 -1.9558)
			(stroke
				(width 0)
				(type default)
			)
			(fill no)
			(layer "B.CrtYd")
		)
		(fp_poly
			(pts
				(xy 1.524 -1.9558) (xy -1.524 -1.9558) (xy -1.524 1.9558) (xy 1.524 1.9558)
			)
			(stroke
				(width 0)
				(type default)
			)
			(fill no)
			(layer "B.Fab")
		)
		(pad "1" smd rect
			(at -0.65024 -0.8255 180)
			(size 0.4064 1.2192)
			(layers "B.Cu" "B.Mask" "B.Paste")
			(net "BMC_SSD_RST#0_A12")
		)
		(pad "2" smd rect
			(at 0 -0.8255 180)
			(size 0.4064 1.2192)
			(layers "B.Cu" "B.Mask" "B.Paste")
			(net "SSD_PERST#0_B12")
		)
		(pad "3" smd rect
			(at 0.65024 -0.8255 180)
			(size 0.4064 1.2192)
			(layers "B.Cu" "B.Mask" "B.Paste")
			(net "GND")
		)
		(pad "4" smd rect
			(at 0.65024 0.8255 180)
			(size 0.4064 1.2192)
			(layers "B.Cu" "B.Mask" "B.Paste")
			(net "SSD_PERST_Y12")
		)
		(pad "5" smd rect
			(at -0.65024 0.8255 180)
			(size 0.4064 1.2192)
			(layers "B.Cu" "B.Mask" "B.Paste")
			(net "P3V3_STBY")
		)
	)
	(footprint ""
		(layer "B.Cu")
		(at 57.032652 -118.4402 -90)
		(property "Reference" "R243"
			(at 0 0 90)
			(layer "B.SilkS")
			(hide yes)
			(effects
				(font
					(size 1.27 1.27)
				)
				(justify mirror)
			)
		)
		(property "Value" "0R2J-2-GP"
			(at -0.064008 -3.993896 270)
			(unlocked yes)
			(layer "B.Fab")
			(hide yes)
			(effects
				(font
					(size 1.016 1.016)
					(thickness 0.1524)
				)
				(justify mirror)
			)
		)
		(property "Device Type" "R402H16"
			(at -0.064008 -5.517896 270)
			(unlocked yes)
			(layer "B.Fab")
			(hide yes)
			(effects
				(font
					(size 1.016 1.016)
					(thickness 0.1524)
				)
				(justify mirror)
			)
		)
		(duplicate_pad_numbers_are_jumpers no)
		(fp_line
			(start -0.508 -0.9398)
			(end 0.508 -0.9398)
			(stroke
				(width 0.1524)
				(type default)
			)
			(layer "B.SilkS")
		)
		(fp_line
			(start 0.508 -0.9398)
			(end 0.508 0.9398)
			(stroke
				(width 0.1524)
				(type default)
			)
			(layer "B.SilkS")
		)
		(fp_rect
			(start 0.508 0.9398)
			(end -0.508 -0.9398)
			(stroke
				(width 0)
				(type default)
			)
			(fill no)
			(layer "B.CrtYd")
		)
		(fp_rect
			(start 0.508 0.9398)
			(end -0.508 -0.9398)
			(stroke
				(width 0)
				(type default)
			)
			(fill no)
			(layer "B.Fab")
		)
		(pad "1" smd custom
			(at 0 -0.4445 90)
			(size 0.1397 0.1397)
			(layers "B.Cu" "B.Mask" "B.Paste")
			(net "BMC_I2C3_MINI3_SDA_S")
			(options
				(clearance outline)
				(anchor circle)
			)
			(primitives
				(gr_poly
					(pts
						(arc
							(start -0.1778 0.2794)
							(mid -0.249642 0.249642)
							(end -0.2794 0.1778)
						)
						(arc
							(start -0.2794 -0.1778)
							(mid -0.249642 -0.249642)
							(end -0.1778 -0.2794)
						)
						(arc
							(start 0.1778 -0.2794)
							(mid 0.249642 -0.249642)
							(end 0.2794 -0.1778)
						)
						(arc
							(start 0.2794 0.1778)
							(mid 0.249642 0.249642)
							(end 0.1778 0.2794)
						)
					)
					(width 0)
					(fill yes)
				)
			)
		)
		(pad "2" smd custom
			(at 0 0.4445 90)
			(size 0.1397 0.1397)
			(layers "B.Cu" "B.Mask" "B.Paste")
			(net "BMC0_SMB3_DAT")
			(options
				(clearance outline)
				(anchor circle)
			)
			(primitives
				(gr_poly
					(pts
						(arc
							(start -0.1778 0.2794)
							(mid -0.249642 0.249642)
							(end -0.2794 0.1778)
						)
						(arc
							(start -0.2794 -0.1778)
							(mid -0.249642 -0.249642)
							(end -0.1778 -0.2794)
						)
						(arc
							(start 0.1778 -0.2794)
							(mid 0.249642 -0.249642)
							(end 0.2794 -0.1778)
						)
						(arc
							(start 0.2794 0.1778)
							(mid 0.249642 0.249642)
							(end 0.1778 0.2794)
						)
					)
					(width 0)
					(fill yes)
				)
			)
		)
	)
	(footprint ""
		(layer "B.Cu")
		(at 72.747124 -183.235092)
		(property "Reference" "R4103"
			(at 0 0 0)
			(layer "B.SilkS")
			(hide yes)
			(effects
				(font
					(size 1.27 1.27)
				)
				(justify mirror)
			)
		)
		(property "Value" "4K7R2F-GP"
			(at -0.064008 -3.993896 0)
			(unlocked yes)
			(layer "B.Fab")
			(hide yes)
			(effects
				(font
					(size 1.016 1.016)
					(thickness 0.1524)
				)
				(justify mirror)
			)
		)
		(property "Device Type" "R402H16"
			(at -0.064008 -5.517896 0)
			(unlocked yes)
			(layer "B.Fab")
			(hide yes)
			(effects
				(font
					(size 1.016 1.016)
					(thickness 0.1524)
				)
				(justify mirror)
			)
		)
		(duplicate_pad_numbers_are_jumpers no)
		(fp_line
			(start -0.508 -0.9398)
			(end 0.508 -0.9398)
			(stroke
				(width 0.1524)
				(type default)
			)
			(layer "B.SilkS")
		)
		(fp_line
			(start 0.508 -0.9398)
			(end 0.508 0.9398)
			(stroke
				(width 0.1524)
				(type default)
			)
			(layer "B.SilkS")
		)
		(fp_rect
			(start 0.508 0.9398)
			(end -0.508 -0.9398)
			(stroke
				(width 0)
				(type default)
			)
			(fill no)
			(layer "B.CrtYd")
		)
		(fp_rect
			(start 0.508 0.9398)
			(end -0.508 -0.9398)
			(stroke
				(width 0)
				(type default)
			)
			(fill no)
			(layer "B.Fab")
		)
		(pad "1" smd custom
			(at 0 -0.4445 180)
			(size 0.1397 0.1397)
			(layers "B.Cu" "B.Mask" "B.Paste")
			(net "SSD_ATNLED#0")
			(options
				(clearance outline)
				(anchor circle)
			)
			(primitives
				(gr_poly
					(pts
						(arc
							(start -0.1778 0.2794)
							(mid -0.249642 0.249642)
							(end -0.2794 0.1778)
						)
						(arc
							(start -0.2794 -0.1778)
							(mid -0.249642 -0.249642)
							(end -0.1778 -0.2794)
						)
						(arc
							(start 0.1778 -0.2794)
							(mid 0.249642 -0.249642)
							(end 0.2794 -0.1778)
						)
						(arc
							(start 0.2794 0.1778)
							(mid 0.249642 0.249642)
							(end 0.1778 0.2794)
						)
					)
					(width 0)
					(fill yes)
				)
			)
		)
		(pad "2" smd custom
			(at 0 0.4445 180)
			(size 0.1397 0.1397)
			(layers "B.Cu" "B.Mask" "B.Paste")
			(net "P3V3_STBY")
			(options
				(clearance outline)
				(anchor circle)
			)
			(primitives
				(gr_poly
					(pts
						(arc
							(start -0.1778 0.2794)
							(mid -0.249642 0.249642)
							(end -0.2794 0.1778)
						)
						(arc
							(start -0.2794 -0.1778)
							(mid -0.249642 -0.249642)
							(end -0.1778 -0.2794)
						)
						(arc
							(start 0.1778 -0.2794)
							(mid 0.249642 -0.249642)
							(end 0.2794 -0.1778)
						)
						(arc
							(start 0.2794 0.1778)
							(mid 0.249642 0.249642)
							(end 0.1778 0.2794)
						)
					)
					(width 0)
					(fill yes)
				)
			)
		)
	)
	(footprint ""
		(layer "B.Cu")
		(at 235.966 -20.447)
		(property "Reference" "R813"
			(at 0 0 0)
			(layer "B.SilkS")
			(hide yes)
			(effects
				(font
					(size 1.27 1.27)
				)
				(justify mirror)
			)
		)
		(property "Value" "4K7R2F-GP"
			(at -0.064008 -3.993896 0)
			(unlocked yes)
			(layer "B.Fab")
			(hide yes)
			(effects
				(font
					(size 1.016 1.016)
					(thickness 0.1524)
				)
				(justify mirror)
			)
		)
		(property "Device Type" "R402H16"
			(at -0.064008 -5.517896 0)
			(unlocked yes)
			(layer "B.Fab")
			(hide yes)
			(effects
				(font
					(size 1.016 1.016)
					(thickness 0.1524)
				)
				(justify mirror)
			)
		)
		(duplicate_pad_numbers_are_jumpers no)
		(fp_line
			(start -0.508 -0.9398)
			(end 0.508 -0.9398)
			(stroke
				(width 0.1524)
				(type default)
			)
			(layer "B.SilkS")
		)
		(fp_line
			(start 0.508 -0.9398)
			(end 0.508 0.9398)
			(stroke
				(width 0.1524)
				(type default)
			)
			(layer "B.SilkS")
		)
		(fp_rect
			(start 0.508 0.9398)
			(end -0.508 -0.9398)
			(stroke
				(width 0)
				(type default)
			)
			(fill no)
			(layer "B.CrtYd")
		)
		(fp_rect
			(start 0.508 0.9398)
			(end -0.508 -0.9398)
			(stroke
				(width 0)
				(type default)
			)
			(fill no)
			(layer "B.Fab")
		)
		(pad "1" smd custom
			(at 0 -0.4445 180)
			(size 0.1397 0.1397)
			(layers "B.Cu" "B.Mask" "B.Paste")
			(net "BOOTSTRAP6")
			(options
				(clearance outline)
				(anchor circle)
			)
			(primitives
				(gr_poly
					(pts
						(arc
							(start -0.1778 0.2794)
							(mid -0.249642 0.249642)
							(end -0.2794 0.1778)
						)
						(arc
							(start -0.2794 -0.1778)
							(mid -0.249642 -0.249642)
							(end -0.1778 -0.2794)
						)
						(arc
							(start 0.1778 -0.2794)
							(mid 0.249642 -0.249642)
							(end 0.2794 -0.1778)
						)
						(arc
							(start 0.2794 0.1778)
							(mid 0.249642 0.249642)
							(end 0.1778 0.2794)
						)
					)
					(width 0)
					(fill yes)
				)
			)
		)
		(pad "2" smd custom
			(at 0 0.4445 180)
			(size 0.1397 0.1397)
			(layers "B.Cu" "B.Mask" "B.Paste")
			(net "DUT_VDDO")
			(options
				(clearance outline)
				(anchor circle)
			)
			(primitives
				(gr_poly
					(pts
						(arc
							(start -0.1778 0.2794)
							(mid -0.249642 0.249642)
							(end -0.2794 0.1778)
						)
						(arc
							(start -0.2794 -0.1778)
							(mid -0.249642 -0.249642)
							(end -0.1778 -0.2794)
						)
						(arc
							(start 0.1778 -0.2794)
							(mid 0.249642 -0.249642)
							(end 0.2794 -0.1778)
						)
						(arc
							(start 0.2794 0.1778)
							(mid 0.249642 0.249642)
							(end 0.1778 0.2794)
						)
					)
					(width 0)
					(fill yes)
				)
			)
		)
	)
	(footprint ""
		(layer "B.Cu")
		(at 265.9253 -8.85571 180)
		(property "Reference" "R2966"
			(at 0 0 0)
			(layer "B.SilkS")
			(hide yes)
			(effects
				(font
					(size 1.27 1.27)
				)
				(justify mirror)
			)
		)
		(property "Value" "0R2J-2-GP"
			(at -0.064008 -3.993896 180)
			(unlocked yes)
			(layer "B.Fab")
			(hide yes)
			(effects
				(font
					(size 1.016 1.016)
					(thickness 0.1524)
				)
				(justify mirror)
			)
		)
		(property "Device Type" "R402H16"
			(at -0.064008 -5.517896 180)
			(unlocked yes)
			(layer "B.Fab")
			(hide yes)
			(effects
				(font
					(size 1.016 1.016)
					(thickness 0.1524)
				)
				(justify mirror)
			)
		)
		(duplicate_pad_numbers_are_jumpers no)
		(fp_line
			(start 0.508 -0.9398)
			(end 0.508 0.9398)
			(stroke
				(width 0.1524)
				(type default)
			)
			(layer "B.SilkS")
		)
		(fp_line
			(start -0.508 -0.9398)
			(end 0.508 -0.9398)
			(stroke
				(width 0.1524)
				(type default)
			)
			(layer "B.SilkS")
		)
		(fp_rect
			(start 0.508 0.9398)
			(end -0.508 -0.9398)
			(stroke
				(width 0)
				(type default)
			)
			(fill no)
			(layer "B.CrtYd")
		)
		(fp_rect
			(start 0.508 0.9398)
			(end -0.508 -0.9398)
			(stroke
				(width 0)
				(type default)
			)
			(fill no)
			(layer "B.Fab")
		)
		(pad "1" smd custom
			(at 0 -0.4445)
			(size 0.1397 0.1397)
			(layers "B.Cu" "B.Mask" "B.Paste")
			(net "HOST7_RST_N")
			(options
				(clearance outline)
				(anchor circle)
			)
			(primitives
				(gr_poly
					(pts
						(arc
							(start -0.1778 0.2794)
							(mid -0.249642 0.249642)
							(end -0.2794 0.1778)
						)
						(arc
							(start -0.2794 -0.1778)
							(mid -0.249642 -0.249642)
							(end -0.1778 -0.2794)
						)
						(arc
							(start 0.1778 -0.2794)
							(mid 0.249642 -0.249642)
							(end 0.2794 -0.1778)
						)
						(arc
							(start 0.2794 0.1778)
							(mid 0.249642 0.249642)
							(end 0.1778 0.2794)
						)
					)
					(width 0)
					(fill yes)
				)
			)
		)
		(pad "2" smd custom
			(at 0 0.4445)
			(size 0.1397 0.1397)
			(layers "B.Cu" "B.Mask" "B.Paste")
			(net "HOST7_RST_N_C")
			(options
				(clearance outline)
				(anchor circle)
			)
			(primitives
				(gr_poly
					(pts
						(arc
							(start -0.1778 0.2794)
							(mid -0.249642 0.249642)
							(end -0.2794 0.1778)
						)
						(arc
							(start -0.2794 -0.1778)
							(mid -0.249642 -0.249642)
							(end -0.1778 -0.2794)
						)
						(arc
							(start 0.1778 -0.2794)
							(mid 0.249642 -0.249642)
							(end 0.2794 -0.1778)
						)
						(arc
							(start 0.2794 0.1778)
							(mid 0.249642 0.249642)
							(end 0.1778 0.2794)
						)
					)
					(width 0)
					(fill yes)
				)
			)
		)
	)
	(footprint ""
		(layer "B.Cu")
		(at 236.609128 -31.9786)
		(property "Reference" "C475"
			(at 0 0 0)
			(layer "B.SilkS")
			(hide yes)
			(effects
				(font
					(size 1.27 1.27)
				)
				(justify mirror)
			)
		)
		(property "Value" "SCD1U16V1KX-1-GP"
			(at 2.8321 -1.7399 0)
			(unlocked yes)
			(layer "B.Fab")
			(hide yes)
			(effects
				(font
					(size 1.016 1.016)
					(thickness 0.1524)
				)
				(justify mirror)
			)
		)
		(property "Device Type" "C0201H13"
			(at 2.8321 -3.2639 0)
			(unlocked yes)
			(layer "B.Fab")
			(hide yes)
			(effects
				(font
					(size 1.016 1.016)
					(thickness 0.1524)
				)
				(justify mirror)
			)
		)
		(duplicate_pad_numbers_are_jumpers no)
		(fp_rect
			(start 0.2794 0.6477)
			(end -0.2794 -0.6477)
			(stroke
				(width 0)
				(type default)
			)
			(fill no)
			(layer "B.CrtYd")
		)
		(fp_rect
			(start 0.2794 0.6477)
			(end -0.2794 -0.6477)
			(stroke
				(width 0)
				(type default)
			)
			(fill no)
			(layer "B.Fab")
		)
		(pad "1" smd custom
			(at 0 -0.2794 180)
			(size 0.0762 0.0762)
			(layers "B.Cu" "B.Mask" "B.Paste")
			(net "DUT_VDDO")
			(options
				(clearance outline)
				(anchor circle)
			)
			(primitives
				(gr_poly
					(pts
						(arc
							(start 0.1524 0.127)
							(mid 0.137521 0.162921)
							(end 0.1016 0.1778)
						)
						(arc
							(start -0.1016 0.1778)
							(mid -0.137521 0.162921)
							(end -0.1524 0.127)
						)
						(arc
							(start -0.1524 -0.127)
							(mid -0.137521 -0.162921)
							(end -0.1016 -0.1778)
						)
						(arc
							(start 0.1016 -0.1778)
							(mid 0.137521 -0.162921)
							(end 0.1524 -0.127)
						)
					)
					(width 0)
					(fill yes)
				)
			)
		)
		(pad "2" smd custom
			(at 0 0.2794 180)
			(size 0.0762 0.0762)
			(layers "B.Cu" "B.Mask" "B.Paste")
			(net "GND")
			(options
				(clearance outline)
				(anchor circle)
			)
			(primitives
				(gr_poly
					(pts
						(arc
							(start 0.1524 0.127)
							(mid 0.137521 0.162921)
							(end 0.1016 0.1778)
						)
						(arc
							(start -0.1016 0.1778)
							(mid -0.137521 0.162921)
							(end -0.1524 0.127)
						)
						(arc
							(start -0.1524 -0.127)
							(mid -0.137521 -0.162921)
							(end -0.1016 -0.1778)
						)
						(arc
							(start 0.1016 -0.1778)
							(mid 0.137521 -0.162921)
							(end 0.1524 -0.127)
						)
					)
					(width 0)
					(fill yes)
				)
			)
		)
	)
	(footprint ""
		(layer "B.Cu")
		(at 310.007 -60.833 180)
		(property "Reference" "PG63"
			(at 0 0 0)
			(layer "B.SilkS")
			(hide yes)
			(effects
				(font
					(size 1.27 1.27)
				)
				(justify mirror)
			)
		)
		(property "Value" "GAP-CLOSE-PWR-3-GP"
			(at -0.0254 -6.5786 180)
			(unlocked yes)
			(layer "B.Fab")
			(hide yes)
			(effects
				(font
					(size 1.016 1.016)
					(thickness 0.1524)
				)
				(justify mirror)
			)
		)
		(property "Device Type" "GAP-CLOSE-PWR-3"
			(at -0.0254 -8.255 180)
			(unlocked yes)
			(layer "B.Fab")
			(hide yes)
			(effects
				(font
					(size 1.016 1.016)
					(thickness 0.1524)
				)
				(justify mirror)
			)
		)
		(duplicate_pad_numbers_are_jumpers no)
		(fp_rect
			(start 0.7112 0.4572)
			(end -0.7112 -0.4572)
			(stroke
				(width 0)
				(type default)
			)
			(fill no)
			(layer "B.CrtYd")
		)
		(fp_poly
			(pts
				(xy 0.7112 -0.4572) (xy -0.7112 -0.4572) (xy -0.7112 0.4572) (xy 0.7112 0.4572)
			)
			(stroke
				(width 0)
				(type default)
			)
			(fill no)
			(layer "B.Fab")
		)
		(pad "1" smd rect
			(at 0.3048 0)
			(size 0.6604 0.762)
			(layers "B.Cu" "B.Mask" "B.Paste")
			(net "DUT_VDD")
		)
		(pad "2" smd rect
			(at -0.3048 0)
			(size 0.6604 0.762)
			(layers "B.Cu" "B.Mask" "B.Paste")
			(net "P0V9_E")
		)
	)
	(footprint ""
		(layer "B.Cu")
		(at 229.60838 -39.999412)
		(property "Reference" "TP268"
			(at 0 0 0)
			(layer "B.SilkS")
			(hide yes)
			(effects
				(font
					(size 1.27 1.27)
				)
				(justify mirror)
			)
		)
		(property "Value" "TPAD28-2-GP"
			(at 0.0127 -1.6637 0)
			(unlocked yes)
			(layer "B.Fab")
			(hide yes)
			(effects
				(font
					(size 1.016 1.016)
					(thickness 0.1524)
				)
				(justify mirror)
			)
		)
		(property "Device Type" "TPAD28"
			(at 0.0127 -3.1877 0)
			(unlocked yes)
			(layer "B.Fab")
			(hide yes)
			(effects
				(font
					(size 1.016 1.016)
					(thickness 0.1524)
				)
				(justify mirror)
			)
		)
		(duplicate_pad_numbers_are_jumpers no)
		(fp_poly
			(pts
				(arc
					(start 0.3556 0)
					(mid -0.3556 0)
					(end 0.3556 0)
				)
			)
			(stroke
				(width 0)
				(type default)
			)
			(fill no)
			(layer "B.CrtYd")
		)
		(fp_poly
			(pts
				(arc
					(start 0.6096 0)
					(mid -0.6096 0)
					(end 0.6096 0)
				)
			)
			(stroke
				(width 0)
				(type default)
			)
			(fill no)
			(layer "B.Fab")
		)
		(pad "1" smd circle
			(at 0 0 180)
			(size 0.7112 0.7112)
			(layers "B.Cu" "B.Mask" "B.Paste")
			(net "LBI_DATA_9")
		)
	)
	(footprint ""
		(layer "B.Cu")
		(at 174.031402 -62.714632)
		(property "Reference" "PC194"
			(at 0 0 0)
			(layer "B.SilkS")
			(hide yes)
			(effects
				(font
					(size 1.27 1.27)
				)
				(justify mirror)
			)
		)
		(property "Value" "SC22U6D3V5MX-5-GP"
			(at 0.0762 -6.1214 0)
			(unlocked yes)
			(layer "B.Fab")
			(hide yes)
			(effects
				(font
					(size 1.016 1.016)
					(thickness 0.1524)
				)
				(justify mirror)
			)
		)
		(property "Device Type" "C805H56"
			(at 0.0762 -8.1534 0)
			(unlocked yes)
			(layer "B.Fab")
			(hide yes)
			(effects
				(font
					(size 1.016 1.016)
					(thickness 0.1524)
				)
				(justify mirror)
			)
		)
		(duplicate_pad_numbers_are_jumpers no)
		(fp_line
			(start -0.635 0)
			(end 0.635 0)
			(stroke
				(width 0.508)
				(type default)
			)
			(layer "B.SilkS")
		)
		(fp_rect
			(start 0.9652 1.778)
			(end -0.9652 -1.778)
			(stroke
				(width 0)
				(type default)
			)
			(fill no)
			(layer "B.CrtYd")
		)
		(fp_poly
			(pts
				(xy 0.9652 -1.778) (xy -0.9652 -1.778) (xy -0.9652 1.778) (xy 0.9652 1.778)
			)
			(stroke
				(width 0)
				(type default)
			)
			(fill no)
			(layer "B.Fab")
		)
		(pad "1" smd rect
			(at 0 -0.9652 180)
			(size 1.397 1.143)
			(layers "B.Cu" "B.Mask" "B.Paste")
			(net "P0V9")
		)
		(pad "2" smd rect
			(at 0 0.9652 180)
			(size 1.397 1.143)
			(layers "B.Cu" "B.Mask" "B.Paste")
			(net "GND")
		)
	)
	(footprint ""
		(layer "B.Cu")
		(at 35.248088 -128.388618 90)
		(property "Reference" "C209"
			(at 0 0 90)
			(layer "B.SilkS")
			(hide yes)
			(effects
				(font
					(size 1.27 1.27)
				)
				(justify mirror)
			)
		)
		(property "Value" "SC220P50V2KX-3GP"
			(at -1.1811 -2.7051 90)
			(unlocked yes)
			(layer "B.Fab")
			(hide yes)
			(effects
				(font
					(size 1.016 1.016)
					(thickness 0.1524)
				)
				(justify mirror)
			)
		)
		(property "Device Type" "C402H22"
			(at -1.1811 -4.2291 90)
			(unlocked yes)
			(layer "B.Fab")
			(hide yes)
			(effects
				(font
					(size 1.016 1.016)
					(thickness 0.1524)
				)
				(justify mirror)
			)
		)
		(duplicate_pad_numbers_are_jumpers no)
		(fp_rect
			(start 0.4318 0.9525)
			(end -0.4318 -0.9525)
			(stroke
				(width 0)
				(type default)
			)
			(fill no)
			(layer "B.CrtYd")
		)
		(fp_rect
			(start 0.4318 0.9525)
			(end -0.4318 -0.9525)
			(stroke
				(width 0)
				(type default)
			)
			(fill no)
			(layer "B.Fab")
		)
		(pad "1" smd custom
			(at 0 -0.4445 270)
			(size 0.1524 0.1524)
			(layers "B.Cu" "B.Mask" "B.Paste")
			(net "P3V3_STBY")
			(options
				(clearance outline)
				(anchor circle)
			)
			(primitives
				(gr_poly
					(pts
						(arc
							(start 0.3048 0.2032)
							(mid 0.275042 0.275042)
							(end 0.2032 0.3048)
						)
						(arc
							(start -0.2032 0.3048)
							(mid -0.275042 0.275042)
							(end -0.3048 0.2032)
						)
						(arc
							(start -0.3048 -0.2032)
							(mid -0.275042 -0.275042)
							(end -0.2032 -0.3048)
						)
						(arc
							(start 0.2032 -0.3048)
							(mid 0.275042 -0.275042)
							(end 0.3048 -0.2032)
						)
					)
					(width 0)
					(fill yes)
				)
			)
		)
		(pad "2" smd custom
			(at 0 0.4445 270)
			(size 0.1524 0.1524)
			(layers "B.Cu" "B.Mask" "B.Paste")
			(net "GND")
			(options
				(clearance outline)
				(anchor circle)
			)
			(primitives
				(gr_poly
					(pts
						(arc
							(start 0.3048 0.2032)
							(mid 0.275042 0.275042)
							(end 0.2032 0.3048)
						)
						(arc
							(start -0.2032 0.3048)
							(mid -0.275042 0.275042)
							(end -0.3048 0.2032)
						)
						(arc
							(start -0.3048 -0.2032)
							(mid -0.275042 -0.275042)
							(end -0.2032 -0.3048)
						)
						(arc
							(start 0.2032 -0.3048)
							(mid 0.275042 -0.275042)
							(end 0.3048 -0.2032)
						)
					)
					(width 0)
					(fill yes)
				)
			)
		)
	)
	(footprint ""
		(layer "B.Cu")
		(at 78.023212 -192.641474)
		(property "Reference" "R3217"
			(at 0 0 0)
			(layer "B.SilkS")
			(hide yes)
			(effects
				(font
					(size 1.27 1.27)
				)
				(justify mirror)
			)
		)
		(property "Value" "0R2J-2-GP"
			(at -0.064008 -3.993896 0)
			(unlocked yes)
			(layer "B.Fab")
			(hide yes)
			(effects
				(font
					(size 1.016 1.016)
					(thickness 0.1524)
				)
				(justify mirror)
			)
		)
		(property "Device Type" "R402H16"
			(at -0.064008 -5.517896 0)
			(unlocked yes)
			(layer "B.Fab")
			(hide yes)
			(effects
				(font
					(size 1.016 1.016)
					(thickness 0.1524)
				)
				(justify mirror)
			)
		)
		(duplicate_pad_numbers_are_jumpers no)
		(fp_line
			(start -0.508 -0.9398)
			(end 0.508 -0.9398)
			(stroke
				(width 0.1524)
				(type default)
			)
			(layer "B.SilkS")
		)
		(fp_line
			(start 0.508 -0.9398)
			(end 0.508 0.9398)
			(stroke
				(width 0.1524)
				(type default)
			)
			(layer "B.SilkS")
		)
		(fp_rect
			(start 0.508 0.9398)
			(end -0.508 -0.9398)
			(stroke
				(width 0)
				(type default)
			)
			(fill no)
			(layer "B.CrtYd")
		)
		(fp_rect
			(start 0.508 0.9398)
			(end -0.508 -0.9398)
			(stroke
				(width 0)
				(type default)
			)
			(fill no)
			(layer "B.Fab")
		)
		(pad "1" smd custom
			(at 0 -0.4445 180)
			(size 0.1397 0.1397)
			(layers "B.Cu" "B.Mask" "B.Paste")
			(net "BMC_SSD_RST#5")
			(options
				(clearance outline)
				(anchor circle)
			)
			(primitives
				(gr_poly
					(pts
						(arc
							(start -0.1778 0.2794)
							(mid -0.249642 0.249642)
							(end -0.2794 0.1778)
						)
						(arc
							(start -0.2794 -0.1778)
							(mid -0.249642 -0.249642)
							(end -0.1778 -0.2794)
						)
						(arc
							(start 0.1778 -0.2794)
							(mid 0.249642 -0.249642)
							(end 0.2794 -0.1778)
						)
						(arc
							(start 0.2794 0.1778)
							(mid 0.249642 0.249642)
							(end 0.1778 0.2794)
						)
					)
					(width 0)
					(fill yes)
				)
			)
		)
		(pad "2" smd custom
			(at 0 0.4445 180)
			(size 0.1397 0.1397)
			(layers "B.Cu" "B.Mask" "B.Paste")
			(net "BMC_SSD_RST#0_A5")
			(options
				(clearance outline)
				(anchor circle)
			)
			(primitives
				(gr_poly
					(pts
						(arc
							(start -0.1778 0.2794)
							(mid -0.249642 0.249642)
							(end -0.2794 0.1778)
						)
						(arc
							(start -0.2794 -0.1778)
							(mid -0.249642 -0.249642)
							(end -0.1778 -0.2794)
						)
						(arc
							(start 0.1778 -0.2794)
							(mid 0.249642 -0.249642)
							(end 0.2794 -0.1778)
						)
						(arc
							(start 0.2794 0.1778)
							(mid 0.249642 0.249642)
							(end 0.1778 0.2794)
						)
					)
					(width 0)
					(fill yes)
				)
			)
		)
	)
	(footprint ""
		(layer "B.Cu")
		(at 43.942 -140.335)
		(property "Reference" "TP145"
			(at 0 0 0)
			(layer "B.SilkS")
			(hide yes)
			(effects
				(font
					(size 1.27 1.27)
				)
				(justify mirror)
			)
		)
		(property "Value" "TPAD28-2-GP"
			(at 0.0127 -1.6637 0)
			(unlocked yes)
			(layer "B.Fab")
			(hide yes)
			(effects
				(font
					(size 1.016 1.016)
					(thickness 0.1524)
				)
				(justify mirror)
			)
		)
		(property "Device Type" "TPAD28"
			(at 0.0127 -3.1877 0)
			(unlocked yes)
			(layer "B.Fab")
			(hide yes)
			(effects
				(font
					(size 1.016 1.016)
					(thickness 0.1524)
				)
				(justify mirror)
			)
		)
		(duplicate_pad_numbers_are_jumpers no)
		(fp_poly
			(pts
				(arc
					(start 0.3556 0)
					(mid -0.3556 0)
					(end 0.3556 0)
				)
			)
			(stroke
				(width 0)
				(type default)
			)
			(fill no)
			(layer "B.CrtYd")
		)
		(fp_poly
			(pts
				(arc
					(start 0.6096 0)
					(mid -0.6096 0)
					(end 0.6096 0)
				)
			)
			(stroke
				(width 0)
				(type default)
			)
			(fill no)
			(layer "B.Fab")
		)
		(pad "1" smd circle
			(at 0 0 180)
			(size 0.7112 0.7112)
			(layers "B.Cu" "B.Mask" "B.Paste")
			(net "TP_GPIOP0")
		)
	)
	(footprint ""
		(layer "B.Cu")
		(at 20.955 -132.715 -90)
		(property "Reference" "R639"
			(at 0 0 90)
			(layer "B.SilkS")
			(hide yes)
			(effects
				(font
					(size 1.27 1.27)
				)
				(justify mirror)
			)
		)
		(property "Value" "0R2J-2-GP"
			(at -0.064008 -3.993896 270)
			(unlocked yes)
			(layer "B.Fab")
			(hide yes)
			(effects
				(font
					(size 1.016 1.016)
					(thickness 0.1524)
				)
				(justify mirror)
			)
		)
		(property "Device Type" "R402H16"
			(at -0.064008 -5.517896 270)
			(unlocked yes)
			(layer "B.Fab")
			(hide yes)
			(effects
				(font
					(size 1.016 1.016)
					(thickness 0.1524)
				)
				(justify mirror)
			)
		)
		(duplicate_pad_numbers_are_jumpers no)
		(fp_line
			(start -0.508 -0.9398)
			(end 0.508 -0.9398)
			(stroke
				(width 0.1524)
				(type default)
			)
			(layer "B.SilkS")
		)
		(fp_line
			(start 0.508 -0.9398)
			(end 0.508 0.9398)
			(stroke
				(width 0.1524)
				(type default)
			)
			(layer "B.SilkS")
		)
		(fp_rect
			(start 0.508 0.9398)
			(end -0.508 -0.9398)
			(stroke
				(width 0)
				(type default)
			)
			(fill no)
			(layer "B.CrtYd")
		)
		(fp_rect
			(start 0.508 0.9398)
			(end -0.508 -0.9398)
			(stroke
				(width 0)
				(type default)
			)
			(fill no)
			(layer "B.Fab")
		)
		(pad "1" smd custom
			(at 0 -0.4445 90)
			(size 0.1397 0.1397)
			(layers "B.Cu" "B.Mask" "B.Paste")
			(net "FLA_CS")
			(options
				(clearance outline)
				(anchor circle)
			)
			(primitives
				(gr_poly
					(pts
						(arc
							(start -0.1778 0.2794)
							(mid -0.249642 0.249642)
							(end -0.2794 0.1778)
						)
						(arc
							(start -0.2794 -0.1778)
							(mid -0.249642 -0.249642)
							(end -0.1778 -0.2794)
						)
						(arc
							(start 0.1778 -0.2794)
							(mid 0.249642 -0.249642)
							(end 0.2794 -0.1778)
						)
						(arc
							(start 0.2794 0.1778)
							(mid 0.249642 0.249642)
							(end 0.1778 0.2794)
						)
					)
					(width 0)
					(fill yes)
				)
			)
		)
		(pad "2" smd custom
			(at 0 0.4445 90)
			(size 0.1397 0.1397)
			(layers "B.Cu" "B.Mask" "B.Paste")
			(net "FLA_CS_R")
			(options
				(clearance outline)
				(anchor circle)
			)
			(primitives
				(gr_poly
					(pts
						(arc
							(start -0.1778 0.2794)
							(mid -0.249642 0.249642)
							(end -0.2794 0.1778)
						)
						(arc
							(start -0.2794 -0.1778)
							(mid -0.249642 -0.249642)
							(end -0.1778 -0.2794)
						)
						(arc
							(start 0.1778 -0.2794)
							(mid 0.249642 -0.249642)
							(end 0.2794 -0.1778)
						)
						(arc
							(start 0.2794 0.1778)
							(mid 0.249642 0.249642)
							(end 0.1778 0.2794)
						)
					)
					(width 0)
					(fill yes)
				)
			)
		)
	)
	(footprint ""
		(layer "B.Cu")
		(at 41.656 -130.175 -90)
		(property "Reference" "C206"
			(at 0 0 90)
			(layer "B.SilkS")
			(hide yes)
			(effects
				(font
					(size 1.27 1.27)
				)
				(justify mirror)
			)
		)
		(property "Value" "SC1U10V2KX-4-GP"
			(at -1.1811 -2.7051 270)
			(unlocked yes)
			(layer "B.Fab")
			(hide yes)
			(effects
				(font
					(size 1.016 1.016)
					(thickness 0.1524)
				)
				(justify mirror)
			)
		)
		(property "Device Type" "C402H22"
			(at -1.1811 -4.2291 270)
			(unlocked yes)
			(layer "B.Fab")
			(hide yes)
			(effects
				(font
					(size 1.016 1.016)
					(thickness 0.1524)
				)
				(justify mirror)
			)
		)
		(duplicate_pad_numbers_are_jumpers no)
		(fp_rect
			(start 0.4318 0.9525)
			(end -0.4318 -0.9525)
			(stroke
				(width 0)
				(type default)
			)
			(fill no)
			(layer "B.CrtYd")
		)
		(fp_rect
			(start 0.4318 0.9525)
			(end -0.4318 -0.9525)
			(stroke
				(width 0)
				(type default)
			)
			(fill no)
			(layer "B.Fab")
		)
		(pad "1" smd custom
			(at 0 -0.4445 90)
			(size 0.1524 0.1524)
			(layers "B.Cu" "B.Mask" "B.Paste")
			(net "P1V26_STBY")
			(options
				(clearance outline)
				(anchor circle)
			)
			(primitives
				(gr_poly
					(pts
						(arc
							(start 0.3048 0.2032)
							(mid 0.275042 0.275042)
							(end 0.2032 0.3048)
						)
						(arc
							(start -0.2032 0.3048)
							(mid -0.275042 0.275042)
							(end -0.3048 0.2032)
						)
						(arc
							(start -0.3048 -0.2032)
							(mid -0.275042 -0.275042)
							(end -0.2032 -0.3048)
						)
						(arc
							(start 0.2032 -0.3048)
							(mid 0.275042 -0.275042)
							(end 0.3048 -0.2032)
						)
					)
					(width 0)
					(fill yes)
				)
			)
		)
		(pad "2" smd custom
			(at 0 0.4445 90)
			(size 0.1524 0.1524)
			(layers "B.Cu" "B.Mask" "B.Paste")
			(net "GND")
			(options
				(clearance outline)
				(anchor circle)
			)
			(primitives
				(gr_poly
					(pts
						(arc
							(start 0.3048 0.2032)
							(mid 0.275042 0.275042)
							(end 0.2032 0.3048)
						)
						(arc
							(start -0.2032 0.3048)
							(mid -0.275042 0.275042)
							(end -0.3048 0.2032)
						)
						(arc
							(start -0.3048 -0.2032)
							(mid -0.275042 -0.275042)
							(end -0.2032 -0.3048)
						)
						(arc
							(start 0.2032 -0.3048)
							(mid 0.275042 -0.275042)
							(end 0.3048 -0.2032)
						)
					)
					(width 0)
					(fill yes)
				)
			)
		)
	)
	(footprint ""
		(layer "B.Cu")
		(at 225.679 -20.447)
		(property "Reference" "R3705"
			(at 0 0 0)
			(layer "B.SilkS")
			(hide yes)
			(effects
				(font
					(size 1.27 1.27)
				)
				(justify mirror)
			)
		)
		(property "Value" "4K7R2F-GP"
			(at -0.064008 -3.993896 0)
			(unlocked yes)
			(layer "B.Fab")
			(hide yes)
			(effects
				(font
					(size 1.016 1.016)
					(thickness 0.1524)
				)
				(justify mirror)
			)
		)
		(property "Device Type" "R402H16"
			(at -0.064008 -5.517896 0)
			(unlocked yes)
			(layer "B.Fab")
			(hide yes)
			(effects
				(font
					(size 1.016 1.016)
					(thickness 0.1524)
				)
				(justify mirror)
			)
		)
		(duplicate_pad_numbers_are_jumpers no)
		(fp_line
			(start -0.508 -0.9398)
			(end 0.508 -0.9398)
			(stroke
				(width 0.1524)
				(type default)
			)
			(layer "B.SilkS")
		)
		(fp_line
			(start 0.508 -0.9398)
			(end 0.508 0.9398)
			(stroke
				(width 0.1524)
				(type default)
			)
			(layer "B.SilkS")
		)
		(fp_rect
			(start 0.508 0.9398)
			(end -0.508 -0.9398)
			(stroke
				(width 0)
				(type default)
			)
			(fill no)
			(layer "B.CrtYd")
		)
		(fp_rect
			(start 0.508 0.9398)
			(end -0.508 -0.9398)
			(stroke
				(width 0)
				(type default)
			)
			(fill no)
			(layer "B.Fab")
		)
		(pad "1" smd custom
			(at 0 -0.4445 180)
			(size 0.1397 0.1397)
			(layers "B.Cu" "B.Mask" "B.Paste")
			(net "HOST5_RST_N_LS")
			(options
				(clearance outline)
				(anchor circle)
			)
			(primitives
				(gr_poly
					(pts
						(arc
							(start -0.1778 0.2794)
							(mid -0.249642 0.249642)
							(end -0.2794 0.1778)
						)
						(arc
							(start -0.2794 -0.1778)
							(mid -0.249642 -0.249642)
							(end -0.1778 -0.2794)
						)
						(arc
							(start 0.1778 -0.2794)
							(mid 0.249642 -0.249642)
							(end 0.2794 -0.1778)
						)
						(arc
							(start 0.2794 0.1778)
							(mid 0.249642 0.249642)
							(end 0.1778 0.2794)
						)
					)
					(width 0)
					(fill yes)
				)
			)
		)
		(pad "2" smd custom
			(at 0 0.4445 180)
			(size 0.1397 0.1397)
			(layers "B.Cu" "B.Mask" "B.Paste")
			(net "DUT_VDDO")
			(options
				(clearance outline)
				(anchor circle)
			)
			(primitives
				(gr_poly
					(pts
						(arc
							(start -0.1778 0.2794)
							(mid -0.249642 0.249642)
							(end -0.2794 0.1778)
						)
						(arc
							(start -0.2794 -0.1778)
							(mid -0.249642 -0.249642)
							(end -0.1778 -0.2794)
						)
						(arc
							(start 0.1778 -0.2794)
							(mid 0.249642 -0.249642)
							(end 0.2794 -0.1778)
						)
						(arc
							(start 0.2794 0.1778)
							(mid 0.249642 0.249642)
							(end 0.1778 0.2794)
						)
					)
					(width 0)
					(fill yes)
				)
			)
		)
	)
	(footprint ""
		(layer "B.Cu")
		(at 265.4808 -9.30021 -90)
		(property "Reference" "R724"
			(at 0 0 90)
			(layer "B.SilkS")
			(hide yes)
			(effects
				(font
					(size 1.27 1.27)
				)
				(justify mirror)
			)
		)
		(property "Value" "0R2J-2-GP"
			(at -0.064008 -3.993896 270)
			(unlocked yes)
			(layer "B.Fab")
			(hide yes)
			(effects
				(font
					(size 1.016 1.016)
					(thickness 0.1524)
				)
				(justify mirror)
			)
		)
		(property "Device Type" "R402H16"
			(at -0.064008 -5.517896 270)
			(unlocked yes)
			(layer "B.Fab")
			(hide yes)
			(effects
				(font
					(size 1.016 1.016)
					(thickness 0.1524)
				)
				(justify mirror)
			)
		)
		(duplicate_pad_numbers_are_jumpers no)
		(fp_line
			(start -0.508 -0.9398)
			(end 0.508 -0.9398)
			(stroke
				(width 0.1524)
				(type default)
			)
			(layer "B.SilkS")
		)
		(fp_line
			(start 0.508 -0.9398)
			(end 0.508 0.9398)
			(stroke
				(width 0.1524)
				(type default)
			)
			(layer "B.SilkS")
		)
		(fp_rect
			(start 0.508 0.9398)
			(end -0.508 -0.9398)
			(stroke
				(width 0)
				(type default)
			)
			(fill no)
			(layer "B.CrtYd")
		)
		(fp_rect
			(start 0.508 0.9398)
			(end -0.508 -0.9398)
			(stroke
				(width 0)
				(type default)
			)
			(fill no)
			(layer "B.Fab")
		)
		(pad "1" smd custom
			(at 0 -0.4445 90)
			(size 0.1397 0.1397)
			(layers "B.Cu" "B.Mask" "B.Paste")
			(net "HOST7_RST_N_C")
			(options
				(clearance outline)
				(anchor circle)
			)
			(primitives
				(gr_poly
					(pts
						(arc
							(start -0.1778 0.2794)
							(mid -0.249642 0.249642)
							(end -0.2794 0.1778)
						)
						(arc
							(start -0.2794 -0.1778)
							(mid -0.249642 -0.249642)
							(end -0.1778 -0.2794)
						)
						(arc
							(start 0.1778 -0.2794)
							(mid 0.249642 -0.249642)
							(end 0.2794 -0.1778)
						)
						(arc
							(start 0.2794 0.1778)
							(mid 0.249642 0.249642)
							(end 0.1778 0.2794)
						)
					)
					(width 0)
					(fill yes)
				)
			)
		)
		(pad "2" smd custom
			(at 0 0.4445 90)
			(size 0.1397 0.1397)
			(layers "B.Cu" "B.Mask" "B.Paste")
			(net "P3V3_STBY")
			(options
				(clearance outline)
				(anchor circle)
			)
			(primitives
				(gr_poly
					(pts
						(arc
							(start -0.1778 0.2794)
							(mid -0.249642 0.249642)
							(end -0.2794 0.1778)
						)
						(arc
							(start -0.2794 -0.1778)
							(mid -0.249642 -0.249642)
							(end -0.1778 -0.2794)
						)
						(arc
							(start 0.1778 -0.2794)
							(mid 0.249642 -0.249642)
							(end 0.2794 -0.1778)
						)
						(arc
							(start 0.2794 0.1778)
							(mid 0.249642 0.249642)
							(end 0.1778 0.2794)
						)
					)
					(width 0)
					(fill yes)
				)
			)
		)
	)
	(footprint ""
		(layer "B.Cu")
		(at 23.90648 -137.586974 90)
		(property "Reference" "R350"
			(at 0 0 90)
			(layer "B.SilkS")
			(hide yes)
			(effects
				(font
					(size 1.27 1.27)
				)
				(justify mirror)
			)
		)
		(property "Value" "3K3R2F-2-GP"
			(at -0.064008 -3.993896 90)
			(unlocked yes)
			(layer "B.Fab")
			(hide yes)
			(effects
				(font
					(size 1.016 1.016)
					(thickness 0.1524)
				)
				(justify mirror)
			)
		)
		(property "Device Type" "R402H16"
			(at -0.064008 -5.517896 90)
			(unlocked yes)
			(layer "B.Fab")
			(hide yes)
			(effects
				(font
					(size 1.016 1.016)
					(thickness 0.1524)
				)
				(justify mirror)
			)
		)
		(duplicate_pad_numbers_are_jumpers no)
		(fp_line
			(start 0.508 -0.9398)
			(end 0.508 0.9398)
			(stroke
				(width 0.1524)
				(type default)
			)
			(layer "B.SilkS")
		)
		(fp_line
			(start -0.508 -0.9398)
			(end 0.508 -0.9398)
			(stroke
				(width 0.1524)
				(type default)
			)
			(layer "B.SilkS")
		)
		(fp_rect
			(start 0.508 0.9398)
			(end -0.508 -0.9398)
			(stroke
				(width 0)
				(type default)
			)
			(fill no)
			(layer "B.CrtYd")
		)
		(fp_rect
			(start 0.508 0.9398)
			(end -0.508 -0.9398)
			(stroke
				(width 0)
				(type default)
			)
			(fill no)
			(layer "B.Fab")
		)
		(pad "1" smd custom
			(at 0 -0.4445 270)
			(size 0.1397 0.1397)
			(layers "B.Cu" "B.Mask" "B.Paste")
			(net "P3V3_STBY")
			(options
				(clearance outline)
				(anchor circle)
			)
			(primitives
				(gr_poly
					(pts
						(arc
							(start -0.1778 0.2794)
							(mid -0.249642 0.249642)
							(end -0.2794 0.1778)
						)
						(arc
							(start -0.2794 -0.1778)
							(mid -0.249642 -0.249642)
							(end -0.1778 -0.2794)
						)
						(arc
							(start 0.1778 -0.2794)
							(mid 0.249642 -0.249642)
							(end 0.2794 -0.1778)
						)
						(arc
							(start 0.2794 0.1778)
							(mid 0.249642 0.249642)
							(end 0.1778 0.2794)
						)
					)
					(width 0)
					(fill yes)
				)
			)
		)
		(pad "2" smd custom
			(at 0 0.4445 270)
			(size 0.1397 0.1397)
			(layers "B.Cu" "B.Mask" "B.Paste")
			(net "ROMD2")
			(options
				(clearance outline)
				(anchor circle)
			)
			(primitives
				(gr_poly
					(pts
						(arc
							(start -0.1778 0.2794)
							(mid -0.249642 0.249642)
							(end -0.2794 0.1778)
						)
						(arc
							(start -0.2794 -0.1778)
							(mid -0.249642 -0.249642)
							(end -0.1778 -0.2794)
						)
						(arc
							(start 0.1778 -0.2794)
							(mid 0.249642 -0.249642)
							(end 0.2794 -0.1778)
						)
						(arc
							(start 0.2794 0.1778)
							(mid 0.249642 0.249642)
							(end 0.1778 0.2794)
						)
					)
					(width 0)
					(fill yes)
				)
			)
		)
	)
	(footprint ""
		(layer "B.Cu")
		(at 162.941 -91.3384 -90)
		(property "Reference" "C720"
			(at 0 0 90)
			(layer "B.SilkS")
			(hide yes)
			(effects
				(font
					(size 1.27 1.27)
				)
				(justify mirror)
			)
		)
		(property "Value" "SC1U10V2KX-4-GP"
			(at -1.1811 -2.7051 270)
			(unlocked yes)
			(layer "B.Fab")
			(hide yes)
			(effects
				(font
					(size 1.016 1.016)
					(thickness 0.1524)
				)
				(justify mirror)
			)
		)
		(property "Device Type" "C402H22"
			(at -1.1811 -4.2291 270)
			(unlocked yes)
			(layer "B.Fab")
			(hide yes)
			(effects
				(font
					(size 1.016 1.016)
					(thickness 0.1524)
				)
				(justify mirror)
			)
		)
		(duplicate_pad_numbers_are_jumpers no)
		(fp_rect
			(start 0.4318 0.9525)
			(end -0.4318 -0.9525)
			(stroke
				(width 0)
				(type default)
			)
			(fill no)
			(layer "B.CrtYd")
		)
		(fp_rect
			(start 0.4318 0.9525)
			(end -0.4318 -0.9525)
			(stroke
				(width 0)
				(type default)
			)
			(fill no)
			(layer "B.Fab")
		)
		(pad "1" smd custom
			(at 0 -0.4445 90)
			(size 0.1524 0.1524)
			(layers "B.Cu" "B.Mask" "B.Paste")
			(net "P1V8_CLKGEN_A")
			(options
				(clearance outline)
				(anchor circle)
			)
			(primitives
				(gr_poly
					(pts
						(arc
							(start 0.3048 0.2032)
							(mid 0.275042 0.275042)
							(end 0.2032 0.3048)
						)
						(arc
							(start -0.2032 0.3048)
							(mid -0.275042 0.275042)
							(end -0.3048 0.2032)
						)
						(arc
							(start -0.3048 -0.2032)
							(mid -0.275042 -0.275042)
							(end -0.2032 -0.3048)
						)
						(arc
							(start 0.2032 -0.3048)
							(mid 0.275042 -0.275042)
							(end 0.3048 -0.2032)
						)
					)
					(width 0)
					(fill yes)
				)
			)
		)
		(pad "2" smd custom
			(at 0 0.4445 90)
			(size 0.1524 0.1524)
			(layers "B.Cu" "B.Mask" "B.Paste")
			(net "GND")
			(options
				(clearance outline)
				(anchor circle)
			)
			(primitives
				(gr_poly
					(pts
						(arc
							(start 0.3048 0.2032)
							(mid 0.275042 0.275042)
							(end 0.2032 0.3048)
						)
						(arc
							(start -0.2032 0.3048)
							(mid -0.275042 0.275042)
							(end -0.3048 0.2032)
						)
						(arc
							(start -0.3048 -0.2032)
							(mid -0.275042 -0.275042)
							(end -0.2032 -0.3048)
						)
						(arc
							(start 0.2032 -0.3048)
							(mid 0.275042 -0.275042)
							(end 0.3048 -0.2032)
						)
					)
					(width 0)
					(fill yes)
				)
			)
		)
	)
	(footprint ""
		(layer "B.Cu")
		(at 272.161 -8.255 90)
		(property "Reference" "R2974"
			(at 0 0 90)
			(layer "B.SilkS")
			(hide yes)
			(effects
				(font
					(size 1.27 1.27)
				)
				(justify mirror)
			)
		)
		(property "Value" "0R2J-2-GP"
			(at -0.064008 -3.993896 90)
			(unlocked yes)
			(layer "B.Fab")
			(hide yes)
			(effects
				(font
					(size 1.016 1.016)
					(thickness 0.1524)
				)
				(justify mirror)
			)
		)
		(property "Device Type" "R402H16"
			(at -0.064008 -5.517896 90)
			(unlocked yes)
			(layer "B.Fab")
			(hide yes)
			(effects
				(font
					(size 1.016 1.016)
					(thickness 0.1524)
				)
				(justify mirror)
			)
		)
		(duplicate_pad_numbers_are_jumpers no)
		(fp_line
			(start 0.508 -0.9398)
			(end 0.508 0.9398)
			(stroke
				(width 0.1524)
				(type default)
			)
			(layer "B.SilkS")
		)
		(fp_line
			(start -0.508 -0.9398)
			(end 0.508 -0.9398)
			(stroke
				(width 0.1524)
				(type default)
			)
			(layer "B.SilkS")
		)
		(fp_rect
			(start 0.508 0.9398)
			(end -0.508 -0.9398)
			(stroke
				(width 0)
				(type default)
			)
			(fill no)
			(layer "B.CrtYd")
		)
		(fp_rect
			(start 0.508 0.9398)
			(end -0.508 -0.9398)
			(stroke
				(width 0)
				(type default)
			)
			(fill no)
			(layer "B.Fab")
		)
		(pad "1" smd custom
			(at 0 -0.4445 270)
			(size 0.1397 0.1397)
			(layers "B.Cu" "B.Mask" "B.Paste")
			(net "PCIE_REFCLK_H0_N")
			(options
				(clearance outline)
				(anchor circle)
			)
			(primitives
				(gr_poly
					(pts
						(arc
							(start -0.1778 0.2794)
							(mid -0.249642 0.249642)
							(end -0.2794 0.1778)
						)
						(arc
							(start -0.2794 -0.1778)
							(mid -0.249642 -0.249642)
							(end -0.1778 -0.2794)
						)
						(arc
							(start 0.1778 -0.2794)
							(mid 0.249642 -0.249642)
							(end 0.2794 -0.1778)
						)
						(arc
							(start 0.2794 0.1778)
							(mid 0.249642 0.249642)
							(end 0.1778 0.2794)
						)
					)
					(width 0)
					(fill yes)
				)
			)
		)
		(pad "2" smd custom
			(at 0 0.4445 270)
			(size 0.1397 0.1397)
			(layers "B.Cu" "B.Mask" "B.Paste")
			(net "PCIE_REFCLK_H0_N_R")
			(options
				(clearance outline)
				(anchor circle)
			)
			(primitives
				(gr_poly
					(pts
						(arc
							(start -0.1778 0.2794)
							(mid -0.249642 0.249642)
							(end -0.2794 0.1778)
						)
						(arc
							(start -0.2794 -0.1778)
							(mid -0.249642 -0.249642)
							(end -0.1778 -0.2794)
						)
						(arc
							(start 0.1778 -0.2794)
							(mid 0.249642 -0.249642)
							(end 0.2794 -0.1778)
						)
						(arc
							(start 0.2794 0.1778)
							(mid 0.249642 0.249642)
							(end 0.1778 0.2794)
						)
					)
					(width 0)
					(fill yes)
				)
			)
		)
	)
	(footprint ""
		(layer "B.Cu")
		(at 223.57334 -201.39914 -90)
		(property "Reference" "R3225"
			(at 0 0 90)
			(layer "B.SilkS")
			(hide yes)
			(effects
				(font
					(size 1.27 1.27)
				)
				(justify mirror)
			)
		)
		(property "Value" "0R2J-2-GP"
			(at -0.064008 -3.993896 270)
			(unlocked yes)
			(layer "B.Fab")
			(hide yes)
			(effects
				(font
					(size 1.016 1.016)
					(thickness 0.1524)
				)
				(justify mirror)
			)
		)
		(property "Device Type" "R402H16"
			(at -0.064008 -5.517896 270)
			(unlocked yes)
			(layer "B.Fab")
			(hide yes)
			(effects
				(font
					(size 1.016 1.016)
					(thickness 0.1524)
				)
				(justify mirror)
			)
		)
		(duplicate_pad_numbers_are_jumpers no)
		(fp_line
			(start -0.508 -0.9398)
			(end 0.508 -0.9398)
			(stroke
				(width 0.1524)
				(type default)
			)
			(layer "B.SilkS")
		)
		(fp_line
			(start 0.508 -0.9398)
			(end 0.508 0.9398)
			(stroke
				(width 0.1524)
				(type default)
			)
			(layer "B.SilkS")
		)
		(fp_rect
			(start 0.508 0.9398)
			(end -0.508 -0.9398)
			(stroke
				(width 0)
				(type default)
			)
			(fill no)
			(layer "B.CrtYd")
		)
		(fp_rect
			(start 0.508 0.9398)
			(end -0.508 -0.9398)
			(stroke
				(width 0)
				(type default)
			)
			(fill no)
			(layer "B.Fab")
		)
		(pad "1" smd custom
			(at 0 -0.4445 90)
			(size 0.1397 0.1397)
			(layers "B.Cu" "B.Mask" "B.Paste")
			(net "SSD_PERST#8")
			(options
				(clearance outline)
				(anchor circle)
			)
			(primitives
				(gr_poly
					(pts
						(arc
							(start -0.1778 0.2794)
							(mid -0.249642 0.249642)
							(end -0.2794 0.1778)
						)
						(arc
							(start -0.2794 -0.1778)
							(mid -0.249642 -0.249642)
							(end -0.1778 -0.2794)
						)
						(arc
							(start 0.1778 -0.2794)
							(mid 0.249642 -0.249642)
							(end 0.2794 -0.1778)
						)
						(arc
							(start 0.2794 0.1778)
							(mid 0.249642 0.249642)
							(end 0.1778 0.2794)
						)
					)
					(width 0)
					(fill yes)
				)
			)
		)
		(pad "2" smd custom
			(at 0 0.4445 90)
			(size 0.1397 0.1397)
			(layers "B.Cu" "B.Mask" "B.Paste")
			(net "SSD_PERST#0_B8")
			(options
				(clearance outline)
				(anchor circle)
			)
			(primitives
				(gr_poly
					(pts
						(arc
							(start -0.1778 0.2794)
							(mid -0.249642 0.249642)
							(end -0.2794 0.1778)
						)
						(arc
							(start -0.2794 -0.1778)
							(mid -0.249642 -0.249642)
							(end -0.1778 -0.2794)
						)
						(arc
							(start 0.1778 -0.2794)
							(mid 0.249642 -0.249642)
							(end 0.2794 -0.1778)
						)
						(arc
							(start 0.2794 0.1778)
							(mid 0.249642 0.249642)
							(end 0.1778 0.2794)
						)
					)
					(width 0)
					(fill yes)
				)
			)
		)
	)
	(footprint ""
		(layer "B.Cu")
		(at 215.702388 -197.096126)
		(property "Reference" "U77"
			(at 0 0 0)
			(layer "B.SilkS")
			(hide yes)
			(effects
				(font
					(size 1.27 1.27)
				)
				(justify mirror)
			)
		)
		(property "Value" "SN74LVC1G08DCKR-GP"
			(at 2.3368 -8.6868 0)
			(unlocked yes)
			(layer "B.Fab")
			(hide yes)
			(effects
				(font
					(size 1.016 1.016)
					(thickness 0.1524)
				)
				(justify mirror)
			)
		)
		(property "Device Type" "SC70-5H44"
			(at 2.3114 -10.414 0)
			(unlocked yes)
			(layer "B.Fab")
			(hide yes)
			(effects
				(font
					(size 1.016 1.016)
					(thickness 0.1524)
				)
				(justify mirror)
			)
		)
		(duplicate_pad_numbers_are_jumpers no)
		(fp_line
			(start -1.3843 -1.8034)
			(end -1.3843 -1.1176)
			(stroke
				(width 0.3302)
				(type default)
			)
			(layer "B.SilkS")
		)
		(fp_line
			(start -1.27 -1.7018)
			(end -1.27 1.7018)
			(stroke
				(width 0.1524)
				(type default)
			)
			(layer "B.SilkS")
		)
		(fp_line
			(start -1.27 1.7018)
			(end 1.27 1.7018)
			(stroke
				(width 0.1524)
				(type default)
			)
			(layer "B.SilkS")
		)
		(fp_line
			(start -0.6604 -1.8034)
			(end -1.3843 -1.8034)
			(stroke
				(width 0.3302)
				(type default)
			)
			(layer "B.SilkS")
		)
		(fp_line
			(start 1.27 -1.7018)
			(end -1.27 -1.7018)
			(stroke
				(width 0.1524)
				(type default)
			)
			(layer "B.SilkS")
		)
		(fp_line
			(start 1.27 1.7018)
			(end 1.27 -1.7018)
			(stroke
				(width 0.1524)
				(type default)
			)
			(layer "B.SilkS")
		)
		(fp_rect
			(start 1.524 1.9558)
			(end -1.524 -1.9558)
			(stroke
				(width 0)
				(type default)
			)
			(fill no)
			(layer "B.CrtYd")
		)
		(fp_poly
			(pts
				(xy 1.524 -1.9558) (xy -1.524 -1.9558) (xy -1.524 1.9558) (xy 1.524 1.9558)
			)
			(stroke
				(width 0)
				(type default)
			)
			(fill no)
			(layer "B.Fab")
		)
		(pad "1" smd rect
			(at -0.65024 -0.8255 180)
			(size 0.4064 1.2192)
			(layers "B.Cu" "B.Mask" "B.Paste")
			(net "BMC_SSD_RST#0_A13")
		)
		(pad "2" smd rect
			(at 0 -0.8255 180)
			(size 0.4064 1.2192)
			(layers "B.Cu" "B.Mask" "B.Paste")
			(net "SSD_PERST#0_B13")
		)
		(pad "3" smd rect
			(at 0.65024 -0.8255 180)
			(size 0.4064 1.2192)
			(layers "B.Cu" "B.Mask" "B.Paste")
			(net "GND")
		)
		(pad "4" smd rect
			(at 0.65024 0.8255 180)
			(size 0.4064 1.2192)
			(layers "B.Cu" "B.Mask" "B.Paste")
			(net "SSD_PERST_Y13")
		)
		(pad "5" smd rect
			(at -0.65024 0.8255 180)
			(size 0.4064 1.2192)
			(layers "B.Cu" "B.Mask" "B.Paste")
			(net "P3V3_STBY")
		)
	)
	(footprint ""
		(layer "B.Cu")
		(at 20.955 -139.827 -90)
		(property "Reference" "R647"
			(at 0 0 90)
			(layer "B.SilkS")
			(hide yes)
			(effects
				(font
					(size 1.27 1.27)
				)
				(justify mirror)
			)
		)
		(property "Value" "0R2J-2-GP"
			(at -0.064008 -3.993896 270)
			(unlocked yes)
			(layer "B.Fab")
			(hide yes)
			(effects
				(font
					(size 1.016 1.016)
					(thickness 0.1524)
				)
				(justify mirror)
			)
		)
		(property "Device Type" "R402H16"
			(at -0.064008 -5.517896 270)
			(unlocked yes)
			(layer "B.Fab")
			(hide yes)
			(effects
				(font
					(size 1.016 1.016)
					(thickness 0.1524)
				)
				(justify mirror)
			)
		)
		(duplicate_pad_numbers_are_jumpers no)
		(fp_line
			(start -0.508 -0.9398)
			(end 0.508 -0.9398)
			(stroke
				(width 0.1524)
				(type default)
			)
			(layer "B.SilkS")
		)
		(fp_line
			(start 0.508 -0.9398)
			(end 0.508 0.9398)
			(stroke
				(width 0.1524)
				(type default)
			)
			(layer "B.SilkS")
		)
		(fp_rect
			(start 0.508 0.9398)
			(end -0.508 -0.9398)
			(stroke
				(width 0)
				(type default)
			)
			(fill no)
			(layer "B.CrtYd")
		)
		(fp_rect
			(start 0.508 0.9398)
			(end -0.508 -0.9398)
			(stroke
				(width 0)
				(type default)
			)
			(fill no)
			(layer "B.Fab")
		)
		(pad "1" smd custom
			(at 0 -0.4445 90)
			(size 0.1397 0.1397)
			(layers "B.Cu" "B.Mask" "B.Paste")
			(net "FLA_CS1")
			(options
				(clearance outline)
				(anchor circle)
			)
			(primitives
				(gr_poly
					(pts
						(arc
							(start -0.1778 0.2794)
							(mid -0.249642 0.249642)
							(end -0.2794 0.1778)
						)
						(arc
							(start -0.2794 -0.1778)
							(mid -0.249642 -0.249642)
							(end -0.1778 -0.2794)
						)
						(arc
							(start 0.1778 -0.2794)
							(mid 0.249642 -0.249642)
							(end 0.2794 -0.1778)
						)
						(arc
							(start 0.2794 0.1778)
							(mid 0.249642 0.249642)
							(end 0.1778 0.2794)
						)
					)
					(width 0)
					(fill yes)
				)
			)
		)
		(pad "2" smd custom
			(at 0 0.4445 90)
			(size 0.1397 0.1397)
			(layers "B.Cu" "B.Mask" "B.Paste")
			(net "FLA_CS1_R")
			(options
				(clearance outline)
				(anchor circle)
			)
			(primitives
				(gr_poly
					(pts
						(arc
							(start -0.1778 0.2794)
							(mid -0.249642 0.249642)
							(end -0.2794 0.1778)
						)
						(arc
							(start -0.2794 -0.1778)
							(mid -0.249642 -0.249642)
							(end -0.1778 -0.2794)
						)
						(arc
							(start 0.1778 -0.2794)
							(mid 0.249642 -0.249642)
							(end 0.2794 -0.1778)
						)
						(arc
							(start 0.2794 0.1778)
							(mid 0.249642 0.249642)
							(end 0.1778 0.2794)
						)
					)
					(width 0)
					(fill yes)
				)
			)
		)
	)
	(footprint ""
		(layer "B.Cu")
		(at 44.098972 -131.287774)
		(property "Reference" "TP317"
			(at 0 0 0)
			(layer "B.SilkS")
			(hide yes)
			(effects
				(font
					(size 1.27 1.27)
				)
				(justify mirror)
			)
		)
		(property "Value" "TPAD28-2-GP"
			(at 0.0127 -1.6637 0)
			(unlocked yes)
			(layer "B.Fab")
			(hide yes)
			(effects
				(font
					(size 1.016 1.016)
					(thickness 0.1524)
				)
				(justify mirror)
			)
		)
		(property "Device Type" "TPAD28"
			(at 0.0127 -3.1877 0)
			(unlocked yes)
			(layer "B.Fab")
			(hide yes)
			(effects
				(font
					(size 1.016 1.016)
					(thickness 0.1524)
				)
				(justify mirror)
			)
		)
		(duplicate_pad_numbers_are_jumpers no)
		(fp_poly
			(pts
				(arc
					(start 0.3556 0)
					(mid -0.3556 0)
					(end 0.3556 0)
				)
			)
			(stroke
				(width 0)
				(type default)
			)
			(fill no)
			(layer "B.CrtYd")
		)
		(fp_poly
			(pts
				(arc
					(start 0.6096 0)
					(mid -0.6096 0)
					(end 0.6096 0)
				)
			)
			(stroke
				(width 0)
				(type default)
			)
			(fill no)
			(layer "B.Fab")
		)
		(pad "1" smd circle
			(at 0 0 180)
			(size 0.7112 0.7112)
			(layers "B.Cu" "B.Mask" "B.Paste")
			(net "DACB")
		)
	)
	(footprint ""
		(layer "B.Cu")
		(at 233.68 -20.447)
		(property "Reference" "R817"
			(at 0 0 0)
			(layer "B.SilkS")
			(hide yes)
			(effects
				(font
					(size 1.27 1.27)
				)
				(justify mirror)
			)
		)
		(property "Value" "4K7R2F-GP"
			(at -0.064008 -3.993896 0)
			(unlocked yes)
			(layer "B.Fab")
			(hide yes)
			(effects
				(font
					(size 1.016 1.016)
					(thickness 0.1524)
				)
				(justify mirror)
			)
		)
		(property "Device Type" "R402H16"
			(at -0.064008 -5.517896 0)
			(unlocked yes)
			(layer "B.Fab")
			(hide yes)
			(effects
				(font
					(size 1.016 1.016)
					(thickness 0.1524)
				)
				(justify mirror)
			)
		)
		(duplicate_pad_numbers_are_jumpers no)
		(fp_line
			(start -0.508 -0.9398)
			(end 0.508 -0.9398)
			(stroke
				(width 0.1524)
				(type default)
			)
			(layer "B.SilkS")
		)
		(fp_line
			(start 0.508 -0.9398)
			(end 0.508 0.9398)
			(stroke
				(width 0.1524)
				(type default)
			)
			(layer "B.SilkS")
		)
		(fp_rect
			(start 0.508 0.9398)
			(end -0.508 -0.9398)
			(stroke
				(width 0)
				(type default)
			)
			(fill no)
			(layer "B.CrtYd")
		)
		(fp_rect
			(start 0.508 0.9398)
			(end -0.508 -0.9398)
			(stroke
				(width 0)
				(type default)
			)
			(fill no)
			(layer "B.Fab")
		)
		(pad "1" smd custom
			(at 0 -0.4445 180)
			(size 0.1397 0.1397)
			(layers "B.Cu" "B.Mask" "B.Paste")
			(net "BOOTSTRAP8")
			(options
				(clearance outline)
				(anchor circle)
			)
			(primitives
				(gr_poly
					(pts
						(arc
							(start -0.1778 0.2794)
							(mid -0.249642 0.249642)
							(end -0.2794 0.1778)
						)
						(arc
							(start -0.2794 -0.1778)
							(mid -0.249642 -0.249642)
							(end -0.1778 -0.2794)
						)
						(arc
							(start 0.1778 -0.2794)
							(mid 0.249642 -0.249642)
							(end 0.2794 -0.1778)
						)
						(arc
							(start 0.2794 0.1778)
							(mid 0.249642 0.249642)
							(end 0.1778 0.2794)
						)
					)
					(width 0)
					(fill yes)
				)
			)
		)
		(pad "2" smd custom
			(at 0 0.4445 180)
			(size 0.1397 0.1397)
			(layers "B.Cu" "B.Mask" "B.Paste")
			(net "DUT_VDDO")
			(options
				(clearance outline)
				(anchor circle)
			)
			(primitives
				(gr_poly
					(pts
						(arc
							(start -0.1778 0.2794)
							(mid -0.249642 0.249642)
							(end -0.2794 0.1778)
						)
						(arc
							(start -0.2794 -0.1778)
							(mid -0.249642 -0.249642)
							(end -0.1778 -0.2794)
						)
						(arc
							(start 0.1778 -0.2794)
							(mid 0.249642 -0.249642)
							(end 0.2794 -0.1778)
						)
						(arc
							(start 0.2794 0.1778)
							(mid 0.249642 0.249642)
							(end 0.1778 0.2794)
						)
					)
					(width 0)
					(fill yes)
				)
			)
		)
	)
	(footprint ""
		(layer "B.Cu")
		(at 228.6254 -54.995572 90)
		(property "Reference" "C537"
			(at 0 0 90)
			(layer "B.SilkS")
			(hide yes)
			(effects
				(font
					(size 1.27 1.27)
				)
				(justify mirror)
			)
		)
		(property "Value" "SCD1U16V1KX-1-GP"
			(at 2.8321 -1.7399 90)
			(unlocked yes)
			(layer "B.Fab")
			(hide yes)
			(effects
				(font
					(size 1.016 1.016)
					(thickness 0.1524)
				)
				(justify mirror)
			)
		)
		(property "Device Type" "C0201H13"
			(at 2.8321 -3.2639 90)
			(unlocked yes)
			(layer "B.Fab")
			(hide yes)
			(effects
				(font
					(size 1.016 1.016)
					(thickness 0.1524)
				)
				(justify mirror)
			)
		)
		(duplicate_pad_numbers_are_jumpers no)
		(fp_rect
			(start 0.2794 0.6477)
			(end -0.2794 -0.6477)
			(stroke
				(width 0)
				(type default)
			)
			(fill no)
			(layer "B.CrtYd")
		)
		(fp_rect
			(start 0.2794 0.6477)
			(end -0.2794 -0.6477)
			(stroke
				(width 0)
				(type default)
			)
			(fill no)
			(layer "B.Fab")
		)
		(pad "1" smd custom
			(at 0 -0.2794 270)
			(size 0.0762 0.0762)
			(layers "B.Cu" "B.Mask" "B.Paste")
			(net "DUT_AVD_PCIE")
			(options
				(clearance outline)
				(anchor circle)
			)
			(primitives
				(gr_poly
					(pts
						(arc
							(start 0.1524 0.127)
							(mid 0.137521 0.162921)
							(end 0.1016 0.1778)
						)
						(arc
							(start -0.1016 0.1778)
							(mid -0.137521 0.162921)
							(end -0.1524 0.127)
						)
						(arc
							(start -0.1524 -0.127)
							(mid -0.137521 -0.162921)
							(end -0.1016 -0.1778)
						)
						(arc
							(start 0.1016 -0.1778)
							(mid 0.137521 -0.162921)
							(end 0.1524 -0.127)
						)
					)
					(width 0)
					(fill yes)
				)
			)
		)
		(pad "2" smd custom
			(at 0 0.2794 270)
			(size 0.0762 0.0762)
			(layers "B.Cu" "B.Mask" "B.Paste")
			(net "GND")
			(options
				(clearance outline)
				(anchor circle)
			)
			(primitives
				(gr_poly
					(pts
						(arc
							(start 0.1524 0.127)
							(mid 0.137521 0.162921)
							(end 0.1016 0.1778)
						)
						(arc
							(start -0.1016 0.1778)
							(mid -0.137521 0.162921)
							(end -0.1524 0.127)
						)
						(arc
							(start -0.1524 -0.127)
							(mid -0.137521 -0.162921)
							(end -0.1016 -0.1778)
						)
						(arc
							(start 0.1016 -0.1778)
							(mid 0.137521 -0.162921)
							(end 0.1524 -0.127)
						)
					)
					(width 0)
					(fill yes)
				)
			)
		)
	)
	(footprint ""
		(layer "B.Cu")
		(at 57.023 -141.859 -90)
		(property "Reference" "R584"
			(at 0 0 90)
			(layer "B.SilkS")
			(hide yes)
			(effects
				(font
					(size 1.27 1.27)
				)
				(justify mirror)
			)
		)
		(property "Value" "0R2J-2-GP"
			(at -0.064008 -3.993896 270)
			(unlocked yes)
			(layer "B.Fab")
			(hide yes)
			(effects
				(font
					(size 1.016 1.016)
					(thickness 0.1524)
				)
				(justify mirror)
			)
		)
		(property "Device Type" "R402H16"
			(at -0.064008 -5.517896 270)
			(unlocked yes)
			(layer "B.Fab")
			(hide yes)
			(effects
				(font
					(size 1.016 1.016)
					(thickness 0.1524)
				)
				(justify mirror)
			)
		)
		(duplicate_pad_numbers_are_jumpers no)
		(fp_line
			(start -0.508 -0.9398)
			(end 0.508 -0.9398)
			(stroke
				(width 0.1524)
				(type default)
			)
			(layer "B.SilkS")
		)
		(fp_line
			(start 0.508 -0.9398)
			(end 0.508 0.9398)
			(stroke
				(width 0.1524)
				(type default)
			)
			(layer "B.SilkS")
		)
		(fp_rect
			(start 0.508 0.9398)
			(end -0.508 -0.9398)
			(stroke
				(width 0)
				(type default)
			)
			(fill no)
			(layer "B.CrtYd")
		)
		(fp_rect
			(start 0.508 0.9398)
			(end -0.508 -0.9398)
			(stroke
				(width 0)
				(type default)
			)
			(fill no)
			(layer "B.Fab")
		)
		(pad "1" smd custom
			(at 0 -0.4445 90)
			(size 0.1397 0.1397)
			(layers "B.Cu" "B.Mask" "B.Paste")
			(net "UART_COUNT")
			(options
				(clearance outline)
				(anchor circle)
			)
			(primitives
				(gr_poly
					(pts
						(arc
							(start -0.1778 0.2794)
							(mid -0.249642 0.249642)
							(end -0.2794 0.1778)
						)
						(arc
							(start -0.2794 -0.1778)
							(mid -0.249642 -0.249642)
							(end -0.1778 -0.2794)
						)
						(arc
							(start 0.1778 -0.2794)
							(mid 0.249642 -0.249642)
							(end 0.2794 -0.1778)
						)
						(arc
							(start 0.2794 0.1778)
							(mid 0.249642 0.249642)
							(end 0.1778 0.2794)
						)
					)
					(width 0)
					(fill yes)
				)
			)
		)
		(pad "2" smd custom
			(at 0 0.4445 90)
			(size 0.1397 0.1397)
			(layers "B.Cu" "B.Mask" "B.Paste")
			(net "BMC0_TACH13")
			(options
				(clearance outline)
				(anchor circle)
			)
			(primitives
				(gr_poly
					(pts
						(arc
							(start -0.1778 0.2794)
							(mid -0.249642 0.249642)
							(end -0.2794 0.1778)
						)
						(arc
							(start -0.2794 -0.1778)
							(mid -0.249642 -0.249642)
							(end -0.1778 -0.2794)
						)
						(arc
							(start 0.1778 -0.2794)
							(mid 0.249642 -0.249642)
							(end 0.2794 -0.1778)
						)
						(arc
							(start 0.2794 0.1778)
							(mid 0.249642 0.249642)
							(end 0.1778 0.2794)
						)
					)
					(width 0)
					(fill yes)
				)
			)
		)
	)
	(footprint ""
		(layer "B.Cu")
		(at 224.040446 -203.69784 180)
		(property "Reference" "R4144"
			(at 0 0 0)
			(layer "B.SilkS")
			(hide yes)
			(effects
				(font
					(size 1.27 1.27)
				)
				(justify mirror)
			)
		)
		(property "Value" "4K7R2F-GP"
			(at -0.064008 -3.993896 180)
			(unlocked yes)
			(layer "B.Fab")
			(hide yes)
			(effects
				(font
					(size 1.016 1.016)
					(thickness 0.1524)
				)
				(justify mirror)
			)
		)
		(property "Device Type" "R402H16"
			(at -0.064008 -5.517896 180)
			(unlocked yes)
			(layer "B.Fab")
			(hide yes)
			(effects
				(font
					(size 1.016 1.016)
					(thickness 0.1524)
				)
				(justify mirror)
			)
		)
		(duplicate_pad_numbers_are_jumpers no)
		(fp_line
			(start 0.508 -0.9398)
			(end 0.508 0.9398)
			(stroke
				(width 0.1524)
				(type default)
			)
			(layer "B.SilkS")
		)
		(fp_line
			(start -0.508 -0.9398)
			(end 0.508 -0.9398)
			(stroke
				(width 0.1524)
				(type default)
			)
			(layer "B.SilkS")
		)
		(fp_rect
			(start 0.508 0.9398)
			(end -0.508 -0.9398)
			(stroke
				(width 0)
				(type default)
			)
			(fill no)
			(layer "B.CrtYd")
		)
		(fp_rect
			(start 0.508 0.9398)
			(end -0.508 -0.9398)
			(stroke
				(width 0)
				(type default)
			)
			(fill no)
			(layer "B.Fab")
		)
		(pad "1" smd custom
			(at 0 -0.4445)
			(size 0.1397 0.1397)
			(layers "B.Cu" "B.Mask" "B.Paste")
			(net "SSD_PRSNT#13")
			(options
				(clearance outline)
				(anchor circle)
			)
			(primitives
				(gr_poly
					(pts
						(arc
							(start -0.1778 0.2794)
							(mid -0.249642 0.249642)
							(end -0.2794 0.1778)
						)
						(arc
							(start -0.2794 -0.1778)
							(mid -0.249642 -0.249642)
							(end -0.1778 -0.2794)
						)
						(arc
							(start 0.1778 -0.2794)
							(mid 0.249642 -0.249642)
							(end 0.2794 -0.1778)
						)
						(arc
							(start 0.2794 0.1778)
							(mid 0.249642 0.249642)
							(end 0.1778 0.2794)
						)
					)
					(width 0)
					(fill yes)
				)
			)
		)
		(pad "2" smd custom
			(at 0 0.4445)
			(size 0.1397 0.1397)
			(layers "B.Cu" "B.Mask" "B.Paste")
			(net "P3V3_STBY")
			(options
				(clearance outline)
				(anchor circle)
			)
			(primitives
				(gr_poly
					(pts
						(arc
							(start -0.1778 0.2794)
							(mid -0.249642 0.249642)
							(end -0.2794 0.1778)
						)
						(arc
							(start -0.2794 -0.1778)
							(mid -0.249642 -0.249642)
							(end -0.1778 -0.2794)
						)
						(arc
							(start 0.1778 -0.2794)
							(mid 0.249642 -0.249642)
							(end 0.2794 -0.1778)
						)
						(arc
							(start 0.2794 0.1778)
							(mid 0.249642 0.249642)
							(end 0.1778 0.2794)
						)
					)
					(width 0)
					(fill yes)
				)
			)
		)
	)
	(footprint ""
		(layer "B.Cu")
		(at 230.6066 -31.9786)
		(property "Reference" "C479"
			(at 0 0 0)
			(layer "B.SilkS")
			(hide yes)
			(effects
				(font
					(size 1.27 1.27)
				)
				(justify mirror)
			)
		)
		(property "Value" "SCD1U16V1KX-1-GP"
			(at 2.8321 -1.7399 0)
			(unlocked yes)
			(layer "B.Fab")
			(hide yes)
			(effects
				(font
					(size 1.016 1.016)
					(thickness 0.1524)
				)
				(justify mirror)
			)
		)
		(property "Device Type" "C0201H13"
			(at 2.8321 -3.2639 0)
			(unlocked yes)
			(layer "B.Fab")
			(hide yes)
			(effects
				(font
					(size 1.016 1.016)
					(thickness 0.1524)
				)
				(justify mirror)
			)
		)
		(duplicate_pad_numbers_are_jumpers no)
		(fp_rect
			(start 0.2794 0.6477)
			(end -0.2794 -0.6477)
			(stroke
				(width 0)
				(type default)
			)
			(fill no)
			(layer "B.CrtYd")
		)
		(fp_rect
			(start 0.2794 0.6477)
			(end -0.2794 -0.6477)
			(stroke
				(width 0)
				(type default)
			)
			(fill no)
			(layer "B.Fab")
		)
		(pad "1" smd custom
			(at 0 -0.2794 180)
			(size 0.0762 0.0762)
			(layers "B.Cu" "B.Mask" "B.Paste")
			(net "DUT_VDDO")
			(options
				(clearance outline)
				(anchor circle)
			)
			(primitives
				(gr_poly
					(pts
						(arc
							(start 0.1524 0.127)
							(mid 0.137521 0.162921)
							(end 0.1016 0.1778)
						)
						(arc
							(start -0.1016 0.1778)
							(mid -0.137521 0.162921)
							(end -0.1524 0.127)
						)
						(arc
							(start -0.1524 -0.127)
							(mid -0.137521 -0.162921)
							(end -0.1016 -0.1778)
						)
						(arc
							(start 0.1016 -0.1778)
							(mid 0.137521 -0.162921)
							(end 0.1524 -0.127)
						)
					)
					(width 0)
					(fill yes)
				)
			)
		)
		(pad "2" smd custom
			(at 0 0.2794 180)
			(size 0.0762 0.0762)
			(layers "B.Cu" "B.Mask" "B.Paste")
			(net "GND")
			(options
				(clearance outline)
				(anchor circle)
			)
			(primitives
				(gr_poly
					(pts
						(arc
							(start 0.1524 0.127)
							(mid 0.137521 0.162921)
							(end 0.1016 0.1778)
						)
						(arc
							(start -0.1016 0.1778)
							(mid -0.137521 0.162921)
							(end -0.1524 0.127)
						)
						(arc
							(start -0.1524 -0.127)
							(mid -0.137521 -0.162921)
							(end -0.1016 -0.1778)
						)
						(arc
							(start 0.1016 -0.1778)
							(mid 0.137521 -0.162921)
							(end 0.1524 -0.127)
						)
					)
					(width 0)
					(fill yes)
				)
			)
		)
	)
	(footprint ""
		(layer "B.Cu")
		(at 341.432388 -178.808126)
		(property "Reference" "U78"
			(at 0 0 0)
			(layer "B.SilkS")
			(hide yes)
			(effects
				(font
					(size 1.27 1.27)
				)
				(justify mirror)
			)
		)
		(property "Value" "SN74LVC1G08DCKR-GP"
			(at 2.3368 -8.6868 0)
			(unlocked yes)
			(layer "B.Fab")
			(hide yes)
			(effects
				(font
					(size 1.016 1.016)
					(thickness 0.1524)
				)
				(justify mirror)
			)
		)
		(property "Device Type" "SC70-5H44"
			(at 2.3114 -10.414 0)
			(unlocked yes)
			(layer "B.Fab")
			(hide yes)
			(effects
				(font
					(size 1.016 1.016)
					(thickness 0.1524)
				)
				(justify mirror)
			)
		)
		(duplicate_pad_numbers_are_jumpers no)
		(fp_line
			(start -1.3843 -1.8034)
			(end -1.3843 -1.1176)
			(stroke
				(width 0.3302)
				(type default)
			)
			(layer "B.SilkS")
		)
		(fp_line
			(start -1.27 -1.7018)
			(end -1.27 1.7018)
			(stroke
				(width 0.1524)
				(type default)
			)
			(layer "B.SilkS")
		)
		(fp_line
			(start -1.27 1.7018)
			(end 1.27 1.7018)
			(stroke
				(width 0.1524)
				(type default)
			)
			(layer "B.SilkS")
		)
		(fp_line
			(start -0.6604 -1.8034)
			(end -1.3843 -1.8034)
			(stroke
				(width 0.3302)
				(type default)
			)
			(layer "B.SilkS")
		)
		(fp_line
			(start 1.27 -1.7018)
			(end -1.27 -1.7018)
			(stroke
				(width 0.1524)
				(type default)
			)
			(layer "B.SilkS")
		)
		(fp_line
			(start 1.27 1.7018)
			(end 1.27 -1.7018)
			(stroke
				(width 0.1524)
				(type default)
			)
			(layer "B.SilkS")
		)
		(fp_rect
			(start 1.524 1.9558)
			(end -1.524 -1.9558)
			(stroke
				(width 0)
				(type default)
			)
			(fill no)
			(layer "B.CrtYd")
		)
		(fp_poly
			(pts
				(xy 1.524 -1.9558) (xy -1.524 -1.9558) (xy -1.524 1.9558) (xy 1.524 1.9558)
			)
			(stroke
				(width 0)
				(type default)
			)
			(fill no)
			(layer "B.Fab")
		)
		(pad "1" smd rect
			(at -0.65024 -0.8255 180)
			(size 0.4064 1.2192)
			(layers "B.Cu" "B.Mask" "B.Paste")
			(net "BMC_SSD_RST#0_A14")
		)
		(pad "2" smd rect
			(at 0 -0.8255 180)
			(size 0.4064 1.2192)
			(layers "B.Cu" "B.Mask" "B.Paste")
			(net "SSD_PERST#0_B14")
		)
		(pad "3" smd rect
			(at 0.65024 -0.8255 180)
			(size 0.4064 1.2192)
			(layers "B.Cu" "B.Mask" "B.Paste")
			(net "GND")
		)
		(pad "4" smd rect
			(at 0.65024 0.8255 180)
			(size 0.4064 1.2192)
			(layers "B.Cu" "B.Mask" "B.Paste")
			(net "SSD_PERST_Y14")
		)
		(pad "5" smd rect
			(at -0.65024 0.8255 180)
			(size 0.4064 1.2192)
			(layers "B.Cu" "B.Mask" "B.Paste")
			(net "P3V3_STBY")
		)
	)
	(footprint ""
		(layer "B.Cu")
		(at 306.76723 -34.71926)
		(property "Reference" "C230"
			(at 0 0 0)
			(layer "B.SilkS")
			(hide yes)
			(effects
				(font
					(size 1.27 1.27)
				)
				(justify mirror)
			)
		)
		(property "Value" "SCD1U10V2KX-5GP"
			(at -1.1811 -2.7051 0)
			(unlocked yes)
			(layer "B.Fab")
			(hide yes)
			(effects
				(font
					(size 1.016 1.016)
					(thickness 0.1524)
				)
				(justify mirror)
			)
		)
		(property "Device Type" "C402H22"
			(at -1.1811 -4.2291 0)
			(unlocked yes)
			(layer "B.Fab")
			(hide yes)
			(effects
				(font
					(size 1.016 1.016)
					(thickness 0.1524)
				)
				(justify mirror)
			)
		)
		(duplicate_pad_numbers_are_jumpers no)
		(fp_rect
			(start 0.4318 0.9525)
			(end -0.4318 -0.9525)
			(stroke
				(width 0)
				(type default)
			)
			(fill no)
			(layer "B.CrtYd")
		)
		(fp_rect
			(start 0.4318 0.9525)
			(end -0.4318 -0.9525)
			(stroke
				(width 0)
				(type default)
			)
			(fill no)
			(layer "B.Fab")
		)
		(pad "1" smd custom
			(at 0 -0.4445 180)
			(size 0.1524 0.1524)
			(layers "B.Cu" "B.Mask" "B.Paste")
			(net "GND")
			(options
				(clearance outline)
				(anchor circle)
			)
			(primitives
				(gr_poly
					(pts
						(arc
							(start 0.3048 0.2032)
							(mid 0.275042 0.275042)
							(end 0.2032 0.3048)
						)
						(arc
							(start -0.2032 0.3048)
							(mid -0.275042 0.275042)
							(end -0.3048 0.2032)
						)
						(arc
							(start -0.3048 -0.2032)
							(mid -0.275042 -0.275042)
							(end -0.2032 -0.3048)
						)
						(arc
							(start 0.2032 -0.3048)
							(mid 0.275042 -0.275042)
							(end 0.3048 -0.2032)
						)
					)
					(width 0)
					(fill yes)
				)
			)
		)
		(pad "2" smd custom
			(at 0 0.4445 180)
			(size 0.1524 0.1524)
			(layers "B.Cu" "B.Mask" "B.Paste")
			(net "P3V3_STBY")
			(options
				(clearance outline)
				(anchor circle)
			)
			(primitives
				(gr_poly
					(pts
						(arc
							(start 0.3048 0.2032)
							(mid 0.275042 0.275042)
							(end 0.2032 0.3048)
						)
						(arc
							(start -0.2032 0.3048)
							(mid -0.275042 0.275042)
							(end -0.3048 0.2032)
						)
						(arc
							(start -0.3048 -0.2032)
							(mid -0.275042 -0.275042)
							(end -0.2032 -0.3048)
						)
						(arc
							(start 0.2032 -0.3048)
							(mid 0.275042 -0.275042)
							(end 0.3048 -0.2032)
						)
					)
					(width 0)
					(fill yes)
				)
			)
		)
	)
	(footprint ""
		(layer "B.Cu")
		(at 266.804648 -4.662678 90)
		(property "Reference" "R196"
			(at 0 0 90)
			(layer "B.SilkS")
			(hide yes)
			(effects
				(font
					(size 1.27 1.27)
				)
				(justify mirror)
			)
		)
		(property "Value" "4K7R2F-GP"
			(at -0.064008 -3.993896 90)
			(unlocked yes)
			(layer "B.Fab")
			(hide yes)
			(effects
				(font
					(size 1.016 1.016)
					(thickness 0.1524)
				)
				(justify mirror)
			)
		)
		(property "Device Type" "R402H16"
			(at -0.064008 -5.517896 90)
			(unlocked yes)
			(layer "B.Fab")
			(hide yes)
			(effects
				(font
					(size 1.016 1.016)
					(thickness 0.1524)
				)
				(justify mirror)
			)
		)
		(duplicate_pad_numbers_are_jumpers no)
		(fp_line
			(start 0.508 -0.9398)
			(end 0.508 0.9398)
			(stroke
				(width 0.1524)
				(type default)
			)
			(layer "B.SilkS")
		)
		(fp_line
			(start -0.508 -0.9398)
			(end 0.508 -0.9398)
			(stroke
				(width 0.1524)
				(type default)
			)
			(layer "B.SilkS")
		)
		(fp_rect
			(start 0.508 0.9398)
			(end -0.508 -0.9398)
			(stroke
				(width 0)
				(type default)
			)
			(fill no)
			(layer "B.CrtYd")
		)
		(fp_rect
			(start 0.508 0.9398)
			(end -0.508 -0.9398)
			(stroke
				(width 0)
				(type default)
			)
			(fill no)
			(layer "B.Fab")
		)
		(pad "1" smd custom
			(at 0 -0.4445 270)
			(size 0.1397 0.1397)
			(layers "B.Cu" "B.Mask" "B.Paste")
			(net "TEMP_1_A1")
			(options
				(clearance outline)
				(anchor circle)
			)
			(primitives
				(gr_poly
					(pts
						(arc
							(start -0.1778 0.2794)
							(mid -0.249642 0.249642)
							(end -0.2794 0.1778)
						)
						(arc
							(start -0.2794 -0.1778)
							(mid -0.249642 -0.249642)
							(end -0.1778 -0.2794)
						)
						(arc
							(start 0.1778 -0.2794)
							(mid 0.249642 -0.249642)
							(end 0.2794 -0.1778)
						)
						(arc
							(start 0.2794 0.1778)
							(mid 0.249642 0.249642)
							(end 0.1778 0.2794)
						)
					)
					(width 0)
					(fill yes)
				)
			)
		)
		(pad "2" smd custom
			(at 0 0.4445 270)
			(size 0.1397 0.1397)
			(layers "B.Cu" "B.Mask" "B.Paste")
			(net "GND")
			(options
				(clearance outline)
				(anchor circle)
			)
			(primitives
				(gr_poly
					(pts
						(arc
							(start -0.1778 0.2794)
							(mid -0.249642 0.249642)
							(end -0.2794 0.1778)
						)
						(arc
							(start -0.2794 -0.1778)
							(mid -0.249642 -0.249642)
							(end -0.1778 -0.2794)
						)
						(arc
							(start 0.1778 -0.2794)
							(mid 0.249642 -0.249642)
							(end 0.2794 -0.1778)
						)
						(arc
							(start 0.2794 0.1778)
							(mid 0.249642 0.249642)
							(end 0.1778 0.2794)
						)
					)
					(width 0)
					(fill yes)
				)
			)
		)
	)
	(footprint ""
		(layer "B.Cu")
		(at 250.707906 -39.50081 180)
		(property "Reference" "R42"
			(at 0 0 0)
			(layer "B.SilkS")
			(hide yes)
			(effects
				(font
					(size 1.27 1.27)
				)
				(justify mirror)
			)
		)
		(property "Value" "0R2J-2-GP"
			(at -0.064008 -3.993896 180)
			(unlocked yes)
			(layer "B.Fab")
			(hide yes)
			(effects
				(font
					(size 1.016 1.016)
					(thickness 0.1524)
				)
				(justify mirror)
			)
		)
		(property "Device Type" "R402H16"
			(at -0.064008 -5.517896 180)
			(unlocked yes)
			(layer "B.Fab")
			(hide yes)
			(effects
				(font
					(size 1.016 1.016)
					(thickness 0.1524)
				)
				(justify mirror)
			)
		)
		(duplicate_pad_numbers_are_jumpers no)
		(fp_line
			(start 0.508 -0.9398)
			(end 0.508 0.9398)
			(stroke
				(width 0.1524)
				(type default)
			)
			(layer "B.SilkS")
		)
		(fp_line
			(start -0.508 -0.9398)
			(end 0.508 -0.9398)
			(stroke
				(width 0.1524)
				(type default)
			)
			(layer "B.SilkS")
		)
		(fp_rect
			(start 0.508 0.9398)
			(end -0.508 -0.9398)
			(stroke
				(width 0)
				(type default)
			)
			(fill no)
			(layer "B.CrtYd")
		)
		(fp_rect
			(start 0.508 0.9398)
			(end -0.508 -0.9398)
			(stroke
				(width 0)
				(type default)
			)
			(fill no)
			(layer "B.Fab")
		)
		(pad "1" smd custom
			(at 0 -0.4445)
			(size 0.1397 0.1397)
			(layers "B.Cu" "B.Mask" "B.Paste")
			(net "VSS_573")
			(options
				(clearance outline)
				(anchor circle)
			)
			(primitives
				(gr_poly
					(pts
						(arc
							(start -0.1778 0.2794)
							(mid -0.249642 0.249642)
							(end -0.2794 0.1778)
						)
						(arc
							(start -0.2794 -0.1778)
							(mid -0.249642 -0.249642)
							(end -0.1778 -0.2794)
						)
						(arc
							(start 0.1778 -0.2794)
							(mid 0.249642 -0.249642)
							(end 0.2794 -0.1778)
						)
						(arc
							(start 0.2794 0.1778)
							(mid 0.249642 0.249642)
							(end 0.1778 0.2794)
						)
					)
					(width 0)
					(fill yes)
				)
			)
		)
		(pad "2" smd custom
			(at 0 0.4445)
			(size 0.1397 0.1397)
			(layers "B.Cu" "B.Mask" "B.Paste")
			(net "GND")
			(options
				(clearance outline)
				(anchor circle)
			)
			(primitives
				(gr_poly
					(pts
						(arc
							(start -0.1778 0.2794)
							(mid -0.249642 0.249642)
							(end -0.2794 0.1778)
						)
						(arc
							(start -0.2794 -0.1778)
							(mid -0.249642 -0.249642)
							(end -0.1778 -0.2794)
						)
						(arc
							(start 0.1778 -0.2794)
							(mid 0.249642 -0.249642)
							(end 0.2794 -0.1778)
						)
						(arc
							(start 0.2794 0.1778)
							(mid 0.249642 0.249642)
							(end 0.1778 0.2794)
						)
					)
					(width 0)
					(fill yes)
				)
			)
		)
	)
	(footprint ""
		(layer "B.Cu")
		(at 231.601518 -38.002718 90)
		(property "Reference" "TP215"
			(at 0 0 90)
			(layer "B.SilkS")
			(hide yes)
			(effects
				(font
					(size 1.27 1.27)
				)
				(justify mirror)
			)
		)
		(property "Value" "TPAD28-2-GP"
			(at 0.0127 -1.6637 90)
			(unlocked yes)
			(layer "B.Fab")
			(hide yes)
			(effects
				(font
					(size 1.016 1.016)
					(thickness 0.1524)
				)
				(justify mirror)
			)
		)
		(property "Device Type" "TPAD28"
			(at 0.0127 -3.1877 90)
			(unlocked yes)
			(layer "B.Fab")
			(hide yes)
			(effects
				(font
					(size 1.016 1.016)
					(thickness 0.1524)
				)
				(justify mirror)
			)
		)
		(duplicate_pad_numbers_are_jumpers no)
		(fp_poly
			(pts
				(arc
					(start 0 0.3556)
					(mid 0 -0.3556)
					(end 0 0.3556)
				)
			)
			(stroke
				(width 0)
				(type default)
			)
			(fill no)
			(layer "B.CrtYd")
		)
		(fp_poly
			(pts
				(arc
					(start 0 0.6096)
					(mid 0 -0.6096)
					(end 0 0.6096)
				)
			)
			(stroke
				(width 0)
				(type default)
			)
			(fill no)
			(layer "B.Fab")
		)
		(pad "1" smd circle
			(at 0 0 270)
			(size 0.7112 0.7112)
			(layers "B.Cu" "B.Mask" "B.Paste")
			(net "MDC")
		)
	)
	(footprint ""
		(layer "B.Cu")
		(at 265.213338 -3.07086 180)
		(property "Reference" "R195"
			(at 0 0 0)
			(layer "B.SilkS")
			(hide yes)
			(effects
				(font
					(size 1.27 1.27)
				)
				(justify mirror)
			)
		)
		(property "Value" "4K7R2F-GP"
			(at -0.064008 -3.993896 180)
			(unlocked yes)
			(layer "B.Fab")
			(hide yes)
			(effects
				(font
					(size 1.016 1.016)
					(thickness 0.1524)
				)
				(justify mirror)
			)
		)
		(property "Device Type" "R402H16"
			(at -0.064008 -5.517896 180)
			(unlocked yes)
			(layer "B.Fab")
			(hide yes)
			(effects
				(font
					(size 1.016 1.016)
					(thickness 0.1524)
				)
				(justify mirror)
			)
		)
		(duplicate_pad_numbers_are_jumpers no)
		(fp_line
			(start 0.508 -0.9398)
			(end 0.508 0.9398)
			(stroke
				(width 0.1524)
				(type default)
			)
			(layer "B.SilkS")
		)
		(fp_line
			(start -0.508 -0.9398)
			(end 0.508 -0.9398)
			(stroke
				(width 0.1524)
				(type default)
			)
			(layer "B.SilkS")
		)
		(fp_rect
			(start 0.508 0.9398)
			(end -0.508 -0.9398)
			(stroke
				(width 0)
				(type default)
			)
			(fill no)
			(layer "B.CrtYd")
		)
		(fp_rect
			(start 0.508 0.9398)
			(end -0.508 -0.9398)
			(stroke
				(width 0)
				(type default)
			)
			(fill no)
			(layer "B.Fab")
		)
		(pad "1" smd custom
			(at 0 -0.4445)
			(size 0.1397 0.1397)
			(layers "B.Cu" "B.Mask" "B.Paste")
			(net "TEMP_1_A0")
			(options
				(clearance outline)
				(anchor circle)
			)
			(primitives
				(gr_poly
					(pts
						(arc
							(start -0.1778 0.2794)
							(mid -0.249642 0.249642)
							(end -0.2794 0.1778)
						)
						(arc
							(start -0.2794 -0.1778)
							(mid -0.249642 -0.249642)
							(end -0.1778 -0.2794)
						)
						(arc
							(start 0.1778 -0.2794)
							(mid 0.249642 -0.249642)
							(end 0.2794 -0.1778)
						)
						(arc
							(start 0.2794 0.1778)
							(mid 0.249642 0.249642)
							(end 0.1778 0.2794)
						)
					)
					(width 0)
					(fill yes)
				)
			)
		)
		(pad "2" smd custom
			(at 0 0.4445)
			(size 0.1397 0.1397)
			(layers "B.Cu" "B.Mask" "B.Paste")
			(net "GND")
			(options
				(clearance outline)
				(anchor circle)
			)
			(primitives
				(gr_poly
					(pts
						(arc
							(start -0.1778 0.2794)
							(mid -0.249642 0.249642)
							(end -0.2794 0.1778)
						)
						(arc
							(start -0.2794 -0.1778)
							(mid -0.249642 -0.249642)
							(end -0.1778 -0.2794)
						)
						(arc
							(start 0.1778 -0.2794)
							(mid 0.249642 -0.249642)
							(end 0.2794 -0.1778)
						)
						(arc
							(start 0.2794 0.1778)
							(mid 0.249642 0.249642)
							(end 0.1778 0.2794)
						)
					)
					(width 0)
					(fill yes)
				)
			)
		)
	)
	(footprint ""
		(layer "B.Cu")
		(at 53.721 -139.827 90)
		(property "Reference" "SR852"
			(at 0 0 90)
			(layer "B.SilkS")
			(hide yes)
			(effects
				(font
					(size 1.27 1.27)
				)
				(justify mirror)
			)
		)
		(property "Value" "4K75R2F-1-GP"
			(at -0.064008 -3.993896 90)
			(unlocked yes)
			(layer "B.Fab")
			(hide yes)
			(effects
				(font
					(size 1.016 1.016)
					(thickness 0.1524)
				)
				(justify mirror)
			)
		)
		(property "Device Type" "R402H16"
			(at -0.064008 -5.517896 90)
			(unlocked yes)
			(layer "B.Fab")
			(hide yes)
			(effects
				(font
					(size 1.016 1.016)
					(thickness 0.1524)
				)
				(justify mirror)
			)
		)
		(duplicate_pad_numbers_are_jumpers no)
		(fp_line
			(start 0.508 -0.9398)
			(end 0.508 0.9398)
			(stroke
				(width 0.1524)
				(type default)
			)
			(layer "B.SilkS")
		)
		(fp_line
			(start -0.508 -0.9398)
			(end 0.508 -0.9398)
			(stroke
				(width 0.1524)
				(type default)
			)
			(layer "B.SilkS")
		)
		(fp_rect
			(start 0.508 0.9398)
			(end -0.508 -0.9398)
			(stroke
				(width 0)
				(type default)
			)
			(fill no)
			(layer "B.CrtYd")
		)
		(fp_rect
			(start 0.508 0.9398)
			(end -0.508 -0.9398)
			(stroke
				(width 0)
				(type default)
			)
			(fill no)
			(layer "B.Fab")
		)
		(pad "1" smd custom
			(at 0 -0.4445 270)
			(size 0.1397 0.1397)
			(layers "B.Cu" "B.Mask" "B.Paste")
			(net "BMC_FW_DET_BOARD_VER_0")
			(options
				(clearance outline)
				(anchor circle)
			)
			(primitives
				(gr_poly
					(pts
						(arc
							(start -0.1778 0.2794)
							(mid -0.249642 0.249642)
							(end -0.2794 0.1778)
						)
						(arc
							(start -0.2794 -0.1778)
							(mid -0.249642 -0.249642)
							(end -0.1778 -0.2794)
						)
						(arc
							(start 0.1778 -0.2794)
							(mid 0.249642 -0.249642)
							(end 0.2794 -0.1778)
						)
						(arc
							(start 0.2794 0.1778)
							(mid 0.249642 0.249642)
							(end 0.1778 0.2794)
						)
					)
					(width 0)
					(fill yes)
				)
			)
		)
		(pad "2" smd custom
			(at 0 0.4445 270)
			(size 0.1397 0.1397)
			(layers "B.Cu" "B.Mask" "B.Paste")
			(net "GND")
			(options
				(clearance outline)
				(anchor circle)
			)
			(primitives
				(gr_poly
					(pts
						(arc
							(start -0.1778 0.2794)
							(mid -0.249642 0.249642)
							(end -0.2794 0.1778)
						)
						(arc
							(start -0.2794 -0.1778)
							(mid -0.249642 -0.249642)
							(end -0.1778 -0.2794)
						)
						(arc
							(start 0.1778 -0.2794)
							(mid 0.249642 -0.249642)
							(end 0.2794 -0.1778)
						)
						(arc
							(start 0.2794 0.1778)
							(mid 0.249642 0.249642)
							(end 0.1778 0.2794)
						)
					)
					(width 0)
					(fill yes)
				)
			)
		)
	)
	(footprint ""
		(layer "B.Cu")
		(at 239.1664 -54.0004 90)
		(property "Reference" "C27"
			(at 0 0 90)
			(layer "B.SilkS")
			(hide yes)
			(effects
				(font
					(size 1.27 1.27)
				)
				(justify mirror)
			)
		)
		(property "Value" "SCD1U16V1KX-1-GP"
			(at 2.8321 -1.7399 90)
			(unlocked yes)
			(layer "B.Fab")
			(hide yes)
			(effects
				(font
					(size 1.016 1.016)
					(thickness 0.1524)
				)
				(justify mirror)
			)
		)
		(property "Device Type" "C0201H13"
			(at 2.8321 -3.2639 90)
			(unlocked yes)
			(layer "B.Fab")
			(hide yes)
			(effects
				(font
					(size 1.016 1.016)
					(thickness 0.1524)
				)
				(justify mirror)
			)
		)
		(duplicate_pad_numbers_are_jumpers no)
		(fp_rect
			(start 0.2794 0.6477)
			(end -0.2794 -0.6477)
			(stroke
				(width 0)
				(type default)
			)
			(fill no)
			(layer "B.CrtYd")
		)
		(fp_rect
			(start 0.2794 0.6477)
			(end -0.2794 -0.6477)
			(stroke
				(width 0)
				(type default)
			)
			(fill no)
			(layer "B.Fab")
		)
		(pad "1" smd custom
			(at 0 -0.2794 270)
			(size 0.0762 0.0762)
			(layers "B.Cu" "B.Mask" "B.Paste")
			(net "DUT_VDD")
			(options
				(clearance outline)
				(anchor circle)
			)
			(primitives
				(gr_poly
					(pts
						(arc
							(start 0.1524 0.127)
							(mid 0.137521 0.162921)
							(end 0.1016 0.1778)
						)
						(arc
							(start -0.1016 0.1778)
							(mid -0.137521 0.162921)
							(end -0.1524 0.127)
						)
						(arc
							(start -0.1524 -0.127)
							(mid -0.137521 -0.162921)
							(end -0.1016 -0.1778)
						)
						(arc
							(start 0.1016 -0.1778)
							(mid 0.137521 -0.162921)
							(end 0.1524 -0.127)
						)
					)
					(width 0)
					(fill yes)
				)
			)
		)
		(pad "2" smd custom
			(at 0 0.2794 270)
			(size 0.0762 0.0762)
			(layers "B.Cu" "B.Mask" "B.Paste")
			(net "GND")
			(options
				(clearance outline)
				(anchor circle)
			)
			(primitives
				(gr_poly
					(pts
						(arc
							(start 0.1524 0.127)
							(mid 0.137521 0.162921)
							(end 0.1016 0.1778)
						)
						(arc
							(start -0.1016 0.1778)
							(mid -0.137521 0.162921)
							(end -0.1524 0.127)
						)
						(arc
							(start -0.1524 -0.127)
							(mid -0.137521 -0.162921)
							(end -0.1016 -0.1778)
						)
						(arc
							(start 0.1016 -0.1778)
							(mid 0.137521 -0.162921)
							(end 0.1524 -0.127)
						)
					)
					(width 0)
					(fill yes)
				)
			)
		)
	)
	(footprint ""
		(layer "B.Cu")
		(at 165.0492 -200.2028 -90)
		(property "Reference" "C4116"
			(at 0 0 90)
			(layer "B.SilkS")
			(hide yes)
			(effects
				(font
					(size 1.27 1.27)
				)
				(justify mirror)
			)
		)
		(property "Value" "SCD1U25V3KX-GP"
			(at 0 -2.8194 270)
			(unlocked yes)
			(layer "B.Fab")
			(hide yes)
			(effects
				(font
					(size 1.016 1.016)
					(thickness 0.1524)
				)
				(justify mirror)
			)
		)
		(property "Device Type" "C603H36"
			(at 0 -4.3434 270)
			(unlocked yes)
			(layer "B.Fab")
			(hide yes)
			(effects
				(font
					(size 1.016 1.016)
					(thickness 0.1524)
				)
				(justify mirror)
			)
		)
		(duplicate_pad_numbers_are_jumpers no)
		(fp_line
			(start -0.508 0)
			(end 0.508 0)
			(stroke
				(width 0.2032)
				(type default)
			)
			(layer "B.SilkS")
		)
		(fp_rect
			(start 0.5842 1.3335)
			(end -0.5842 -1.3335)
			(stroke
				(width 0)
				(type default)
			)
			(fill no)
			(layer "B.CrtYd")
		)
		(fp_rect
			(start 0.5842 1.3335)
			(end -0.5842 -1.3335)
			(stroke
				(width 0)
				(type default)
			)
			(fill no)
			(layer "B.Fab")
		)
		(pad "1" smd custom
			(at 0 -0.762 90)
			(size 0.2159 0.2159)
			(layers "B.Cu" "B.Mask" "B.Paste")
			(net "GND")
			(options
				(clearance outline)
				(anchor circle)
			)
			(primitives
				(gr_poly
					(pts
						(arc
							(start -0.3302 0.4318)
							(mid -0.402042 0.402042)
							(end -0.4318 0.3302)
						)
						(arc
							(start -0.4318 -0.3302)
							(mid -0.402042 -0.402042)
							(end -0.3302 -0.4318)
						)
						(arc
							(start 0.3302 -0.4318)
							(mid 0.402042 -0.402042)
							(end 0.4318 -0.3302)
						)
						(arc
							(start 0.4318 0.3302)
							(mid 0.402042 0.402042)
							(end 0.3302 0.4318)
						)
					)
					(width 0)
					(fill yes)
				)
			)
		)
		(pad "2" smd custom
			(at 0 0.762 90)
			(size 0.2159 0.2159)
			(layers "B.Cu" "B.Mask" "B.Paste")
			(net "SSD_PWREN11_R")
			(options
				(clearance outline)
				(anchor circle)
			)
			(primitives
				(gr_poly
					(pts
						(arc
							(start -0.3302 0.4318)
							(mid -0.402042 0.402042)
							(end -0.4318 0.3302)
						)
						(arc
							(start -0.4318 -0.3302)
							(mid -0.402042 -0.402042)
							(end -0.3302 -0.4318)
						)
						(arc
							(start 0.3302 -0.4318)
							(mid 0.402042 -0.402042)
							(end 0.4318 -0.3302)
						)
						(arc
							(start 0.4318 0.3302)
							(mid 0.402042 0.402042)
							(end 0.3302 0.4318)
						)
					)
					(width 0)
					(fill yes)
				)
			)
		)
	)
	(footprint ""
		(layer "B.Cu")
		(at 52.965604 -113.83391 -90)
		(property "Reference" "R437"
			(at 0 0 90)
			(layer "B.SilkS")
			(hide yes)
			(effects
				(font
					(size 1.27 1.27)
				)
				(justify mirror)
			)
		)
		(property "Value" "4K7R2F-GP"
			(at -0.064008 -3.993896 270)
			(unlocked yes)
			(layer "B.Fab")
			(hide yes)
			(effects
				(font
					(size 1.016 1.016)
					(thickness 0.1524)
				)
				(justify mirror)
			)
		)
		(property "Device Type" "R402H16"
			(at -0.064008 -5.517896 270)
			(unlocked yes)
			(layer "B.Fab")
			(hide yes)
			(effects
				(font
					(size 1.016 1.016)
					(thickness 0.1524)
				)
				(justify mirror)
			)
		)
		(duplicate_pad_numbers_are_jumpers no)
		(fp_line
			(start -0.508 -0.9398)
			(end 0.508 -0.9398)
			(stroke
				(width 0.1524)
				(type default)
			)
			(layer "B.SilkS")
		)
		(fp_line
			(start 0.508 -0.9398)
			(end 0.508 0.9398)
			(stroke
				(width 0.1524)
				(type default)
			)
			(layer "B.SilkS")
		)
		(fp_rect
			(start 0.508 0.9398)
			(end -0.508 -0.9398)
			(stroke
				(width 0)
				(type default)
			)
			(fill no)
			(layer "B.CrtYd")
		)
		(fp_rect
			(start 0.508 0.9398)
			(end -0.508 -0.9398)
			(stroke
				(width 0)
				(type default)
			)
			(fill no)
			(layer "B.Fab")
		)
		(pad "1" smd custom
			(at 0 -0.4445 90)
			(size 0.1397 0.1397)
			(layers "B.Cu" "B.Mask" "B.Paste")
			(net "BMC_I2C12_MINI6_SCL_S")
			(options
				(clearance outline)
				(anchor circle)
			)
			(primitives
				(gr_poly
					(pts
						(arc
							(start -0.1778 0.2794)
							(mid -0.249642 0.249642)
							(end -0.2794 0.1778)
						)
						(arc
							(start -0.2794 -0.1778)
							(mid -0.249642 -0.249642)
							(end -0.1778 -0.2794)
						)
						(arc
							(start 0.1778 -0.2794)
							(mid 0.249642 -0.249642)
							(end 0.2794 -0.1778)
						)
						(arc
							(start 0.2794 0.1778)
							(mid 0.249642 0.249642)
							(end 0.1778 0.2794)
						)
					)
					(width 0)
					(fill yes)
				)
			)
		)
		(pad "2" smd custom
			(at 0 0.4445 90)
			(size 0.1397 0.1397)
			(layers "B.Cu" "B.Mask" "B.Paste")
			(net "P3V3_STBY")
			(options
				(clearance outline)
				(anchor circle)
			)
			(primitives
				(gr_poly
					(pts
						(arc
							(start -0.1778 0.2794)
							(mid -0.249642 0.249642)
							(end -0.2794 0.1778)
						)
						(arc
							(start -0.2794 -0.1778)
							(mid -0.249642 -0.249642)
							(end -0.1778 -0.2794)
						)
						(arc
							(start 0.1778 -0.2794)
							(mid 0.249642 -0.249642)
							(end 0.2794 -0.1778)
						)
						(arc
							(start 0.2794 0.1778)
							(mid 0.249642 0.249642)
							(end 0.1778 0.2794)
						)
					)
					(width 0)
					(fill yes)
				)
			)
		)
	)
	(footprint ""
		(layer "B.Cu")
		(at 70.993 -192.532)
		(property "Reference" "R3234"
			(at 0 0 0)
			(layer "B.SilkS")
			(hide yes)
			(effects
				(font
					(size 1.27 1.27)
				)
				(justify mirror)
			)
		)
		(property "Value" "0R2J-2-GP"
			(at -0.064008 -3.993896 0)
			(unlocked yes)
			(layer "B.Fab")
			(hide yes)
			(effects
				(font
					(size 1.016 1.016)
					(thickness 0.1524)
				)
				(justify mirror)
			)
		)
		(property "Device Type" "R402H16"
			(at -0.064008 -5.517896 0)
			(unlocked yes)
			(layer "B.Fab")
			(hide yes)
			(effects
				(font
					(size 1.016 1.016)
					(thickness 0.1524)
				)
				(justify mirror)
			)
		)
		(duplicate_pad_numbers_are_jumpers no)
		(fp_line
			(start -0.508 -0.9398)
			(end 0.508 -0.9398)
			(stroke
				(width 0.1524)
				(type default)
			)
			(layer "B.SilkS")
		)
		(fp_line
			(start 0.508 -0.9398)
			(end 0.508 0.9398)
			(stroke
				(width 0.1524)
				(type default)
			)
			(layer "B.SilkS")
		)
		(fp_rect
			(start 0.508 0.9398)
			(end -0.508 -0.9398)
			(stroke
				(width 0)
				(type default)
			)
			(fill no)
			(layer "B.CrtYd")
		)
		(fp_rect
			(start 0.508 0.9398)
			(end -0.508 -0.9398)
			(stroke
				(width 0)
				(type default)
			)
			(fill no)
			(layer "B.Fab")
		)
		(pad "1" smd custom
			(at 0 -0.4445 180)
			(size 0.1397 0.1397)
			(layers "B.Cu" "B.Mask" "B.Paste")
			(net "SSD_PERST#11")
			(options
				(clearance outline)
				(anchor circle)
			)
			(primitives
				(gr_poly
					(pts
						(arc
							(start -0.1778 0.2794)
							(mid -0.249642 0.249642)
							(end -0.2794 0.1778)
						)
						(arc
							(start -0.2794 -0.1778)
							(mid -0.249642 -0.249642)
							(end -0.1778 -0.2794)
						)
						(arc
							(start 0.1778 -0.2794)
							(mid 0.249642 -0.249642)
							(end 0.2794 -0.1778)
						)
						(arc
							(start 0.2794 0.1778)
							(mid 0.249642 0.249642)
							(end 0.1778 0.2794)
						)
					)
					(width 0)
					(fill yes)
				)
			)
		)
		(pad "2" smd custom
			(at 0 0.4445 180)
			(size 0.1397 0.1397)
			(layers "B.Cu" "B.Mask" "B.Paste")
			(net "SSD_PERST#0_B11")
			(options
				(clearance outline)
				(anchor circle)
			)
			(primitives
				(gr_poly
					(pts
						(arc
							(start -0.1778 0.2794)
							(mid -0.249642 0.249642)
							(end -0.2794 0.1778)
						)
						(arc
							(start -0.2794 -0.1778)
							(mid -0.249642 -0.249642)
							(end -0.1778 -0.2794)
						)
						(arc
							(start 0.1778 -0.2794)
							(mid 0.249642 -0.249642)
							(end 0.2794 -0.1778)
						)
						(arc
							(start 0.2794 0.1778)
							(mid 0.249642 0.249642)
							(end 0.1778 0.2794)
						)
					)
					(width 0)
					(fill yes)
				)
			)
		)
	)
	(footprint ""
		(layer "B.Cu")
		(at 25.86228 -78.00848 90)
		(property "Reference" "C625"
			(at 0 0 90)
			(layer "B.SilkS")
			(hide yes)
			(effects
				(font
					(size 1.27 1.27)
				)
				(justify mirror)
			)
		)
		(property "Value" "SC47U6D3V5MX-1-GP"
			(at 0.0762 -6.1214 90)
			(unlocked yes)
			(layer "B.Fab")
			(hide yes)
			(effects
				(font
					(size 1.016 1.016)
					(thickness 0.1524)
				)
				(justify mirror)
			)
		)
		(property "Device Type" "C805H54"
			(at 0.0762 -8.1534 90)
			(unlocked yes)
			(layer "B.Fab")
			(hide yes)
			(effects
				(font
					(size 1.016 1.016)
					(thickness 0.1524)
				)
				(justify mirror)
			)
		)
		(duplicate_pad_numbers_are_jumpers no)
		(fp_line
			(start -0.635 0)
			(end 0.635 0)
			(stroke
				(width 0.508)
				(type default)
			)
			(layer "B.SilkS")
		)
		(fp_rect
			(start 0.9652 1.778)
			(end -0.9652 -1.778)
			(stroke
				(width 0)
				(type default)
			)
			(fill no)
			(layer "B.CrtYd")
		)
		(fp_poly
			(pts
				(xy 0.9652 -1.778) (xy -0.9652 -1.778) (xy -0.9652 1.778) (xy 0.9652 1.778)
			)
			(stroke
				(width 0)
				(type default)
			)
			(fill no)
			(layer "B.Fab")
		)
		(pad "1" smd rect
			(at 0 -0.9652 270)
			(size 1.397 1.143)
			(layers "B.Cu" "B.Mask" "B.Paste")
			(net "P3V3_STBY")
		)
		(pad "2" smd rect
			(at 0 0.9652 270)
			(size 1.397 1.143)
			(layers "B.Cu" "B.Mask" "B.Paste")
			(net "GND")
		)
	)
	(footprint ""
		(layer "B.Cu")
		(at 46.228 -118.364)
		(property "Reference" "TP155"
			(at 0 0 0)
			(layer "B.SilkS")
			(hide yes)
			(effects
				(font
					(size 1.27 1.27)
				)
				(justify mirror)
			)
		)
		(property "Value" "TPAD28-2-GP"
			(at 0.0127 -1.6637 0)
			(unlocked yes)
			(layer "B.Fab")
			(hide yes)
			(effects
				(font
					(size 1.016 1.016)
					(thickness 0.1524)
				)
				(justify mirror)
			)
		)
		(property "Device Type" "TPAD28"
			(at 0.0127 -3.1877 0)
			(unlocked yes)
			(layer "B.Fab")
			(hide yes)
			(effects
				(font
					(size 1.016 1.016)
					(thickness 0.1524)
				)
				(justify mirror)
			)
		)
		(duplicate_pad_numbers_are_jumpers no)
		(fp_poly
			(pts
				(arc
					(start 0.3556 0)
					(mid -0.3556 0)
					(end 0.3556 0)
				)
			)
			(stroke
				(width 0)
				(type default)
			)
			(fill no)
			(layer "B.CrtYd")
		)
		(fp_poly
			(pts
				(arc
					(start 0.6096 0)
					(mid -0.6096 0)
					(end 0.6096 0)
				)
			)
			(stroke
				(width 0)
				(type default)
			)
			(fill no)
			(layer "B.Fab")
		)
		(pad "1" smd circle
			(at 0 0 180)
			(size 0.7112 0.7112)
			(layers "B.Cu" "B.Mask" "B.Paste")
			(net "TP_GPIOA7")
		)
	)
	(footprint ""
		(layer "B.Cu")
		(at 238.6203 -40.005 90)
		(property "Reference" "C482"
			(at 0 0 90)
			(layer "B.SilkS")
			(hide yes)
			(effects
				(font
					(size 1.27 1.27)
				)
				(justify mirror)
			)
		)
		(property "Value" "SCD1U16V1KX-1-GP"
			(at 2.8321 -1.7399 90)
			(unlocked yes)
			(layer "B.Fab")
			(hide yes)
			(effects
				(font
					(size 1.016 1.016)
					(thickness 0.1524)
				)
				(justify mirror)
			)
		)
		(property "Device Type" "C0201H13"
			(at 2.8321 -3.2639 90)
			(unlocked yes)
			(layer "B.Fab")
			(hide yes)
			(effects
				(font
					(size 1.016 1.016)
					(thickness 0.1524)
				)
				(justify mirror)
			)
		)
		(duplicate_pad_numbers_are_jumpers no)
		(fp_rect
			(start 0.2794 0.6477)
			(end -0.2794 -0.6477)
			(stroke
				(width 0)
				(type default)
			)
			(fill no)
			(layer "B.CrtYd")
		)
		(fp_rect
			(start 0.2794 0.6477)
			(end -0.2794 -0.6477)
			(stroke
				(width 0)
				(type default)
			)
			(fill no)
			(layer "B.Fab")
		)
		(pad "1" smd custom
			(at 0 -0.2794 270)
			(size 0.0762 0.0762)
			(layers "B.Cu" "B.Mask" "B.Paste")
			(net "DUT_VDDO")
			(options
				(clearance outline)
				(anchor circle)
			)
			(primitives
				(gr_poly
					(pts
						(arc
							(start 0.1524 0.127)
							(mid 0.137521 0.162921)
							(end 0.1016 0.1778)
						)
						(arc
							(start -0.1016 0.1778)
							(mid -0.137521 0.162921)
							(end -0.1524 0.127)
						)
						(arc
							(start -0.1524 -0.127)
							(mid -0.137521 -0.162921)
							(end -0.1016 -0.1778)
						)
						(arc
							(start 0.1016 -0.1778)
							(mid 0.137521 -0.162921)
							(end 0.1524 -0.127)
						)
					)
					(width 0)
					(fill yes)
				)
			)
		)
		(pad "2" smd custom
			(at 0 0.2794 270)
			(size 0.0762 0.0762)
			(layers "B.Cu" "B.Mask" "B.Paste")
			(net "GND")
			(options
				(clearance outline)
				(anchor circle)
			)
			(primitives
				(gr_poly
					(pts
						(arc
							(start 0.1524 0.127)
							(mid 0.137521 0.162921)
							(end 0.1016 0.1778)
						)
						(arc
							(start -0.1016 0.1778)
							(mid -0.137521 0.162921)
							(end -0.1524 0.127)
						)
						(arc
							(start -0.1524 -0.127)
							(mid -0.137521 -0.162921)
							(end -0.1016 -0.1778)
						)
						(arc
							(start 0.1016 -0.1778)
							(mid 0.137521 -0.162921)
							(end 0.1524 -0.127)
						)
					)
					(width 0)
					(fill yes)
				)
			)
		)
	)
	(footprint ""
		(layer "B.Cu")
		(at 75.184 -148.082 -90)
		(property "Reference" "R193"
			(at 0 0 90)
			(layer "B.SilkS")
			(hide yes)
			(effects
				(font
					(size 1.27 1.27)
				)
				(justify mirror)
			)
		)
		(property "Value" "8K2R2J-3-GP"
			(at -0.064008 -3.993896 270)
			(unlocked yes)
			(layer "B.Fab")
			(hide yes)
			(effects
				(font
					(size 1.016 1.016)
					(thickness 0.1524)
				)
				(justify mirror)
			)
		)
		(property "Device Type" "R402H16"
			(at -0.064008 -5.517896 270)
			(unlocked yes)
			(layer "B.Fab")
			(hide yes)
			(effects
				(font
					(size 1.016 1.016)
					(thickness 0.1524)
				)
				(justify mirror)
			)
		)
		(duplicate_pad_numbers_are_jumpers no)
		(fp_line
			(start -0.508 -0.9398)
			(end 0.508 -0.9398)
			(stroke
				(width 0.1524)
				(type default)
			)
			(layer "B.SilkS")
		)
		(fp_line
			(start 0.508 -0.9398)
			(end 0.508 0.9398)
			(stroke
				(width 0.1524)
				(type default)
			)
			(layer "B.SilkS")
		)
		(fp_rect
			(start 0.508 0.9398)
			(end -0.508 -0.9398)
			(stroke
				(width 0)
				(type default)
			)
			(fill no)
			(layer "B.CrtYd")
		)
		(fp_rect
			(start 0.508 0.9398)
			(end -0.508 -0.9398)
			(stroke
				(width 0)
				(type default)
			)
			(fill no)
			(layer "B.Fab")
		)
		(pad "1" smd custom
			(at 0 -0.4445 90)
			(size 0.1397 0.1397)
			(layers "B.Cu" "B.Mask" "B.Paste")
			(net "P3V3_STBY")
			(options
				(clearance outline)
				(anchor circle)
			)
			(primitives
				(gr_poly
					(pts
						(arc
							(start -0.1778 0.2794)
							(mid -0.249642 0.249642)
							(end -0.2794 0.1778)
						)
						(arc
							(start -0.2794 -0.1778)
							(mid -0.249642 -0.249642)
							(end -0.1778 -0.2794)
						)
						(arc
							(start 0.1778 -0.2794)
							(mid 0.249642 -0.249642)
							(end 0.2794 -0.1778)
						)
						(arc
							(start 0.2794 0.1778)
							(mid 0.249642 0.249642)
							(end 0.1778 0.2794)
						)
					)
					(width 0)
					(fill yes)
				)
			)
		)
		(pad "2" smd custom
			(at 0 0.4445 90)
			(size 0.1397 0.1397)
			(layers "B.Cu" "B.Mask" "B.Paste")
			(net "EEPROM_A1_R")
			(options
				(clearance outline)
				(anchor circle)
			)
			(primitives
				(gr_poly
					(pts
						(arc
							(start -0.1778 0.2794)
							(mid -0.249642 0.249642)
							(end -0.2794 0.1778)
						)
						(arc
							(start -0.2794 -0.1778)
							(mid -0.249642 -0.249642)
							(end -0.1778 -0.2794)
						)
						(arc
							(start 0.1778 -0.2794)
							(mid 0.249642 -0.249642)
							(end 0.2794 -0.1778)
						)
						(arc
							(start 0.2794 0.1778)
							(mid 0.249642 0.249642)
							(end 0.1778 0.2794)
						)
					)
					(width 0)
					(fill yes)
				)
			)
		)
	)
	(footprint ""
		(layer "B.Cu")
		(at 51.2318 -115.90909)
		(property "Reference" "R470"
			(at 0 0 0)
			(layer "B.SilkS")
			(hide yes)
			(effects
				(font
					(size 1.27 1.27)
				)
				(justify mirror)
			)
		)
		(property "Value" "0R2J-2-GP"
			(at -0.064008 -3.993896 0)
			(unlocked yes)
			(layer "B.Fab")
			(hide yes)
			(effects
				(font
					(size 1.016 1.016)
					(thickness 0.1524)
				)
				(justify mirror)
			)
		)
		(property "Device Type" "R402H16"
			(at -0.064008 -5.517896 0)
			(unlocked yes)
			(layer "B.Fab")
			(hide yes)
			(effects
				(font
					(size 1.016 1.016)
					(thickness 0.1524)
				)
				(justify mirror)
			)
		)
		(duplicate_pad_numbers_are_jumpers no)
		(fp_line
			(start -0.508 -0.9398)
			(end 0.508 -0.9398)
			(stroke
				(width 0.1524)
				(type default)
			)
			(layer "B.SilkS")
		)
		(fp_line
			(start 0.508 -0.9398)
			(end 0.508 0.9398)
			(stroke
				(width 0.1524)
				(type default)
			)
			(layer "B.SilkS")
		)
		(fp_rect
			(start 0.508 0.9398)
			(end -0.508 -0.9398)
			(stroke
				(width 0)
				(type default)
			)
			(fill no)
			(layer "B.CrtYd")
		)
		(fp_rect
			(start 0.508 0.9398)
			(end -0.508 -0.9398)
			(stroke
				(width 0)
				(type default)
			)
			(fill no)
			(layer "B.Fab")
		)
		(pad "1" smd custom
			(at 0 -0.4445 180)
			(size 0.1397 0.1397)
			(layers "B.Cu" "B.Mask" "B.Paste")
			(net "BMC0_SMB10_DAT")
			(options
				(clearance outline)
				(anchor circle)
			)
			(primitives
				(gr_poly
					(pts
						(arc
							(start -0.1778 0.2794)
							(mid -0.249642 0.249642)
							(end -0.2794 0.1778)
						)
						(arc
							(start -0.2794 -0.1778)
							(mid -0.249642 -0.249642)
							(end -0.1778 -0.2794)
						)
						(arc
							(start 0.1778 -0.2794)
							(mid 0.249642 -0.249642)
							(end 0.2794 -0.1778)
						)
						(arc
							(start 0.2794 0.1778)
							(mid 0.249642 0.249642)
							(end 0.1778 0.2794)
						)
					)
					(width 0)
					(fill yes)
				)
			)
		)
		(pad "2" smd custom
			(at 0 0.4445 180)
			(size 0.1397 0.1397)
			(layers "B.Cu" "B.Mask" "B.Paste")
			(net "BMC_I2C10_8536_SDA")
			(options
				(clearance outline)
				(anchor circle)
			)
			(primitives
				(gr_poly
					(pts
						(arc
							(start -0.1778 0.2794)
							(mid -0.249642 0.249642)
							(end -0.2794 0.1778)
						)
						(arc
							(start -0.2794 -0.1778)
							(mid -0.249642 -0.249642)
							(end -0.1778 -0.2794)
						)
						(arc
							(start 0.1778 -0.2794)
							(mid 0.249642 -0.249642)
							(end 0.2794 -0.1778)
						)
						(arc
							(start 0.2794 0.1778)
							(mid 0.249642 0.249642)
							(end 0.1778 0.2794)
						)
					)
					(width 0)
					(fill yes)
				)
			)
		)
	)
	(footprint ""
		(layer "B.Cu")
		(at 133.55828 -33.54578)
		(property "Reference" "R2918"
			(at 0 0 0)
			(layer "B.SilkS")
			(hide yes)
			(effects
				(font
					(size 1.27 1.27)
				)
				(justify mirror)
			)
		)
		(property "Value" "0R2J-2-GP"
			(at -0.064008 -3.993896 0)
			(unlocked yes)
			(layer "B.Fab")
			(hide yes)
			(effects
				(font
					(size 1.016 1.016)
					(thickness 0.1524)
				)
				(justify mirror)
			)
		)
		(property "Device Type" "R402H16"
			(at -0.064008 -5.517896 0)
			(unlocked yes)
			(layer "B.Fab")
			(hide yes)
			(effects
				(font
					(size 1.016 1.016)
					(thickness 0.1524)
				)
				(justify mirror)
			)
		)
		(duplicate_pad_numbers_are_jumpers no)
		(fp_line
			(start -0.508 -0.9398)
			(end 0.508 -0.9398)
			(stroke
				(width 0.1524)
				(type default)
			)
			(layer "B.SilkS")
		)
		(fp_line
			(start 0.508 -0.9398)
			(end 0.508 0.9398)
			(stroke
				(width 0.1524)
				(type default)
			)
			(layer "B.SilkS")
		)
		(fp_rect
			(start 0.508 0.9398)
			(end -0.508 -0.9398)
			(stroke
				(width 0)
				(type default)
			)
			(fill no)
			(layer "B.CrtYd")
		)
		(fp_rect
			(start 0.508 0.9398)
			(end -0.508 -0.9398)
			(stroke
				(width 0)
				(type default)
			)
			(fill no)
			(layer "B.Fab")
		)
		(pad "1" smd custom
			(at 0 -0.4445 180)
			(size 0.1397 0.1397)
			(layers "B.Cu" "B.Mask" "B.Paste")
			(net "CBL_PRSNT_N_1")
			(options
				(clearance outline)
				(anchor circle)
			)
			(primitives
				(gr_poly
					(pts
						(arc
							(start -0.1778 0.2794)
							(mid -0.249642 0.249642)
							(end -0.2794 0.1778)
						)
						(arc
							(start -0.2794 -0.1778)
							(mid -0.249642 -0.249642)
							(end -0.1778 -0.2794)
						)
						(arc
							(start 0.1778 -0.2794)
							(mid 0.249642 -0.249642)
							(end 0.2794 -0.1778)
						)
						(arc
							(start 0.2794 0.1778)
							(mid 0.249642 0.249642)
							(end 0.1778 0.2794)
						)
					)
					(width 0)
					(fill yes)
				)
			)
		)
		(pad "2" smd custom
			(at 0 0.4445 180)
			(size 0.1397 0.1397)
			(layers "B.Cu" "B.Mask" "B.Paste")
			(net "8644_CBL_PRSNT_R_1")
			(options
				(clearance outline)
				(anchor circle)
			)
			(primitives
				(gr_poly
					(pts
						(arc
							(start -0.1778 0.2794)
							(mid -0.249642 0.249642)
							(end -0.2794 0.1778)
						)
						(arc
							(start -0.2794 -0.1778)
							(mid -0.249642 -0.249642)
							(end -0.1778 -0.2794)
						)
						(arc
							(start 0.1778 -0.2794)
							(mid 0.249642 -0.249642)
							(end 0.2794 -0.1778)
						)
						(arc
							(start 0.2794 0.1778)
							(mid 0.249642 0.249642)
							(end 0.1778 0.2794)
						)
					)
					(width 0)
					(fill yes)
				)
			)
		)
	)
	(footprint ""
		(layer "B.Cu")
		(at 243.586 -59.0042 -90)
		(property "Reference" "C508"
			(at 0 0 90)
			(layer "B.SilkS")
			(hide yes)
			(effects
				(font
					(size 1.27 1.27)
				)
				(justify mirror)
			)
		)
		(property "Value" "SCD1U16V1KX-1-GP"
			(at 2.8321 -1.7399 270)
			(unlocked yes)
			(layer "B.Fab")
			(hide yes)
			(effects
				(font
					(size 1.016 1.016)
					(thickness 0.1524)
				)
				(justify mirror)
			)
		)
		(property "Device Type" "C0201H13"
			(at 2.8321 -3.2639 270)
			(unlocked yes)
			(layer "B.Fab")
			(hide yes)
			(effects
				(font
					(size 1.016 1.016)
					(thickness 0.1524)
				)
				(justify mirror)
			)
		)
		(duplicate_pad_numbers_are_jumpers no)
		(fp_rect
			(start 0.2794 0.6477)
			(end -0.2794 -0.6477)
			(stroke
				(width 0)
				(type default)
			)
			(fill no)
			(layer "B.CrtYd")
		)
		(fp_rect
			(start 0.2794 0.6477)
			(end -0.2794 -0.6477)
			(stroke
				(width 0)
				(type default)
			)
			(fill no)
			(layer "B.Fab")
		)
		(pad "1" smd custom
			(at 0 -0.2794 90)
			(size 0.0762 0.0762)
			(layers "B.Cu" "B.Mask" "B.Paste")
			(net "DUT_AVD_TX")
			(options
				(clearance outline)
				(anchor circle)
			)
			(primitives
				(gr_poly
					(pts
						(arc
							(start 0.1524 0.127)
							(mid 0.137521 0.162921)
							(end 0.1016 0.1778)
						)
						(arc
							(start -0.1016 0.1778)
							(mid -0.137521 0.162921)
							(end -0.1524 0.127)
						)
						(arc
							(start -0.1524 -0.127)
							(mid -0.137521 -0.162921)
							(end -0.1016 -0.1778)
						)
						(arc
							(start 0.1016 -0.1778)
							(mid 0.137521 -0.162921)
							(end 0.1524 -0.127)
						)
					)
					(width 0)
					(fill yes)
				)
			)
		)
		(pad "2" smd custom
			(at 0 0.2794 90)
			(size 0.0762 0.0762)
			(layers "B.Cu" "B.Mask" "B.Paste")
			(net "GND")
			(options
				(clearance outline)
				(anchor circle)
			)
			(primitives
				(gr_poly
					(pts
						(arc
							(start 0.1524 0.127)
							(mid 0.137521 0.162921)
							(end 0.1016 0.1778)
						)
						(arc
							(start -0.1016 0.1778)
							(mid -0.137521 0.162921)
							(end -0.1524 0.127)
						)
						(arc
							(start -0.1524 -0.127)
							(mid -0.137521 -0.162921)
							(end -0.1016 -0.1778)
						)
						(arc
							(start 0.1016 -0.1778)
							(mid 0.137521 -0.162921)
							(end 0.1524 -0.127)
						)
					)
					(width 0)
					(fill yes)
				)
			)
		)
	)
	(footprint ""
		(layer "B.Cu")
		(at 66.938652 -121.3104 -90)
		(property "Reference" "R261"
			(at 0 0 90)
			(layer "B.SilkS")
			(hide yes)
			(effects
				(font
					(size 1.27 1.27)
				)
				(justify mirror)
			)
		)
		(property "Value" "0R2J-2-GP"
			(at -0.064008 -3.993896 270)
			(unlocked yes)
			(layer "B.Fab")
			(hide yes)
			(effects
				(font
					(size 1.016 1.016)
					(thickness 0.1524)
				)
				(justify mirror)
			)
		)
		(property "Device Type" "R402H16"
			(at -0.064008 -5.517896 270)
			(unlocked yes)
			(layer "B.Fab")
			(hide yes)
			(effects
				(font
					(size 1.016 1.016)
					(thickness 0.1524)
				)
				(justify mirror)
			)
		)
		(duplicate_pad_numbers_are_jumpers no)
		(fp_line
			(start -0.508 -0.9398)
			(end 0.508 -0.9398)
			(stroke
				(width 0.1524)
				(type default)
			)
			(layer "B.SilkS")
		)
		(fp_line
			(start 0.508 -0.9398)
			(end 0.508 0.9398)
			(stroke
				(width 0.1524)
				(type default)
			)
			(layer "B.SilkS")
		)
		(fp_rect
			(start 0.508 0.9398)
			(end -0.508 -0.9398)
			(stroke
				(width 0)
				(type default)
			)
			(fill no)
			(layer "B.CrtYd")
		)
		(fp_rect
			(start 0.508 0.9398)
			(end -0.508 -0.9398)
			(stroke
				(width 0)
				(type default)
			)
			(fill no)
			(layer "B.Fab")
		)
		(pad "1" smd custom
			(at 0 -0.4445 90)
			(size 0.1397 0.1397)
			(layers "B.Cu" "B.Mask" "B.Paste")
			(net "LAN_SMB_CLK")
			(options
				(clearance outline)
				(anchor circle)
			)
			(primitives
				(gr_poly
					(pts
						(arc
							(start -0.1778 0.2794)
							(mid -0.249642 0.249642)
							(end -0.2794 0.1778)
						)
						(arc
							(start -0.2794 -0.1778)
							(mid -0.249642 -0.249642)
							(end -0.1778 -0.2794)
						)
						(arc
							(start 0.1778 -0.2794)
							(mid 0.249642 -0.249642)
							(end 0.2794 -0.1778)
						)
						(arc
							(start 0.2794 0.1778)
							(mid 0.249642 0.249642)
							(end 0.1778 0.2794)
						)
					)
					(width 0)
					(fill yes)
				)
			)
		)
		(pad "2" smd custom
			(at 0 0.4445 90)
			(size 0.1397 0.1397)
			(layers "B.Cu" "B.Mask" "B.Paste")
			(net "BMC0_SMB4_CLK")
			(options
				(clearance outline)
				(anchor circle)
			)
			(primitives
				(gr_poly
					(pts
						(arc
							(start -0.1778 0.2794)
							(mid -0.249642 0.249642)
							(end -0.2794 0.1778)
						)
						(arc
							(start -0.2794 -0.1778)
							(mid -0.249642 -0.249642)
							(end -0.1778 -0.2794)
						)
						(arc
							(start 0.1778 -0.2794)
							(mid 0.249642 -0.249642)
							(end 0.2794 -0.1778)
						)
						(arc
							(start 0.2794 0.1778)
							(mid 0.249642 0.249642)
							(end 0.1778 0.2794)
						)
					)
					(width 0)
					(fill yes)
				)
			)
		)
	)
	(footprint ""
		(layer "B.Cu")
		(at 237.1598 -43.997372 90)
		(property "Reference" "C432"
			(at 0 0 90)
			(layer "B.SilkS")
			(hide yes)
			(effects
				(font
					(size 1.27 1.27)
				)
				(justify mirror)
			)
		)
		(property "Value" "SCD1U16V1KX-1-GP"
			(at 2.8321 -1.7399 90)
			(unlocked yes)
			(layer "B.Fab")
			(hide yes)
			(effects
				(font
					(size 1.016 1.016)
					(thickness 0.1524)
				)
				(justify mirror)
			)
		)
		(property "Device Type" "C0201H13"
			(at 2.8321 -3.2639 90)
			(unlocked yes)
			(layer "B.Fab")
			(hide yes)
			(effects
				(font
					(size 1.016 1.016)
					(thickness 0.1524)
				)
				(justify mirror)
			)
		)
		(duplicate_pad_numbers_are_jumpers no)
		(fp_rect
			(start 0.2794 0.6477)
			(end -0.2794 -0.6477)
			(stroke
				(width 0)
				(type default)
			)
			(fill no)
			(layer "B.CrtYd")
		)
		(fp_rect
			(start 0.2794 0.6477)
			(end -0.2794 -0.6477)
			(stroke
				(width 0)
				(type default)
			)
			(fill no)
			(layer "B.Fab")
		)
		(pad "1" smd custom
			(at 0 -0.2794 270)
			(size 0.0762 0.0762)
			(layers "B.Cu" "B.Mask" "B.Paste")
			(net "DUT_VDD")
			(options
				(clearance outline)
				(anchor circle)
			)
			(primitives
				(gr_poly
					(pts
						(arc
							(start 0.1524 0.127)
							(mid 0.137521 0.162921)
							(end 0.1016 0.1778)
						)
						(arc
							(start -0.1016 0.1778)
							(mid -0.137521 0.162921)
							(end -0.1524 0.127)
						)
						(arc
							(start -0.1524 -0.127)
							(mid -0.137521 -0.162921)
							(end -0.1016 -0.1778)
						)
						(arc
							(start 0.1016 -0.1778)
							(mid 0.137521 -0.162921)
							(end 0.1524 -0.127)
						)
					)
					(width 0)
					(fill yes)
				)
			)
		)
		(pad "2" smd custom
			(at 0 0.2794 270)
			(size 0.0762 0.0762)
			(layers "B.Cu" "B.Mask" "B.Paste")
			(net "GND")
			(options
				(clearance outline)
				(anchor circle)
			)
			(primitives
				(gr_poly
					(pts
						(arc
							(start 0.1524 0.127)
							(mid 0.137521 0.162921)
							(end 0.1016 0.1778)
						)
						(arc
							(start -0.1016 0.1778)
							(mid -0.137521 0.162921)
							(end -0.1524 0.127)
						)
						(arc
							(start -0.1524 -0.127)
							(mid -0.137521 -0.162921)
							(end -0.1016 -0.1778)
						)
						(arc
							(start 0.1016 -0.1778)
							(mid 0.137521 -0.162921)
							(end 0.1524 -0.127)
						)
					)
					(width 0)
					(fill yes)
				)
			)
		)
	)
	(footprint ""
		(layer "B.Cu")
		(at 61.341 -34.036 180)
		(property "Reference" "PR31"
			(at 0 0 0)
			(layer "B.SilkS")
			(hide yes)
			(effects
				(font
					(size 1.27 1.27)
				)
				(justify mirror)
			)
		)
		(property "Value" "121KR2F-L-GP"
			(at -0.064008 -3.993896 180)
			(unlocked yes)
			(layer "B.Fab")
			(hide yes)
			(effects
				(font
					(size 1.016 1.016)
					(thickness 0.1524)
				)
				(justify mirror)
			)
		)
		(property "Device Type" "R402H16"
			(at -0.064008 -5.517896 180)
			(unlocked yes)
			(layer "B.Fab")
			(hide yes)
			(effects
				(font
					(size 1.016 1.016)
					(thickness 0.1524)
				)
				(justify mirror)
			)
		)
		(duplicate_pad_numbers_are_jumpers no)
		(fp_line
			(start 0.508 -0.9398)
			(end 0.508 0.9398)
			(stroke
				(width 0.1524)
				(type default)
			)
			(layer "B.SilkS")
		)
		(fp_line
			(start -0.508 -0.9398)
			(end 0.508 -0.9398)
			(stroke
				(width 0.1524)
				(type default)
			)
			(layer "B.SilkS")
		)
		(fp_rect
			(start 0.508 0.9398)
			(end -0.508 -0.9398)
			(stroke
				(width 0)
				(type default)
			)
			(fill no)
			(layer "B.CrtYd")
		)
		(fp_rect
			(start 0.508 0.9398)
			(end -0.508 -0.9398)
			(stroke
				(width 0)
				(type default)
			)
			(fill no)
			(layer "B.Fab")
		)
		(pad "1" smd custom
			(at 0 -0.4445)
			(size 0.1397 0.1397)
			(layers "B.Cu" "B.Mask" "B.Paste")
			(net "AGND_P3V3_STBY")
			(options
				(clearance outline)
				(anchor circle)
			)
			(primitives
				(gr_poly
					(pts
						(arc
							(start -0.1778 0.2794)
							(mid -0.249642 0.249642)
							(end -0.2794 0.1778)
						)
						(arc
							(start -0.2794 -0.1778)
							(mid -0.249642 -0.249642)
							(end -0.1778 -0.2794)
						)
						(arc
							(start 0.1778 -0.2794)
							(mid 0.249642 -0.249642)
							(end 0.2794 -0.1778)
						)
						(arc
							(start 0.2794 0.1778)
							(mid 0.249642 0.249642)
							(end 0.1778 0.2794)
						)
					)
					(width 0)
					(fill yes)
				)
			)
		)
		(pad "2" smd custom
			(at 0 0.4445)
			(size 0.1397 0.1397)
			(layers "B.Cu" "B.Mask" "B.Paste")
			(net "P3V3_STBY_TRIP")
			(options
				(clearance outline)
				(anchor circle)
			)
			(primitives
				(gr_poly
					(pts
						(arc
							(start -0.1778 0.2794)
							(mid -0.249642 0.249642)
							(end -0.2794 0.1778)
						)
						(arc
							(start -0.2794 -0.1778)
							(mid -0.249642 -0.249642)
							(end -0.1778 -0.2794)
						)
						(arc
							(start 0.1778 -0.2794)
							(mid 0.249642 -0.249642)
							(end 0.2794 -0.1778)
						)
						(arc
							(start 0.2794 0.1778)
							(mid 0.249642 0.249642)
							(end 0.1778 0.2794)
						)
					)
					(width 0)
					(fill yes)
				)
			)
		)
	)
	(footprint ""
		(layer "B.Cu")
		(at 235.585 -56.00192 -90)
		(property "Reference" "C521"
			(at 0 0 90)
			(layer "B.SilkS")
			(hide yes)
			(effects
				(font
					(size 1.27 1.27)
				)
				(justify mirror)
			)
		)
		(property "Value" "SCD1U16V1KX-1-GP"
			(at 2.8321 -1.7399 270)
			(unlocked yes)
			(layer "B.Fab")
			(hide yes)
			(effects
				(font
					(size 1.016 1.016)
					(thickness 0.1524)
				)
				(justify mirror)
			)
		)
		(property "Device Type" "C0201H13"
			(at 2.8321 -3.2639 270)
			(unlocked yes)
			(layer "B.Fab")
			(hide yes)
			(effects
				(font
					(size 1.016 1.016)
					(thickness 0.1524)
				)
				(justify mirror)
			)
		)
		(duplicate_pad_numbers_are_jumpers no)
		(fp_rect
			(start 0.2794 0.6477)
			(end -0.2794 -0.6477)
			(stroke
				(width 0)
				(type default)
			)
			(fill no)
			(layer "B.CrtYd")
		)
		(fp_rect
			(start 0.2794 0.6477)
			(end -0.2794 -0.6477)
			(stroke
				(width 0)
				(type default)
			)
			(fill no)
			(layer "B.Fab")
		)
		(pad "1" smd custom
			(at 0 -0.2794 90)
			(size 0.0762 0.0762)
			(layers "B.Cu" "B.Mask" "B.Paste")
			(net "DUT_AVD_TX")
			(options
				(clearance outline)
				(anchor circle)
			)
			(primitives
				(gr_poly
					(pts
						(arc
							(start 0.1524 0.127)
							(mid 0.137521 0.162921)
							(end 0.1016 0.1778)
						)
						(arc
							(start -0.1016 0.1778)
							(mid -0.137521 0.162921)
							(end -0.1524 0.127)
						)
						(arc
							(start -0.1524 -0.127)
							(mid -0.137521 -0.162921)
							(end -0.1016 -0.1778)
						)
						(arc
							(start 0.1016 -0.1778)
							(mid 0.137521 -0.162921)
							(end 0.1524 -0.127)
						)
					)
					(width 0)
					(fill yes)
				)
			)
		)
		(pad "2" smd custom
			(at 0 0.2794 90)
			(size 0.0762 0.0762)
			(layers "B.Cu" "B.Mask" "B.Paste")
			(net "GND")
			(options
				(clearance outline)
				(anchor circle)
			)
			(primitives
				(gr_poly
					(pts
						(arc
							(start 0.1524 0.127)
							(mid 0.137521 0.162921)
							(end 0.1016 0.1778)
						)
						(arc
							(start -0.1016 0.1778)
							(mid -0.137521 0.162921)
							(end -0.1524 0.127)
						)
						(arc
							(start -0.1524 -0.127)
							(mid -0.137521 -0.162921)
							(end -0.1016 -0.1778)
						)
						(arc
							(start 0.1016 -0.1778)
							(mid 0.137521 -0.162921)
							(end 0.1524 -0.127)
						)
					)
					(width 0)
					(fill yes)
				)
			)
		)
	)
	(footprint ""
		(layer "B.Cu")
		(at 252.603 -45.991272 -90)
		(property "Reference" "C612"
			(at 0 0 90)
			(layer "B.SilkS")
			(hide yes)
			(effects
				(font
					(size 1.27 1.27)
				)
				(justify mirror)
			)
		)
		(property "Value" "SCD1U16V1KX-1-GP"
			(at 2.8321 -1.7399 270)
			(unlocked yes)
			(layer "B.Fab")
			(hide yes)
			(effects
				(font
					(size 1.016 1.016)
					(thickness 0.1524)
				)
				(justify mirror)
			)
		)
		(property "Device Type" "C0201H13"
			(at 2.8321 -3.2639 270)
			(unlocked yes)
			(layer "B.Fab")
			(hide yes)
			(effects
				(font
					(size 1.016 1.016)
					(thickness 0.1524)
				)
				(justify mirror)
			)
		)
		(duplicate_pad_numbers_are_jumpers no)
		(fp_rect
			(start 0.2794 0.6477)
			(end -0.2794 -0.6477)
			(stroke
				(width 0)
				(type default)
			)
			(fill no)
			(layer "B.CrtYd")
		)
		(fp_rect
			(start 0.2794 0.6477)
			(end -0.2794 -0.6477)
			(stroke
				(width 0)
				(type default)
			)
			(fill no)
			(layer "B.Fab")
		)
		(pad "1" smd custom
			(at 0 -0.2794 90)
			(size 0.0762 0.0762)
			(layers "B.Cu" "B.Mask" "B.Paste")
			(net "DUT_AVD_PCIE")
			(options
				(clearance outline)
				(anchor circle)
			)
			(primitives
				(gr_poly
					(pts
						(arc
							(start 0.1524 0.127)
							(mid 0.137521 0.162921)
							(end 0.1016 0.1778)
						)
						(arc
							(start -0.1016 0.1778)
							(mid -0.137521 0.162921)
							(end -0.1524 0.127)
						)
						(arc
							(start -0.1524 -0.127)
							(mid -0.137521 -0.162921)
							(end -0.1016 -0.1778)
						)
						(arc
							(start 0.1016 -0.1778)
							(mid 0.137521 -0.162921)
							(end 0.1524 -0.127)
						)
					)
					(width 0)
					(fill yes)
				)
			)
		)
		(pad "2" smd custom
			(at 0 0.2794 90)
			(size 0.0762 0.0762)
			(layers "B.Cu" "B.Mask" "B.Paste")
			(net "GND")
			(options
				(clearance outline)
				(anchor circle)
			)
			(primitives
				(gr_poly
					(pts
						(arc
							(start 0.1524 0.127)
							(mid 0.137521 0.162921)
							(end 0.1016 0.1778)
						)
						(arc
							(start -0.1016 0.1778)
							(mid -0.137521 0.162921)
							(end -0.1524 0.127)
						)
						(arc
							(start -0.1524 -0.127)
							(mid -0.137521 -0.162921)
							(end -0.1016 -0.1778)
						)
						(arc
							(start 0.1016 -0.1778)
							(mid 0.137521 -0.162921)
							(end 0.1524 -0.127)
						)
					)
					(width 0)
					(fill yes)
				)
			)
		)
	)
	(footprint ""
		(layer "B.Cu")
		(at 211.900008 -4.064)
		(property "Reference" "R3709"
			(at 0 0 0)
			(layer "B.SilkS")
			(hide yes)
			(effects
				(font
					(size 1.27 1.27)
				)
				(justify mirror)
			)
		)
		(property "Value" "1KR2F-3-GP"
			(at -0.064008 -3.993896 0)
			(unlocked yes)
			(layer "B.Fab")
			(hide yes)
			(effects
				(font
					(size 1.016 1.016)
					(thickness 0.1524)
				)
				(justify mirror)
			)
		)
		(property "Device Type" "R402H16"
			(at -0.064008 -5.517896 0)
			(unlocked yes)
			(layer "B.Fab")
			(hide yes)
			(effects
				(font
					(size 1.016 1.016)
					(thickness 0.1524)
				)
				(justify mirror)
			)
		)
		(duplicate_pad_numbers_are_jumpers no)
		(fp_line
			(start -0.508 -0.9398)
			(end 0.508 -0.9398)
			(stroke
				(width 0.1524)
				(type default)
			)
			(layer "B.SilkS")
		)
		(fp_line
			(start 0.508 -0.9398)
			(end 0.508 0.9398)
			(stroke
				(width 0.1524)
				(type default)
			)
			(layer "B.SilkS")
		)
		(fp_rect
			(start 0.508 0.9398)
			(end -0.508 -0.9398)
			(stroke
				(width 0)
				(type default)
			)
			(fill no)
			(layer "B.CrtYd")
		)
		(fp_rect
			(start 0.508 0.9398)
			(end -0.508 -0.9398)
			(stroke
				(width 0)
				(type default)
			)
			(fill no)
			(layer "B.Fab")
		)
		(pad "1" smd custom
			(at 0 -0.4445 180)
			(size 0.1397 0.1397)
			(layers "B.Cu" "B.Mask" "B.Paste")
			(net "HOST5_RST_N")
			(options
				(clearance outline)
				(anchor circle)
			)
			(primitives
				(gr_poly
					(pts
						(arc
							(start -0.1778 0.2794)
							(mid -0.249642 0.249642)
							(end -0.2794 0.1778)
						)
						(arc
							(start -0.2794 -0.1778)
							(mid -0.249642 -0.249642)
							(end -0.1778 -0.2794)
						)
						(arc
							(start 0.1778 -0.2794)
							(mid 0.249642 -0.249642)
							(end 0.2794 -0.1778)
						)
						(arc
							(start 0.2794 0.1778)
							(mid 0.249642 0.249642)
							(end 0.1778 0.2794)
						)
					)
					(width 0)
					(fill yes)
				)
			)
		)
		(pad "2" smd custom
			(at 0 0.4445 180)
			(size 0.1397 0.1397)
			(layers "B.Cu" "B.Mask" "B.Paste")
			(net "P3V3_STBY")
			(options
				(clearance outline)
				(anchor circle)
			)
			(primitives
				(gr_poly
					(pts
						(arc
							(start -0.1778 0.2794)
							(mid -0.249642 0.249642)
							(end -0.2794 0.1778)
						)
						(arc
							(start -0.2794 -0.1778)
							(mid -0.249642 -0.249642)
							(end -0.1778 -0.2794)
						)
						(arc
							(start 0.1778 -0.2794)
							(mid 0.249642 -0.249642)
							(end 0.2794 -0.1778)
						)
						(arc
							(start 0.2794 0.1778)
							(mid 0.249642 0.249642)
							(end 0.1778 0.2794)
						)
					)
					(width 0)
					(fill yes)
				)
			)
		)
	)
	(footprint ""
		(layer "B.Cu")
		(at 48.1584 -113.1316)
		(property "Reference" "R422"
			(at 0 0 0)
			(layer "B.SilkS")
			(hide yes)
			(effects
				(font
					(size 1.27 1.27)
				)
				(justify mirror)
			)
		)
		(property "Value" "4K7R2F-GP"
			(at -0.064008 -3.993896 0)
			(unlocked yes)
			(layer "B.Fab")
			(hide yes)
			(effects
				(font
					(size 1.016 1.016)
					(thickness 0.1524)
				)
				(justify mirror)
			)
		)
		(property "Device Type" "R402H16"
			(at -0.064008 -5.517896 0)
			(unlocked yes)
			(layer "B.Fab")
			(hide yes)
			(effects
				(font
					(size 1.016 1.016)
					(thickness 0.1524)
				)
				(justify mirror)
			)
		)
		(duplicate_pad_numbers_are_jumpers no)
		(fp_line
			(start -0.508 -0.9398)
			(end 0.508 -0.9398)
			(stroke
				(width 0.1524)
				(type default)
			)
			(layer "B.SilkS")
		)
		(fp_line
			(start 0.508 -0.9398)
			(end 0.508 0.9398)
			(stroke
				(width 0.1524)
				(type default)
			)
			(layer "B.SilkS")
		)
		(fp_rect
			(start 0.508 0.9398)
			(end -0.508 -0.9398)
			(stroke
				(width 0)
				(type default)
			)
			(fill no)
			(layer "B.CrtYd")
		)
		(fp_rect
			(start 0.508 0.9398)
			(end -0.508 -0.9398)
			(stroke
				(width 0)
				(type default)
			)
			(fill no)
			(layer "B.Fab")
		)
		(pad "1" smd custom
			(at 0 -0.4445 180)
			(size 0.1397 0.1397)
			(layers "B.Cu" "B.Mask" "B.Paste")
			(net "BMC_I2C9_CLKBUF2_SCL")
			(options
				(clearance outline)
				(anchor circle)
			)
			(primitives
				(gr_poly
					(pts
						(arc
							(start -0.1778 0.2794)
							(mid -0.249642 0.249642)
							(end -0.2794 0.1778)
						)
						(arc
							(start -0.2794 -0.1778)
							(mid -0.249642 -0.249642)
							(end -0.1778 -0.2794)
						)
						(arc
							(start 0.1778 -0.2794)
							(mid 0.249642 -0.249642)
							(end 0.2794 -0.1778)
						)
						(arc
							(start 0.2794 0.1778)
							(mid 0.249642 0.249642)
							(end 0.1778 0.2794)
						)
					)
					(width 0)
					(fill yes)
				)
			)
		)
		(pad "2" smd custom
			(at 0 0.4445 180)
			(size 0.1397 0.1397)
			(layers "B.Cu" "B.Mask" "B.Paste")
			(net "P3V3_STBY")
			(options
				(clearance outline)
				(anchor circle)
			)
			(primitives
				(gr_poly
					(pts
						(arc
							(start -0.1778 0.2794)
							(mid -0.249642 0.249642)
							(end -0.2794 0.1778)
						)
						(arc
							(start -0.2794 -0.1778)
							(mid -0.249642 -0.249642)
							(end -0.1778 -0.2794)
						)
						(arc
							(start 0.1778 -0.2794)
							(mid 0.249642 -0.249642)
							(end 0.2794 -0.1778)
						)
						(arc
							(start 0.2794 0.1778)
							(mid 0.249642 0.249642)
							(end 0.1778 0.2794)
						)
					)
					(width 0)
					(fill yes)
				)
			)
		)
	)
	(footprint ""
		(layer "B.Cu")
		(at 241.0968 -48.9966 90)
		(property "Reference" "C34"
			(at 0 0 90)
			(layer "B.SilkS")
			(hide yes)
			(effects
				(font
					(size 1.27 1.27)
				)
				(justify mirror)
			)
		)
		(property "Value" "SCD1U16V1KX-1-GP"
			(at 2.8321 -1.7399 90)
			(unlocked yes)
			(layer "B.Fab")
			(hide yes)
			(effects
				(font
					(size 1.016 1.016)
					(thickness 0.1524)
				)
				(justify mirror)
			)
		)
		(property "Device Type" "C0201H13"
			(at 2.8321 -3.2639 90)
			(unlocked yes)
			(layer "B.Fab")
			(hide yes)
			(effects
				(font
					(size 1.016 1.016)
					(thickness 0.1524)
				)
				(justify mirror)
			)
		)
		(duplicate_pad_numbers_are_jumpers no)
		(fp_rect
			(start 0.2794 0.6477)
			(end -0.2794 -0.6477)
			(stroke
				(width 0)
				(type default)
			)
			(fill no)
			(layer "B.CrtYd")
		)
		(fp_rect
			(start 0.2794 0.6477)
			(end -0.2794 -0.6477)
			(stroke
				(width 0)
				(type default)
			)
			(fill no)
			(layer "B.Fab")
		)
		(pad "1" smd custom
			(at 0 -0.2794 270)
			(size 0.0762 0.0762)
			(layers "B.Cu" "B.Mask" "B.Paste")
			(net "DUT_VDD")
			(options
				(clearance outline)
				(anchor circle)
			)
			(primitives
				(gr_poly
					(pts
						(arc
							(start 0.1524 0.127)
							(mid 0.137521 0.162921)
							(end 0.1016 0.1778)
						)
						(arc
							(start -0.1016 0.1778)
							(mid -0.137521 0.162921)
							(end -0.1524 0.127)
						)
						(arc
							(start -0.1524 -0.127)
							(mid -0.137521 -0.162921)
							(end -0.1016 -0.1778)
						)
						(arc
							(start 0.1016 -0.1778)
							(mid 0.137521 -0.162921)
							(end 0.1524 -0.127)
						)
					)
					(width 0)
					(fill yes)
				)
			)
		)
		(pad "2" smd custom
			(at 0 0.2794 270)
			(size 0.0762 0.0762)
			(layers "B.Cu" "B.Mask" "B.Paste")
			(net "GND")
			(options
				(clearance outline)
				(anchor circle)
			)
			(primitives
				(gr_poly
					(pts
						(arc
							(start 0.1524 0.127)
							(mid 0.137521 0.162921)
							(end 0.1016 0.1778)
						)
						(arc
							(start -0.1016 0.1778)
							(mid -0.137521 0.162921)
							(end -0.1524 0.127)
						)
						(arc
							(start -0.1524 -0.127)
							(mid -0.137521 -0.162921)
							(end -0.1016 -0.1778)
						)
						(arc
							(start 0.1016 -0.1778)
							(mid 0.137521 -0.162921)
							(end 0.1524 -0.127)
						)
					)
					(width 0)
					(fill yes)
				)
			)
		)
	)
	(footprint ""
		(layer "B.Cu")
		(at 77.065124 -195.681092 180)
		(property "Reference" "R4112"
			(at 0 0 0)
			(layer "B.SilkS")
			(hide yes)
			(effects
				(font
					(size 1.27 1.27)
				)
				(justify mirror)
			)
		)
		(property "Value" "4K7R2F-GP"
			(at -0.064008 -3.993896 180)
			(unlocked yes)
			(layer "B.Fab")
			(hide yes)
			(effects
				(font
					(size 1.016 1.016)
					(thickness 0.1524)
				)
				(justify mirror)
			)
		)
		(property "Device Type" "R402H16"
			(at -0.064008 -5.517896 180)
			(unlocked yes)
			(layer "B.Fab")
			(hide yes)
			(effects
				(font
					(size 1.016 1.016)
					(thickness 0.1524)
				)
				(justify mirror)
			)
		)
		(duplicate_pad_numbers_are_jumpers no)
		(fp_line
			(start 0.508 -0.9398)
			(end 0.508 0.9398)
			(stroke
				(width 0.1524)
				(type default)
			)
			(layer "B.SilkS")
		)
		(fp_line
			(start -0.508 -0.9398)
			(end 0.508 -0.9398)
			(stroke
				(width 0.1524)
				(type default)
			)
			(layer "B.SilkS")
		)
		(fp_rect
			(start 0.508 0.9398)
			(end -0.508 -0.9398)
			(stroke
				(width 0)
				(type default)
			)
			(fill no)
			(layer "B.CrtYd")
		)
		(fp_rect
			(start 0.508 0.9398)
			(end -0.508 -0.9398)
			(stroke
				(width 0)
				(type default)
			)
			(fill no)
			(layer "B.Fab")
		)
		(pad "1" smd custom
			(at 0 -0.4445)
			(size 0.1397 0.1397)
			(layers "B.Cu" "B.Mask" "B.Paste")
			(net "SSD_PERST#10")
			(options
				(clearance outline)
				(anchor circle)
			)
			(primitives
				(gr_poly
					(pts
						(arc
							(start -0.1778 0.2794)
							(mid -0.249642 0.249642)
							(end -0.2794 0.1778)
						)
						(arc
							(start -0.2794 -0.1778)
							(mid -0.249642 -0.249642)
							(end -0.1778 -0.2794)
						)
						(arc
							(start 0.1778 -0.2794)
							(mid 0.249642 -0.249642)
							(end 0.2794 -0.1778)
						)
						(arc
							(start 0.2794 0.1778)
							(mid 0.249642 0.249642)
							(end 0.1778 0.2794)
						)
					)
					(width 0)
					(fill yes)
				)
			)
		)
		(pad "2" smd custom
			(at 0 0.4445)
			(size 0.1397 0.1397)
			(layers "B.Cu" "B.Mask" "B.Paste")
			(net "P3V3_STBY")
			(options
				(clearance outline)
				(anchor circle)
			)
			(primitives
				(gr_poly
					(pts
						(arc
							(start -0.1778 0.2794)
							(mid -0.249642 0.249642)
							(end -0.2794 0.1778)
						)
						(arc
							(start -0.2794 -0.1778)
							(mid -0.249642 -0.249642)
							(end -0.1778 -0.2794)
						)
						(arc
							(start 0.1778 -0.2794)
							(mid 0.249642 -0.249642)
							(end 0.2794 -0.1778)
						)
						(arc
							(start 0.2794 0.1778)
							(mid 0.249642 0.249642)
							(end 0.1778 0.2794)
						)
					)
					(width 0)
					(fill yes)
				)
			)
		)
	)
	(footprint ""
		(layer "B.Cu")
		(at 253.5936 -34.993072 90)
		(property "Reference" "C606"
			(at 0 0 90)
			(layer "B.SilkS")
			(hide yes)
			(effects
				(font
					(size 1.27 1.27)
				)
				(justify mirror)
			)
		)
		(property "Value" "SCD1U16V1KX-1-GP"
			(at 2.8321 -1.7399 90)
			(unlocked yes)
			(layer "B.Fab")
			(hide yes)
			(effects
				(font
					(size 1.016 1.016)
					(thickness 0.1524)
				)
				(justify mirror)
			)
		)
		(property "Device Type" "C0201H13"
			(at 2.8321 -3.2639 90)
			(unlocked yes)
			(layer "B.Fab")
			(hide yes)
			(effects
				(font
					(size 1.016 1.016)
					(thickness 0.1524)
				)
				(justify mirror)
			)
		)
		(duplicate_pad_numbers_are_jumpers no)
		(fp_rect
			(start 0.2794 0.6477)
			(end -0.2794 -0.6477)
			(stroke
				(width 0)
				(type default)
			)
			(fill no)
			(layer "B.CrtYd")
		)
		(fp_rect
			(start 0.2794 0.6477)
			(end -0.2794 -0.6477)
			(stroke
				(width 0)
				(type default)
			)
			(fill no)
			(layer "B.Fab")
		)
		(pad "1" smd custom
			(at 0 -0.2794 270)
			(size 0.0762 0.0762)
			(layers "B.Cu" "B.Mask" "B.Paste")
			(net "DUT_AVD_PCIE")
			(options
				(clearance outline)
				(anchor circle)
			)
			(primitives
				(gr_poly
					(pts
						(arc
							(start 0.1524 0.127)
							(mid 0.137521 0.162921)
							(end 0.1016 0.1778)
						)
						(arc
							(start -0.1016 0.1778)
							(mid -0.137521 0.162921)
							(end -0.1524 0.127)
						)
						(arc
							(start -0.1524 -0.127)
							(mid -0.137521 -0.162921)
							(end -0.1016 -0.1778)
						)
						(arc
							(start 0.1016 -0.1778)
							(mid 0.137521 -0.162921)
							(end 0.1524 -0.127)
						)
					)
					(width 0)
					(fill yes)
				)
			)
		)
		(pad "2" smd custom
			(at 0 0.2794 270)
			(size 0.0762 0.0762)
			(layers "B.Cu" "B.Mask" "B.Paste")
			(net "GND")
			(options
				(clearance outline)
				(anchor circle)
			)
			(primitives
				(gr_poly
					(pts
						(arc
							(start 0.1524 0.127)
							(mid 0.137521 0.162921)
							(end 0.1016 0.1778)
						)
						(arc
							(start -0.1016 0.1778)
							(mid -0.137521 0.162921)
							(end -0.1524 0.127)
						)
						(arc
							(start -0.1524 -0.127)
							(mid -0.137521 -0.162921)
							(end -0.1016 -0.1778)
						)
						(arc
							(start 0.1016 -0.1778)
							(mid 0.137521 -0.162921)
							(end 0.1524 -0.127)
						)
					)
					(width 0)
					(fill yes)
				)
			)
		)
	)
	(footprint ""
		(layer "B.Cu")
		(at 245.684802 -25.4)
		(property "Reference" "TP284"
			(at 0 0 0)
			(layer "B.SilkS")
			(hide yes)
			(effects
				(font
					(size 1.27 1.27)
				)
				(justify mirror)
			)
		)
		(property "Value" "TPAD28-2-GP"
			(at 0.0127 -1.6637 0)
			(unlocked yes)
			(layer "B.Fab")
			(hide yes)
			(effects
				(font
					(size 1.016 1.016)
					(thickness 0.1524)
				)
				(justify mirror)
			)
		)
		(property "Device Type" "TPAD28"
			(at 0.0127 -3.1877 0)
			(unlocked yes)
			(layer "B.Fab")
			(hide yes)
			(effects
				(font
					(size 1.016 1.016)
					(thickness 0.1524)
				)
				(justify mirror)
			)
		)
		(duplicate_pad_numbers_are_jumpers no)
		(fp_poly
			(pts
				(arc
					(start 0.3556 0)
					(mid -0.3556 0)
					(end 0.3556 0)
				)
			)
			(stroke
				(width 0)
				(type default)
			)
			(fill no)
			(layer "B.CrtYd")
		)
		(fp_poly
			(pts
				(arc
					(start 0.6096 0)
					(mid -0.6096 0)
					(end 0.6096 0)
				)
			)
			(stroke
				(width 0)
				(type default)
			)
			(fill no)
			(layer "B.Fab")
		)
		(pad "1" smd circle
			(at 0 0 180)
			(size 0.7112 0.7112)
			(layers "B.Cu" "B.Mask" "B.Paste")
			(net "TWI_SCL4")
		)
	)
	(footprint ""
		(layer "B.Cu")
		(at 241.1476 -11.2014 -90)
		(property "Reference" "R41"
			(at 0 0 90)
			(layer "B.SilkS")
			(hide yes)
			(effects
				(font
					(size 1.27 1.27)
				)
				(justify mirror)
			)
		)
		(property "Value" "1KR3F-GP"
			(at 0.0254 -2.5146 270)
			(unlocked yes)
			(layer "B.Fab")
			(hide yes)
			(effects
				(font
					(size 1.016 1.016)
					(thickness 0.1524)
				)
				(justify mirror)
			)
		)
		(property "Device Type" "R603H22"
			(at 0.0254 -4.0386 270)
			(unlocked yes)
			(layer "B.Fab")
			(hide yes)
			(effects
				(font
					(size 1.016 1.016)
					(thickness 0.1524)
				)
				(justify mirror)
			)
		)
		(duplicate_pad_numbers_are_jumpers no)
		(fp_line
			(start -0.2032 0)
			(end -0.4826 0)
			(stroke
				(width 0.2032)
				(type default)
			)
			(layer "B.SilkS")
		)
		(fp_line
			(start 0.4826 0)
			(end 0.2032 0)
			(stroke
				(width 0.2032)
				(type default)
			)
			(layer "B.SilkS")
		)
		(fp_rect
			(start 0.5842 1.3335)
			(end -0.5842 -1.3335)
			(stroke
				(width 0)
				(type default)
			)
			(fill no)
			(layer "B.CrtYd")
		)
		(fp_rect
			(start 0.5842 1.3335)
			(end -0.5842 -1.3335)
			(stroke
				(width 0)
				(type default)
			)
			(fill no)
			(layer "B.Fab")
		)
		(pad "1" smd custom
			(at 0 -0.762 90)
			(size 0.2159 0.2159)
			(layers "B.Cu" "B.Mask" "B.Paste")
			(net "DUT_VDDO")
			(options
				(clearance outline)
				(anchor circle)
			)
			(primitives
				(gr_poly
					(pts
						(arc
							(start -0.3302 0.4318)
							(mid -0.402042 0.402042)
							(end -0.4318 0.3302)
						)
						(arc
							(start -0.4318 -0.3302)
							(mid -0.402042 -0.402042)
							(end -0.3302 -0.4318)
						)
						(arc
							(start 0.3302 -0.4318)
							(mid 0.402042 -0.402042)
							(end 0.4318 -0.3302)
						)
						(arc
							(start 0.4318 0.3302)
							(mid 0.402042 0.402042)
							(end 0.3302 0.4318)
						)
					)
					(width 0)
					(fill yes)
				)
			)
		)
		(pad "2" smd custom
			(at 0 0.762 90)
			(size 0.2159 0.2159)
			(layers "B.Cu" "B.Mask" "B.Paste")
			(net "DUT_VDDO_REF")
			(options
				(clearance outline)
				(anchor circle)
			)
			(primitives
				(gr_poly
					(pts
						(arc
							(start -0.3302 0.4318)
							(mid -0.402042 0.402042)
							(end -0.4318 0.3302)
						)
						(arc
							(start -0.4318 -0.3302)
							(mid -0.402042 -0.402042)
							(end -0.3302 -0.4318)
						)
						(arc
							(start 0.3302 -0.4318)
							(mid 0.402042 -0.402042)
							(end 0.4318 -0.3302)
						)
						(arc
							(start 0.4318 0.3302)
							(mid 0.402042 0.402042)
							(end 0.3302 0.4318)
						)
					)
					(width 0)
					(fill yes)
				)
			)
		)
	)
	(footprint ""
		(layer "B.Cu")
		(at 238.252 -23.241 180)
		(property "Reference" "R782"
			(at 0 0 0)
			(layer "B.SilkS")
			(hide yes)
			(effects
				(font
					(size 1.27 1.27)
				)
				(justify mirror)
			)
		)
		(property "Value" "4K7R2F-GP"
			(at -0.064008 -3.993896 180)
			(unlocked yes)
			(layer "B.Fab")
			(hide yes)
			(effects
				(font
					(size 1.016 1.016)
					(thickness 0.1524)
				)
				(justify mirror)
			)
		)
		(property "Device Type" "R402H16"
			(at -0.064008 -5.517896 180)
			(unlocked yes)
			(layer "B.Fab")
			(hide yes)
			(effects
				(font
					(size 1.016 1.016)
					(thickness 0.1524)
				)
				(justify mirror)
			)
		)
		(duplicate_pad_numbers_are_jumpers no)
		(fp_line
			(start 0.508 -0.9398)
			(end 0.508 0.9398)
			(stroke
				(width 0.1524)
				(type default)
			)
			(layer "B.SilkS")
		)
		(fp_line
			(start -0.508 -0.9398)
			(end 0.508 -0.9398)
			(stroke
				(width 0.1524)
				(type default)
			)
			(layer "B.SilkS")
		)
		(fp_rect
			(start 0.508 0.9398)
			(end -0.508 -0.9398)
			(stroke
				(width 0)
				(type default)
			)
			(fill no)
			(layer "B.CrtYd")
		)
		(fp_rect
			(start 0.508 0.9398)
			(end -0.508 -0.9398)
			(stroke
				(width 0)
				(type default)
			)
			(fill no)
			(layer "B.Fab")
		)
		(pad "1" smd custom
			(at 0 -0.4445)
			(size 0.1397 0.1397)
			(layers "B.Cu" "B.Mask" "B.Paste")
			(net "BOOTSTRAP2")
			(options
				(clearance outline)
				(anchor circle)
			)
			(primitives
				(gr_poly
					(pts
						(arc
							(start -0.1778 0.2794)
							(mid -0.249642 0.249642)
							(end -0.2794 0.1778)
						)
						(arc
							(start -0.2794 -0.1778)
							(mid -0.249642 -0.249642)
							(end -0.1778 -0.2794)
						)
						(arc
							(start 0.1778 -0.2794)
							(mid 0.249642 -0.249642)
							(end 0.2794 -0.1778)
						)
						(arc
							(start 0.2794 0.1778)
							(mid 0.249642 0.249642)
							(end 0.1778 0.2794)
						)
					)
					(width 0)
					(fill yes)
				)
			)
		)
		(pad "2" smd custom
			(at 0 0.4445)
			(size 0.1397 0.1397)
			(layers "B.Cu" "B.Mask" "B.Paste")
			(net "BOOTSTRAP_R_2")
			(options
				(clearance outline)
				(anchor circle)
			)
			(primitives
				(gr_poly
					(pts
						(arc
							(start -0.1778 0.2794)
							(mid -0.249642 0.249642)
							(end -0.2794 0.1778)
						)
						(arc
							(start -0.2794 -0.1778)
							(mid -0.249642 -0.249642)
							(end -0.1778 -0.2794)
						)
						(arc
							(start 0.1778 -0.2794)
							(mid 0.249642 -0.249642)
							(end 0.2794 -0.1778)
						)
						(arc
							(start 0.2794 0.1778)
							(mid 0.249642 0.249642)
							(end 0.1778 0.2794)
						)
					)
					(width 0)
					(fill yes)
				)
			)
		)
	)
	(footprint ""
		(layer "B.Cu")
		(at 23.941786 -130.446018 90)
		(property "Reference" "R349"
			(at 0 0 90)
			(layer "B.SilkS")
			(hide yes)
			(effects
				(font
					(size 1.27 1.27)
				)
				(justify mirror)
			)
		)
		(property "Value" "3K3R2F-2-GP"
			(at -0.064008 -3.993896 90)
			(unlocked yes)
			(layer "B.Fab")
			(hide yes)
			(effects
				(font
					(size 1.016 1.016)
					(thickness 0.1524)
				)
				(justify mirror)
			)
		)
		(property "Device Type" "R402H16"
			(at -0.064008 -5.517896 90)
			(unlocked yes)
			(layer "B.Fab")
			(hide yes)
			(effects
				(font
					(size 1.016 1.016)
					(thickness 0.1524)
				)
				(justify mirror)
			)
		)
		(duplicate_pad_numbers_are_jumpers no)
		(fp_line
			(start 0.508 -0.9398)
			(end 0.508 0.9398)
			(stroke
				(width 0.1524)
				(type default)
			)
			(layer "B.SilkS")
		)
		(fp_line
			(start -0.508 -0.9398)
			(end 0.508 -0.9398)
			(stroke
				(width 0.1524)
				(type default)
			)
			(layer "B.SilkS")
		)
		(fp_rect
			(start 0.508 0.9398)
			(end -0.508 -0.9398)
			(stroke
				(width 0)
				(type default)
			)
			(fill no)
			(layer "B.CrtYd")
		)
		(fp_rect
			(start 0.508 0.9398)
			(end -0.508 -0.9398)
			(stroke
				(width 0)
				(type default)
			)
			(fill no)
			(layer "B.Fab")
		)
		(pad "1" smd custom
			(at 0 -0.4445 270)
			(size 0.1397 0.1397)
			(layers "B.Cu" "B.Mask" "B.Paste")
			(net "P3V3_STBY")
			(options
				(clearance outline)
				(anchor circle)
			)
			(primitives
				(gr_poly
					(pts
						(arc
							(start -0.1778 0.2794)
							(mid -0.249642 0.249642)
							(end -0.2794 0.1778)
						)
						(arc
							(start -0.2794 -0.1778)
							(mid -0.249642 -0.249642)
							(end -0.1778 -0.2794)
						)
						(arc
							(start 0.1778 -0.2794)
							(mid 0.249642 -0.249642)
							(end 0.2794 -0.1778)
						)
						(arc
							(start 0.2794 0.1778)
							(mid 0.249642 0.249642)
							(end 0.1778 0.2794)
						)
					)
					(width 0)
					(fill yes)
				)
			)
		)
		(pad "2" smd custom
			(at 0 0.4445 270)
			(size 0.1397 0.1397)
			(layers "B.Cu" "B.Mask" "B.Paste")
			(net "ROMA18")
			(options
				(clearance outline)
				(anchor circle)
			)
			(primitives
				(gr_poly
					(pts
						(arc
							(start -0.1778 0.2794)
							(mid -0.249642 0.249642)
							(end -0.2794 0.1778)
						)
						(arc
							(start -0.2794 -0.1778)
							(mid -0.249642 -0.249642)
							(end -0.1778 -0.2794)
						)
						(arc
							(start 0.1778 -0.2794)
							(mid 0.249642 -0.249642)
							(end 0.2794 -0.1778)
						)
						(arc
							(start 0.2794 0.1778)
							(mid 0.249642 0.249642)
							(end 0.1778 0.2794)
						)
					)
					(width 0)
					(fill yes)
				)
			)
		)
	)
	(footprint ""
		(layer "B.Cu")
		(at 310.007 -61.595 180)
		(property "Reference" "PG62"
			(at 0 0 0)
			(layer "B.SilkS")
			(hide yes)
			(effects
				(font
					(size 1.27 1.27)
				)
				(justify mirror)
			)
		)
		(property "Value" "GAP-CLOSE-PWR-3-GP"
			(at -0.0254 -6.5786 180)
			(unlocked yes)
			(layer "B.Fab")
			(hide yes)
			(effects
				(font
					(size 1.016 1.016)
					(thickness 0.1524)
				)
				(justify mirror)
			)
		)
		(property "Device Type" "GAP-CLOSE-PWR-3"
			(at -0.0254 -8.255 180)
			(unlocked yes)
			(layer "B.Fab")
			(hide yes)
			(effects
				(font
					(size 1.016 1.016)
					(thickness 0.1524)
				)
				(justify mirror)
			)
		)
		(duplicate_pad_numbers_are_jumpers no)
		(fp_rect
			(start 0.7112 0.4572)
			(end -0.7112 -0.4572)
			(stroke
				(width 0)
				(type default)
			)
			(fill no)
			(layer "B.CrtYd")
		)
		(fp_poly
			(pts
				(xy 0.7112 -0.4572) (xy -0.7112 -0.4572) (xy -0.7112 0.4572) (xy 0.7112 0.4572)
			)
			(stroke
				(width 0)
				(type default)
			)
			(fill no)
			(layer "B.Fab")
		)
		(pad "1" smd rect
			(at 0.3048 0)
			(size 0.6604 0.762)
			(layers "B.Cu" "B.Mask" "B.Paste")
			(net "DUT_VDD")
		)
		(pad "2" smd rect
			(at -0.3048 0)
			(size 0.6604 0.762)
			(layers "B.Cu" "B.Mask" "B.Paste")
			(net "P0V9_E")
		)
	)
	(footprint ""
		(layer "B.Cu")
		(at 271.018 -5.207 90)
		(property "Reference" "R2975"
			(at 0 0 90)
			(layer "B.SilkS")
			(hide yes)
			(effects
				(font
					(size 1.27 1.27)
				)
				(justify mirror)
			)
		)
		(property "Value" "0R2J-2-GP"
			(at -0.064008 -3.993896 90)
			(unlocked yes)
			(layer "B.Fab")
			(hide yes)
			(effects
				(font
					(size 1.016 1.016)
					(thickness 0.1524)
				)
				(justify mirror)
			)
		)
		(property "Device Type" "R402H16"
			(at -0.064008 -5.517896 90)
			(unlocked yes)
			(layer "B.Fab")
			(hide yes)
			(effects
				(font
					(size 1.016 1.016)
					(thickness 0.1524)
				)
				(justify mirror)
			)
		)
		(duplicate_pad_numbers_are_jumpers no)
		(fp_line
			(start 0.508 -0.9398)
			(end 0.508 0.9398)
			(stroke
				(width 0.1524)
				(type default)
			)
			(layer "B.SilkS")
		)
		(fp_line
			(start -0.508 -0.9398)
			(end 0.508 -0.9398)
			(stroke
				(width 0.1524)
				(type default)
			)
			(layer "B.SilkS")
		)
		(fp_rect
			(start 0.508 0.9398)
			(end -0.508 -0.9398)
			(stroke
				(width 0)
				(type default)
			)
			(fill no)
			(layer "B.CrtYd")
		)
		(fp_rect
			(start 0.508 0.9398)
			(end -0.508 -0.9398)
			(stroke
				(width 0)
				(type default)
			)
			(fill no)
			(layer "B.Fab")
		)
		(pad "1" smd custom
			(at 0 -0.4445 270)
			(size 0.1397 0.1397)
			(layers "B.Cu" "B.Mask" "B.Paste")
			(net "PCIE_REFCLK_H1_N")
			(options
				(clearance outline)
				(anchor circle)
			)
			(primitives
				(gr_poly
					(pts
						(arc
							(start -0.1778 0.2794)
							(mid -0.249642 0.249642)
							(end -0.2794 0.1778)
						)
						(arc
							(start -0.2794 -0.1778)
							(mid -0.249642 -0.249642)
							(end -0.1778 -0.2794)
						)
						(arc
							(start 0.1778 -0.2794)
							(mid 0.249642 -0.249642)
							(end 0.2794 -0.1778)
						)
						(arc
							(start 0.2794 0.1778)
							(mid 0.249642 0.249642)
							(end 0.1778 0.2794)
						)
					)
					(width 0)
					(fill yes)
				)
			)
		)
		(pad "2" smd custom
			(at 0 0.4445 270)
			(size 0.1397 0.1397)
			(layers "B.Cu" "B.Mask" "B.Paste")
			(net "PCIE_REFCLK_H1_N_R")
			(options
				(clearance outline)
				(anchor circle)
			)
			(primitives
				(gr_poly
					(pts
						(arc
							(start -0.1778 0.2794)
							(mid -0.249642 0.249642)
							(end -0.2794 0.1778)
						)
						(arc
							(start -0.2794 -0.1778)
							(mid -0.249642 -0.249642)
							(end -0.1778 -0.2794)
						)
						(arc
							(start 0.1778 -0.2794)
							(mid 0.249642 -0.249642)
							(end 0.2794 -0.1778)
						)
						(arc
							(start 0.2794 0.1778)
							(mid 0.249642 0.249642)
							(end 0.1778 0.2794)
						)
					)
					(width 0)
					(fill yes)
				)
			)
		)
	)
	(footprint ""
		(layer "B.Cu")
		(at 249.5804 -44.9961 90)
		(property "Reference" "C596"
			(at 0 0 90)
			(layer "B.SilkS")
			(hide yes)
			(effects
				(font
					(size 1.27 1.27)
				)
				(justify mirror)
			)
		)
		(property "Value" "SCD1U16V1KX-1-GP"
			(at 2.8321 -1.7399 90)
			(unlocked yes)
			(layer "B.Fab")
			(hide yes)
			(effects
				(font
					(size 1.016 1.016)
					(thickness 0.1524)
				)
				(justify mirror)
			)
		)
		(property "Device Type" "C0201H13"
			(at 2.8321 -3.2639 90)
			(unlocked yes)
			(layer "B.Fab")
			(hide yes)
			(effects
				(font
					(size 1.016 1.016)
					(thickness 0.1524)
				)
				(justify mirror)
			)
		)
		(duplicate_pad_numbers_are_jumpers no)
		(fp_rect
			(start 0.2794 0.6477)
			(end -0.2794 -0.6477)
			(stroke
				(width 0)
				(type default)
			)
			(fill no)
			(layer "B.CrtYd")
		)
		(fp_rect
			(start 0.2794 0.6477)
			(end -0.2794 -0.6477)
			(stroke
				(width 0)
				(type default)
			)
			(fill no)
			(layer "B.Fab")
		)
		(pad "1" smd custom
			(at 0 -0.2794 270)
			(size 0.0762 0.0762)
			(layers "B.Cu" "B.Mask" "B.Paste")
			(net "DUT_AVD_PCIE")
			(options
				(clearance outline)
				(anchor circle)
			)
			(primitives
				(gr_poly
					(pts
						(arc
							(start 0.1524 0.127)
							(mid 0.137521 0.162921)
							(end 0.1016 0.1778)
						)
						(arc
							(start -0.1016 0.1778)
							(mid -0.137521 0.162921)
							(end -0.1524 0.127)
						)
						(arc
							(start -0.1524 -0.127)
							(mid -0.137521 -0.162921)
							(end -0.1016 -0.1778)
						)
						(arc
							(start 0.1016 -0.1778)
							(mid 0.137521 -0.162921)
							(end 0.1524 -0.127)
						)
					)
					(width 0)
					(fill yes)
				)
			)
		)
		(pad "2" smd custom
			(at 0 0.2794 270)
			(size 0.0762 0.0762)
			(layers "B.Cu" "B.Mask" "B.Paste")
			(net "GND")
			(options
				(clearance outline)
				(anchor circle)
			)
			(primitives
				(gr_poly
					(pts
						(arc
							(start 0.1524 0.127)
							(mid 0.137521 0.162921)
							(end 0.1016 0.1778)
						)
						(arc
							(start -0.1016 0.1778)
							(mid -0.137521 0.162921)
							(end -0.1524 0.127)
						)
						(arc
							(start -0.1524 -0.127)
							(mid -0.137521 -0.162921)
							(end -0.1016 -0.1778)
						)
						(arc
							(start 0.1016 -0.1778)
							(mid 0.137521 -0.162921)
							(end 0.1524 -0.127)
						)
					)
					(width 0)
					(fill yes)
				)
			)
		)
	)
	(footprint ""
		(layer "B.Cu")
		(at 125.095 -205.74)
		(property "Reference" "R3222"
			(at 0 0 0)
			(layer "B.SilkS")
			(hide yes)
			(effects
				(font
					(size 1.27 1.27)
				)
				(justify mirror)
			)
		)
		(property "Value" "0R2J-2-GP"
			(at -0.064008 -3.993896 0)
			(unlocked yes)
			(layer "B.Fab")
			(hide yes)
			(effects
				(font
					(size 1.016 1.016)
					(thickness 0.1524)
				)
				(justify mirror)
			)
		)
		(property "Device Type" "R402H16"
			(at -0.064008 -5.517896 0)
			(unlocked yes)
			(layer "B.Fab")
			(hide yes)
			(effects
				(font
					(size 1.016 1.016)
					(thickness 0.1524)
				)
				(justify mirror)
			)
		)
		(duplicate_pad_numbers_are_jumpers no)
		(fp_line
			(start -0.508 -0.9398)
			(end 0.508 -0.9398)
			(stroke
				(width 0.1524)
				(type default)
			)
			(layer "B.SilkS")
		)
		(fp_line
			(start 0.508 -0.9398)
			(end 0.508 0.9398)
			(stroke
				(width 0.1524)
				(type default)
			)
			(layer "B.SilkS")
		)
		(fp_rect
			(start 0.508 0.9398)
			(end -0.508 -0.9398)
			(stroke
				(width 0)
				(type default)
			)
			(fill no)
			(layer "B.CrtYd")
		)
		(fp_rect
			(start 0.508 0.9398)
			(end -0.508 -0.9398)
			(stroke
				(width 0)
				(type default)
			)
			(fill no)
			(layer "B.Fab")
		)
		(pad "1" smd custom
			(at 0 -0.4445 180)
			(size 0.1397 0.1397)
			(layers "B.Cu" "B.Mask" "B.Paste")
			(net "SSD_PERST#7")
			(options
				(clearance outline)
				(anchor circle)
			)
			(primitives
				(gr_poly
					(pts
						(arc
							(start -0.1778 0.2794)
							(mid -0.249642 0.249642)
							(end -0.2794 0.1778)
						)
						(arc
							(start -0.2794 -0.1778)
							(mid -0.249642 -0.249642)
							(end -0.1778 -0.2794)
						)
						(arc
							(start 0.1778 -0.2794)
							(mid 0.249642 -0.249642)
							(end 0.2794 -0.1778)
						)
						(arc
							(start 0.2794 0.1778)
							(mid 0.249642 0.249642)
							(end 0.1778 0.2794)
						)
					)
					(width 0)
					(fill yes)
				)
			)
		)
		(pad "2" smd custom
			(at 0 0.4445 180)
			(size 0.1397 0.1397)
			(layers "B.Cu" "B.Mask" "B.Paste")
			(net "SSD_PERST#0_B7")
			(options
				(clearance outline)
				(anchor circle)
			)
			(primitives
				(gr_poly
					(pts
						(arc
							(start -0.1778 0.2794)
							(mid -0.249642 0.249642)
							(end -0.2794 0.1778)
						)
						(arc
							(start -0.2794 -0.1778)
							(mid -0.249642 -0.249642)
							(end -0.1778 -0.2794)
						)
						(arc
							(start 0.1778 -0.2794)
							(mid 0.249642 -0.249642)
							(end 0.2794 -0.1778)
						)
						(arc
							(start 0.2794 0.1778)
							(mid 0.249642 0.249642)
							(end 0.1778 0.2794)
						)
					)
					(width 0)
					(fill yes)
				)
			)
		)
	)
	(footprint ""
		(layer "B.Cu")
		(at 148.428202 -56.542432)
		(property "Reference" "PR173"
			(at 0 0 0)
			(layer "B.SilkS")
			(hide yes)
			(effects
				(font
					(size 1.27 1.27)
				)
				(justify mirror)
			)
		)
		(property "Value" "100KR2F-L1-GP"
			(at -0.064008 -3.993896 0)
			(unlocked yes)
			(layer "B.Fab")
			(hide yes)
			(effects
				(font
					(size 1.016 1.016)
					(thickness 0.1524)
				)
				(justify mirror)
			)
		)
		(property "Device Type" "R402H16"
			(at -0.064008 -5.517896 0)
			(unlocked yes)
			(layer "B.Fab")
			(hide yes)
			(effects
				(font
					(size 1.016 1.016)
					(thickness 0.1524)
				)
				(justify mirror)
			)
		)
		(duplicate_pad_numbers_are_jumpers no)
		(fp_line
			(start -0.508 -0.9398)
			(end 0.508 -0.9398)
			(stroke
				(width 0.1524)
				(type default)
			)
			(layer "B.SilkS")
		)
		(fp_line
			(start 0.508 -0.9398)
			(end 0.508 0.9398)
			(stroke
				(width 0.1524)
				(type default)
			)
			(layer "B.SilkS")
		)
		(fp_rect
			(start 0.508 0.9398)
			(end -0.508 -0.9398)
			(stroke
				(width 0)
				(type default)
			)
			(fill no)
			(layer "B.CrtYd")
		)
		(fp_rect
			(start 0.508 0.9398)
			(end -0.508 -0.9398)
			(stroke
				(width 0)
				(type default)
			)
			(fill no)
			(layer "B.Fab")
		)
		(pad "1" smd custom
			(at 0 -0.4445 180)
			(size 0.1397 0.1397)
			(layers "B.Cu" "B.Mask" "B.Paste")
			(net "P0V9_MODE")
			(options
				(clearance outline)
				(anchor circle)
			)
			(primitives
				(gr_poly
					(pts
						(arc
							(start -0.1778 0.2794)
							(mid -0.249642 0.249642)
							(end -0.2794 0.1778)
						)
						(arc
							(start -0.2794 -0.1778)
							(mid -0.249642 -0.249642)
							(end -0.1778 -0.2794)
						)
						(arc
							(start 0.1778 -0.2794)
							(mid 0.249642 -0.249642)
							(end 0.2794 -0.1778)
						)
						(arc
							(start 0.2794 0.1778)
							(mid 0.249642 0.249642)
							(end 0.1778 0.2794)
						)
					)
					(width 0)
					(fill yes)
				)
			)
		)
		(pad "2" smd custom
			(at 0 0.4445 180)
			(size 0.1397 0.1397)
			(layers "B.Cu" "B.Mask" "B.Paste")
			(net "AGND_P0V9")
			(options
				(clearance outline)
				(anchor circle)
			)
			(primitives
				(gr_poly
					(pts
						(arc
							(start -0.1778 0.2794)
							(mid -0.249642 0.249642)
							(end -0.2794 0.1778)
						)
						(arc
							(start -0.2794 -0.1778)
							(mid -0.249642 -0.249642)
							(end -0.1778 -0.2794)
						)
						(arc
							(start 0.1778 -0.2794)
							(mid 0.249642 -0.249642)
							(end 0.2794 -0.1778)
						)
						(arc
							(start 0.2794 0.1778)
							(mid 0.249642 0.249642)
							(end 0.1778 0.2794)
						)
					)
					(width 0)
					(fill yes)
				)
			)
		)
	)
	(footprint ""
		(layer "B.Cu")
		(at 235.1024 -48.9966 90)
		(property "Reference" "C36"
			(at 0 0 90)
			(layer "B.SilkS")
			(hide yes)
			(effects
				(font
					(size 1.27 1.27)
				)
				(justify mirror)
			)
		)
		(property "Value" "SCD1U16V1KX-1-GP"
			(at 2.8321 -1.7399 90)
			(unlocked yes)
			(layer "B.Fab")
			(hide yes)
			(effects
				(font
					(size 1.016 1.016)
					(thickness 0.1524)
				)
				(justify mirror)
			)
		)
		(property "Device Type" "C0201H13"
			(at 2.8321 -3.2639 90)
			(unlocked yes)
			(layer "B.Fab")
			(hide yes)
			(effects
				(font
					(size 1.016 1.016)
					(thickness 0.1524)
				)
				(justify mirror)
			)
		)
		(duplicate_pad_numbers_are_jumpers no)
		(fp_rect
			(start 0.2794 0.6477)
			(end -0.2794 -0.6477)
			(stroke
				(width 0)
				(type default)
			)
			(fill no)
			(layer "B.CrtYd")
		)
		(fp_rect
			(start 0.2794 0.6477)
			(end -0.2794 -0.6477)
			(stroke
				(width 0)
				(type default)
			)
			(fill no)
			(layer "B.Fab")
		)
		(pad "1" smd custom
			(at 0 -0.2794 270)
			(size 0.0762 0.0762)
			(layers "B.Cu" "B.Mask" "B.Paste")
			(net "DUT_VDD")
			(options
				(clearance outline)
				(anchor circle)
			)
			(primitives
				(gr_poly
					(pts
						(arc
							(start 0.1524 0.127)
							(mid 0.137521 0.162921)
							(end 0.1016 0.1778)
						)
						(arc
							(start -0.1016 0.1778)
							(mid -0.137521 0.162921)
							(end -0.1524 0.127)
						)
						(arc
							(start -0.1524 -0.127)
							(mid -0.137521 -0.162921)
							(end -0.1016 -0.1778)
						)
						(arc
							(start 0.1016 -0.1778)
							(mid 0.137521 -0.162921)
							(end 0.1524 -0.127)
						)
					)
					(width 0)
					(fill yes)
				)
			)
		)
		(pad "2" smd custom
			(at 0 0.2794 270)
			(size 0.0762 0.0762)
			(layers "B.Cu" "B.Mask" "B.Paste")
			(net "GND")
			(options
				(clearance outline)
				(anchor circle)
			)
			(primitives
				(gr_poly
					(pts
						(arc
							(start 0.1524 0.127)
							(mid 0.137521 0.162921)
							(end 0.1016 0.1778)
						)
						(arc
							(start -0.1016 0.1778)
							(mid -0.137521 0.162921)
							(end -0.1524 0.127)
						)
						(arc
							(start -0.1524 -0.127)
							(mid -0.137521 -0.162921)
							(end -0.1016 -0.1778)
						)
						(arc
							(start 0.1016 -0.1778)
							(mid 0.137521 -0.162921)
							(end 0.1524 -0.127)
						)
					)
					(width 0)
					(fill yes)
				)
			)
		)
	)
	(footprint ""
		(layer "B.Cu")
		(at 53.7845 -125.918976 -90)
		(property "Reference" "R335"
			(at 0 0 90)
			(layer "B.SilkS")
			(hide yes)
			(effects
				(font
					(size 1.27 1.27)
				)
				(justify mirror)
			)
		)
		(property "Value" "10KR2F-2-GP"
			(at -0.064008 -3.993896 270)
			(unlocked yes)
			(layer "B.Fab")
			(hide yes)
			(effects
				(font
					(size 1.016 1.016)
					(thickness 0.1524)
				)
				(justify mirror)
			)
		)
		(property "Device Type" "R402H16"
			(at -0.064008 -5.517896 270)
			(unlocked yes)
			(layer "B.Fab")
			(hide yes)
			(effects
				(font
					(size 1.016 1.016)
					(thickness 0.1524)
				)
				(justify mirror)
			)
		)
		(duplicate_pad_numbers_are_jumpers no)
		(fp_line
			(start -0.508 -0.9398)
			(end 0.508 -0.9398)
			(stroke
				(width 0.1524)
				(type default)
			)
			(layer "B.SilkS")
		)
		(fp_line
			(start 0.508 -0.9398)
			(end 0.508 0.9398)
			(stroke
				(width 0.1524)
				(type default)
			)
			(layer "B.SilkS")
		)
		(fp_rect
			(start 0.508 0.9398)
			(end -0.508 -0.9398)
			(stroke
				(width 0)
				(type default)
			)
			(fill no)
			(layer "B.CrtYd")
		)
		(fp_rect
			(start 0.508 0.9398)
			(end -0.508 -0.9398)
			(stroke
				(width 0)
				(type default)
			)
			(fill no)
			(layer "B.Fab")
		)
		(pad "1" smd custom
			(at 0 -0.4445 90)
			(size 0.1397 0.1397)
			(layers "B.Cu" "B.Mask" "B.Paste")
			(net "GND")
			(options
				(clearance outline)
				(anchor circle)
			)
			(primitives
				(gr_poly
					(pts
						(arc
							(start -0.1778 0.2794)
							(mid -0.249642 0.249642)
							(end -0.2794 0.1778)
						)
						(arc
							(start -0.2794 -0.1778)
							(mid -0.249642 -0.249642)
							(end -0.1778 -0.2794)
						)
						(arc
							(start 0.1778 -0.2794)
							(mid 0.249642 -0.249642)
							(end 0.2794 -0.1778)
						)
						(arc
							(start 0.2794 0.1778)
							(mid 0.249642 0.249642)
							(end 0.1778 0.2794)
						)
					)
					(width 0)
					(fill yes)
				)
			)
		)
		(pad "2" smd custom
			(at 0 0.4445 90)
			(size 0.1397 0.1397)
			(layers "B.Cu" "B.Mask" "B.Paste")
			(net "BMC0_JTAG_RTCK")
			(options
				(clearance outline)
				(anchor circle)
			)
			(primitives
				(gr_poly
					(pts
						(arc
							(start -0.1778 0.2794)
							(mid -0.249642 0.249642)
							(end -0.2794 0.1778)
						)
						(arc
							(start -0.2794 -0.1778)
							(mid -0.249642 -0.249642)
							(end -0.1778 -0.2794)
						)
						(arc
							(start 0.1778 -0.2794)
							(mid 0.249642 -0.249642)
							(end 0.2794 -0.1778)
						)
						(arc
							(start 0.2794 0.1778)
							(mid 0.249642 0.249642)
							(end 0.1778 0.2794)
						)
					)
					(width 0)
					(fill yes)
				)
			)
		)
	)
	(footprint ""
		(layer "B.Cu")
		(at 237.617 -59.0042 90)
		(property "Reference" "C529"
			(at 0 0 90)
			(layer "B.SilkS")
			(hide yes)
			(effects
				(font
					(size 1.27 1.27)
				)
				(justify mirror)
			)
		)
		(property "Value" "SCD1U16V1KX-1-GP"
			(at 2.8321 -1.7399 90)
			(unlocked yes)
			(layer "B.Fab")
			(hide yes)
			(effects
				(font
					(size 1.016 1.016)
					(thickness 0.1524)
				)
				(justify mirror)
			)
		)
		(property "Device Type" "C0201H13"
			(at 2.8321 -3.2639 90)
			(unlocked yes)
			(layer "B.Fab")
			(hide yes)
			(effects
				(font
					(size 1.016 1.016)
					(thickness 0.1524)
				)
				(justify mirror)
			)
		)
		(duplicate_pad_numbers_are_jumpers no)
		(fp_rect
			(start 0.2794 0.6477)
			(end -0.2794 -0.6477)
			(stroke
				(width 0)
				(type default)
			)
			(fill no)
			(layer "B.CrtYd")
		)
		(fp_rect
			(start 0.2794 0.6477)
			(end -0.2794 -0.6477)
			(stroke
				(width 0)
				(type default)
			)
			(fill no)
			(layer "B.Fab")
		)
		(pad "1" smd custom
			(at 0 -0.2794 270)
			(size 0.0762 0.0762)
			(layers "B.Cu" "B.Mask" "B.Paste")
			(net "DUT_AVD_TX")
			(options
				(clearance outline)
				(anchor circle)
			)
			(primitives
				(gr_poly
					(pts
						(arc
							(start 0.1524 0.127)
							(mid 0.137521 0.162921)
							(end 0.1016 0.1778)
						)
						(arc
							(start -0.1016 0.1778)
							(mid -0.137521 0.162921)
							(end -0.1524 0.127)
						)
						(arc
							(start -0.1524 -0.127)
							(mid -0.137521 -0.162921)
							(end -0.1016 -0.1778)
						)
						(arc
							(start 0.1016 -0.1778)
							(mid 0.137521 -0.162921)
							(end 0.1524 -0.127)
						)
					)
					(width 0)
					(fill yes)
				)
			)
		)
		(pad "2" smd custom
			(at 0 0.2794 270)
			(size 0.0762 0.0762)
			(layers "B.Cu" "B.Mask" "B.Paste")
			(net "GND")
			(options
				(clearance outline)
				(anchor circle)
			)
			(primitives
				(gr_poly
					(pts
						(arc
							(start 0.1524 0.127)
							(mid 0.137521 0.162921)
							(end 0.1016 0.1778)
						)
						(arc
							(start -0.1016 0.1778)
							(mid -0.137521 0.162921)
							(end -0.1524 0.127)
						)
						(arc
							(start -0.1524 -0.127)
							(mid -0.137521 -0.162921)
							(end -0.1016 -0.1778)
						)
						(arc
							(start 0.1016 -0.1778)
							(mid 0.137521 -0.162921)
							(end 0.1524 -0.127)
						)
					)
					(width 0)
					(fill yes)
				)
			)
		)
	)
	(footprint ""
		(layer "B.Cu")
		(at 175.961802 -71.071232 90)
		(property "Reference" "PG34"
			(at 0 0 90)
			(layer "B.SilkS")
			(hide yes)
			(effects
				(font
					(size 1.27 1.27)
				)
				(justify mirror)
			)
		)
		(property "Value" "GAP-CLOSE-PWR-3-GP"
			(at -0.0254 -6.5786 90)
			(unlocked yes)
			(layer "B.Fab")
			(hide yes)
			(effects
				(font
					(size 1.016 1.016)
					(thickness 0.1524)
				)
				(justify mirror)
			)
		)
		(property "Device Type" "GAP-CLOSE-PWR-3"
			(at -0.0254 -8.255 90)
			(unlocked yes)
			(layer "B.Fab")
			(hide yes)
			(effects
				(font
					(size 1.016 1.016)
					(thickness 0.1524)
				)
				(justify mirror)
			)
		)
		(duplicate_pad_numbers_are_jumpers no)
		(fp_rect
			(start 0.7112 0.4572)
			(end -0.7112 -0.4572)
			(stroke
				(width 0)
				(type default)
			)
			(fill no)
			(layer "B.CrtYd")
		)
		(fp_poly
			(pts
				(xy 0.7112 -0.4572) (xy -0.7112 -0.4572) (xy -0.7112 0.4572) (xy 0.7112 0.4572)
			)
			(stroke
				(width 0)
				(type default)
			)
			(fill no)
			(layer "B.Fab")
		)
		(pad "1" smd rect
			(at 0.3048 0 270)
			(size 0.6604 0.762)
			(layers "B.Cu" "B.Mask" "B.Paste")
			(net "DUT_AVD_TX")
		)
		(pad "2" smd rect
			(at -0.3048 0 270)
			(size 0.6604 0.762)
			(layers "B.Cu" "B.Mask" "B.Paste")
			(net "P0V9")
		)
	)
	(footprint ""
		(layer "B.Cu")
		(at 315.140086 -37.732462 180)
		(property "Reference" "C231"
			(at 0 0 0)
			(layer "B.SilkS")
			(hide yes)
			(effects
				(font
					(size 1.27 1.27)
				)
				(justify mirror)
			)
		)
		(property "Value" "SCD1U10V2KX-5GP"
			(at -1.1811 -2.7051 180)
			(unlocked yes)
			(layer "B.Fab")
			(hide yes)
			(effects
				(font
					(size 1.016 1.016)
					(thickness 0.1524)
				)
				(justify mirror)
			)
		)
		(property "Device Type" "C402H22"
			(at -1.1811 -4.2291 180)
			(unlocked yes)
			(layer "B.Fab")
			(hide yes)
			(effects
				(font
					(size 1.016 1.016)
					(thickness 0.1524)
				)
				(justify mirror)
			)
		)
		(duplicate_pad_numbers_are_jumpers no)
		(fp_rect
			(start 0.4318 0.9525)
			(end -0.4318 -0.9525)
			(stroke
				(width 0)
				(type default)
			)
			(fill no)
			(layer "B.CrtYd")
		)
		(fp_rect
			(start 0.4318 0.9525)
			(end -0.4318 -0.9525)
			(stroke
				(width 0)
				(type default)
			)
			(fill no)
			(layer "B.Fab")
		)
		(pad "1" smd custom
			(at 0 -0.4445)
			(size 0.1524 0.1524)
			(layers "B.Cu" "B.Mask" "B.Paste")
			(net "GND")
			(options
				(clearance outline)
				(anchor circle)
			)
			(primitives
				(gr_poly
					(pts
						(arc
							(start 0.3048 0.2032)
							(mid 0.275042 0.275042)
							(end 0.2032 0.3048)
						)
						(arc
							(start -0.2032 0.3048)
							(mid -0.275042 0.275042)
							(end -0.3048 0.2032)
						)
						(arc
							(start -0.3048 -0.2032)
							(mid -0.275042 -0.275042)
							(end -0.2032 -0.3048)
						)
						(arc
							(start 0.2032 -0.3048)
							(mid 0.275042 -0.275042)
							(end 0.3048 -0.2032)
						)
					)
					(width 0)
					(fill yes)
				)
			)
		)
		(pad "2" smd custom
			(at 0 0.4445)
			(size 0.1524 0.1524)
			(layers "B.Cu" "B.Mask" "B.Paste")
			(net "P3V3_STBY")
			(options
				(clearance outline)
				(anchor circle)
			)
			(primitives
				(gr_poly
					(pts
						(arc
							(start 0.3048 0.2032)
							(mid 0.275042 0.275042)
							(end 0.2032 0.3048)
						)
						(arc
							(start -0.2032 0.3048)
							(mid -0.275042 0.275042)
							(end -0.3048 0.2032)
						)
						(arc
							(start -0.3048 -0.2032)
							(mid -0.275042 -0.275042)
							(end -0.2032 -0.3048)
						)
						(arc
							(start 0.2032 -0.3048)
							(mid 0.275042 -0.275042)
							(end 0.3048 -0.2032)
						)
					)
					(width 0)
					(fill yes)
				)
			)
		)
	)
	(footprint ""
		(layer "B.Cu")
		(at 147.920202 -59.336432)
		(property "Reference" "PC212"
			(at 0 0 0)
			(layer "B.SilkS")
			(hide yes)
			(effects
				(font
					(size 1.27 1.27)
				)
				(justify mirror)
			)
		)
		(property "Value" "SC4D7U25V5KX-1-GP"
			(at 0.0762 -6.1214 0)
			(unlocked yes)
			(layer "B.Fab")
			(hide yes)
			(effects
				(font
					(size 1.016 1.016)
					(thickness 0.1524)
				)
				(justify mirror)
			)
		)
		(property "Device Type" "C805H58"
			(at 0.0762 -8.1534 0)
			(unlocked yes)
			(layer "B.Fab")
			(hide yes)
			(effects
				(font
					(size 1.016 1.016)
					(thickness 0.1524)
				)
				(justify mirror)
			)
		)
		(duplicate_pad_numbers_are_jumpers no)
		(fp_line
			(start -0.635 0)
			(end 0.635 0)
			(stroke
				(width 0.508)
				(type default)
			)
			(layer "B.SilkS")
		)
		(fp_rect
			(start 0.9652 1.778)
			(end -0.9652 -1.778)
			(stroke
				(width 0)
				(type default)
			)
			(fill no)
			(layer "B.CrtYd")
		)
		(fp_poly
			(pts
				(xy 0.9652 -1.778) (xy -0.9652 -1.778) (xy -0.9652 1.778) (xy 0.9652 1.778)
			)
			(stroke
				(width 0)
				(type default)
			)
			(fill no)
			(layer "B.Fab")
		)
		(pad "1" smd rect
			(at 0 -0.9652 180)
			(size 1.397 1.143)
			(layers "B.Cu" "B.Mask" "B.Paste")
			(net "P0V9_VDD")
		)
		(pad "2" smd rect
			(at 0 0.9652 180)
			(size 1.397 1.143)
			(layers "B.Cu" "B.Mask" "B.Paste")
			(net "GND")
		)
	)
	(footprint ""
		(layer "B.Cu")
		(at 273.2786 -3.1496 90)
		(property "Reference" "R2914"
			(at 0 0 90)
			(layer "B.SilkS")
			(hide yes)
			(effects
				(font
					(size 1.27 1.27)
				)
				(justify mirror)
			)
		)
		(property "Value" "0R2J-2-GP"
			(at -0.064008 -3.993896 90)
			(unlocked yes)
			(layer "B.Fab")
			(hide yes)
			(effects
				(font
					(size 1.016 1.016)
					(thickness 0.1524)
				)
				(justify mirror)
			)
		)
		(property "Device Type" "R402H16"
			(at -0.064008 -5.517896 90)
			(unlocked yes)
			(layer "B.Fab")
			(hide yes)
			(effects
				(font
					(size 1.016 1.016)
					(thickness 0.1524)
				)
				(justify mirror)
			)
		)
		(duplicate_pad_numbers_are_jumpers no)
		(fp_line
			(start 0.508 -0.9398)
			(end 0.508 0.9398)
			(stroke
				(width 0.1524)
				(type default)
			)
			(layer "B.SilkS")
		)
		(fp_line
			(start -0.508 -0.9398)
			(end 0.508 -0.9398)
			(stroke
				(width 0.1524)
				(type default)
			)
			(layer "B.SilkS")
		)
		(fp_rect
			(start 0.508 0.9398)
			(end -0.508 -0.9398)
			(stroke
				(width 0)
				(type default)
			)
			(fill no)
			(layer "B.CrtYd")
		)
		(fp_rect
			(start 0.508 0.9398)
			(end -0.508 -0.9398)
			(stroke
				(width 0)
				(type default)
			)
			(fill no)
			(layer "B.Fab")
		)
		(pad "1" smd custom
			(at 0 -0.4445 270)
			(size 0.1397 0.1397)
			(layers "B.Cu" "B.Mask" "B.Paste")
			(net "BMC_I2C14_MINI8_SDA")
			(options
				(clearance outline)
				(anchor circle)
			)
			(primitives
				(gr_poly
					(pts
						(arc
							(start -0.1778 0.2794)
							(mid -0.249642 0.249642)
							(end -0.2794 0.1778)
						)
						(arc
							(start -0.2794 -0.1778)
							(mid -0.249642 -0.249642)
							(end -0.1778 -0.2794)
						)
						(arc
							(start 0.1778 -0.2794)
							(mid 0.249642 -0.249642)
							(end 0.2794 -0.1778)
						)
						(arc
							(start 0.2794 0.1778)
							(mid 0.249642 0.249642)
							(end 0.1778 0.2794)
						)
					)
					(width 0)
					(fill yes)
				)
			)
		)
		(pad "2" smd custom
			(at 0 0.4445 270)
			(size 0.1397 0.1397)
			(layers "B.Cu" "B.Mask" "B.Paste")
			(net "8644_CBL_PRSNT_R_8")
			(options
				(clearance outline)
				(anchor circle)
			)
			(primitives
				(gr_poly
					(pts
						(arc
							(start -0.1778 0.2794)
							(mid -0.249642 0.249642)
							(end -0.2794 0.1778)
						)
						(arc
							(start -0.2794 -0.1778)
							(mid -0.249642 -0.249642)
							(end -0.1778 -0.2794)
						)
						(arc
							(start 0.1778 -0.2794)
							(mid 0.249642 -0.249642)
							(end 0.2794 -0.1778)
						)
						(arc
							(start 0.2794 0.1778)
							(mid 0.249642 0.249642)
							(end 0.1778 0.2794)
						)
					)
					(width 0)
					(fill yes)
				)
			)
		)
	)
	(footprint ""
		(layer "B.Cu")
		(at 214.948008 -4.064)
		(property "Reference" "R3710"
			(at 0 0 0)
			(layer "B.SilkS")
			(hide yes)
			(effects
				(font
					(size 1.27 1.27)
				)
				(justify mirror)
			)
		)
		(property "Value" "1KR2F-3-GP"
			(at -0.064008 -3.993896 0)
			(unlocked yes)
			(layer "B.Fab")
			(hide yes)
			(effects
				(font
					(size 1.016 1.016)
					(thickness 0.1524)
				)
				(justify mirror)
			)
		)
		(property "Device Type" "R402H16"
			(at -0.064008 -5.517896 0)
			(unlocked yes)
			(layer "B.Fab")
			(hide yes)
			(effects
				(font
					(size 1.016 1.016)
					(thickness 0.1524)
				)
				(justify mirror)
			)
		)
		(duplicate_pad_numbers_are_jumpers no)
		(fp_line
			(start -0.508 -0.9398)
			(end 0.508 -0.9398)
			(stroke
				(width 0.1524)
				(type default)
			)
			(layer "B.SilkS")
		)
		(fp_line
			(start 0.508 -0.9398)
			(end 0.508 0.9398)
			(stroke
				(width 0.1524)
				(type default)
			)
			(layer "B.SilkS")
		)
		(fp_rect
			(start 0.508 0.9398)
			(end -0.508 -0.9398)
			(stroke
				(width 0)
				(type default)
			)
			(fill no)
			(layer "B.CrtYd")
		)
		(fp_rect
			(start 0.508 0.9398)
			(end -0.508 -0.9398)
			(stroke
				(width 0)
				(type default)
			)
			(fill no)
			(layer "B.Fab")
		)
		(pad "1" smd custom
			(at 0 -0.4445 180)
			(size 0.1397 0.1397)
			(layers "B.Cu" "B.Mask" "B.Paste")
			(net "HOST2_RST_N")
			(options
				(clearance outline)
				(anchor circle)
			)
			(primitives
				(gr_poly
					(pts
						(arc
							(start -0.1778 0.2794)
							(mid -0.249642 0.249642)
							(end -0.2794 0.1778)
						)
						(arc
							(start -0.2794 -0.1778)
							(mid -0.249642 -0.249642)
							(end -0.1778 -0.2794)
						)
						(arc
							(start 0.1778 -0.2794)
							(mid 0.249642 -0.249642)
							(end 0.2794 -0.1778)
						)
						(arc
							(start 0.2794 0.1778)
							(mid 0.249642 0.249642)
							(end 0.1778 0.2794)
						)
					)
					(width 0)
					(fill yes)
				)
			)
		)
		(pad "2" smd custom
			(at 0 0.4445 180)
			(size 0.1397 0.1397)
			(layers "B.Cu" "B.Mask" "B.Paste")
			(net "P3V3_STBY")
			(options
				(clearance outline)
				(anchor circle)
			)
			(primitives
				(gr_poly
					(pts
						(arc
							(start -0.1778 0.2794)
							(mid -0.249642 0.249642)
							(end -0.2794 0.1778)
						)
						(arc
							(start -0.2794 -0.1778)
							(mid -0.249642 -0.249642)
							(end -0.1778 -0.2794)
						)
						(arc
							(start 0.1778 -0.2794)
							(mid 0.249642 -0.249642)
							(end 0.2794 -0.1778)
						)
						(arc
							(start 0.2794 0.1778)
							(mid 0.249642 0.249642)
							(end 0.1778 0.2794)
						)
					)
					(width 0)
					(fill yes)
				)
			)
		)
	)
	(footprint ""
		(layer "B.Cu")
		(at 51.5366 -130.7846 90)
		(property "Reference" "R534"
			(at 0 0 90)
			(layer "B.SilkS")
			(hide yes)
			(effects
				(font
					(size 1.27 1.27)
				)
				(justify mirror)
			)
		)
		(property "Value" "0R2J-2-GP"
			(at -0.064008 -3.993896 90)
			(unlocked yes)
			(layer "B.Fab")
			(hide yes)
			(effects
				(font
					(size 1.016 1.016)
					(thickness 0.1524)
				)
				(justify mirror)
			)
		)
		(property "Device Type" "R402H16"
			(at -0.064008 -5.517896 90)
			(unlocked yes)
			(layer "B.Fab")
			(hide yes)
			(effects
				(font
					(size 1.016 1.016)
					(thickness 0.1524)
				)
				(justify mirror)
			)
		)
		(duplicate_pad_numbers_are_jumpers no)
		(fp_line
			(start 0.508 -0.9398)
			(end 0.508 0.9398)
			(stroke
				(width 0.1524)
				(type default)
			)
			(layer "B.SilkS")
		)
		(fp_line
			(start -0.508 -0.9398)
			(end 0.508 -0.9398)
			(stroke
				(width 0.1524)
				(type default)
			)
			(layer "B.SilkS")
		)
		(fp_rect
			(start 0.508 0.9398)
			(end -0.508 -0.9398)
			(stroke
				(width 0)
				(type default)
			)
			(fill no)
			(layer "B.CrtYd")
		)
		(fp_rect
			(start 0.508 0.9398)
			(end -0.508 -0.9398)
			(stroke
				(width 0)
				(type default)
			)
			(fill no)
			(layer "B.Fab")
		)
		(pad "1" smd custom
			(at 0 -0.4445 270)
			(size 0.1397 0.1397)
			(layers "B.Cu" "B.Mask" "B.Paste")
			(net "BMC_USB1_HDN2")
			(options
				(clearance outline)
				(anchor circle)
			)
			(primitives
				(gr_poly
					(pts
						(arc
							(start -0.1778 0.2794)
							(mid -0.249642 0.249642)
							(end -0.2794 0.1778)
						)
						(arc
							(start -0.2794 -0.1778)
							(mid -0.249642 -0.249642)
							(end -0.1778 -0.2794)
						)
						(arc
							(start 0.1778 -0.2794)
							(mid 0.249642 -0.249642)
							(end 0.2794 -0.1778)
						)
						(arc
							(start 0.2794 0.1778)
							(mid 0.249642 0.249642)
							(end 0.1778 0.2794)
						)
					)
					(width 0)
					(fill yes)
				)
			)
		)
		(pad "2" smd custom
			(at 0 0.4445 270)
			(size 0.1397 0.1397)
			(layers "B.Cu" "B.Mask" "B.Paste")
			(net "USB_P4_DN_BMC")
			(options
				(clearance outline)
				(anchor circle)
			)
			(primitives
				(gr_poly
					(pts
						(arc
							(start -0.1778 0.2794)
							(mid -0.249642 0.249642)
							(end -0.2794 0.1778)
						)
						(arc
							(start -0.2794 -0.1778)
							(mid -0.249642 -0.249642)
							(end -0.1778 -0.2794)
						)
						(arc
							(start 0.1778 -0.2794)
							(mid 0.249642 -0.249642)
							(end 0.2794 -0.1778)
						)
						(arc
							(start 0.2794 0.1778)
							(mid 0.249642 0.249642)
							(end 0.1778 0.2794)
						)
					)
					(width 0)
					(fill yes)
				)
			)
		)
	)
	(footprint ""
		(layer "B.Cu")
		(at 41.656 -131.064 -90)
		(property "Reference" "C214"
			(at 0 0 90)
			(layer "B.SilkS")
			(hide yes)
			(effects
				(font
					(size 1.27 1.27)
				)
				(justify mirror)
			)
		)
		(property "Value" "SC1U10V2KX-4-GP"
			(at -1.1811 -2.7051 270)
			(unlocked yes)
			(layer "B.Fab")
			(hide yes)
			(effects
				(font
					(size 1.016 1.016)
					(thickness 0.1524)
				)
				(justify mirror)
			)
		)
		(property "Device Type" "C402H22"
			(at -1.1811 -4.2291 270)
			(unlocked yes)
			(layer "B.Fab")
			(hide yes)
			(effects
				(font
					(size 1.016 1.016)
					(thickness 0.1524)
				)
				(justify mirror)
			)
		)
		(duplicate_pad_numbers_are_jumpers no)
		(fp_rect
			(start 0.4318 0.9525)
			(end -0.4318 -0.9525)
			(stroke
				(width 0)
				(type default)
			)
			(fill no)
			(layer "B.CrtYd")
		)
		(fp_rect
			(start 0.4318 0.9525)
			(end -0.4318 -0.9525)
			(stroke
				(width 0)
				(type default)
			)
			(fill no)
			(layer "B.Fab")
		)
		(pad "1" smd custom
			(at 0 -0.4445 90)
			(size 0.1524 0.1524)
			(layers "B.Cu" "B.Mask" "B.Paste")
			(net "P3V3_STBY")
			(options
				(clearance outline)
				(anchor circle)
			)
			(primitives
				(gr_poly
					(pts
						(arc
							(start 0.3048 0.2032)
							(mid 0.275042 0.275042)
							(end 0.2032 0.3048)
						)
						(arc
							(start -0.2032 0.3048)
							(mid -0.275042 0.275042)
							(end -0.3048 0.2032)
						)
						(arc
							(start -0.3048 -0.2032)
							(mid -0.275042 -0.275042)
							(end -0.2032 -0.3048)
						)
						(arc
							(start 0.2032 -0.3048)
							(mid 0.275042 -0.275042)
							(end 0.3048 -0.2032)
						)
					)
					(width 0)
					(fill yes)
				)
			)
		)
		(pad "2" smd custom
			(at 0 0.4445 90)
			(size 0.1524 0.1524)
			(layers "B.Cu" "B.Mask" "B.Paste")
			(net "GND")
			(options
				(clearance outline)
				(anchor circle)
			)
			(primitives
				(gr_poly
					(pts
						(arc
							(start 0.3048 0.2032)
							(mid 0.275042 0.275042)
							(end 0.2032 0.3048)
						)
						(arc
							(start -0.2032 0.3048)
							(mid -0.275042 0.275042)
							(end -0.3048 0.2032)
						)
						(arc
							(start -0.3048 -0.2032)
							(mid -0.275042 -0.275042)
							(end -0.2032 -0.3048)
						)
						(arc
							(start 0.2032 -0.3048)
							(mid 0.275042 -0.275042)
							(end 0.3048 -0.2032)
						)
					)
					(width 0)
					(fill yes)
				)
			)
		)
	)
	(footprint ""
		(layer "B.Cu")
		(at 20.955 -136.779 90)
		(property "Reference" "R606"
			(at 0 0 90)
			(layer "B.SilkS")
			(hide yes)
			(effects
				(font
					(size 1.27 1.27)
				)
				(justify mirror)
			)
		)
		(property "Value" "22R2F-1-GP"
			(at -0.064008 -3.993896 90)
			(unlocked yes)
			(layer "B.Fab")
			(hide yes)
			(effects
				(font
					(size 1.016 1.016)
					(thickness 0.1524)
				)
				(justify mirror)
			)
		)
		(property "Device Type" "R402H16"
			(at -0.064008 -5.517896 90)
			(unlocked yes)
			(layer "B.Fab")
			(hide yes)
			(effects
				(font
					(size 1.016 1.016)
					(thickness 0.1524)
				)
				(justify mirror)
			)
		)
		(duplicate_pad_numbers_are_jumpers no)
		(fp_line
			(start 0.508 -0.9398)
			(end 0.508 0.9398)
			(stroke
				(width 0.1524)
				(type default)
			)
			(layer "B.SilkS")
		)
		(fp_line
			(start -0.508 -0.9398)
			(end 0.508 -0.9398)
			(stroke
				(width 0.1524)
				(type default)
			)
			(layer "B.SilkS")
		)
		(fp_rect
			(start 0.508 0.9398)
			(end -0.508 -0.9398)
			(stroke
				(width 0)
				(type default)
			)
			(fill no)
			(layer "B.CrtYd")
		)
		(fp_rect
			(start 0.508 0.9398)
			(end -0.508 -0.9398)
			(stroke
				(width 0)
				(type default)
			)
			(fill no)
			(layer "B.Fab")
		)
		(pad "1" smd custom
			(at 0 -0.4445 270)
			(size 0.1397 0.1397)
			(layers "B.Cu" "B.Mask" "B.Paste")
			(net "ROMD1_R")
			(options
				(clearance outline)
				(anchor circle)
			)
			(primitives
				(gr_poly
					(pts
						(arc
							(start -0.1778 0.2794)
							(mid -0.249642 0.249642)
							(end -0.2794 0.1778)
						)
						(arc
							(start -0.2794 -0.1778)
							(mid -0.249642 -0.249642)
							(end -0.1778 -0.2794)
						)
						(arc
							(start 0.1778 -0.2794)
							(mid 0.249642 -0.249642)
							(end 0.2794 -0.1778)
						)
						(arc
							(start 0.2794 0.1778)
							(mid 0.249642 0.249642)
							(end 0.1778 0.2794)
						)
					)
					(width 0)
					(fill yes)
				)
			)
		)
		(pad "2" smd custom
			(at 0 0.4445 270)
			(size 0.1397 0.1397)
			(layers "B.Cu" "B.Mask" "B.Paste")
			(net "ROMD1")
			(options
				(clearance outline)
				(anchor circle)
			)
			(primitives
				(gr_poly
					(pts
						(arc
							(start -0.1778 0.2794)
							(mid -0.249642 0.249642)
							(end -0.2794 0.1778)
						)
						(arc
							(start -0.2794 -0.1778)
							(mid -0.249642 -0.249642)
							(end -0.1778 -0.2794)
						)
						(arc
							(start 0.1778 -0.2794)
							(mid 0.249642 -0.249642)
							(end 0.2794 -0.1778)
						)
						(arc
							(start 0.2794 0.1778)
							(mid 0.249642 0.249642)
							(end 0.1778 0.2794)
						)
					)
					(width 0)
					(fill yes)
				)
			)
		)
	)
	(footprint ""
		(layer "B.Cu")
		(at 155.454604 -33.592008)
		(property "Reference" "R2931"
			(at 0 0 0)
			(layer "B.SilkS")
			(hide yes)
			(effects
				(font
					(size 1.27 1.27)
				)
				(justify mirror)
			)
		)
		(property "Value" "0R2J-2-GP"
			(at -0.064008 -3.993896 0)
			(unlocked yes)
			(layer "B.Fab")
			(hide yes)
			(effects
				(font
					(size 1.016 1.016)
					(thickness 0.1524)
				)
				(justify mirror)
			)
		)
		(property "Device Type" "R402H16"
			(at -0.064008 -5.517896 0)
			(unlocked yes)
			(layer "B.Fab")
			(hide yes)
			(effects
				(font
					(size 1.016 1.016)
					(thickness 0.1524)
				)
				(justify mirror)
			)
		)
		(duplicate_pad_numbers_are_jumpers no)
		(fp_line
			(start -0.508 -0.9398)
			(end 0.508 -0.9398)
			(stroke
				(width 0.1524)
				(type default)
			)
			(layer "B.SilkS")
		)
		(fp_line
			(start 0.508 -0.9398)
			(end 0.508 0.9398)
			(stroke
				(width 0.1524)
				(type default)
			)
			(layer "B.SilkS")
		)
		(fp_rect
			(start 0.508 0.9398)
			(end -0.508 -0.9398)
			(stroke
				(width 0)
				(type default)
			)
			(fill no)
			(layer "B.CrtYd")
		)
		(fp_rect
			(start 0.508 0.9398)
			(end -0.508 -0.9398)
			(stroke
				(width 0)
				(type default)
			)
			(fill no)
			(layer "B.Fab")
		)
		(pad "1" smd custom
			(at 0 -0.4445 180)
			(size 0.1397 0.1397)
			(layers "B.Cu" "B.Mask" "B.Paste")
			(net "CBL_PRSNT_N_3")
			(options
				(clearance outline)
				(anchor circle)
			)
			(primitives
				(gr_poly
					(pts
						(arc
							(start -0.1778 0.2794)
							(mid -0.249642 0.249642)
							(end -0.2794 0.1778)
						)
						(arc
							(start -0.2794 -0.1778)
							(mid -0.249642 -0.249642)
							(end -0.1778 -0.2794)
						)
						(arc
							(start 0.1778 -0.2794)
							(mid 0.249642 -0.249642)
							(end 0.2794 -0.1778)
						)
						(arc
							(start 0.2794 0.1778)
							(mid 0.249642 0.249642)
							(end 0.1778 0.2794)
						)
					)
					(width 0)
					(fill yes)
				)
			)
		)
		(pad "2" smd custom
			(at 0 0.4445 180)
			(size 0.1397 0.1397)
			(layers "B.Cu" "B.Mask" "B.Paste")
			(net "8644_SDA_R_3")
			(options
				(clearance outline)
				(anchor circle)
			)
			(primitives
				(gr_poly
					(pts
						(arc
							(start -0.1778 0.2794)
							(mid -0.249642 0.249642)
							(end -0.2794 0.1778)
						)
						(arc
							(start -0.2794 -0.1778)
							(mid -0.249642 -0.249642)
							(end -0.1778 -0.2794)
						)
						(arc
							(start 0.1778 -0.2794)
							(mid 0.249642 -0.249642)
							(end 0.2794 -0.1778)
						)
						(arc
							(start 0.2794 0.1778)
							(mid 0.249642 0.249642)
							(end 0.1778 0.2794)
						)
					)
					(width 0)
					(fill yes)
				)
			)
		)
	)
	(footprint ""
		(layer "B.Cu")
		(at 182.9054 -10.1092)
		(property "Reference" "R250"
			(at 0 0 0)
			(layer "B.SilkS")
			(hide yes)
			(effects
				(font
					(size 1.27 1.27)
				)
				(justify mirror)
			)
		)
		(property "Value" "4K7R2F-GP"
			(at -0.064008 -3.993896 0)
			(unlocked yes)
			(layer "B.Fab")
			(hide yes)
			(effects
				(font
					(size 1.016 1.016)
					(thickness 0.1524)
				)
				(justify mirror)
			)
		)
		(property "Device Type" "R402H16"
			(at -0.064008 -5.517896 0)
			(unlocked yes)
			(layer "B.Fab")
			(hide yes)
			(effects
				(font
					(size 1.016 1.016)
					(thickness 0.1524)
				)
				(justify mirror)
			)
		)
		(duplicate_pad_numbers_are_jumpers no)
		(fp_line
			(start -0.508 -0.9398)
			(end 0.508 -0.9398)
			(stroke
				(width 0.1524)
				(type default)
			)
			(layer "B.SilkS")
		)
		(fp_line
			(start 0.508 -0.9398)
			(end 0.508 0.9398)
			(stroke
				(width 0.1524)
				(type default)
			)
			(layer "B.SilkS")
		)
		(fp_rect
			(start 0.508 0.9398)
			(end -0.508 -0.9398)
			(stroke
				(width 0)
				(type default)
			)
			(fill no)
			(layer "B.CrtYd")
		)
		(fp_rect
			(start 0.508 0.9398)
			(end -0.508 -0.9398)
			(stroke
				(width 0)
				(type default)
			)
			(fill no)
			(layer "B.Fab")
		)
		(pad "1" smd custom
			(at 0 -0.4445 180)
			(size 0.1397 0.1397)
			(layers "B.Cu" "B.Mask" "B.Paste")
			(net "P3V3_STBY")
			(options
				(clearance outline)
				(anchor circle)
			)
			(primitives
				(gr_poly
					(pts
						(arc
							(start -0.1778 0.2794)
							(mid -0.249642 0.249642)
							(end -0.2794 0.1778)
						)
						(arc
							(start -0.2794 -0.1778)
							(mid -0.249642 -0.249642)
							(end -0.1778 -0.2794)
						)
						(arc
							(start 0.1778 -0.2794)
							(mid 0.249642 -0.249642)
							(end 0.2794 -0.1778)
						)
						(arc
							(start 0.2794 0.1778)
							(mid 0.249642 0.249642)
							(end 0.1778 0.2794)
						)
					)
					(width 0)
					(fill yes)
				)
			)
		)
		(pad "2" smd custom
			(at 0 0.4445 180)
			(size 0.1397 0.1397)
			(layers "B.Cu" "B.Mask" "B.Paste")
			(net "CLK_P_3_R")
			(options
				(clearance outline)
				(anchor circle)
			)
			(primitives
				(gr_poly
					(pts
						(arc
							(start -0.1778 0.2794)
							(mid -0.249642 0.249642)
							(end -0.2794 0.1778)
						)
						(arc
							(start -0.2794 -0.1778)
							(mid -0.249642 -0.249642)
							(end -0.1778 -0.2794)
						)
						(arc
							(start 0.1778 -0.2794)
							(mid 0.249642 -0.249642)
							(end 0.2794 -0.1778)
						)
						(arc
							(start 0.2794 0.1778)
							(mid 0.249642 0.249642)
							(end 0.1778 0.2794)
						)
					)
					(width 0)
					(fill yes)
				)
			)
		)
	)
	(footprint ""
		(layer "B.Cu")
		(at 75.832716 -183.238902)
		(property "Reference" "R4107"
			(at 0 0 0)
			(layer "B.SilkS")
			(hide yes)
			(effects
				(font
					(size 1.27 1.27)
				)
				(justify mirror)
			)
		)
		(property "Value" "4K7R2F-GP"
			(at -0.064008 -3.993896 0)
			(unlocked yes)
			(layer "B.Fab")
			(hide yes)
			(effects
				(font
					(size 1.016 1.016)
					(thickness 0.1524)
				)
				(justify mirror)
			)
		)
		(property "Device Type" "R402H16"
			(at -0.064008 -5.517896 0)
			(unlocked yes)
			(layer "B.Fab")
			(hide yes)
			(effects
				(font
					(size 1.016 1.016)
					(thickness 0.1524)
				)
				(justify mirror)
			)
		)
		(duplicate_pad_numbers_are_jumpers no)
		(fp_line
			(start -0.508 -0.9398)
			(end 0.508 -0.9398)
			(stroke
				(width 0.1524)
				(type default)
			)
			(layer "B.SilkS")
		)
		(fp_line
			(start 0.508 -0.9398)
			(end 0.508 0.9398)
			(stroke
				(width 0.1524)
				(type default)
			)
			(layer "B.SilkS")
		)
		(fp_rect
			(start 0.508 0.9398)
			(end -0.508 -0.9398)
			(stroke
				(width 0)
				(type default)
			)
			(fill no)
			(layer "B.CrtYd")
		)
		(fp_rect
			(start 0.508 0.9398)
			(end -0.508 -0.9398)
			(stroke
				(width 0)
				(type default)
			)
			(fill no)
			(layer "B.Fab")
		)
		(pad "1" smd custom
			(at 0 -0.4445 180)
			(size 0.1397 0.1397)
			(layers "B.Cu" "B.Mask" "B.Paste")
			(net "SSD_PRSNT#5")
			(options
				(clearance outline)
				(anchor circle)
			)
			(primitives
				(gr_poly
					(pts
						(arc
							(start -0.1778 0.2794)
							(mid -0.249642 0.249642)
							(end -0.2794 0.1778)
						)
						(arc
							(start -0.2794 -0.1778)
							(mid -0.249642 -0.249642)
							(end -0.1778 -0.2794)
						)
						(arc
							(start 0.1778 -0.2794)
							(mid 0.249642 -0.249642)
							(end 0.2794 -0.1778)
						)
						(arc
							(start 0.2794 0.1778)
							(mid 0.249642 0.249642)
							(end 0.1778 0.2794)
						)
					)
					(width 0)
					(fill yes)
				)
			)
		)
		(pad "2" smd custom
			(at 0 0.4445 180)
			(size 0.1397 0.1397)
			(layers "B.Cu" "B.Mask" "B.Paste")
			(net "P3V3_STBY")
			(options
				(clearance outline)
				(anchor circle)
			)
			(primitives
				(gr_poly
					(pts
						(arc
							(start -0.1778 0.2794)
							(mid -0.249642 0.249642)
							(end -0.2794 0.1778)
						)
						(arc
							(start -0.2794 -0.1778)
							(mid -0.249642 -0.249642)
							(end -0.1778 -0.2794)
						)
						(arc
							(start 0.1778 -0.2794)
							(mid 0.249642 -0.249642)
							(end 0.2794 -0.1778)
						)
						(arc
							(start 0.2794 0.1778)
							(mid 0.249642 0.249642)
							(end 0.1778 0.2794)
						)
					)
					(width 0)
					(fill yes)
				)
			)
		)
	)
	(footprint ""
		(layer "B.Cu")
		(at 17.1196 -69.1134 180)
		(property "Reference" "R374"
			(at 0 0 0)
			(layer "B.SilkS")
			(hide yes)
			(effects
				(font
					(size 1.27 1.27)
				)
				(justify mirror)
			)
		)
		(property "Value" "0R3J-0-U-GP"
			(at 0.0254 -2.5146 180)
			(unlocked yes)
			(layer "B.Fab")
			(hide yes)
			(effects
				(font
					(size 1.016 1.016)
					(thickness 0.1524)
				)
				(justify mirror)
			)
		)
		(property "Device Type" "R603H22"
			(at 0.0254 -4.0386 180)
			(unlocked yes)
			(layer "B.Fab")
			(hide yes)
			(effects
				(font
					(size 1.016 1.016)
					(thickness 0.1524)
				)
				(justify mirror)
			)
		)
		(duplicate_pad_numbers_are_jumpers no)
		(fp_line
			(start 0.4826 0)
			(end 0.2032 0)
			(stroke
				(width 0.2032)
				(type default)
			)
			(layer "B.SilkS")
		)
		(fp_line
			(start -0.2032 0)
			(end -0.4826 0)
			(stroke
				(width 0.2032)
				(type default)
			)
			(layer "B.SilkS")
		)
		(fp_rect
			(start 0.5842 1.3335)
			(end -0.5842 -1.3335)
			(stroke
				(width 0)
				(type default)
			)
			(fill no)
			(layer "B.CrtYd")
		)
		(fp_rect
			(start 0.5842 1.3335)
			(end -0.5842 -1.3335)
			(stroke
				(width 0)
				(type default)
			)
			(fill no)
			(layer "B.Fab")
		)
		(pad "1" smd custom
			(at 0 -0.762)
			(size 0.2159 0.2159)
			(layers "B.Cu" "B.Mask" "B.Paste")
			(net "P1V5_I210")
			(options
				(clearance outline)
				(anchor circle)
			)
			(primitives
				(gr_poly
					(pts
						(arc
							(start -0.3302 0.4318)
							(mid -0.402042 0.402042)
							(end -0.4318 0.3302)
						)
						(arc
							(start -0.4318 -0.3302)
							(mid -0.402042 -0.402042)
							(end -0.3302 -0.4318)
						)
						(arc
							(start 0.3302 -0.4318)
							(mid 0.402042 -0.402042)
							(end 0.4318 -0.3302)
						)
						(arc
							(start 0.4318 0.3302)
							(mid 0.402042 0.402042)
							(end 0.3302 0.4318)
						)
					)
					(width 0)
					(fill yes)
				)
			)
		)
		(pad "2" smd custom
			(at 0 0.762)
			(size 0.2159 0.2159)
			(layers "B.Cu" "B.Mask" "B.Paste")
			(net "LAN1_51")
			(options
				(clearance outline)
				(anchor circle)
			)
			(primitives
				(gr_poly
					(pts
						(arc
							(start -0.3302 0.4318)
							(mid -0.402042 0.402042)
							(end -0.4318 0.3302)
						)
						(arc
							(start -0.4318 -0.3302)
							(mid -0.402042 -0.402042)
							(end -0.3302 -0.4318)
						)
						(arc
							(start 0.3302 -0.4318)
							(mid 0.402042 -0.402042)
							(end 0.4318 -0.3302)
						)
						(arc
							(start 0.4318 0.3302)
							(mid 0.402042 0.402042)
							(end 0.3302 0.4318)
						)
					)
					(width 0)
					(fill yes)
				)
			)
		)
	)
	(footprint ""
		(layer "B.Cu")
		(at 42.926 -117.602)
		(property "Reference" "TP97"
			(at 0 0 0)
			(layer "B.SilkS")
			(hide yes)
			(effects
				(font
					(size 1.27 1.27)
				)
				(justify mirror)
			)
		)
		(property "Value" "TPAD28-2-GP"
			(at 0.0127 -1.6637 0)
			(unlocked yes)
			(layer "B.Fab")
			(hide yes)
			(effects
				(font
					(size 1.016 1.016)
					(thickness 0.1524)
				)
				(justify mirror)
			)
		)
		(property "Device Type" "TPAD28"
			(at 0.0127 -3.1877 0)
			(unlocked yes)
			(layer "B.Fab")
			(hide yes)
			(effects
				(font
					(size 1.016 1.016)
					(thickness 0.1524)
				)
				(justify mirror)
			)
		)
		(duplicate_pad_numbers_are_jumpers no)
		(fp_poly
			(pts
				(arc
					(start 0.3556 0)
					(mid -0.3556 0)
					(end 0.3556 0)
				)
			)
			(stroke
				(width 0)
				(type default)
			)
			(fill no)
			(layer "B.CrtYd")
		)
		(fp_poly
			(pts
				(arc
					(start 0.6096 0)
					(mid -0.6096 0)
					(end 0.6096 0)
				)
			)
			(stroke
				(width 0)
				(type default)
			)
			(fill no)
			(layer "B.Fab")
		)
		(pad "1" smd circle
			(at 0 0 180)
			(size 0.7112 0.7112)
			(layers "B.Cu" "B.Mask" "B.Paste")
			(net "TP_GPIOH7")
		)
	)
	(footprint ""
		(layer "B.Cu")
		(at 226.613212 -200.007474)
		(property "Reference" "R3238"
			(at 0 0 0)
			(layer "B.SilkS")
			(hide yes)
			(effects
				(font
					(size 1.27 1.27)
				)
				(justify mirror)
			)
		)
		(property "Value" "0R2J-2-GP"
			(at -0.064008 -3.993896 0)
			(unlocked yes)
			(layer "B.Fab")
			(hide yes)
			(effects
				(font
					(size 1.016 1.016)
					(thickness 0.1524)
				)
				(justify mirror)
			)
		)
		(property "Device Type" "R402H16"
			(at -0.064008 -5.517896 0)
			(unlocked yes)
			(layer "B.Fab")
			(hide yes)
			(effects
				(font
					(size 1.016 1.016)
					(thickness 0.1524)
				)
				(justify mirror)
			)
		)
		(duplicate_pad_numbers_are_jumpers no)
		(fp_line
			(start -0.508 -0.9398)
			(end 0.508 -0.9398)
			(stroke
				(width 0.1524)
				(type default)
			)
			(layer "B.SilkS")
		)
		(fp_line
			(start 0.508 -0.9398)
			(end 0.508 0.9398)
			(stroke
				(width 0.1524)
				(type default)
			)
			(layer "B.SilkS")
		)
		(fp_rect
			(start 0.508 0.9398)
			(end -0.508 -0.9398)
			(stroke
				(width 0)
				(type default)
			)
			(fill no)
			(layer "B.CrtYd")
		)
		(fp_rect
			(start 0.508 0.9398)
			(end -0.508 -0.9398)
			(stroke
				(width 0)
				(type default)
			)
			(fill no)
			(layer "B.Fab")
		)
		(pad "1" smd custom
			(at 0 -0.4445 180)
			(size 0.1397 0.1397)
			(layers "B.Cu" "B.Mask" "B.Paste")
			(net "BMC_SSD_RST#12")
			(options
				(clearance outline)
				(anchor circle)
			)
			(primitives
				(gr_poly
					(pts
						(arc
							(start -0.1778 0.2794)
							(mid -0.249642 0.249642)
							(end -0.2794 0.1778)
						)
						(arc
							(start -0.2794 -0.1778)
							(mid -0.249642 -0.249642)
							(end -0.1778 -0.2794)
						)
						(arc
							(start 0.1778 -0.2794)
							(mid 0.249642 -0.249642)
							(end 0.2794 -0.1778)
						)
						(arc
							(start 0.2794 0.1778)
							(mid 0.249642 0.249642)
							(end 0.1778 0.2794)
						)
					)
					(width 0)
					(fill yes)
				)
			)
		)
		(pad "2" smd custom
			(at 0 0.4445 180)
			(size 0.1397 0.1397)
			(layers "B.Cu" "B.Mask" "B.Paste")
			(net "BMC_SSD_RST#0_A12")
			(options
				(clearance outline)
				(anchor circle)
			)
			(primitives
				(gr_poly
					(pts
						(arc
							(start -0.1778 0.2794)
							(mid -0.249642 0.249642)
							(end -0.2794 0.1778)
						)
						(arc
							(start -0.2794 -0.1778)
							(mid -0.249642 -0.249642)
							(end -0.1778 -0.2794)
						)
						(arc
							(start 0.1778 -0.2794)
							(mid 0.249642 -0.249642)
							(end 0.2794 -0.1778)
						)
						(arc
							(start 0.2794 0.1778)
							(mid 0.249642 0.249642)
							(end 0.1778 0.2794)
						)
					)
					(width 0)
					(fill yes)
				)
			)
		)
	)
	(footprint ""
		(layer "B.Cu")
		(at 181.321202 -9.457944 -90)
		(property "Reference" "R207"
			(at 0 0 90)
			(layer "B.SilkS")
			(hide yes)
			(effects
				(font
					(size 1.27 1.27)
				)
				(justify mirror)
			)
		)
		(property "Value" "4K7R2F-GP"
			(at -0.064008 -3.993896 270)
			(unlocked yes)
			(layer "B.Fab")
			(hide yes)
			(effects
				(font
					(size 1.016 1.016)
					(thickness 0.1524)
				)
				(justify mirror)
			)
		)
		(property "Device Type" "R402H16"
			(at -0.064008 -5.517896 270)
			(unlocked yes)
			(layer "B.Fab")
			(hide yes)
			(effects
				(font
					(size 1.016 1.016)
					(thickness 0.1524)
				)
				(justify mirror)
			)
		)
		(duplicate_pad_numbers_are_jumpers no)
		(fp_line
			(start -0.508 -0.9398)
			(end 0.508 -0.9398)
			(stroke
				(width 0.1524)
				(type default)
			)
			(layer "B.SilkS")
		)
		(fp_line
			(start 0.508 -0.9398)
			(end 0.508 0.9398)
			(stroke
				(width 0.1524)
				(type default)
			)
			(layer "B.SilkS")
		)
		(fp_rect
			(start 0.508 0.9398)
			(end -0.508 -0.9398)
			(stroke
				(width 0)
				(type default)
			)
			(fill no)
			(layer "B.CrtYd")
		)
		(fp_rect
			(start 0.508 0.9398)
			(end -0.508 -0.9398)
			(stroke
				(width 0)
				(type default)
			)
			(fill no)
			(layer "B.Fab")
		)
		(pad "1" smd custom
			(at 0 -0.4445 90)
			(size 0.1397 0.1397)
			(layers "B.Cu" "B.Mask" "B.Paste")
			(net "CLK_P_3_R")
			(options
				(clearance outline)
				(anchor circle)
			)
			(primitives
				(gr_poly
					(pts
						(arc
							(start -0.1778 0.2794)
							(mid -0.249642 0.249642)
							(end -0.2794 0.1778)
						)
						(arc
							(start -0.2794 -0.1778)
							(mid -0.249642 -0.249642)
							(end -0.1778 -0.2794)
						)
						(arc
							(start 0.1778 -0.2794)
							(mid 0.249642 -0.249642)
							(end 0.2794 -0.1778)
						)
						(arc
							(start 0.2794 0.1778)
							(mid 0.249642 0.249642)
							(end 0.1778 0.2794)
						)
					)
					(width 0)
					(fill yes)
				)
			)
		)
		(pad "2" smd custom
			(at 0 0.4445 90)
			(size 0.1397 0.1397)
			(layers "B.Cu" "B.Mask" "B.Paste")
			(net "GND")
			(options
				(clearance outline)
				(anchor circle)
			)
			(primitives
				(gr_poly
					(pts
						(arc
							(start -0.1778 0.2794)
							(mid -0.249642 0.249642)
							(end -0.2794 0.1778)
						)
						(arc
							(start -0.2794 -0.1778)
							(mid -0.249642 -0.249642)
							(end -0.1778 -0.2794)
						)
						(arc
							(start 0.1778 -0.2794)
							(mid 0.249642 -0.249642)
							(end 0.2794 -0.1778)
						)
						(arc
							(start 0.2794 0.1778)
							(mid 0.249642 0.249642)
							(end 0.1778 0.2794)
						)
					)
					(width 0)
					(fill yes)
				)
			)
		)
	)
	(footprint ""
		(layer "B.Cu")
		(at 63.881 -124.46 90)
		(property "Reference" "R251"
			(at 0 0 90)
			(layer "B.SilkS")
			(hide yes)
			(effects
				(font
					(size 1.27 1.27)
				)
				(justify mirror)
			)
		)
		(property "Value" "0R2J-2-GP"
			(at -0.064008 -3.993896 90)
			(unlocked yes)
			(layer "B.Fab")
			(hide yes)
			(effects
				(font
					(size 1.016 1.016)
					(thickness 0.1524)
				)
				(justify mirror)
			)
		)
		(property "Device Type" "R402H16"
			(at -0.064008 -5.517896 90)
			(unlocked yes)
			(layer "B.Fab")
			(hide yes)
			(effects
				(font
					(size 1.016 1.016)
					(thickness 0.1524)
				)
				(justify mirror)
			)
		)
		(duplicate_pad_numbers_are_jumpers no)
		(fp_line
			(start 0.508 -0.9398)
			(end 0.508 0.9398)
			(stroke
				(width 0.1524)
				(type default)
			)
			(layer "B.SilkS")
		)
		(fp_line
			(start -0.508 -0.9398)
			(end 0.508 -0.9398)
			(stroke
				(width 0.1524)
				(type default)
			)
			(layer "B.SilkS")
		)
		(fp_rect
			(start 0.508 0.9398)
			(end -0.508 -0.9398)
			(stroke
				(width 0)
				(type default)
			)
			(fill no)
			(layer "B.CrtYd")
		)
		(fp_rect
			(start 0.508 0.9398)
			(end -0.508 -0.9398)
			(stroke
				(width 0)
				(type default)
			)
			(fill no)
			(layer "B.Fab")
		)
		(pad "1" smd custom
			(at 0 -0.4445 270)
			(size 0.1397 0.1397)
			(layers "B.Cu" "B.Mask" "B.Paste")
			(net "BMC_I2C6_C_FCB_SDA")
			(options
				(clearance outline)
				(anchor circle)
			)
			(primitives
				(gr_poly
					(pts
						(arc
							(start -0.1778 0.2794)
							(mid -0.249642 0.249642)
							(end -0.2794 0.1778)
						)
						(arc
							(start -0.2794 -0.1778)
							(mid -0.249642 -0.249642)
							(end -0.1778 -0.2794)
						)
						(arc
							(start 0.1778 -0.2794)
							(mid 0.249642 -0.249642)
							(end 0.2794 -0.1778)
						)
						(arc
							(start 0.2794 0.1778)
							(mid 0.249642 0.249642)
							(end 0.1778 0.2794)
						)
					)
					(width 0)
					(fill yes)
				)
			)
		)
		(pad "2" smd custom
			(at 0 0.4445 270)
			(size 0.1397 0.1397)
			(layers "B.Cu" "B.Mask" "B.Paste")
			(net "BMC0_SMB6_DAT")
			(options
				(clearance outline)
				(anchor circle)
			)
			(primitives
				(gr_poly
					(pts
						(arc
							(start -0.1778 0.2794)
							(mid -0.249642 0.249642)
							(end -0.2794 0.1778)
						)
						(arc
							(start -0.2794 -0.1778)
							(mid -0.249642 -0.249642)
							(end -0.1778 -0.2794)
						)
						(arc
							(start 0.1778 -0.2794)
							(mid 0.249642 -0.249642)
							(end 0.2794 -0.1778)
						)
						(arc
							(start 0.2794 0.1778)
							(mid 0.249642 0.249642)
							(end 0.1778 0.2794)
						)
					)
					(width 0)
					(fill yes)
				)
			)
		)
	)
	(footprint ""
		(layer "B.Cu")
		(at 320.167 -68.58 180)
		(property "Reference" "PC96"
			(at 0 0 0)
			(layer "B.SilkS")
			(hide yes)
			(effects
				(font
					(size 1.27 1.27)
				)
				(justify mirror)
			)
		)
		(property "Value" "SC4D7U16V5KX-1-GP"
			(at 0.0762 -6.1214 180)
			(unlocked yes)
			(layer "B.Fab")
			(hide yes)
			(effects
				(font
					(size 1.016 1.016)
					(thickness 0.1524)
				)
				(justify mirror)
			)
		)
		(property "Device Type" "C805H56"
			(at 0.0762 -8.1534 180)
			(unlocked yes)
			(layer "B.Fab")
			(hide yes)
			(effects
				(font
					(size 1.016 1.016)
					(thickness 0.1524)
				)
				(justify mirror)
			)
		)
		(duplicate_pad_numbers_are_jumpers no)
		(fp_line
			(start -0.635 0)
			(end 0.635 0)
			(stroke
				(width 0.508)
				(type default)
			)
			(layer "B.SilkS")
		)
		(fp_rect
			(start 0.9652 1.778)
			(end -0.9652 -1.778)
			(stroke
				(width 0)
				(type default)
			)
			(fill no)
			(layer "B.CrtYd")
		)
		(fp_poly
			(pts
				(xy 0.9652 -1.778) (xy -0.9652 -1.778) (xy -0.9652 1.778) (xy 0.9652 1.778)
			)
			(stroke
				(width 0)
				(type default)
			)
			(fill no)
			(layer "B.Fab")
		)
		(pad "1" smd rect
			(at 0 -0.9652)
			(size 1.397 1.143)
			(layers "B.Cu" "B.Mask" "B.Paste")
			(net "P0V9_E")
		)
		(pad "2" smd rect
			(at 0 0.9652)
			(size 1.397 1.143)
			(layers "B.Cu" "B.Mask" "B.Paste")
			(net "GND")
		)
	)
	(footprint ""
		(layer "B.Cu")
		(at 178.0794 -64.643)
		(property "Reference" "PG27"
			(at 0 0 0)
			(layer "B.SilkS")
			(hide yes)
			(effects
				(font
					(size 1.27 1.27)
				)
				(justify mirror)
			)
		)
		(property "Value" "GAP-CLOSE-PWR-3-GP"
			(at -0.0254 -6.5786 0)
			(unlocked yes)
			(layer "B.Fab")
			(hide yes)
			(effects
				(font
					(size 1.016 1.016)
					(thickness 0.1524)
				)
				(justify mirror)
			)
		)
		(property "Device Type" "GAP-CLOSE-PWR-3"
			(at -0.0254 -8.255 0)
			(unlocked yes)
			(layer "B.Fab")
			(hide yes)
			(effects
				(font
					(size 1.016 1.016)
					(thickness 0.1524)
				)
				(justify mirror)
			)
		)
		(duplicate_pad_numbers_are_jumpers no)
		(fp_rect
			(start 0.7112 0.4572)
			(end -0.7112 -0.4572)
			(stroke
				(width 0)
				(type default)
			)
			(fill no)
			(layer "B.CrtYd")
		)
		(fp_poly
			(pts
				(xy 0.7112 -0.4572) (xy -0.7112 -0.4572) (xy -0.7112 0.4572) (xy 0.7112 0.4572)
			)
			(stroke
				(width 0)
				(type default)
			)
			(fill no)
			(layer "B.Fab")
		)
		(pad "1" smd rect
			(at 0.3048 0 180)
			(size 0.6604 0.762)
			(layers "B.Cu" "B.Mask" "B.Paste")
			(net "DUT_AVD_PCIE")
		)
		(pad "2" smd rect
			(at -0.3048 0 180)
			(size 0.6604 0.762)
			(layers "B.Cu" "B.Mask" "B.Paste")
			(net "P0V9")
		)
	)
	(footprint ""
		(layer "B.Cu")
		(at 10.922 -108.204 90)
		(property "Reference" "PC83"
			(at 0 0 90)
			(layer "B.SilkS")
			(hide yes)
			(effects
				(font
					(size 1.27 1.27)
				)
				(justify mirror)
			)
		)
		(property "Value" "SC1KP50V2KX-1GP"
			(at -1.1811 -2.7051 90)
			(unlocked yes)
			(layer "B.Fab")
			(hide yes)
			(effects
				(font
					(size 1.016 1.016)
					(thickness 0.1524)
				)
				(justify mirror)
			)
		)
		(property "Device Type" "C402H22"
			(at -1.1811 -4.2291 90)
			(unlocked yes)
			(layer "B.Fab")
			(hide yes)
			(effects
				(font
					(size 1.016 1.016)
					(thickness 0.1524)
				)
				(justify mirror)
			)
		)
		(duplicate_pad_numbers_are_jumpers no)
		(fp_rect
			(start 0.4318 0.9525)
			(end -0.4318 -0.9525)
			(stroke
				(width 0)
				(type default)
			)
			(fill no)
			(layer "B.CrtYd")
		)
		(fp_rect
			(start 0.4318 0.9525)
			(end -0.4318 -0.9525)
			(stroke
				(width 0)
				(type default)
			)
			(fill no)
			(layer "B.Fab")
		)
		(pad "1" smd custom
			(at 0 -0.4445 270)
			(size 0.1524 0.1524)
			(layers "B.Cu" "B.Mask" "B.Paste")
			(net "PWRGD_P1V26_STBY")
			(options
				(clearance outline)
				(anchor circle)
			)
			(primitives
				(gr_poly
					(pts
						(arc
							(start 0.3048 0.2032)
							(mid 0.275042 0.275042)
							(end 0.2032 0.3048)
						)
						(arc
							(start -0.2032 0.3048)
							(mid -0.275042 0.275042)
							(end -0.3048 0.2032)
						)
						(arc
							(start -0.3048 -0.2032)
							(mid -0.275042 -0.275042)
							(end -0.2032 -0.3048)
						)
						(arc
							(start 0.2032 -0.3048)
							(mid 0.275042 -0.275042)
							(end 0.3048 -0.2032)
						)
					)
					(width 0)
					(fill yes)
				)
			)
		)
		(pad "2" smd custom
			(at 0 0.4445 270)
			(size 0.1524 0.1524)
			(layers "B.Cu" "B.Mask" "B.Paste")
			(net "GND")
			(options
				(clearance outline)
				(anchor circle)
			)
			(primitives
				(gr_poly
					(pts
						(arc
							(start 0.3048 0.2032)
							(mid 0.275042 0.275042)
							(end 0.2032 0.3048)
						)
						(arc
							(start -0.2032 0.3048)
							(mid -0.275042 0.275042)
							(end -0.3048 0.2032)
						)
						(arc
							(start -0.3048 -0.2032)
							(mid -0.275042 -0.275042)
							(end -0.2032 -0.3048)
						)
						(arc
							(start 0.2032 -0.3048)
							(mid 0.275042 -0.275042)
							(end 0.3048 -0.2032)
						)
					)
					(width 0)
					(fill yes)
				)
			)
		)
	)
	(footprint ""
		(layer "B.Cu")
		(at 210.884008 -4.064)
		(property "Reference" "R3712"
			(at 0 0 0)
			(layer "B.SilkS")
			(hide yes)
			(effects
				(font
					(size 1.27 1.27)
				)
				(justify mirror)
			)
		)
		(property "Value" "1KR2F-3-GP"
			(at -0.064008 -3.993896 0)
			(unlocked yes)
			(layer "B.Fab")
			(hide yes)
			(effects
				(font
					(size 1.016 1.016)
					(thickness 0.1524)
				)
				(justify mirror)
			)
		)
		(property "Device Type" "R402H16"
			(at -0.064008 -5.517896 0)
			(unlocked yes)
			(layer "B.Fab")
			(hide yes)
			(effects
				(font
					(size 1.016 1.016)
					(thickness 0.1524)
				)
				(justify mirror)
			)
		)
		(duplicate_pad_numbers_are_jumpers no)
		(fp_line
			(start -0.508 -0.9398)
			(end 0.508 -0.9398)
			(stroke
				(width 0.1524)
				(type default)
			)
			(layer "B.SilkS")
		)
		(fp_line
			(start 0.508 -0.9398)
			(end 0.508 0.9398)
			(stroke
				(width 0.1524)
				(type default)
			)
			(layer "B.SilkS")
		)
		(fp_rect
			(start 0.508 0.9398)
			(end -0.508 -0.9398)
			(stroke
				(width 0)
				(type default)
			)
			(fill no)
			(layer "B.CrtYd")
		)
		(fp_rect
			(start 0.508 0.9398)
			(end -0.508 -0.9398)
			(stroke
				(width 0)
				(type default)
			)
			(fill no)
			(layer "B.Fab")
		)
		(pad "1" smd custom
			(at 0 -0.4445 180)
			(size 0.1397 0.1397)
			(layers "B.Cu" "B.Mask" "B.Paste")
			(net "HOST6_RST_N")
			(options
				(clearance outline)
				(anchor circle)
			)
			(primitives
				(gr_poly
					(pts
						(arc
							(start -0.1778 0.2794)
							(mid -0.249642 0.249642)
							(end -0.2794 0.1778)
						)
						(arc
							(start -0.2794 -0.1778)
							(mid -0.249642 -0.249642)
							(end -0.1778 -0.2794)
						)
						(arc
							(start 0.1778 -0.2794)
							(mid 0.249642 -0.249642)
							(end 0.2794 -0.1778)
						)
						(arc
							(start 0.2794 0.1778)
							(mid 0.249642 0.249642)
							(end 0.1778 0.2794)
						)
					)
					(width 0)
					(fill yes)
				)
			)
		)
		(pad "2" smd custom
			(at 0 0.4445 180)
			(size 0.1397 0.1397)
			(layers "B.Cu" "B.Mask" "B.Paste")
			(net "P3V3_STBY")
			(options
				(clearance outline)
				(anchor circle)
			)
			(primitives
				(gr_poly
					(pts
						(arc
							(start -0.1778 0.2794)
							(mid -0.249642 0.249642)
							(end -0.2794 0.1778)
						)
						(arc
							(start -0.2794 -0.1778)
							(mid -0.249642 -0.249642)
							(end -0.1778 -0.2794)
						)
						(arc
							(start 0.1778 -0.2794)
							(mid 0.249642 -0.249642)
							(end 0.2794 -0.1778)
						)
						(arc
							(start 0.2794 0.1778)
							(mid 0.249642 0.249642)
							(end 0.1778 0.2794)
						)
					)
					(width 0)
					(fill yes)
				)
			)
		)
	)
	(footprint ""
		(layer "B.Cu")
		(at 50.927 -104.14 180)
		(property "Reference" "R331"
			(at 0 0 0)
			(layer "B.SilkS")
			(hide yes)
			(effects
				(font
					(size 1.27 1.27)
				)
				(justify mirror)
			)
		)
		(property "Value" "4K7R2F-GP"
			(at -0.064008 -3.993896 180)
			(unlocked yes)
			(layer "B.Fab")
			(hide yes)
			(effects
				(font
					(size 1.016 1.016)
					(thickness 0.1524)
				)
				(justify mirror)
			)
		)
		(property "Device Type" "R402H16"
			(at -0.064008 -5.517896 180)
			(unlocked yes)
			(layer "B.Fab")
			(hide yes)
			(effects
				(font
					(size 1.016 1.016)
					(thickness 0.1524)
				)
				(justify mirror)
			)
		)
		(duplicate_pad_numbers_are_jumpers no)
		(fp_line
			(start 0.508 -0.9398)
			(end 0.508 0.9398)
			(stroke
				(width 0.1524)
				(type default)
			)
			(layer "B.SilkS")
		)
		(fp_line
			(start -0.508 -0.9398)
			(end 0.508 -0.9398)
			(stroke
				(width 0.1524)
				(type default)
			)
			(layer "B.SilkS")
		)
		(fp_rect
			(start 0.508 0.9398)
			(end -0.508 -0.9398)
			(stroke
				(width 0)
				(type default)
			)
			(fill no)
			(layer "B.CrtYd")
		)
		(fp_rect
			(start 0.508 0.9398)
			(end -0.508 -0.9398)
			(stroke
				(width 0)
				(type default)
			)
			(fill no)
			(layer "B.Fab")
		)
		(pad "1" smd custom
			(at 0 -0.4445)
			(size 0.1397 0.1397)
			(layers "B.Cu" "B.Mask" "B.Paste")
			(net "P3V3_STBY")
			(options
				(clearance outline)
				(anchor circle)
			)
			(primitives
				(gr_poly
					(pts
						(arc
							(start -0.1778 0.2794)
							(mid -0.249642 0.249642)
							(end -0.2794 0.1778)
						)
						(arc
							(start -0.2794 -0.1778)
							(mid -0.249642 -0.249642)
							(end -0.1778 -0.2794)
						)
						(arc
							(start 0.1778 -0.2794)
							(mid 0.249642 -0.249642)
							(end 0.2794 -0.1778)
						)
						(arc
							(start 0.2794 0.1778)
							(mid 0.249642 0.249642)
							(end 0.1778 0.2794)
						)
					)
					(width 0)
					(fill yes)
				)
			)
		)
		(pad "2" smd custom
			(at 0 0.4445)
			(size 0.1397 0.1397)
			(layers "B.Cu" "B.Mask" "B.Paste")
			(net "I2C8_LS_G2")
			(options
				(clearance outline)
				(anchor circle)
			)
			(primitives
				(gr_poly
					(pts
						(arc
							(start -0.1778 0.2794)
							(mid -0.249642 0.249642)
							(end -0.2794 0.1778)
						)
						(arc
							(start -0.2794 -0.1778)
							(mid -0.249642 -0.249642)
							(end -0.1778 -0.2794)
						)
						(arc
							(start 0.1778 -0.2794)
							(mid 0.249642 -0.249642)
							(end 0.2794 -0.1778)
						)
						(arc
							(start 0.2794 0.1778)
							(mid 0.249642 0.249642)
							(end 0.1778 0.2794)
						)
					)
					(width 0)
					(fill yes)
				)
			)
		)
	)
	(footprint ""
		(layer "B.Cu")
		(at 221.8182 -13.3858 90)
		(property "Reference" "C373"
			(at 0 0 90)
			(layer "B.SilkS")
			(hide yes)
			(effects
				(font
					(size 1.27 1.27)
				)
				(justify mirror)
			)
		)
		(property "Value" "SCD1U25V2KX-2-GP"
			(at -1.1811 -2.7051 90)
			(unlocked yes)
			(layer "B.Fab")
			(hide yes)
			(effects
				(font
					(size 1.016 1.016)
					(thickness 0.1524)
				)
				(justify mirror)
			)
		)
		(property "Device Type" "C402H22"
			(at -1.1811 -4.2291 90)
			(unlocked yes)
			(layer "B.Fab")
			(hide yes)
			(effects
				(font
					(size 1.016 1.016)
					(thickness 0.1524)
				)
				(justify mirror)
			)
		)
		(duplicate_pad_numbers_are_jumpers no)
		(fp_rect
			(start 0.4318 0.9525)
			(end -0.4318 -0.9525)
			(stroke
				(width 0)
				(type default)
			)
			(fill no)
			(layer "B.CrtYd")
		)
		(fp_rect
			(start 0.4318 0.9525)
			(end -0.4318 -0.9525)
			(stroke
				(width 0)
				(type default)
			)
			(fill no)
			(layer "B.Fab")
		)
		(pad "1" smd custom
			(at 0 -0.4445 270)
			(size 0.1524 0.1524)
			(layers "B.Cu" "B.Mask" "B.Paste")
			(net "P3V3_STBY")
			(options
				(clearance outline)
				(anchor circle)
			)
			(primitives
				(gr_poly
					(pts
						(arc
							(start 0.3048 0.2032)
							(mid 0.275042 0.275042)
							(end 0.2032 0.3048)
						)
						(arc
							(start -0.2032 0.3048)
							(mid -0.275042 0.275042)
							(end -0.3048 0.2032)
						)
						(arc
							(start -0.3048 -0.2032)
							(mid -0.275042 -0.275042)
							(end -0.2032 -0.3048)
						)
						(arc
							(start 0.2032 -0.3048)
							(mid 0.275042 -0.275042)
							(end 0.3048 -0.2032)
						)
					)
					(width 0)
					(fill yes)
				)
			)
		)
		(pad "2" smd custom
			(at 0 0.4445 270)
			(size 0.1524 0.1524)
			(layers "B.Cu" "B.Mask" "B.Paste")
			(net "GND")
			(options
				(clearance outline)
				(anchor circle)
			)
			(primitives
				(gr_poly
					(pts
						(arc
							(start 0.3048 0.2032)
							(mid 0.275042 0.275042)
							(end 0.2032 0.3048)
						)
						(arc
							(start -0.2032 0.3048)
							(mid -0.275042 0.275042)
							(end -0.3048 0.2032)
						)
						(arc
							(start -0.3048 -0.2032)
							(mid -0.275042 -0.275042)
							(end -0.2032 -0.3048)
						)
						(arc
							(start 0.2032 -0.3048)
							(mid 0.275042 -0.275042)
							(end 0.3048 -0.2032)
						)
					)
					(width 0)
					(fill yes)
				)
			)
		)
	)
	(footprint ""
		(layer "B.Cu")
		(at 337.852512 -172.432218)
		(property "Reference" "R4160"
			(at 0 0 0)
			(layer "B.SilkS")
			(hide yes)
			(effects
				(font
					(size 1.27 1.27)
				)
				(justify mirror)
			)
		)
		(property "Value" "4K7R2F-GP"
			(at -0.064008 -3.993896 0)
			(unlocked yes)
			(layer "B.Fab")
			(hide yes)
			(effects
				(font
					(size 1.016 1.016)
					(thickness 0.1524)
				)
				(justify mirror)
			)
		)
		(property "Device Type" "R402H16"
			(at -0.064008 -5.517896 0)
			(unlocked yes)
			(layer "B.Fab")
			(hide yes)
			(effects
				(font
					(size 1.016 1.016)
					(thickness 0.1524)
				)
				(justify mirror)
			)
		)
		(duplicate_pad_numbers_are_jumpers no)
		(fp_line
			(start -0.508 -0.9398)
			(end 0.508 -0.9398)
			(stroke
				(width 0.1524)
				(type default)
			)
			(layer "B.SilkS")
		)
		(fp_line
			(start 0.508 -0.9398)
			(end 0.508 0.9398)
			(stroke
				(width 0.1524)
				(type default)
			)
			(layer "B.SilkS")
		)
		(fp_rect
			(start 0.508 0.9398)
			(end -0.508 -0.9398)
			(stroke
				(width 0)
				(type default)
			)
			(fill no)
			(layer "B.CrtYd")
		)
		(fp_rect
			(start 0.508 0.9398)
			(end -0.508 -0.9398)
			(stroke
				(width 0)
				(type default)
			)
			(fill no)
			(layer "B.Fab")
		)
		(pad "1" smd custom
			(at 0 -0.4445 180)
			(size 0.1397 0.1397)
			(layers "B.Cu" "B.Mask" "B.Paste")
			(net "SSD_ATNLED#9")
			(options
				(clearance outline)
				(anchor circle)
			)
			(primitives
				(gr_poly
					(pts
						(arc
							(start -0.1778 0.2794)
							(mid -0.249642 0.249642)
							(end -0.2794 0.1778)
						)
						(arc
							(start -0.2794 -0.1778)
							(mid -0.249642 -0.249642)
							(end -0.1778 -0.2794)
						)
						(arc
							(start 0.1778 -0.2794)
							(mid 0.249642 -0.249642)
							(end 0.2794 -0.1778)
						)
						(arc
							(start 0.2794 0.1778)
							(mid 0.249642 0.249642)
							(end 0.1778 0.2794)
						)
					)
					(width 0)
					(fill yes)
				)
			)
		)
		(pad "2" smd custom
			(at 0 0.4445 180)
			(size 0.1397 0.1397)
			(layers "B.Cu" "B.Mask" "B.Paste")
			(net "P3V3_STBY")
			(options
				(clearance outline)
				(anchor circle)
			)
			(primitives
				(gr_poly
					(pts
						(arc
							(start -0.1778 0.2794)
							(mid -0.249642 0.249642)
							(end -0.2794 0.1778)
						)
						(arc
							(start -0.2794 -0.1778)
							(mid -0.249642 -0.249642)
							(end -0.1778 -0.2794)
						)
						(arc
							(start 0.1778 -0.2794)
							(mid 0.249642 -0.249642)
							(end 0.2794 -0.1778)
						)
						(arc
							(start 0.2794 0.1778)
							(mid 0.249642 0.249642)
							(end 0.1778 0.2794)
						)
					)
					(width 0)
					(fill yes)
				)
			)
		)
	)
	(footprint ""
		(layer "B.Cu")
		(at 241.6048 -57.995058 90)
		(property "Reference" "C500"
			(at 0 0 90)
			(layer "B.SilkS")
			(hide yes)
			(effects
				(font
					(size 1.27 1.27)
				)
				(justify mirror)
			)
		)
		(property "Value" "SCD1U16V1KX-1-GP"
			(at 2.8321 -1.7399 90)
			(unlocked yes)
			(layer "B.Fab")
			(hide yes)
			(effects
				(font
					(size 1.016 1.016)
					(thickness 0.1524)
				)
				(justify mirror)
			)
		)
		(property "Device Type" "C0201H13"
			(at 2.8321 -3.2639 90)
			(unlocked yes)
			(layer "B.Fab")
			(hide yes)
			(effects
				(font
					(size 1.016 1.016)
					(thickness 0.1524)
				)
				(justify mirror)
			)
		)
		(duplicate_pad_numbers_are_jumpers no)
		(fp_rect
			(start 0.2794 0.6477)
			(end -0.2794 -0.6477)
			(stroke
				(width 0)
				(type default)
			)
			(fill no)
			(layer "B.CrtYd")
		)
		(fp_rect
			(start 0.2794 0.6477)
			(end -0.2794 -0.6477)
			(stroke
				(width 0)
				(type default)
			)
			(fill no)
			(layer "B.Fab")
		)
		(pad "1" smd custom
			(at 0 -0.2794 270)
			(size 0.0762 0.0762)
			(layers "B.Cu" "B.Mask" "B.Paste")
			(net "DUT_AVD_TX")
			(options
				(clearance outline)
				(anchor circle)
			)
			(primitives
				(gr_poly
					(pts
						(arc
							(start 0.1524 0.127)
							(mid 0.137521 0.162921)
							(end 0.1016 0.1778)
						)
						(arc
							(start -0.1016 0.1778)
							(mid -0.137521 0.162921)
							(end -0.1524 0.127)
						)
						(arc
							(start -0.1524 -0.127)
							(mid -0.137521 -0.162921)
							(end -0.1016 -0.1778)
						)
						(arc
							(start 0.1016 -0.1778)
							(mid 0.137521 -0.162921)
							(end 0.1524 -0.127)
						)
					)
					(width 0)
					(fill yes)
				)
			)
		)
		(pad "2" smd custom
			(at 0 0.2794 270)
			(size 0.0762 0.0762)
			(layers "B.Cu" "B.Mask" "B.Paste")
			(net "GND")
			(options
				(clearance outline)
				(anchor circle)
			)
			(primitives
				(gr_poly
					(pts
						(arc
							(start 0.1524 0.127)
							(mid 0.137521 0.162921)
							(end 0.1016 0.1778)
						)
						(arc
							(start -0.1016 0.1778)
							(mid -0.137521 0.162921)
							(end -0.1524 0.127)
						)
						(arc
							(start -0.1524 -0.127)
							(mid -0.137521 -0.162921)
							(end -0.1016 -0.1778)
						)
						(arc
							(start 0.1016 -0.1778)
							(mid 0.137521 -0.162921)
							(end 0.1524 -0.127)
						)
					)
					(width 0)
					(fill yes)
				)
			)
		)
	)
	(footprint ""
		(layer "B.Cu")
		(at 137.332212 -199.753474)
		(property "Reference" "R3221"
			(at 0 0 0)
			(layer "B.SilkS")
			(hide yes)
			(effects
				(font
					(size 1.27 1.27)
				)
				(justify mirror)
			)
		)
		(property "Value" "0R2J-2-GP"
			(at -0.064008 -3.993896 0)
			(unlocked yes)
			(layer "B.Fab")
			(hide yes)
			(effects
				(font
					(size 1.016 1.016)
					(thickness 0.1524)
				)
				(justify mirror)
			)
		)
		(property "Device Type" "R402H16"
			(at -0.064008 -5.517896 0)
			(unlocked yes)
			(layer "B.Fab")
			(hide yes)
			(effects
				(font
					(size 1.016 1.016)
					(thickness 0.1524)
				)
				(justify mirror)
			)
		)
		(duplicate_pad_numbers_are_jumpers no)
		(fp_line
			(start -0.508 -0.9398)
			(end 0.508 -0.9398)
			(stroke
				(width 0.1524)
				(type default)
			)
			(layer "B.SilkS")
		)
		(fp_line
			(start 0.508 -0.9398)
			(end 0.508 0.9398)
			(stroke
				(width 0.1524)
				(type default)
			)
			(layer "B.SilkS")
		)
		(fp_rect
			(start 0.508 0.9398)
			(end -0.508 -0.9398)
			(stroke
				(width 0)
				(type default)
			)
			(fill no)
			(layer "B.CrtYd")
		)
		(fp_rect
			(start 0.508 0.9398)
			(end -0.508 -0.9398)
			(stroke
				(width 0)
				(type default)
			)
			(fill no)
			(layer "B.Fab")
		)
		(pad "1" smd custom
			(at 0 -0.4445 180)
			(size 0.1397 0.1397)
			(layers "B.Cu" "B.Mask" "B.Paste")
			(net "SSD_PERST_Y6")
			(options
				(clearance outline)
				(anchor circle)
			)
			(primitives
				(gr_poly
					(pts
						(arc
							(start -0.1778 0.2794)
							(mid -0.249642 0.249642)
							(end -0.2794 0.1778)
						)
						(arc
							(start -0.2794 -0.1778)
							(mid -0.249642 -0.249642)
							(end -0.1778 -0.2794)
						)
						(arc
							(start 0.1778 -0.2794)
							(mid 0.249642 -0.249642)
							(end 0.2794 -0.1778)
						)
						(arc
							(start 0.2794 0.1778)
							(mid 0.249642 0.249642)
							(end 0.1778 0.2794)
						)
					)
					(width 0)
					(fill yes)
				)
			)
		)
		(pad "2" smd custom
			(at 0 0.4445 180)
			(size 0.1397 0.1397)
			(layers "B.Cu" "B.Mask" "B.Paste")
			(net "SSD_PERST#6_R")
			(options
				(clearance outline)
				(anchor circle)
			)
			(primitives
				(gr_poly
					(pts
						(arc
							(start -0.1778 0.2794)
							(mid -0.249642 0.249642)
							(end -0.2794 0.1778)
						)
						(arc
							(start -0.2794 -0.1778)
							(mid -0.249642 -0.249642)
							(end -0.1778 -0.2794)
						)
						(arc
							(start 0.1778 -0.2794)
							(mid 0.249642 -0.249642)
							(end 0.2794 -0.1778)
						)
						(arc
							(start 0.2794 0.1778)
							(mid 0.249642 0.249642)
							(end 0.1778 0.2794)
						)
					)
					(width 0)
					(fill yes)
				)
			)
		)
	)
	(footprint ""
		(layer "B.Cu")
		(at 75.184 -149.479 -90)
		(property "Reference" "R194"
			(at 0 0 90)
			(layer "B.SilkS")
			(hide yes)
			(effects
				(font
					(size 1.27 1.27)
				)
				(justify mirror)
			)
		)
		(property "Value" "8K2R2J-3-GP"
			(at -0.064008 -3.993896 270)
			(unlocked yes)
			(layer "B.Fab")
			(hide yes)
			(effects
				(font
					(size 1.016 1.016)
					(thickness 0.1524)
				)
				(justify mirror)
			)
		)
		(property "Device Type" "R402H16"
			(at -0.064008 -5.517896 270)
			(unlocked yes)
			(layer "B.Fab")
			(hide yes)
			(effects
				(font
					(size 1.016 1.016)
					(thickness 0.1524)
				)
				(justify mirror)
			)
		)
		(duplicate_pad_numbers_are_jumpers no)
		(fp_line
			(start -0.508 -0.9398)
			(end 0.508 -0.9398)
			(stroke
				(width 0.1524)
				(type default)
			)
			(layer "B.SilkS")
		)
		(fp_line
			(start 0.508 -0.9398)
			(end 0.508 0.9398)
			(stroke
				(width 0.1524)
				(type default)
			)
			(layer "B.SilkS")
		)
		(fp_rect
			(start 0.508 0.9398)
			(end -0.508 -0.9398)
			(stroke
				(width 0)
				(type default)
			)
			(fill no)
			(layer "B.CrtYd")
		)
		(fp_rect
			(start 0.508 0.9398)
			(end -0.508 -0.9398)
			(stroke
				(width 0)
				(type default)
			)
			(fill no)
			(layer "B.Fab")
		)
		(pad "1" smd custom
			(at 0 -0.4445 90)
			(size 0.1397 0.1397)
			(layers "B.Cu" "B.Mask" "B.Paste")
			(net "P3V3_STBY")
			(options
				(clearance outline)
				(anchor circle)
			)
			(primitives
				(gr_poly
					(pts
						(arc
							(start -0.1778 0.2794)
							(mid -0.249642 0.249642)
							(end -0.2794 0.1778)
						)
						(arc
							(start -0.2794 -0.1778)
							(mid -0.249642 -0.249642)
							(end -0.1778 -0.2794)
						)
						(arc
							(start 0.1778 -0.2794)
							(mid 0.249642 -0.249642)
							(end 0.2794 -0.1778)
						)
						(arc
							(start 0.2794 0.1778)
							(mid 0.249642 0.249642)
							(end 0.1778 0.2794)
						)
					)
					(width 0)
					(fill yes)
				)
			)
		)
		(pad "2" smd custom
			(at 0 0.4445 90)
			(size 0.1397 0.1397)
			(layers "B.Cu" "B.Mask" "B.Paste")
			(net "EEPROM_A2_R")
			(options
				(clearance outline)
				(anchor circle)
			)
			(primitives
				(gr_poly
					(pts
						(arc
							(start -0.1778 0.2794)
							(mid -0.249642 0.249642)
							(end -0.2794 0.1778)
						)
						(arc
							(start -0.2794 -0.1778)
							(mid -0.249642 -0.249642)
							(end -0.1778 -0.2794)
						)
						(arc
							(start 0.1778 -0.2794)
							(mid 0.249642 -0.249642)
							(end 0.2794 -0.1778)
						)
						(arc
							(start 0.2794 0.1778)
							(mid 0.249642 0.249642)
							(end 0.1778 0.2794)
						)
					)
					(width 0)
					(fill yes)
				)
			)
		)
	)
	(footprint ""
		(layer "B.Cu")
		(at 63.9572 -118.0338 180)
		(property "Reference" "R21"
			(at 0 0 0)
			(layer "B.SilkS")
			(hide yes)
			(effects
				(font
					(size 1.27 1.27)
				)
				(justify mirror)
			)
		)
		(property "Value" "0R2J-2-GP"
			(at -0.064008 -3.993896 180)
			(unlocked yes)
			(layer "B.Fab")
			(hide yes)
			(effects
				(font
					(size 1.016 1.016)
					(thickness 0.1524)
				)
				(justify mirror)
			)
		)
		(property "Device Type" "R402H16"
			(at -0.064008 -5.517896 180)
			(unlocked yes)
			(layer "B.Fab")
			(hide yes)
			(effects
				(font
					(size 1.016 1.016)
					(thickness 0.1524)
				)
				(justify mirror)
			)
		)
		(duplicate_pad_numbers_are_jumpers no)
		(fp_line
			(start 0.508 -0.9398)
			(end 0.508 0.9398)
			(stroke
				(width 0.1524)
				(type default)
			)
			(layer "B.SilkS")
		)
		(fp_line
			(start -0.508 -0.9398)
			(end 0.508 -0.9398)
			(stroke
				(width 0.1524)
				(type default)
			)
			(layer "B.SilkS")
		)
		(fp_rect
			(start 0.508 0.9398)
			(end -0.508 -0.9398)
			(stroke
				(width 0)
				(type default)
			)
			(fill no)
			(layer "B.CrtYd")
		)
		(fp_rect
			(start 0.508 0.9398)
			(end -0.508 -0.9398)
			(stroke
				(width 0)
				(type default)
			)
			(fill no)
			(layer "B.Fab")
		)
		(pad "1" smd custom
			(at 0 -0.4445)
			(size 0.1397 0.1397)
			(layers "B.Cu" "B.Mask" "B.Paste")
			(net "BMC_I2C3_MINI3_SCL_S")
			(options
				(clearance outline)
				(anchor circle)
			)
			(primitives
				(gr_poly
					(pts
						(arc
							(start -0.1778 0.2794)
							(mid -0.249642 0.249642)
							(end -0.2794 0.1778)
						)
						(arc
							(start -0.2794 -0.1778)
							(mid -0.249642 -0.249642)
							(end -0.1778 -0.2794)
						)
						(arc
							(start 0.1778 -0.2794)
							(mid 0.249642 -0.249642)
							(end 0.2794 -0.1778)
						)
						(arc
							(start 0.2794 0.1778)
							(mid 0.249642 0.249642)
							(end 0.1778 0.2794)
						)
					)
					(width 0)
					(fill yes)
				)
			)
		)
		(pad "2" smd custom
			(at 0 0.4445)
			(size 0.1397 0.1397)
			(layers "B.Cu" "B.Mask" "B.Paste")
			(net "BMC_I2C3_MINI3_SCL")
			(options
				(clearance outline)
				(anchor circle)
			)
			(primitives
				(gr_poly
					(pts
						(arc
							(start -0.1778 0.2794)
							(mid -0.249642 0.249642)
							(end -0.2794 0.1778)
						)
						(arc
							(start -0.2794 -0.1778)
							(mid -0.249642 -0.249642)
							(end -0.1778 -0.2794)
						)
						(arc
							(start 0.1778 -0.2794)
							(mid 0.249642 -0.249642)
							(end 0.2794 -0.1778)
						)
						(arc
							(start 0.2794 0.1778)
							(mid 0.249642 0.249642)
							(end 0.1778 0.2794)
						)
					)
					(width 0)
					(fill yes)
				)
			)
		)
	)
	(footprint ""
		(layer "B.Cu")
		(at 242.443 -18.288 -90)
		(property "Reference" "R28"
			(at 0 0 90)
			(layer "B.SilkS")
			(hide yes)
			(effects
				(font
					(size 1.27 1.27)
				)
				(justify mirror)
			)
		)
		(property "Value" "0R2J-2-GP"
			(at -0.064008 -3.993896 270)
			(unlocked yes)
			(layer "B.Fab")
			(hide yes)
			(effects
				(font
					(size 1.016 1.016)
					(thickness 0.1524)
				)
				(justify mirror)
			)
		)
		(property "Device Type" "R402H16"
			(at -0.064008 -5.517896 270)
			(unlocked yes)
			(layer "B.Fab")
			(hide yes)
			(effects
				(font
					(size 1.016 1.016)
					(thickness 0.1524)
				)
				(justify mirror)
			)
		)
		(duplicate_pad_numbers_are_jumpers no)
		(fp_line
			(start -0.508 -0.9398)
			(end 0.508 -0.9398)
			(stroke
				(width 0.1524)
				(type default)
			)
			(layer "B.SilkS")
		)
		(fp_line
			(start 0.508 -0.9398)
			(end 0.508 0.9398)
			(stroke
				(width 0.1524)
				(type default)
			)
			(layer "B.SilkS")
		)
		(fp_rect
			(start 0.508 0.9398)
			(end -0.508 -0.9398)
			(stroke
				(width 0)
				(type default)
			)
			(fill no)
			(layer "B.CrtYd")
		)
		(fp_rect
			(start 0.508 0.9398)
			(end -0.508 -0.9398)
			(stroke
				(width 0)
				(type default)
			)
			(fill no)
			(layer "B.Fab")
		)
		(pad "1" smd custom
			(at 0 -0.4445 90)
			(size 0.1397 0.1397)
			(layers "B.Cu" "B.Mask" "B.Paste")
			(net "VSS_572")
			(options
				(clearance outline)
				(anchor circle)
			)
			(primitives
				(gr_poly
					(pts
						(arc
							(start -0.1778 0.2794)
							(mid -0.249642 0.249642)
							(end -0.2794 0.1778)
						)
						(arc
							(start -0.2794 -0.1778)
							(mid -0.249642 -0.249642)
							(end -0.1778 -0.2794)
						)
						(arc
							(start 0.1778 -0.2794)
							(mid 0.249642 -0.249642)
							(end 0.2794 -0.1778)
						)
						(arc
							(start 0.2794 0.1778)
							(mid 0.249642 0.249642)
							(end 0.1778 0.2794)
						)
					)
					(width 0)
					(fill yes)
				)
			)
		)
		(pad "2" smd custom
			(at 0 0.4445 90)
			(size 0.1397 0.1397)
			(layers "B.Cu" "B.Mask" "B.Paste")
			(net "GND")
			(options
				(clearance outline)
				(anchor circle)
			)
			(primitives
				(gr_poly
					(pts
						(arc
							(start -0.1778 0.2794)
							(mid -0.249642 0.249642)
							(end -0.2794 0.1778)
						)
						(arc
							(start -0.2794 -0.1778)
							(mid -0.249642 -0.249642)
							(end -0.1778 -0.2794)
						)
						(arc
							(start 0.1778 -0.2794)
							(mid 0.249642 -0.249642)
							(end 0.2794 -0.1778)
						)
						(arc
							(start 0.2794 0.1778)
							(mid 0.249642 0.249642)
							(end 0.1778 0.2794)
						)
					)
					(width 0)
					(fill yes)
				)
			)
		)
	)
	(footprint ""
		(layer "B.Cu")
		(at 271.7038 -1.6002)
		(property "Reference" "R2907"
			(at 0 0 0)
			(layer "B.SilkS")
			(hide yes)
			(effects
				(font
					(size 1.27 1.27)
				)
				(justify mirror)
			)
		)
		(property "Value" "0R2J-2-GP"
			(at -0.064008 -3.993896 0)
			(unlocked yes)
			(layer "B.Fab")
			(hide yes)
			(effects
				(font
					(size 1.016 1.016)
					(thickness 0.1524)
				)
				(justify mirror)
			)
		)
		(property "Device Type" "R402H16"
			(at -0.064008 -5.517896 0)
			(unlocked yes)
			(layer "B.Fab")
			(hide yes)
			(effects
				(font
					(size 1.016 1.016)
					(thickness 0.1524)
				)
				(justify mirror)
			)
		)
		(duplicate_pad_numbers_are_jumpers no)
		(fp_line
			(start -0.508 -0.9398)
			(end 0.508 -0.9398)
			(stroke
				(width 0.1524)
				(type default)
			)
			(layer "B.SilkS")
		)
		(fp_line
			(start 0.508 -0.9398)
			(end 0.508 0.9398)
			(stroke
				(width 0.1524)
				(type default)
			)
			(layer "B.SilkS")
		)
		(fp_rect
			(start 0.508 0.9398)
			(end -0.508 -0.9398)
			(stroke
				(width 0)
				(type default)
			)
			(fill no)
			(layer "B.CrtYd")
		)
		(fp_rect
			(start 0.508 0.9398)
			(end -0.508 -0.9398)
			(stroke
				(width 0)
				(type default)
			)
			(fill no)
			(layer "B.Fab")
		)
		(pad "1" smd custom
			(at 0 -0.4445 180)
			(size 0.1397 0.1397)
			(layers "B.Cu" "B.Mask" "B.Paste")
			(net "BMC_I2C14_MINI8_SDA")
			(options
				(clearance outline)
				(anchor circle)
			)
			(primitives
				(gr_poly
					(pts
						(arc
							(start -0.1778 0.2794)
							(mid -0.249642 0.249642)
							(end -0.2794 0.1778)
						)
						(arc
							(start -0.2794 -0.1778)
							(mid -0.249642 -0.249642)
							(end -0.1778 -0.2794)
						)
						(arc
							(start 0.1778 -0.2794)
							(mid 0.249642 -0.249642)
							(end 0.2794 -0.1778)
						)
						(arc
							(start 0.2794 0.1778)
							(mid 0.249642 0.249642)
							(end 0.1778 0.2794)
						)
					)
					(width 0)
					(fill yes)
				)
			)
		)
		(pad "2" smd custom
			(at 0 0.4445 180)
			(size 0.1397 0.1397)
			(layers "B.Cu" "B.Mask" "B.Paste")
			(net "8644_SDA_R_8")
			(options
				(clearance outline)
				(anchor circle)
			)
			(primitives
				(gr_poly
					(pts
						(arc
							(start -0.1778 0.2794)
							(mid -0.249642 0.249642)
							(end -0.2794 0.1778)
						)
						(arc
							(start -0.2794 -0.1778)
							(mid -0.249642 -0.249642)
							(end -0.1778 -0.2794)
						)
						(arc
							(start 0.1778 -0.2794)
							(mid 0.249642 -0.249642)
							(end 0.2794 -0.1778)
						)
						(arc
							(start 0.2794 0.1778)
							(mid 0.249642 0.249642)
							(end 0.1778 0.2794)
						)
					)
					(width 0)
					(fill yes)
				)
			)
		)
	)
	(footprint ""
		(layer "B.Cu")
		(at 59.7154 -117.983 180)
		(property "Reference" "R19"
			(at 0 0 0)
			(layer "B.SilkS")
			(hide yes)
			(effects
				(font
					(size 1.27 1.27)
				)
				(justify mirror)
			)
		)
		(property "Value" "0R2J-2-GP"
			(at -0.064008 -3.993896 180)
			(unlocked yes)
			(layer "B.Fab")
			(hide yes)
			(effects
				(font
					(size 1.016 1.016)
					(thickness 0.1524)
				)
				(justify mirror)
			)
		)
		(property "Device Type" "R402H16"
			(at -0.064008 -5.517896 180)
			(unlocked yes)
			(layer "B.Fab")
			(hide yes)
			(effects
				(font
					(size 1.016 1.016)
					(thickness 0.1524)
				)
				(justify mirror)
			)
		)
		(duplicate_pad_numbers_are_jumpers no)
		(fp_line
			(start 0.508 -0.9398)
			(end 0.508 0.9398)
			(stroke
				(width 0.1524)
				(type default)
			)
			(layer "B.SilkS")
		)
		(fp_line
			(start -0.508 -0.9398)
			(end 0.508 -0.9398)
			(stroke
				(width 0.1524)
				(type default)
			)
			(layer "B.SilkS")
		)
		(fp_rect
			(start 0.508 0.9398)
			(end -0.508 -0.9398)
			(stroke
				(width 0)
				(type default)
			)
			(fill no)
			(layer "B.CrtYd")
		)
		(fp_rect
			(start 0.508 0.9398)
			(end -0.508 -0.9398)
			(stroke
				(width 0)
				(type default)
			)
			(fill no)
			(layer "B.Fab")
		)
		(pad "1" smd custom
			(at 0 -0.4445)
			(size 0.1397 0.1397)
			(layers "B.Cu" "B.Mask" "B.Paste")
			(net "BMC_I2C3_MINI3_SDA")
			(options
				(clearance outline)
				(anchor circle)
			)
			(primitives
				(gr_poly
					(pts
						(arc
							(start -0.1778 0.2794)
							(mid -0.249642 0.249642)
							(end -0.2794 0.1778)
						)
						(arc
							(start -0.2794 -0.1778)
							(mid -0.249642 -0.249642)
							(end -0.1778 -0.2794)
						)
						(arc
							(start 0.1778 -0.2794)
							(mid 0.249642 -0.249642)
							(end 0.2794 -0.1778)
						)
						(arc
							(start 0.2794 0.1778)
							(mid 0.249642 0.249642)
							(end 0.1778 0.2794)
						)
					)
					(width 0)
					(fill yes)
				)
			)
		)
		(pad "2" smd custom
			(at 0 0.4445)
			(size 0.1397 0.1397)
			(layers "B.Cu" "B.Mask" "B.Paste")
			(net "BMC_I2C3_MINI3_SDA_S")
			(options
				(clearance outline)
				(anchor circle)
			)
			(primitives
				(gr_poly
					(pts
						(arc
							(start -0.1778 0.2794)
							(mid -0.249642 0.249642)
							(end -0.2794 0.1778)
						)
						(arc
							(start -0.2794 -0.1778)
							(mid -0.249642 -0.249642)
							(end -0.1778 -0.2794)
						)
						(arc
							(start 0.1778 -0.2794)
							(mid 0.249642 -0.249642)
							(end 0.2794 -0.1778)
						)
						(arc
							(start 0.2794 0.1778)
							(mid 0.249642 0.249642)
							(end 0.1778 0.2794)
						)
					)
					(width 0)
					(fill yes)
				)
			)
		)
	)
	(footprint ""
		(layer "B.Cu")
		(at 229.59568 -34.99612)
		(property "Reference" "TP274"
			(at 0 0 0)
			(layer "B.SilkS")
			(hide yes)
			(effects
				(font
					(size 1.27 1.27)
				)
				(justify mirror)
			)
		)
		(property "Value" "TPAD28-2-GP"
			(at 0.0127 -1.6637 0)
			(unlocked yes)
			(layer "B.Fab")
			(hide yes)
			(effects
				(font
					(size 1.016 1.016)
					(thickness 0.1524)
				)
				(justify mirror)
			)
		)
		(property "Device Type" "TPAD28"
			(at 0.0127 -3.1877 0)
			(unlocked yes)
			(layer "B.Fab")
			(hide yes)
			(effects
				(font
					(size 1.016 1.016)
					(thickness 0.1524)
				)
				(justify mirror)
			)
		)
		(duplicate_pad_numbers_are_jumpers no)
		(fp_poly
			(pts
				(arc
					(start 0.3556 0)
					(mid -0.3556 0)
					(end 0.3556 0)
				)
			)
			(stroke
				(width 0)
				(type default)
			)
			(fill no)
			(layer "B.CrtYd")
		)
		(fp_poly
			(pts
				(arc
					(start 0.6096 0)
					(mid -0.6096 0)
					(end 0.6096 0)
				)
			)
			(stroke
				(width 0)
				(type default)
			)
			(fill no)
			(layer "B.Fab")
		)
		(pad "1" smd circle
			(at 0 0 180)
			(size 0.7112 0.7112)
			(layers "B.Cu" "B.Mask" "B.Paste")
			(net "LBI_DATA11_R")
		)
	)
	(footprint ""
		(layer "B.Cu")
		(at 59.0804 -25.4762)
		(property "Reference" "R701"
			(at 0 0 0)
			(layer "B.SilkS")
			(hide yes)
			(effects
				(font
					(size 1.27 1.27)
				)
				(justify mirror)
			)
		)
		(property "Value" "4K7R2F-GP"
			(at -0.064008 -3.993896 0)
			(unlocked yes)
			(layer "B.Fab")
			(hide yes)
			(effects
				(font
					(size 1.016 1.016)
					(thickness 0.1524)
				)
				(justify mirror)
			)
		)
		(property "Device Type" "R402H16"
			(at -0.064008 -5.517896 0)
			(unlocked yes)
			(layer "B.Fab")
			(hide yes)
			(effects
				(font
					(size 1.016 1.016)
					(thickness 0.1524)
				)
				(justify mirror)
			)
		)
		(duplicate_pad_numbers_are_jumpers no)
		(fp_line
			(start -0.508 -0.9398)
			(end 0.508 -0.9398)
			(stroke
				(width 0.1524)
				(type default)
			)
			(layer "B.SilkS")
		)
		(fp_line
			(start 0.508 -0.9398)
			(end 0.508 0.9398)
			(stroke
				(width 0.1524)
				(type default)
			)
			(layer "B.SilkS")
		)
		(fp_rect
			(start 0.508 0.9398)
			(end -0.508 -0.9398)
			(stroke
				(width 0)
				(type default)
			)
			(fill no)
			(layer "B.CrtYd")
		)
		(fp_rect
			(start 0.508 0.9398)
			(end -0.508 -0.9398)
			(stroke
				(width 0)
				(type default)
			)
			(fill no)
			(layer "B.Fab")
		)
		(pad "1" smd custom
			(at 0 -0.4445 180)
			(size 0.1397 0.1397)
			(layers "B.Cu" "B.Mask" "B.Paste")
			(net "P3V3_STBY")
			(options
				(clearance outline)
				(anchor circle)
			)
			(primitives
				(gr_poly
					(pts
						(arc
							(start -0.1778 0.2794)
							(mid -0.249642 0.249642)
							(end -0.2794 0.1778)
						)
						(arc
							(start -0.2794 -0.1778)
							(mid -0.249642 -0.249642)
							(end -0.1778 -0.2794)
						)
						(arc
							(start 0.1778 -0.2794)
							(mid 0.249642 -0.249642)
							(end 0.2794 -0.1778)
						)
						(arc
							(start 0.2794 0.1778)
							(mid 0.249642 0.249642)
							(end 0.1778 0.2794)
						)
					)
					(width 0)
					(fill yes)
				)
			)
		)
		(pad "2" smd custom
			(at 0 0.4445 180)
			(size 0.1397 0.1397)
			(layers "B.Cu" "B.Mask" "B.Paste")
			(net "IPMB_DAT")
			(options
				(clearance outline)
				(anchor circle)
			)
			(primitives
				(gr_poly
					(pts
						(arc
							(start -0.1778 0.2794)
							(mid -0.249642 0.249642)
							(end -0.2794 0.1778)
						)
						(arc
							(start -0.2794 -0.1778)
							(mid -0.249642 -0.249642)
							(end -0.1778 -0.2794)
						)
						(arc
							(start 0.1778 -0.2794)
							(mid 0.249642 -0.249642)
							(end 0.2794 -0.1778)
						)
						(arc
							(start 0.2794 0.1778)
							(mid 0.249642 0.249642)
							(end 0.1778 0.2794)
						)
					)
					(width 0)
					(fill yes)
				)
			)
		)
	)
	(footprint ""
		(layer "B.Cu")
		(at 255.505712 -5.99567 90)
		(property "Reference" "R191"
			(at 0 0 90)
			(layer "B.SilkS")
			(hide yes)
			(effects
				(font
					(size 1.27 1.27)
				)
				(justify mirror)
			)
		)
		(property "Value" "0R2J-2-GP"
			(at -0.064008 -3.993896 90)
			(unlocked yes)
			(layer "B.Fab")
			(hide yes)
			(effects
				(font
					(size 1.016 1.016)
					(thickness 0.1524)
				)
				(justify mirror)
			)
		)
		(property "Device Type" "R402H16"
			(at -0.064008 -5.517896 90)
			(unlocked yes)
			(layer "B.Fab")
			(hide yes)
			(effects
				(font
					(size 1.016 1.016)
					(thickness 0.1524)
				)
				(justify mirror)
			)
		)
		(duplicate_pad_numbers_are_jumpers no)
		(fp_line
			(start 0.508 -0.9398)
			(end 0.508 0.9398)
			(stroke
				(width 0.1524)
				(type default)
			)
			(layer "B.SilkS")
		)
		(fp_line
			(start -0.508 -0.9398)
			(end 0.508 -0.9398)
			(stroke
				(width 0.1524)
				(type default)
			)
			(layer "B.SilkS")
		)
		(fp_rect
			(start 0.508 0.9398)
			(end -0.508 -0.9398)
			(stroke
				(width 0)
				(type default)
			)
			(fill no)
			(layer "B.CrtYd")
		)
		(fp_rect
			(start 0.508 0.9398)
			(end -0.508 -0.9398)
			(stroke
				(width 0)
				(type default)
			)
			(fill no)
			(layer "B.Fab")
		)
		(pad "1" smd custom
			(at 0 -0.4445 270)
			(size 0.1397 0.1397)
			(layers "B.Cu" "B.Mask" "B.Paste")
			(net "BMC_I2C5_D_PEB_SDA")
			(options
				(clearance outline)
				(anchor circle)
			)
			(primitives
				(gr_poly
					(pts
						(arc
							(start -0.1778 0.2794)
							(mid -0.249642 0.249642)
							(end -0.2794 0.1778)
						)
						(arc
							(start -0.2794 -0.1778)
							(mid -0.249642 -0.249642)
							(end -0.1778 -0.2794)
						)
						(arc
							(start 0.1778 -0.2794)
							(mid 0.249642 -0.249642)
							(end 0.2794 -0.1778)
						)
						(arc
							(start 0.2794 0.1778)
							(mid 0.249642 0.249642)
							(end 0.1778 0.2794)
						)
					)
					(width 0)
					(fill yes)
				)
			)
		)
		(pad "2" smd custom
			(at 0 0.4445 270)
			(size 0.1397 0.1397)
			(layers "B.Cu" "B.Mask" "B.Paste")
			(net "TEMP_1_SDA")
			(options
				(clearance outline)
				(anchor circle)
			)
			(primitives
				(gr_poly
					(pts
						(arc
							(start -0.1778 0.2794)
							(mid -0.249642 0.249642)
							(end -0.2794 0.1778)
						)
						(arc
							(start -0.2794 -0.1778)
							(mid -0.249642 -0.249642)
							(end -0.1778 -0.2794)
						)
						(arc
							(start 0.1778 -0.2794)
							(mid 0.249642 -0.249642)
							(end 0.2794 -0.1778)
						)
						(arc
							(start 0.2794 0.1778)
							(mid 0.249642 0.249642)
							(end 0.1778 0.2794)
						)
					)
					(width 0)
					(fill yes)
				)
			)
		)
	)
	(footprint ""
		(layer "B.Cu")
		(at 270.18615 -11.258042 90)
		(property "Reference" "R2963"
			(at 0 0 90)
			(layer "B.SilkS")
			(hide yes)
			(effects
				(font
					(size 1.27 1.27)
				)
				(justify mirror)
			)
		)
		(property "Value" "0R2J-2-GP"
			(at -0.064008 -3.993896 90)
			(unlocked yes)
			(layer "B.Fab")
			(hide yes)
			(effects
				(font
					(size 1.016 1.016)
					(thickness 0.1524)
				)
				(justify mirror)
			)
		)
		(property "Device Type" "R402H16"
			(at -0.064008 -5.517896 90)
			(unlocked yes)
			(layer "B.Fab")
			(hide yes)
			(effects
				(font
					(size 1.016 1.016)
					(thickness 0.1524)
				)
				(justify mirror)
			)
		)
		(duplicate_pad_numbers_are_jumpers no)
		(fp_line
			(start 0.508 -0.9398)
			(end 0.508 0.9398)
			(stroke
				(width 0.1524)
				(type default)
			)
			(layer "B.SilkS")
		)
		(fp_line
			(start -0.508 -0.9398)
			(end 0.508 -0.9398)
			(stroke
				(width 0.1524)
				(type default)
			)
			(layer "B.SilkS")
		)
		(fp_rect
			(start 0.508 0.9398)
			(end -0.508 -0.9398)
			(stroke
				(width 0)
				(type default)
			)
			(fill no)
			(layer "B.CrtYd")
		)
		(fp_rect
			(start 0.508 0.9398)
			(end -0.508 -0.9398)
			(stroke
				(width 0)
				(type default)
			)
			(fill no)
			(layer "B.Fab")
		)
		(pad "1" smd custom
			(at 0 -0.4445 270)
			(size 0.1397 0.1397)
			(layers "B.Cu" "B.Mask" "B.Paste")
			(net "HOST6_RST_N")
			(options
				(clearance outline)
				(anchor circle)
			)
			(primitives
				(gr_poly
					(pts
						(arc
							(start -0.1778 0.2794)
							(mid -0.249642 0.249642)
							(end -0.2794 0.1778)
						)
						(arc
							(start -0.2794 -0.1778)
							(mid -0.249642 -0.249642)
							(end -0.1778 -0.2794)
						)
						(arc
							(start 0.1778 -0.2794)
							(mid 0.249642 -0.249642)
							(end 0.2794 -0.1778)
						)
						(arc
							(start 0.2794 0.1778)
							(mid 0.249642 0.249642)
							(end 0.1778 0.2794)
						)
					)
					(width 0)
					(fill yes)
				)
			)
		)
		(pad "2" smd custom
			(at 0 0.4445 270)
			(size 0.1397 0.1397)
			(layers "B.Cu" "B.Mask" "B.Paste")
			(net "HOST6_RST_N_C")
			(options
				(clearance outline)
				(anchor circle)
			)
			(primitives
				(gr_poly
					(pts
						(arc
							(start -0.1778 0.2794)
							(mid -0.249642 0.249642)
							(end -0.2794 0.1778)
						)
						(arc
							(start -0.2794 -0.1778)
							(mid -0.249642 -0.249642)
							(end -0.1778 -0.2794)
						)
						(arc
							(start 0.1778 -0.2794)
							(mid 0.249642 -0.249642)
							(end 0.2794 -0.1778)
						)
						(arc
							(start 0.2794 0.1778)
							(mid 0.249642 0.249642)
							(end 0.1778 0.2794)
						)
					)
					(width 0)
					(fill yes)
				)
			)
		)
	)
	(footprint ""
		(layer "B.Cu")
		(at 58.039 -37.211)
		(property "Reference" "PC26"
			(at 0 0 0)
			(layer "B.SilkS")
			(hide yes)
			(effects
				(font
					(size 1.27 1.27)
				)
				(justify mirror)
			)
		)
		(property "Value" "SC4D7U25V5KX-1-GP"
			(at 0.0762 -6.1214 0)
			(unlocked yes)
			(layer "B.Fab")
			(hide yes)
			(effects
				(font
					(size 1.016 1.016)
					(thickness 0.1524)
				)
				(justify mirror)
			)
		)
		(property "Device Type" "C805H58"
			(at 0.0762 -8.1534 0)
			(unlocked yes)
			(layer "B.Fab")
			(hide yes)
			(effects
				(font
					(size 1.016 1.016)
					(thickness 0.1524)
				)
				(justify mirror)
			)
		)
		(duplicate_pad_numbers_are_jumpers no)
		(fp_line
			(start -0.635 0)
			(end 0.635 0)
			(stroke
				(width 0.508)
				(type default)
			)
			(layer "B.SilkS")
		)
		(fp_rect
			(start 0.9652 1.778)
			(end -0.9652 -1.778)
			(stroke
				(width 0)
				(type default)
			)
			(fill no)
			(layer "B.CrtYd")
		)
		(fp_poly
			(pts
				(xy 0.9652 -1.778) (xy -0.9652 -1.778) (xy -0.9652 1.778) (xy 0.9652 1.778)
			)
			(stroke
				(width 0)
				(type default)
			)
			(fill no)
			(layer "B.Fab")
		)
		(pad "1" smd rect
			(at 0 -0.9652 180)
			(size 1.397 1.143)
			(layers "B.Cu" "B.Mask" "B.Paste")
			(net "P3V3_STBY_VDD")
		)
		(pad "2" smd rect
			(at 0 0.9652 180)
			(size 1.397 1.143)
			(layers "B.Cu" "B.Mask" "B.Paste")
			(net "GND")
		)
	)
	(footprint ""
		(layer "B.Cu")
		(at 232.537 -20.447)
		(property "Reference" "R819"
			(at 0 0 0)
			(layer "B.SilkS")
			(hide yes)
			(effects
				(font
					(size 1.27 1.27)
				)
				(justify mirror)
			)
		)
		(property "Value" "4K7R2F-GP"
			(at -0.064008 -3.993896 0)
			(unlocked yes)
			(layer "B.Fab")
			(hide yes)
			(effects
				(font
					(size 1.016 1.016)
					(thickness 0.1524)
				)
				(justify mirror)
			)
		)
		(property "Device Type" "R402H16"
			(at -0.064008 -5.517896 0)
			(unlocked yes)
			(layer "B.Fab")
			(hide yes)
			(effects
				(font
					(size 1.016 1.016)
					(thickness 0.1524)
				)
				(justify mirror)
			)
		)
		(duplicate_pad_numbers_are_jumpers no)
		(fp_line
			(start -0.508 -0.9398)
			(end 0.508 -0.9398)
			(stroke
				(width 0.1524)
				(type default)
			)
			(layer "B.SilkS")
		)
		(fp_line
			(start 0.508 -0.9398)
			(end 0.508 0.9398)
			(stroke
				(width 0.1524)
				(type default)
			)
			(layer "B.SilkS")
		)
		(fp_rect
			(start 0.508 0.9398)
			(end -0.508 -0.9398)
			(stroke
				(width 0)
				(type default)
			)
			(fill no)
			(layer "B.CrtYd")
		)
		(fp_rect
			(start 0.508 0.9398)
			(end -0.508 -0.9398)
			(stroke
				(width 0)
				(type default)
			)
			(fill no)
			(layer "B.Fab")
		)
		(pad "1" smd custom
			(at 0 -0.4445 180)
			(size 0.1397 0.1397)
			(layers "B.Cu" "B.Mask" "B.Paste")
			(net "BOOTSTRAP9")
			(options
				(clearance outline)
				(anchor circle)
			)
			(primitives
				(gr_poly
					(pts
						(arc
							(start -0.1778 0.2794)
							(mid -0.249642 0.249642)
							(end -0.2794 0.1778)
						)
						(arc
							(start -0.2794 -0.1778)
							(mid -0.249642 -0.249642)
							(end -0.1778 -0.2794)
						)
						(arc
							(start 0.1778 -0.2794)
							(mid 0.249642 -0.249642)
							(end 0.2794 -0.1778)
						)
						(arc
							(start 0.2794 0.1778)
							(mid 0.249642 0.249642)
							(end 0.1778 0.2794)
						)
					)
					(width 0)
					(fill yes)
				)
			)
		)
		(pad "2" smd custom
			(at 0 0.4445 180)
			(size 0.1397 0.1397)
			(layers "B.Cu" "B.Mask" "B.Paste")
			(net "DUT_VDDO")
			(options
				(clearance outline)
				(anchor circle)
			)
			(primitives
				(gr_poly
					(pts
						(arc
							(start -0.1778 0.2794)
							(mid -0.249642 0.249642)
							(end -0.2794 0.1778)
						)
						(arc
							(start -0.2794 -0.1778)
							(mid -0.249642 -0.249642)
							(end -0.1778 -0.2794)
						)
						(arc
							(start 0.1778 -0.2794)
							(mid 0.249642 -0.249642)
							(end 0.2794 -0.1778)
						)
						(arc
							(start 0.2794 0.1778)
							(mid 0.249642 0.249642)
							(end 0.1778 0.2794)
						)
					)
					(width 0)
					(fill yes)
				)
			)
		)
	)
	(footprint ""
		(layer "B.Cu")
		(at 132.5626 -196.3674)
		(property "Reference" "R4126"
			(at 0 0 0)
			(layer "B.SilkS")
			(hide yes)
			(effects
				(font
					(size 1.27 1.27)
				)
				(justify mirror)
			)
		)
		(property "Value" "4K7R2F-GP"
			(at -0.064008 -3.993896 0)
			(unlocked yes)
			(layer "B.Fab")
			(hide yes)
			(effects
				(font
					(size 1.016 1.016)
					(thickness 0.1524)
				)
				(justify mirror)
			)
		)
		(property "Device Type" "R402H16"
			(at -0.064008 -5.517896 0)
			(unlocked yes)
			(layer "B.Fab")
			(hide yes)
			(effects
				(font
					(size 1.016 1.016)
					(thickness 0.1524)
				)
				(justify mirror)
			)
		)
		(duplicate_pad_numbers_are_jumpers no)
		(fp_line
			(start -0.508 -0.9398)
			(end 0.508 -0.9398)
			(stroke
				(width 0.1524)
				(type default)
			)
			(layer "B.SilkS")
		)
		(fp_line
			(start 0.508 -0.9398)
			(end 0.508 0.9398)
			(stroke
				(width 0.1524)
				(type default)
			)
			(layer "B.SilkS")
		)
		(fp_rect
			(start 0.508 0.9398)
			(end -0.508 -0.9398)
			(stroke
				(width 0)
				(type default)
			)
			(fill no)
			(layer "B.CrtYd")
		)
		(fp_rect
			(start 0.508 0.9398)
			(end -0.508 -0.9398)
			(stroke
				(width 0)
				(type default)
			)
			(fill no)
			(layer "B.Fab")
		)
		(pad "1" smd custom
			(at 0 -0.4445 180)
			(size 0.1397 0.1397)
			(layers "B.Cu" "B.Mask" "B.Paste")
			(net "SSD_ATNLED#2")
			(options
				(clearance outline)
				(anchor circle)
			)
			(primitives
				(gr_poly
					(pts
						(arc
							(start -0.1778 0.2794)
							(mid -0.249642 0.249642)
							(end -0.2794 0.1778)
						)
						(arc
							(start -0.2794 -0.1778)
							(mid -0.249642 -0.249642)
							(end -0.1778 -0.2794)
						)
						(arc
							(start 0.1778 -0.2794)
							(mid 0.249642 -0.249642)
							(end 0.2794 -0.1778)
						)
						(arc
							(start 0.2794 0.1778)
							(mid 0.249642 0.249642)
							(end 0.1778 0.2794)
						)
					)
					(width 0)
					(fill yes)
				)
			)
		)
		(pad "2" smd custom
			(at 0 0.4445 180)
			(size 0.1397 0.1397)
			(layers "B.Cu" "B.Mask" "B.Paste")
			(net "P3V3_STBY")
			(options
				(clearance outline)
				(anchor circle)
			)
			(primitives
				(gr_poly
					(pts
						(arc
							(start -0.1778 0.2794)
							(mid -0.249642 0.249642)
							(end -0.2794 0.1778)
						)
						(arc
							(start -0.2794 -0.1778)
							(mid -0.249642 -0.249642)
							(end -0.1778 -0.2794)
						)
						(arc
							(start 0.1778 -0.2794)
							(mid 0.249642 -0.249642)
							(end 0.2794 -0.1778)
						)
						(arc
							(start 0.2794 0.1778)
							(mid 0.249642 0.249642)
							(end 0.1778 0.2794)
						)
					)
					(width 0)
					(fill yes)
				)
			)
		)
	)
	(footprint ""
		(layer "B.Cu")
		(at 316.103 -68.58 180)
		(property "Reference" "PC179"
			(at 0 0 0)
			(layer "B.SilkS")
			(hide yes)
			(effects
				(font
					(size 1.27 1.27)
				)
				(justify mirror)
			)
		)
		(property "Value" "SC22U6D3V5MX-5-GP"
			(at 0.0762 -6.1214 180)
			(unlocked yes)
			(layer "B.Fab")
			(hide yes)
			(effects
				(font
					(size 1.016 1.016)
					(thickness 0.1524)
				)
				(justify mirror)
			)
		)
		(property "Device Type" "C805H56"
			(at 0.0762 -8.1534 180)
			(unlocked yes)
			(layer "B.Fab")
			(hide yes)
			(effects
				(font
					(size 1.016 1.016)
					(thickness 0.1524)
				)
				(justify mirror)
			)
		)
		(duplicate_pad_numbers_are_jumpers no)
		(fp_line
			(start -0.635 0)
			(end 0.635 0)
			(stroke
				(width 0.508)
				(type default)
			)
			(layer "B.SilkS")
		)
		(fp_rect
			(start 0.9652 1.778)
			(end -0.9652 -1.778)
			(stroke
				(width 0)
				(type default)
			)
			(fill no)
			(layer "B.CrtYd")
		)
		(fp_poly
			(pts
				(xy 0.9652 -1.778) (xy -0.9652 -1.778) (xy -0.9652 1.778) (xy 0.9652 1.778)
			)
			(stroke
				(width 0)
				(type default)
			)
			(fill no)
			(layer "B.Fab")
		)
		(pad "1" smd rect
			(at 0 -0.9652)
			(size 1.397 1.143)
			(layers "B.Cu" "B.Mask" "B.Paste")
			(net "P0V9_E")
		)
		(pad "2" smd rect
			(at 0 0.9652)
			(size 1.397 1.143)
			(layers "B.Cu" "B.Mask" "B.Paste")
			(net "GND")
		)
	)
	(footprint ""
		(layer "B.Cu")
		(at 243.459 -32.004 90)
		(property "Reference" "C473"
			(at 0 0 90)
			(layer "B.SilkS")
			(hide yes)
			(effects
				(font
					(size 1.27 1.27)
				)
				(justify mirror)
			)
		)
		(property "Value" "SCD1U16V1KX-1-GP"
			(at 2.8321 -1.7399 90)
			(unlocked yes)
			(layer "B.Fab")
			(hide yes)
			(effects
				(font
					(size 1.016 1.016)
					(thickness 0.1524)
				)
				(justify mirror)
			)
		)
		(property "Device Type" "C0201H13"
			(at 2.8321 -3.2639 90)
			(unlocked yes)
			(layer "B.Fab")
			(hide yes)
			(effects
				(font
					(size 1.016 1.016)
					(thickness 0.1524)
				)
				(justify mirror)
			)
		)
		(duplicate_pad_numbers_are_jumpers no)
		(fp_rect
			(start 0.2794 0.6477)
			(end -0.2794 -0.6477)
			(stroke
				(width 0)
				(type default)
			)
			(fill no)
			(layer "B.CrtYd")
		)
		(fp_rect
			(start 0.2794 0.6477)
			(end -0.2794 -0.6477)
			(stroke
				(width 0)
				(type default)
			)
			(fill no)
			(layer "B.Fab")
		)
		(pad "1" smd custom
			(at 0 -0.2794 270)
			(size 0.0762 0.0762)
			(layers "B.Cu" "B.Mask" "B.Paste")
			(net "DUT_VDDO")
			(options
				(clearance outline)
				(anchor circle)
			)
			(primitives
				(gr_poly
					(pts
						(arc
							(start 0.1524 0.127)
							(mid 0.137521 0.162921)
							(end 0.1016 0.1778)
						)
						(arc
							(start -0.1016 0.1778)
							(mid -0.137521 0.162921)
							(end -0.1524 0.127)
						)
						(arc
							(start -0.1524 -0.127)
							(mid -0.137521 -0.162921)
							(end -0.1016 -0.1778)
						)
						(arc
							(start 0.1016 -0.1778)
							(mid 0.137521 -0.162921)
							(end 0.1524 -0.127)
						)
					)
					(width 0)
					(fill yes)
				)
			)
		)
		(pad "2" smd custom
			(at 0 0.2794 270)
			(size 0.0762 0.0762)
			(layers "B.Cu" "B.Mask" "B.Paste")
			(net "GND")
			(options
				(clearance outline)
				(anchor circle)
			)
			(primitives
				(gr_poly
					(pts
						(arc
							(start 0.1524 0.127)
							(mid 0.137521 0.162921)
							(end 0.1016 0.1778)
						)
						(arc
							(start -0.1016 0.1778)
							(mid -0.137521 0.162921)
							(end -0.1524 0.127)
						)
						(arc
							(start -0.1524 -0.127)
							(mid -0.137521 -0.162921)
							(end -0.1016 -0.1778)
						)
						(arc
							(start 0.1016 -0.1778)
							(mid 0.137521 -0.162921)
							(end 0.1524 -0.127)
						)
					)
					(width 0)
					(fill yes)
				)
			)
		)
	)
	(footprint ""
		(layer "B.Cu")
		(at 234.823 -23.241 180)
		(property "Reference" "R784"
			(at 0 0 0)
			(layer "B.SilkS")
			(hide yes)
			(effects
				(font
					(size 1.27 1.27)
				)
				(justify mirror)
			)
		)
		(property "Value" "4K7R2F-GP"
			(at -0.064008 -3.993896 180)
			(unlocked yes)
			(layer "B.Fab")
			(hide yes)
			(effects
				(font
					(size 1.016 1.016)
					(thickness 0.1524)
				)
				(justify mirror)
			)
		)
		(property "Device Type" "R402H16"
			(at -0.064008 -5.517896 180)
			(unlocked yes)
			(layer "B.Fab")
			(hide yes)
			(effects
				(font
					(size 1.016 1.016)
					(thickness 0.1524)
				)
				(justify mirror)
			)
		)
		(duplicate_pad_numbers_are_jumpers no)
		(fp_line
			(start 0.508 -0.9398)
			(end 0.508 0.9398)
			(stroke
				(width 0.1524)
				(type default)
			)
			(layer "B.SilkS")
		)
		(fp_line
			(start -0.508 -0.9398)
			(end 0.508 -0.9398)
			(stroke
				(width 0.1524)
				(type default)
			)
			(layer "B.SilkS")
		)
		(fp_rect
			(start 0.508 0.9398)
			(end -0.508 -0.9398)
			(stroke
				(width 0)
				(type default)
			)
			(fill no)
			(layer "B.CrtYd")
		)
		(fp_rect
			(start 0.508 0.9398)
			(end -0.508 -0.9398)
			(stroke
				(width 0)
				(type default)
			)
			(fill no)
			(layer "B.Fab")
		)
		(pad "1" smd custom
			(at 0 -0.4445)
			(size 0.1397 0.1397)
			(layers "B.Cu" "B.Mask" "B.Paste")
			(net "BOOTSTRAP4")
			(options
				(clearance outline)
				(anchor circle)
			)
			(primitives
				(gr_poly
					(pts
						(arc
							(start -0.1778 0.2794)
							(mid -0.249642 0.249642)
							(end -0.2794 0.1778)
						)
						(arc
							(start -0.2794 -0.1778)
							(mid -0.249642 -0.249642)
							(end -0.1778 -0.2794)
						)
						(arc
							(start 0.1778 -0.2794)
							(mid 0.249642 -0.249642)
							(end 0.2794 -0.1778)
						)
						(arc
							(start 0.2794 0.1778)
							(mid 0.249642 0.249642)
							(end 0.1778 0.2794)
						)
					)
					(width 0)
					(fill yes)
				)
			)
		)
		(pad "2" smd custom
			(at 0 0.4445)
			(size 0.1397 0.1397)
			(layers "B.Cu" "B.Mask" "B.Paste")
			(net "BOOTSTRAP_R_4")
			(options
				(clearance outline)
				(anchor circle)
			)
			(primitives
				(gr_poly
					(pts
						(arc
							(start -0.1778 0.2794)
							(mid -0.249642 0.249642)
							(end -0.2794 0.1778)
						)
						(arc
							(start -0.2794 -0.1778)
							(mid -0.249642 -0.249642)
							(end -0.1778 -0.2794)
						)
						(arc
							(start 0.1778 -0.2794)
							(mid 0.249642 -0.249642)
							(end 0.2794 -0.1778)
						)
						(arc
							(start 0.2794 0.1778)
							(mid 0.249642 0.249642)
							(end 0.1778 0.2794)
						)
					)
					(width 0)
					(fill yes)
				)
			)
		)
	)
	(footprint ""
		(layer "B.Cu")
		(at 243.59997 -38.999922 -90)
		(property "Reference" "TP239"
			(at 0 0 90)
			(layer "B.SilkS")
			(hide yes)
			(effects
				(font
					(size 1.27 1.27)
				)
				(justify mirror)
			)
		)
		(property "Value" "TPAD28-2-GP"
			(at 0.0127 -1.6637 270)
			(unlocked yes)
			(layer "B.Fab")
			(hide yes)
			(effects
				(font
					(size 1.016 1.016)
					(thickness 0.1524)
				)
				(justify mirror)
			)
		)
		(property "Device Type" "TPAD28"
			(at 0.0127 -3.1877 270)
			(unlocked yes)
			(layer "B.Fab")
			(hide yes)
			(effects
				(font
					(size 1.016 1.016)
					(thickness 0.1524)
				)
				(justify mirror)
			)
		)
		(duplicate_pad_numbers_are_jumpers no)
		(fp_poly
			(pts
				(arc
					(start 0 -0.3556)
					(mid 0 0.3556)
					(end 0 -0.3556)
				)
			)
			(stroke
				(width 0)
				(type default)
			)
			(fill no)
			(layer "B.CrtYd")
		)
		(fp_poly
			(pts
				(arc
					(start 0 -0.6096)
					(mid 0 0.6096)
					(end 0 -0.6096)
				)
			)
			(stroke
				(width 0)
				(type default)
			)
			(fill no)
			(layer "B.Fab")
		)
		(pad "1" smd circle
			(at 0 0 90)
			(size 0.7112 0.7112)
			(layers "B.Cu" "B.Mask" "B.Paste")
			(net "RS232_URTSB0")
		)
	)
	(footprint ""
		(layer "B.Cu")
		(at 184.0484 -61.595)
		(property "Reference" "C584"
			(at 0 0 0)
			(layer "B.SilkS")
			(hide yes)
			(effects
				(font
					(size 1.27 1.27)
				)
				(justify mirror)
			)
		)
		(property "Value" "SC4D7U16V5KX-1-GP"
			(at 0.0762 -6.1214 0)
			(unlocked yes)
			(layer "B.Fab")
			(hide yes)
			(effects
				(font
					(size 1.016 1.016)
					(thickness 0.1524)
				)
				(justify mirror)
			)
		)
		(property "Device Type" "C805H56"
			(at 0.0762 -8.1534 0)
			(unlocked yes)
			(layer "B.Fab")
			(hide yes)
			(effects
				(font
					(size 1.016 1.016)
					(thickness 0.1524)
				)
				(justify mirror)
			)
		)
		(duplicate_pad_numbers_are_jumpers no)
		(fp_line
			(start -0.635 0)
			(end 0.635 0)
			(stroke
				(width 0.508)
				(type default)
			)
			(layer "B.SilkS")
		)
		(fp_rect
			(start 0.9652 1.778)
			(end -0.9652 -1.778)
			(stroke
				(width 0)
				(type default)
			)
			(fill no)
			(layer "B.CrtYd")
		)
		(fp_poly
			(pts
				(xy 0.9652 -1.778) (xy -0.9652 -1.778) (xy -0.9652 1.778) (xy 0.9652 1.778)
			)
			(stroke
				(width 0)
				(type default)
			)
			(fill no)
			(layer "B.Fab")
		)
		(pad "1" smd rect
			(at 0 -0.9652 180)
			(size 1.397 1.143)
			(layers "B.Cu" "B.Mask" "B.Paste")
			(net "DUT_AVD_PCIE")
		)
		(pad "2" smd rect
			(at 0 0.9652 180)
			(size 1.397 1.143)
			(layers "B.Cu" "B.Mask" "B.Paste")
			(net "GND")
		)
	)
	(footprint ""
		(layer "B.Cu")
		(at 50.2158 -115.90909)
		(property "Reference" "R471"
			(at 0 0 0)
			(layer "B.SilkS")
			(hide yes)
			(effects
				(font
					(size 1.27 1.27)
				)
				(justify mirror)
			)
		)
		(property "Value" "0R2J-2-GP"
			(at -0.064008 -3.993896 0)
			(unlocked yes)
			(layer "B.Fab")
			(hide yes)
			(effects
				(font
					(size 1.016 1.016)
					(thickness 0.1524)
				)
				(justify mirror)
			)
		)
		(property "Device Type" "R402H16"
			(at -0.064008 -5.517896 0)
			(unlocked yes)
			(layer "B.Fab")
			(hide yes)
			(effects
				(font
					(size 1.016 1.016)
					(thickness 0.1524)
				)
				(justify mirror)
			)
		)
		(duplicate_pad_numbers_are_jumpers no)
		(fp_line
			(start -0.508 -0.9398)
			(end 0.508 -0.9398)
			(stroke
				(width 0.1524)
				(type default)
			)
			(layer "B.SilkS")
		)
		(fp_line
			(start 0.508 -0.9398)
			(end 0.508 0.9398)
			(stroke
				(width 0.1524)
				(type default)
			)
			(layer "B.SilkS")
		)
		(fp_rect
			(start 0.508 0.9398)
			(end -0.508 -0.9398)
			(stroke
				(width 0)
				(type default)
			)
			(fill no)
			(layer "B.CrtYd")
		)
		(fp_rect
			(start 0.508 0.9398)
			(end -0.508 -0.9398)
			(stroke
				(width 0)
				(type default)
			)
			(fill no)
			(layer "B.Fab")
		)
		(pad "1" smd custom
			(at 0 -0.4445 180)
			(size 0.1397 0.1397)
			(layers "B.Cu" "B.Mask" "B.Paste")
			(net "BMC0_SMB10_CLK")
			(options
				(clearance outline)
				(anchor circle)
			)
			(primitives
				(gr_poly
					(pts
						(arc
							(start -0.1778 0.2794)
							(mid -0.249642 0.249642)
							(end -0.2794 0.1778)
						)
						(arc
							(start -0.2794 -0.1778)
							(mid -0.249642 -0.249642)
							(end -0.1778 -0.2794)
						)
						(arc
							(start 0.1778 -0.2794)
							(mid 0.249642 -0.249642)
							(end 0.2794 -0.1778)
						)
						(arc
							(start 0.2794 0.1778)
							(mid 0.249642 0.249642)
							(end 0.1778 0.2794)
						)
					)
					(width 0)
					(fill yes)
				)
			)
		)
		(pad "2" smd custom
			(at 0 0.4445 180)
			(size 0.1397 0.1397)
			(layers "B.Cu" "B.Mask" "B.Paste")
			(net "BMC_I2C10_8536_SCL")
			(options
				(clearance outline)
				(anchor circle)
			)
			(primitives
				(gr_poly
					(pts
						(arc
							(start -0.1778 0.2794)
							(mid -0.249642 0.249642)
							(end -0.2794 0.1778)
						)
						(arc
							(start -0.2794 -0.1778)
							(mid -0.249642 -0.249642)
							(end -0.1778 -0.2794)
						)
						(arc
							(start 0.1778 -0.2794)
							(mid 0.249642 -0.249642)
							(end 0.2794 -0.1778)
						)
						(arc
							(start 0.2794 0.1778)
							(mid 0.249642 0.249642)
							(end 0.1778 0.2794)
						)
					)
					(width 0)
					(fill yes)
				)
			)
		)
	)
	(footprint ""
		(layer "B.Cu")
		(at 239.6236 -37.0332 180)
		(property "Reference" "R5"
			(at 0 0 0)
			(layer "B.SilkS")
			(hide yes)
			(effects
				(font
					(size 1.27 1.27)
				)
				(justify mirror)
			)
		)
		(property "Value" "33R1J-GP"
			(at 3.3274 -1.3335 180)
			(unlocked yes)
			(layer "B.Fab")
			(hide yes)
			(effects
				(font
					(size 1.016 1.016)
					(thickness 0.1524)
				)
				(justify mirror)
			)
		)
		(property "Device Type" "R0201H12"
			(at 3.3274 -2.8575 180)
			(unlocked yes)
			(layer "B.Fab")
			(hide yes)
			(effects
				(font
					(size 1.016 1.016)
					(thickness 0.1524)
				)
				(justify mirror)
			)
		)
		(duplicate_pad_numbers_are_jumpers no)
		(fp_rect
			(start 0.2794 0.6477)
			(end -0.2794 -0.6477)
			(stroke
				(width 0)
				(type default)
			)
			(fill no)
			(layer "B.CrtYd")
		)
		(fp_rect
			(start 0.2794 0.6477)
			(end -0.2794 -0.6477)
			(stroke
				(width 0)
				(type default)
			)
			(fill no)
			(layer "B.Fab")
		)
		(pad "1" smd custom
			(at 0 -0.2794)
			(size 0.0762 0.0762)
			(layers "B.Cu" "B.Mask" "B.Paste")
			(net "PCIE_REFCLK_D_N")
			(options
				(clearance outline)
				(anchor circle)
			)
			(primitives
				(gr_poly
					(pts
						(arc
							(start 0.1524 0.127)
							(mid 0.137521 0.162921)
							(end 0.1016 0.1778)
						)
						(arc
							(start -0.1016 0.1778)
							(mid -0.137521 0.162921)
							(end -0.1524 0.127)
						)
						(arc
							(start -0.1524 -0.127)
							(mid -0.137521 -0.162921)
							(end -0.1016 -0.1778)
						)
						(arc
							(start 0.1016 -0.1778)
							(mid 0.137521 -0.162921)
							(end 0.1524 -0.127)
						)
					)
					(width 0)
					(fill yes)
				)
			)
		)
		(pad "2" smd custom
			(at 0 0.2794)
			(size 0.0762 0.0762)
			(layers "B.Cu" "B.Mask" "B.Paste")
			(net "PCIE_REFCLK_D_P")
			(options
				(clearance outline)
				(anchor circle)
			)
			(primitives
				(gr_poly
					(pts
						(arc
							(start 0.1524 0.127)
							(mid 0.137521 0.162921)
							(end 0.1016 0.1778)
						)
						(arc
							(start -0.1016 0.1778)
							(mid -0.137521 0.162921)
							(end -0.1524 0.127)
						)
						(arc
							(start -0.1524 -0.127)
							(mid -0.137521 -0.162921)
							(end -0.1016 -0.1778)
						)
						(arc
							(start 0.1016 -0.1778)
							(mid 0.137521 -0.162921)
							(end 0.1524 -0.127)
						)
					)
					(width 0)
					(fill yes)
				)
			)
		)
	)
	(footprint ""
		(layer "B.Cu")
		(at 57.032652 -117.4242 -90)
		(property "Reference" "R242"
			(at 0 0 90)
			(layer "B.SilkS")
			(hide yes)
			(effects
				(font
					(size 1.27 1.27)
				)
				(justify mirror)
			)
		)
		(property "Value" "0R2J-2-GP"
			(at -0.064008 -3.993896 270)
			(unlocked yes)
			(layer "B.Fab")
			(hide yes)
			(effects
				(font
					(size 1.016 1.016)
					(thickness 0.1524)
				)
				(justify mirror)
			)
		)
		(property "Device Type" "R402H16"
			(at -0.064008 -5.517896 270)
			(unlocked yes)
			(layer "B.Fab")
			(hide yes)
			(effects
				(font
					(size 1.016 1.016)
					(thickness 0.1524)
				)
				(justify mirror)
			)
		)
		(duplicate_pad_numbers_are_jumpers no)
		(fp_line
			(start -0.508 -0.9398)
			(end 0.508 -0.9398)
			(stroke
				(width 0.1524)
				(type default)
			)
			(layer "B.SilkS")
		)
		(fp_line
			(start 0.508 -0.9398)
			(end 0.508 0.9398)
			(stroke
				(width 0.1524)
				(type default)
			)
			(layer "B.SilkS")
		)
		(fp_rect
			(start 0.508 0.9398)
			(end -0.508 -0.9398)
			(stroke
				(width 0)
				(type default)
			)
			(fill no)
			(layer "B.CrtYd")
		)
		(fp_rect
			(start 0.508 0.9398)
			(end -0.508 -0.9398)
			(stroke
				(width 0)
				(type default)
			)
			(fill no)
			(layer "B.Fab")
		)
		(pad "1" smd custom
			(at 0 -0.4445 90)
			(size 0.1397 0.1397)
			(layers "B.Cu" "B.Mask" "B.Paste")
			(net "BMC_I2C3_MINI3_SCL_S")
			(options
				(clearance outline)
				(anchor circle)
			)
			(primitives
				(gr_poly
					(pts
						(arc
							(start -0.1778 0.2794)
							(mid -0.249642 0.249642)
							(end -0.2794 0.1778)
						)
						(arc
							(start -0.2794 -0.1778)
							(mid -0.249642 -0.249642)
							(end -0.1778 -0.2794)
						)
						(arc
							(start 0.1778 -0.2794)
							(mid 0.249642 -0.249642)
							(end 0.2794 -0.1778)
						)
						(arc
							(start 0.2794 0.1778)
							(mid 0.249642 0.249642)
							(end 0.1778 0.2794)
						)
					)
					(width 0)
					(fill yes)
				)
			)
		)
		(pad "2" smd custom
			(at 0 0.4445 90)
			(size 0.1397 0.1397)
			(layers "B.Cu" "B.Mask" "B.Paste")
			(net "BMC0_SMB3_CLK")
			(options
				(clearance outline)
				(anchor circle)
			)
			(primitives
				(gr_poly
					(pts
						(arc
							(start -0.1778 0.2794)
							(mid -0.249642 0.249642)
							(end -0.2794 0.1778)
						)
						(arc
							(start -0.2794 -0.1778)
							(mid -0.249642 -0.249642)
							(end -0.1778 -0.2794)
						)
						(arc
							(start 0.1778 -0.2794)
							(mid 0.249642 -0.249642)
							(end 0.2794 -0.1778)
						)
						(arc
							(start 0.2794 0.1778)
							(mid 0.249642 0.249642)
							(end 0.1778 0.2794)
						)
					)
					(width 0)
					(fill yes)
				)
			)
		)
	)
	(footprint ""
		(layer "B.Cu")
		(at 134.62 -202.565)
		(property "Reference" "R142"
			(at 0 0 0)
			(layer "B.SilkS")
			(hide yes)
			(effects
				(font
					(size 1.27 1.27)
				)
				(justify mirror)
			)
		)
		(property "Value" "4K7R2F-GP"
			(at -0.064008 -3.993896 0)
			(unlocked yes)
			(layer "B.Fab")
			(hide yes)
			(effects
				(font
					(size 1.016 1.016)
					(thickness 0.1524)
				)
				(justify mirror)
			)
		)
		(property "Device Type" "R402H16"
			(at -0.064008 -5.517896 0)
			(unlocked yes)
			(layer "B.Fab")
			(hide yes)
			(effects
				(font
					(size 1.016 1.016)
					(thickness 0.1524)
				)
				(justify mirror)
			)
		)
		(duplicate_pad_numbers_are_jumpers no)
		(fp_line
			(start -0.508 -0.9398)
			(end 0.508 -0.9398)
			(stroke
				(width 0.1524)
				(type default)
			)
			(layer "B.SilkS")
		)
		(fp_line
			(start 0.508 -0.9398)
			(end 0.508 0.9398)
			(stroke
				(width 0.1524)
				(type default)
			)
			(layer "B.SilkS")
		)
		(fp_rect
			(start 0.508 0.9398)
			(end -0.508 -0.9398)
			(stroke
				(width 0)
				(type default)
			)
			(fill no)
			(layer "B.CrtYd")
		)
		(fp_rect
			(start 0.508 0.9398)
			(end -0.508 -0.9398)
			(stroke
				(width 0)
				(type default)
			)
			(fill no)
			(layer "B.Fab")
		)
		(pad "1" smd custom
			(at 0 -0.4445 180)
			(size 0.1397 0.1397)
			(layers "B.Cu" "B.Mask" "B.Paste")
			(net "BMC_SSD_RST#0_A6")
			(options
				(clearance outline)
				(anchor circle)
			)
			(primitives
				(gr_poly
					(pts
						(arc
							(start -0.1778 0.2794)
							(mid -0.249642 0.249642)
							(end -0.2794 0.1778)
						)
						(arc
							(start -0.2794 -0.1778)
							(mid -0.249642 -0.249642)
							(end -0.1778 -0.2794)
						)
						(arc
							(start 0.1778 -0.2794)
							(mid 0.249642 -0.249642)
							(end 0.2794 -0.1778)
						)
						(arc
							(start 0.2794 0.1778)
							(mid 0.249642 0.249642)
							(end 0.1778 0.2794)
						)
					)
					(width 0)
					(fill yes)
				)
			)
		)
		(pad "2" smd custom
			(at 0 0.4445 180)
			(size 0.1397 0.1397)
			(layers "B.Cu" "B.Mask" "B.Paste")
			(net "P3V3_STBY")
			(options
				(clearance outline)
				(anchor circle)
			)
			(primitives
				(gr_poly
					(pts
						(arc
							(start -0.1778 0.2794)
							(mid -0.249642 0.249642)
							(end -0.2794 0.1778)
						)
						(arc
							(start -0.2794 -0.1778)
							(mid -0.249642 -0.249642)
							(end -0.1778 -0.2794)
						)
						(arc
							(start 0.1778 -0.2794)
							(mid 0.249642 -0.249642)
							(end 0.2794 -0.1778)
						)
						(arc
							(start 0.2794 0.1778)
							(mid 0.249642 0.249642)
							(end 0.1778 0.2794)
						)
					)
					(width 0)
					(fill yes)
				)
			)
		)
	)
	(footprint ""
		(layer "B.Cu")
		(at 69.699124 -183.235092 180)
		(property "Reference" "R521"
			(at 0 0 0)
			(layer "B.SilkS")
			(hide yes)
			(effects
				(font
					(size 1.27 1.27)
				)
				(justify mirror)
			)
		)
		(property "Value" "10KR2F-2-GP"
			(at -0.064008 -3.993896 180)
			(unlocked yes)
			(layer "B.Fab")
			(hide yes)
			(effects
				(font
					(size 1.016 1.016)
					(thickness 0.1524)
				)
				(justify mirror)
			)
		)
		(property "Device Type" "R402H16"
			(at -0.064008 -5.517896 180)
			(unlocked yes)
			(layer "B.Fab")
			(hide yes)
			(effects
				(font
					(size 1.016 1.016)
					(thickness 0.1524)
				)
				(justify mirror)
			)
		)
		(duplicate_pad_numbers_are_jumpers no)
		(fp_line
			(start 0.508 -0.9398)
			(end 0.508 0.9398)
			(stroke
				(width 0.1524)
				(type default)
			)
			(layer "B.SilkS")
		)
		(fp_line
			(start -0.508 -0.9398)
			(end 0.508 -0.9398)
			(stroke
				(width 0.1524)
				(type default)
			)
			(layer "B.SilkS")
		)
		(fp_rect
			(start 0.508 0.9398)
			(end -0.508 -0.9398)
			(stroke
				(width 0)
				(type default)
			)
			(fill no)
			(layer "B.CrtYd")
		)
		(fp_rect
			(start 0.508 0.9398)
			(end -0.508 -0.9398)
			(stroke
				(width 0)
				(type default)
			)
			(fill no)
			(layer "B.Fab")
		)
		(pad "1" smd custom
			(at 0 -0.4445)
			(size 0.1397 0.1397)
			(layers "B.Cu" "B.Mask" "B.Paste")
			(net "P3V3_STBY")
			(options
				(clearance outline)
				(anchor circle)
			)
			(primitives
				(gr_poly
					(pts
						(arc
							(start -0.1778 0.2794)
							(mid -0.249642 0.249642)
							(end -0.2794 0.1778)
						)
						(arc
							(start -0.2794 -0.1778)
							(mid -0.249642 -0.249642)
							(end -0.1778 -0.2794)
						)
						(arc
							(start 0.1778 -0.2794)
							(mid 0.249642 -0.249642)
							(end 0.2794 -0.1778)
						)
						(arc
							(start 0.2794 0.1778)
							(mid 0.249642 0.249642)
							(end 0.1778 0.2794)
						)
					)
					(width 0)
					(fill yes)
				)
			)
		)
		(pad "2" smd custom
			(at 0 0.4445)
			(size 0.1397 0.1397)
			(layers "B.Cu" "B.Mask" "B.Paste")
			(net "IOEXP1_AD1")
			(options
				(clearance outline)
				(anchor circle)
			)
			(primitives
				(gr_poly
					(pts
						(arc
							(start -0.1778 0.2794)
							(mid -0.249642 0.249642)
							(end -0.2794 0.1778)
						)
						(arc
							(start -0.2794 -0.1778)
							(mid -0.249642 -0.249642)
							(end -0.1778 -0.2794)
						)
						(arc
							(start 0.1778 -0.2794)
							(mid 0.249642 -0.249642)
							(end 0.2794 -0.1778)
						)
						(arc
							(start 0.2794 0.1778)
							(mid 0.249642 0.249642)
							(end 0.1778 0.2794)
						)
					)
					(width 0)
					(fill yes)
				)
			)
		)
	)
	(footprint ""
		(layer "B.Cu")
		(at 56.134 -132.08)
		(property "Reference" "C8087"
			(at 0 0 0)
			(layer "B.SilkS")
			(hide yes)
			(effects
				(font
					(size 1.27 1.27)
				)
				(justify mirror)
			)
		)
		(property "Value" "SCD1U25V2KX-2-GP"
			(at -1.1811 -2.7051 0)
			(unlocked yes)
			(layer "B.Fab")
			(hide yes)
			(effects
				(font
					(size 1.016 1.016)
					(thickness 0.1524)
				)
				(justify mirror)
			)
		)
		(property "Device Type" "C402H22"
			(at -1.1811 -4.2291 0)
			(unlocked yes)
			(layer "B.Fab")
			(hide yes)
			(effects
				(font
					(size 1.016 1.016)
					(thickness 0.1524)
				)
				(justify mirror)
			)
		)
		(duplicate_pad_numbers_are_jumpers no)
		(fp_rect
			(start 0.4318 0.9525)
			(end -0.4318 -0.9525)
			(stroke
				(width 0)
				(type default)
			)
			(fill no)
			(layer "B.CrtYd")
		)
		(fp_rect
			(start 0.4318 0.9525)
			(end -0.4318 -0.9525)
			(stroke
				(width 0)
				(type default)
			)
			(fill no)
			(layer "B.Fab")
		)
		(pad "1" smd custom
			(at 0 -0.4445 180)
			(size 0.1524 0.1524)
			(layers "B.Cu" "B.Mask" "B.Paste")
			(net "ADC_P3V3_STBY")
			(options
				(clearance outline)
				(anchor circle)
			)
			(primitives
				(gr_poly
					(pts
						(arc
							(start 0.3048 0.2032)
							(mid 0.275042 0.275042)
							(end 0.2032 0.3048)
						)
						(arc
							(start -0.2032 0.3048)
							(mid -0.275042 0.275042)
							(end -0.3048 0.2032)
						)
						(arc
							(start -0.3048 -0.2032)
							(mid -0.275042 -0.275042)
							(end -0.2032 -0.3048)
						)
						(arc
							(start 0.2032 -0.3048)
							(mid 0.275042 -0.275042)
							(end 0.3048 -0.2032)
						)
					)
					(width 0)
					(fill yes)
				)
			)
		)
		(pad "2" smd custom
			(at 0 0.4445 180)
			(size 0.1524 0.1524)
			(layers "B.Cu" "B.Mask" "B.Paste")
			(net "GND")
			(options
				(clearance outline)
				(anchor circle)
			)
			(primitives
				(gr_poly
					(pts
						(arc
							(start 0.3048 0.2032)
							(mid 0.275042 0.275042)
							(end 0.2032 0.3048)
						)
						(arc
							(start -0.2032 0.3048)
							(mid -0.275042 0.275042)
							(end -0.3048 0.2032)
						)
						(arc
							(start -0.3048 -0.2032)
							(mid -0.275042 -0.275042)
							(end -0.2032 -0.3048)
						)
						(arc
							(start 0.2032 -0.3048)
							(mid 0.275042 -0.275042)
							(end 0.3048 -0.2032)
						)
					)
					(width 0)
					(fill yes)
				)
			)
		)
	)
	(footprint ""
		(layer "B.Cu")
		(at 224.079562 -194.05473)
		(property "Reference" "R3227"
			(at 0 0 0)
			(layer "B.SilkS")
			(hide yes)
			(effects
				(font
					(size 1.27 1.27)
				)
				(justify mirror)
			)
		)
		(property "Value" "0R2J-2-GP"
			(at -0.064008 -3.993896 0)
			(unlocked yes)
			(layer "B.Fab")
			(hide yes)
			(effects
				(font
					(size 1.016 1.016)
					(thickness 0.1524)
				)
				(justify mirror)
			)
		)
		(property "Device Type" "R402H16"
			(at -0.064008 -5.517896 0)
			(unlocked yes)
			(layer "B.Fab")
			(hide yes)
			(effects
				(font
					(size 1.016 1.016)
					(thickness 0.1524)
				)
				(justify mirror)
			)
		)
		(duplicate_pad_numbers_are_jumpers no)
		(fp_line
			(start -0.508 -0.9398)
			(end 0.508 -0.9398)
			(stroke
				(width 0.1524)
				(type default)
			)
			(layer "B.SilkS")
		)
		(fp_line
			(start 0.508 -0.9398)
			(end 0.508 0.9398)
			(stroke
				(width 0.1524)
				(type default)
			)
			(layer "B.SilkS")
		)
		(fp_rect
			(start 0.508 0.9398)
			(end -0.508 -0.9398)
			(stroke
				(width 0)
				(type default)
			)
			(fill no)
			(layer "B.CrtYd")
		)
		(fp_rect
			(start 0.508 0.9398)
			(end -0.508 -0.9398)
			(stroke
				(width 0)
				(type default)
			)
			(fill no)
			(layer "B.Fab")
		)
		(pad "1" smd custom
			(at 0 -0.4445 180)
			(size 0.1397 0.1397)
			(layers "B.Cu" "B.Mask" "B.Paste")
			(net "SSD_PERST_Y8")
			(options
				(clearance outline)
				(anchor circle)
			)
			(primitives
				(gr_poly
					(pts
						(arc
							(start -0.1778 0.2794)
							(mid -0.249642 0.249642)
							(end -0.2794 0.1778)
						)
						(arc
							(start -0.2794 -0.1778)
							(mid -0.249642 -0.249642)
							(end -0.1778 -0.2794)
						)
						(arc
							(start 0.1778 -0.2794)
							(mid 0.249642 -0.249642)
							(end 0.2794 -0.1778)
						)
						(arc
							(start 0.2794 0.1778)
							(mid 0.249642 0.249642)
							(end 0.1778 0.2794)
						)
					)
					(width 0)
					(fill yes)
				)
			)
		)
		(pad "2" smd custom
			(at 0 0.4445 180)
			(size 0.1397 0.1397)
			(layers "B.Cu" "B.Mask" "B.Paste")
			(net "SSD_PERST#8_R")
			(options
				(clearance outline)
				(anchor circle)
			)
			(primitives
				(gr_poly
					(pts
						(arc
							(start -0.1778 0.2794)
							(mid -0.249642 0.249642)
							(end -0.2794 0.1778)
						)
						(arc
							(start -0.2794 -0.1778)
							(mid -0.249642 -0.249642)
							(end -0.1778 -0.2794)
						)
						(arc
							(start 0.1778 -0.2794)
							(mid 0.249642 -0.249642)
							(end 0.2794 -0.1778)
						)
						(arc
							(start 0.2794 0.1778)
							(mid 0.249642 0.249642)
							(end 0.1778 0.2794)
						)
					)
					(width 0)
					(fill yes)
				)
			)
		)
	)
	(footprint ""
		(layer "B.Cu")
		(at 216.5096 -21.7932 180)
		(property "Reference" "R63"
			(at 0 0 0)
			(layer "B.SilkS")
			(hide yes)
			(effects
				(font
					(size 1.27 1.27)
				)
				(justify mirror)
			)
		)
		(property "Value" "10KR2F-2-GP"
			(at -0.064008 -3.993896 180)
			(unlocked yes)
			(layer "B.Fab")
			(hide yes)
			(effects
				(font
					(size 1.016 1.016)
					(thickness 0.1524)
				)
				(justify mirror)
			)
		)
		(property "Device Type" "R402H16"
			(at -0.064008 -5.517896 180)
			(unlocked yes)
			(layer "B.Fab")
			(hide yes)
			(effects
				(font
					(size 1.016 1.016)
					(thickness 0.1524)
				)
				(justify mirror)
			)
		)
		(duplicate_pad_numbers_are_jumpers no)
		(fp_line
			(start 0.508 -0.9398)
			(end 0.508 0.9398)
			(stroke
				(width 0.1524)
				(type default)
			)
			(layer "B.SilkS")
		)
		(fp_line
			(start -0.508 -0.9398)
			(end 0.508 -0.9398)
			(stroke
				(width 0.1524)
				(type default)
			)
			(layer "B.SilkS")
		)
		(fp_rect
			(start 0.508 0.9398)
			(end -0.508 -0.9398)
			(stroke
				(width 0)
				(type default)
			)
			(fill no)
			(layer "B.CrtYd")
		)
		(fp_rect
			(start 0.508 0.9398)
			(end -0.508 -0.9398)
			(stroke
				(width 0)
				(type default)
			)
			(fill no)
			(layer "B.Fab")
		)
		(pad "1" smd custom
			(at 0 -0.4445)
			(size 0.1397 0.1397)
			(layers "B.Cu" "B.Mask" "B.Paste")
			(net "DUT_VDDO")
			(options
				(clearance outline)
				(anchor circle)
			)
			(primitives
				(gr_poly
					(pts
						(arc
							(start -0.1778 0.2794)
							(mid -0.249642 0.249642)
							(end -0.2794 0.1778)
						)
						(arc
							(start -0.2794 -0.1778)
							(mid -0.249642 -0.249642)
							(end -0.1778 -0.2794)
						)
						(arc
							(start 0.1778 -0.2794)
							(mid 0.249642 -0.249642)
							(end 0.2794 -0.1778)
						)
						(arc
							(start 0.2794 0.1778)
							(mid 0.249642 0.249642)
							(end 0.1778 0.2794)
						)
					)
					(width 0)
					(fill yes)
				)
			)
		)
		(pad "2" smd custom
			(at 0 0.4445)
			(size 0.1397 0.1397)
			(layers "B.Cu" "B.Mask" "B.Paste")
			(net "PM8536_RST#")
			(options
				(clearance outline)
				(anchor circle)
			)
			(primitives
				(gr_poly
					(pts
						(arc
							(start -0.1778 0.2794)
							(mid -0.249642 0.249642)
							(end -0.2794 0.1778)
						)
						(arc
							(start -0.2794 -0.1778)
							(mid -0.249642 -0.249642)
							(end -0.1778 -0.2794)
						)
						(arc
							(start 0.1778 -0.2794)
							(mid 0.249642 -0.249642)
							(end 0.2794 -0.1778)
						)
						(arc
							(start 0.2794 0.1778)
							(mid 0.249642 0.249642)
							(end 0.1778 0.2794)
						)
					)
					(width 0)
					(fill yes)
				)
			)
		)
	)
	(footprint ""
		(layer "B.Cu")
		(at 184.785 -71.628 180)
		(property "Reference" "C532"
			(at 0 0 0)
			(layer "B.SilkS")
			(hide yes)
			(effects
				(font
					(size 1.27 1.27)
				)
				(justify mirror)
			)
		)
		(property "Value" "SC4D7U16V5KX-1-GP"
			(at 0.0762 -6.1214 180)
			(unlocked yes)
			(layer "B.Fab")
			(hide yes)
			(effects
				(font
					(size 1.016 1.016)
					(thickness 0.1524)
				)
				(justify mirror)
			)
		)
		(property "Device Type" "C805H56"
			(at 0.0762 -8.1534 180)
			(unlocked yes)
			(layer "B.Fab")
			(hide yes)
			(effects
				(font
					(size 1.016 1.016)
					(thickness 0.1524)
				)
				(justify mirror)
			)
		)
		(duplicate_pad_numbers_are_jumpers no)
		(fp_line
			(start -0.635 0)
			(end 0.635 0)
			(stroke
				(width 0.508)
				(type default)
			)
			(layer "B.SilkS")
		)
		(fp_rect
			(start 0.9652 1.778)
			(end -0.9652 -1.778)
			(stroke
				(width 0)
				(type default)
			)
			(fill no)
			(layer "B.CrtYd")
		)
		(fp_poly
			(pts
				(xy 0.9652 -1.778) (xy -0.9652 -1.778) (xy -0.9652 1.778) (xy 0.9652 1.778)
			)
			(stroke
				(width 0)
				(type default)
			)
			(fill no)
			(layer "B.Fab")
		)
		(pad "1" smd rect
			(at 0 -0.9652)
			(size 1.397 1.143)
			(layers "B.Cu" "B.Mask" "B.Paste")
			(net "DUT_AVD_PCIE")
		)
		(pad "2" smd rect
			(at 0 0.9652)
			(size 1.397 1.143)
			(layers "B.Cu" "B.Mask" "B.Paste")
			(net "GND")
		)
	)
	(footprint ""
		(layer "B.Cu")
		(at 255.505712 -7.01167 90)
		(property "Reference" "R190"
			(at 0 0 90)
			(layer "B.SilkS")
			(hide yes)
			(effects
				(font
					(size 1.27 1.27)
				)
				(justify mirror)
			)
		)
		(property "Value" "0R2J-2-GP"
			(at -0.064008 -3.993896 90)
			(unlocked yes)
			(layer "B.Fab")
			(hide yes)
			(effects
				(font
					(size 1.016 1.016)
					(thickness 0.1524)
				)
				(justify mirror)
			)
		)
		(property "Device Type" "R402H16"
			(at -0.064008 -5.517896 90)
			(unlocked yes)
			(layer "B.Fab")
			(hide yes)
			(effects
				(font
					(size 1.016 1.016)
					(thickness 0.1524)
				)
				(justify mirror)
			)
		)
		(duplicate_pad_numbers_are_jumpers no)
		(fp_line
			(start 0.508 -0.9398)
			(end 0.508 0.9398)
			(stroke
				(width 0.1524)
				(type default)
			)
			(layer "B.SilkS")
		)
		(fp_line
			(start -0.508 -0.9398)
			(end 0.508 -0.9398)
			(stroke
				(width 0.1524)
				(type default)
			)
			(layer "B.SilkS")
		)
		(fp_rect
			(start 0.508 0.9398)
			(end -0.508 -0.9398)
			(stroke
				(width 0)
				(type default)
			)
			(fill no)
			(layer "B.CrtYd")
		)
		(fp_rect
			(start 0.508 0.9398)
			(end -0.508 -0.9398)
			(stroke
				(width 0)
				(type default)
			)
			(fill no)
			(layer "B.Fab")
		)
		(pad "1" smd custom
			(at 0 -0.4445 270)
			(size 0.1397 0.1397)
			(layers "B.Cu" "B.Mask" "B.Paste")
			(net "BMC_I2C5_D_PEB_SCL")
			(options
				(clearance outline)
				(anchor circle)
			)
			(primitives
				(gr_poly
					(pts
						(arc
							(start -0.1778 0.2794)
							(mid -0.249642 0.249642)
							(end -0.2794 0.1778)
						)
						(arc
							(start -0.2794 -0.1778)
							(mid -0.249642 -0.249642)
							(end -0.1778 -0.2794)
						)
						(arc
							(start 0.1778 -0.2794)
							(mid 0.249642 -0.249642)
							(end 0.2794 -0.1778)
						)
						(arc
							(start 0.2794 0.1778)
							(mid 0.249642 0.249642)
							(end 0.1778 0.2794)
						)
					)
					(width 0)
					(fill yes)
				)
			)
		)
		(pad "2" smd custom
			(at 0 0.4445 270)
			(size 0.1397 0.1397)
			(layers "B.Cu" "B.Mask" "B.Paste")
			(net "TEMP_1_SCL")
			(options
				(clearance outline)
				(anchor circle)
			)
			(primitives
				(gr_poly
					(pts
						(arc
							(start -0.1778 0.2794)
							(mid -0.249642 0.249642)
							(end -0.2794 0.1778)
						)
						(arc
							(start -0.2794 -0.1778)
							(mid -0.249642 -0.249642)
							(end -0.1778 -0.2794)
						)
						(arc
							(start 0.1778 -0.2794)
							(mid 0.249642 -0.249642)
							(end 0.2794 -0.1778)
						)
						(arc
							(start 0.2794 0.1778)
							(mid 0.249642 0.249642)
							(end 0.1778 0.2794)
						)
					)
					(width 0)
					(fill yes)
				)
			)
		)
	)
	(footprint ""
		(layer "B.Cu")
		(at 317.5 -55.372)
		(property "Reference" "PC177"
			(at 0 0 0)
			(layer "B.SilkS")
			(hide yes)
			(effects
				(font
					(size 1.27 1.27)
				)
				(justify mirror)
			)
		)
		(property "Value" "SC22U6D3V5MX-5-GP"
			(at 0.0762 -6.1214 0)
			(unlocked yes)
			(layer "B.Fab")
			(hide yes)
			(effects
				(font
					(size 1.016 1.016)
					(thickness 0.1524)
				)
				(justify mirror)
			)
		)
		(property "Device Type" "C805H56"
			(at 0.0762 -8.1534 0)
			(unlocked yes)
			(layer "B.Fab")
			(hide yes)
			(effects
				(font
					(size 1.016 1.016)
					(thickness 0.1524)
				)
				(justify mirror)
			)
		)
		(duplicate_pad_numbers_are_jumpers no)
		(fp_line
			(start -0.635 0)
			(end 0.635 0)
			(stroke
				(width 0.508)
				(type default)
			)
			(layer "B.SilkS")
		)
		(fp_rect
			(start 0.9652 1.778)
			(end -0.9652 -1.778)
			(stroke
				(width 0)
				(type default)
			)
			(fill no)
			(layer "B.CrtYd")
		)
		(fp_poly
			(pts
				(xy 0.9652 -1.778) (xy -0.9652 -1.778) (xy -0.9652 1.778) (xy 0.9652 1.778)
			)
			(stroke
				(width 0)
				(type default)
			)
			(fill no)
			(layer "B.Fab")
		)
		(pad "1" smd rect
			(at 0 -0.9652 180)
			(size 1.397 1.143)
			(layers "B.Cu" "B.Mask" "B.Paste")
			(net "P0V9_E")
		)
		(pad "2" smd rect
			(at 0 0.9652 180)
			(size 1.397 1.143)
			(layers "B.Cu" "B.Mask" "B.Paste")
			(net "GND")
		)
	)
	(footprint ""
		(layer "B.Cu")
		(at 228.6254 -56.989472 90)
		(property "Reference" "C535"
			(at 0 0 90)
			(layer "B.SilkS")
			(hide yes)
			(effects
				(font
					(size 1.27 1.27)
				)
				(justify mirror)
			)
		)
		(property "Value" "SCD1U16V1KX-1-GP"
			(at 2.8321 -1.7399 90)
			(unlocked yes)
			(layer "B.Fab")
			(hide yes)
			(effects
				(font
					(size 1.016 1.016)
					(thickness 0.1524)
				)
				(justify mirror)
			)
		)
		(property "Device Type" "C0201H13"
			(at 2.8321 -3.2639 90)
			(unlocked yes)
			(layer "B.Fab")
			(hide yes)
			(effects
				(font
					(size 1.016 1.016)
					(thickness 0.1524)
				)
				(justify mirror)
			)
		)
		(duplicate_pad_numbers_are_jumpers no)
		(fp_rect
			(start 0.2794 0.6477)
			(end -0.2794 -0.6477)
			(stroke
				(width 0)
				(type default)
			)
			(fill no)
			(layer "B.CrtYd")
		)
		(fp_rect
			(start 0.2794 0.6477)
			(end -0.2794 -0.6477)
			(stroke
				(width 0)
				(type default)
			)
			(fill no)
			(layer "B.Fab")
		)
		(pad "1" smd custom
			(at 0 -0.2794 270)
			(size 0.0762 0.0762)
			(layers "B.Cu" "B.Mask" "B.Paste")
			(net "DUT_AVD_PCIE")
			(options
				(clearance outline)
				(anchor circle)
			)
			(primitives
				(gr_poly
					(pts
						(arc
							(start 0.1524 0.127)
							(mid 0.137521 0.162921)
							(end 0.1016 0.1778)
						)
						(arc
							(start -0.1016 0.1778)
							(mid -0.137521 0.162921)
							(end -0.1524 0.127)
						)
						(arc
							(start -0.1524 -0.127)
							(mid -0.137521 -0.162921)
							(end -0.1016 -0.1778)
						)
						(arc
							(start 0.1016 -0.1778)
							(mid 0.137521 -0.162921)
							(end 0.1524 -0.127)
						)
					)
					(width 0)
					(fill yes)
				)
			)
		)
		(pad "2" smd custom
			(at 0 0.2794 270)
			(size 0.0762 0.0762)
			(layers "B.Cu" "B.Mask" "B.Paste")
			(net "GND")
			(options
				(clearance outline)
				(anchor circle)
			)
			(primitives
				(gr_poly
					(pts
						(arc
							(start 0.1524 0.127)
							(mid 0.137521 0.162921)
							(end 0.1016 0.1778)
						)
						(arc
							(start -0.1016 0.1778)
							(mid -0.137521 0.162921)
							(end -0.1524 0.127)
						)
						(arc
							(start -0.1524 -0.127)
							(mid -0.137521 -0.162921)
							(end -0.1016 -0.1778)
						)
						(arc
							(start 0.1016 -0.1778)
							(mid 0.137521 -0.162921)
							(end 0.1524 -0.127)
						)
					)
					(width 0)
					(fill yes)
				)
			)
		)
	)
	(footprint ""
		(layer "B.Cu")
		(at 310.007 -63.881 180)
		(property "Reference" "PG52"
			(at 0 0 0)
			(layer "B.SilkS")
			(hide yes)
			(effects
				(font
					(size 1.27 1.27)
				)
				(justify mirror)
			)
		)
		(property "Value" "GAP-CLOSE-PWR-3-GP"
			(at -0.0254 -6.5786 180)
			(unlocked yes)
			(layer "B.Fab")
			(hide yes)
			(effects
				(font
					(size 1.016 1.016)
					(thickness 0.1524)
				)
				(justify mirror)
			)
		)
		(property "Device Type" "GAP-CLOSE-PWR-3"
			(at -0.0254 -8.255 180)
			(unlocked yes)
			(layer "B.Fab")
			(hide yes)
			(effects
				(font
					(size 1.016 1.016)
					(thickness 0.1524)
				)
				(justify mirror)
			)
		)
		(duplicate_pad_numbers_are_jumpers no)
		(fp_rect
			(start 0.7112 0.4572)
			(end -0.7112 -0.4572)
			(stroke
				(width 0)
				(type default)
			)
			(fill no)
			(layer "B.CrtYd")
		)
		(fp_poly
			(pts
				(xy 0.7112 -0.4572) (xy -0.7112 -0.4572) (xy -0.7112 0.4572) (xy 0.7112 0.4572)
			)
			(stroke
				(width 0)
				(type default)
			)
			(fill no)
			(layer "B.Fab")
		)
		(pad "1" smd rect
			(at 0.3048 0)
			(size 0.6604 0.762)
			(layers "B.Cu" "B.Mask" "B.Paste")
			(net "DUT_VDD")
		)
		(pad "2" smd rect
			(at -0.3048 0)
			(size 0.6604 0.762)
			(layers "B.Cu" "B.Mask" "B.Paste")
			(net "P0V9_E")
		)
	)
	(footprint ""
		(layer "B.Cu")
		(at 264.033 -13.589)
		(property "Reference" "PC223"
			(at 0 0 0)
			(layer "B.SilkS")
			(hide yes)
			(effects
				(font
					(size 1.27 1.27)
				)
				(justify mirror)
			)
		)
		(property "Value" "SC1U16V3KX-5GP"
			(at 0 -2.8194 0)
			(unlocked yes)
			(layer "B.Fab")
			(hide yes)
			(effects
				(font
					(size 1.016 1.016)
					(thickness 0.1524)
				)
				(justify mirror)
			)
		)
		(property "Device Type" "C603H36"
			(at 0 -4.3434 0)
			(unlocked yes)
			(layer "B.Fab")
			(hide yes)
			(effects
				(font
					(size 1.016 1.016)
					(thickness 0.1524)
				)
				(justify mirror)
			)
		)
		(duplicate_pad_numbers_are_jumpers no)
		(fp_line
			(start -0.508 0)
			(end 0.508 0)
			(stroke
				(width 0.2032)
				(type default)
			)
			(layer "B.SilkS")
		)
		(fp_rect
			(start 0.5842 1.3335)
			(end -0.5842 -1.3335)
			(stroke
				(width 0)
				(type default)
			)
			(fill no)
			(layer "B.CrtYd")
		)
		(fp_rect
			(start 0.5842 1.3335)
			(end -0.5842 -1.3335)
			(stroke
				(width 0)
				(type default)
			)
			(fill no)
			(layer "B.Fab")
		)
		(pad "1" smd custom
			(at 0 -0.762 180)
			(size 0.2159 0.2159)
			(layers "B.Cu" "B.Mask" "B.Paste")
			(net "PWRGD_P1V8_STBY")
			(options
				(clearance outline)
				(anchor circle)
			)
			(primitives
				(gr_poly
					(pts
						(arc
							(start -0.3302 0.4318)
							(mid -0.402042 0.402042)
							(end -0.4318 0.3302)
						)
						(arc
							(start -0.4318 -0.3302)
							(mid -0.402042 -0.402042)
							(end -0.3302 -0.4318)
						)
						(arc
							(start 0.3302 -0.4318)
							(mid 0.402042 -0.402042)
							(end 0.4318 -0.3302)
						)
						(arc
							(start 0.4318 0.3302)
							(mid 0.402042 0.402042)
							(end 0.3302 0.4318)
						)
					)
					(width 0)
					(fill yes)
				)
			)
		)
		(pad "2" smd custom
			(at 0 0.762 180)
			(size 0.2159 0.2159)
			(layers "B.Cu" "B.Mask" "B.Paste")
			(net "GND")
			(options
				(clearance outline)
				(anchor circle)
			)
			(primitives
				(gr_poly
					(pts
						(arc
							(start -0.3302 0.4318)
							(mid -0.402042 0.402042)
							(end -0.4318 0.3302)
						)
						(arc
							(start -0.4318 -0.3302)
							(mid -0.402042 -0.402042)
							(end -0.3302 -0.4318)
						)
						(arc
							(start 0.3302 -0.4318)
							(mid 0.402042 -0.402042)
							(end 0.4318 -0.3302)
						)
						(arc
							(start 0.4318 0.3302)
							(mid 0.402042 0.402042)
							(end 0.3302 0.4318)
						)
					)
					(width 0)
					(fill yes)
				)
			)
		)
	)
	(footprint ""
		(layer "B.Cu")
		(at 229.108 -20.447)
		(property "Reference" "R3702"
			(at 0 0 0)
			(layer "B.SilkS")
			(hide yes)
			(effects
				(font
					(size 1.27 1.27)
				)
				(justify mirror)
			)
		)
		(property "Value" "4K7R2F-GP"
			(at -0.064008 -3.993896 0)
			(unlocked yes)
			(layer "B.Fab")
			(hide yes)
			(effects
				(font
					(size 1.016 1.016)
					(thickness 0.1524)
				)
				(justify mirror)
			)
		)
		(property "Device Type" "R402H16"
			(at -0.064008 -5.517896 0)
			(unlocked yes)
			(layer "B.Fab")
			(hide yes)
			(effects
				(font
					(size 1.016 1.016)
					(thickness 0.1524)
				)
				(justify mirror)
			)
		)
		(duplicate_pad_numbers_are_jumpers no)
		(fp_line
			(start -0.508 -0.9398)
			(end 0.508 -0.9398)
			(stroke
				(width 0.1524)
				(type default)
			)
			(layer "B.SilkS")
		)
		(fp_line
			(start 0.508 -0.9398)
			(end 0.508 0.9398)
			(stroke
				(width 0.1524)
				(type default)
			)
			(layer "B.SilkS")
		)
		(fp_rect
			(start 0.508 0.9398)
			(end -0.508 -0.9398)
			(stroke
				(width 0)
				(type default)
			)
			(fill no)
			(layer "B.CrtYd")
		)
		(fp_rect
			(start 0.508 0.9398)
			(end -0.508 -0.9398)
			(stroke
				(width 0)
				(type default)
			)
			(fill no)
			(layer "B.Fab")
		)
		(pad "1" smd custom
			(at 0 -0.4445 180)
			(size 0.1397 0.1397)
			(layers "B.Cu" "B.Mask" "B.Paste")
			(net "HOST2_RST_N_LS")
			(options
				(clearance outline)
				(anchor circle)
			)
			(primitives
				(gr_poly
					(pts
						(arc
							(start -0.1778 0.2794)
							(mid -0.249642 0.249642)
							(end -0.2794 0.1778)
						)
						(arc
							(start -0.2794 -0.1778)
							(mid -0.249642 -0.249642)
							(end -0.1778 -0.2794)
						)
						(arc
							(start 0.1778 -0.2794)
							(mid 0.249642 -0.249642)
							(end 0.2794 -0.1778)
						)
						(arc
							(start 0.2794 0.1778)
							(mid 0.249642 0.249642)
							(end 0.1778 0.2794)
						)
					)
					(width 0)
					(fill yes)
				)
			)
		)
		(pad "2" smd custom
			(at 0 0.4445 180)
			(size 0.1397 0.1397)
			(layers "B.Cu" "B.Mask" "B.Paste")
			(net "DUT_VDDO")
			(options
				(clearance outline)
				(anchor circle)
			)
			(primitives
				(gr_poly
					(pts
						(arc
							(start -0.1778 0.2794)
							(mid -0.249642 0.249642)
							(end -0.2794 0.1778)
						)
						(arc
							(start -0.2794 -0.1778)
							(mid -0.249642 -0.249642)
							(end -0.1778 -0.2794)
						)
						(arc
							(start 0.1778 -0.2794)
							(mid 0.249642 -0.249642)
							(end 0.2794 -0.1778)
						)
						(arc
							(start 0.2794 0.1778)
							(mid 0.249642 0.249642)
							(end 0.1778 0.2794)
						)
					)
					(width 0)
					(fill yes)
				)
			)
		)
	)
	(footprint ""
		(layer "B.Cu")
		(at 237.109 -23.241 180)
		(property "Reference" "R787"
			(at 0 0 0)
			(layer "B.SilkS")
			(hide yes)
			(effects
				(font
					(size 1.27 1.27)
				)
				(justify mirror)
			)
		)
		(property "Value" "4K7R2F-GP"
			(at -0.064008 -3.993896 180)
			(unlocked yes)
			(layer "B.Fab")
			(hide yes)
			(effects
				(font
					(size 1.016 1.016)
					(thickness 0.1524)
				)
				(justify mirror)
			)
		)
		(property "Device Type" "R402H16"
			(at -0.064008 -5.517896 180)
			(unlocked yes)
			(layer "B.Fab")
			(hide yes)
			(effects
				(font
					(size 1.016 1.016)
					(thickness 0.1524)
				)
				(justify mirror)
			)
		)
		(duplicate_pad_numbers_are_jumpers no)
		(fp_line
			(start 0.508 -0.9398)
			(end 0.508 0.9398)
			(stroke
				(width 0.1524)
				(type default)
			)
			(layer "B.SilkS")
		)
		(fp_line
			(start -0.508 -0.9398)
			(end 0.508 -0.9398)
			(stroke
				(width 0.1524)
				(type default)
			)
			(layer "B.SilkS")
		)
		(fp_rect
			(start 0.508 0.9398)
			(end -0.508 -0.9398)
			(stroke
				(width 0)
				(type default)
			)
			(fill no)
			(layer "B.CrtYd")
		)
		(fp_rect
			(start 0.508 0.9398)
			(end -0.508 -0.9398)
			(stroke
				(width 0)
				(type default)
			)
			(fill no)
			(layer "B.Fab")
		)
		(pad "1" smd custom
			(at 0 -0.4445)
			(size 0.1397 0.1397)
			(layers "B.Cu" "B.Mask" "B.Paste")
			(net "BOOTSTRAP7")
			(options
				(clearance outline)
				(anchor circle)
			)
			(primitives
				(gr_poly
					(pts
						(arc
							(start -0.1778 0.2794)
							(mid -0.249642 0.249642)
							(end -0.2794 0.1778)
						)
						(arc
							(start -0.2794 -0.1778)
							(mid -0.249642 -0.249642)
							(end -0.1778 -0.2794)
						)
						(arc
							(start 0.1778 -0.2794)
							(mid 0.249642 -0.249642)
							(end 0.2794 -0.1778)
						)
						(arc
							(start 0.2794 0.1778)
							(mid 0.249642 0.249642)
							(end 0.1778 0.2794)
						)
					)
					(width 0)
					(fill yes)
				)
			)
		)
		(pad "2" smd custom
			(at 0 0.4445)
			(size 0.1397 0.1397)
			(layers "B.Cu" "B.Mask" "B.Paste")
			(net "BOOTSTRAP_R_7")
			(options
				(clearance outline)
				(anchor circle)
			)
			(primitives
				(gr_poly
					(pts
						(arc
							(start -0.1778 0.2794)
							(mid -0.249642 0.249642)
							(end -0.2794 0.1778)
						)
						(arc
							(start -0.2794 -0.1778)
							(mid -0.249642 -0.249642)
							(end -0.1778 -0.2794)
						)
						(arc
							(start 0.1778 -0.2794)
							(mid 0.249642 -0.249642)
							(end 0.2794 -0.1778)
						)
						(arc
							(start 0.2794 0.1778)
							(mid 0.249642 0.249642)
							(end 0.1778 0.2794)
						)
					)
					(width 0)
					(fill yes)
				)
			)
		)
	)
	(footprint ""
		(layer "B.Cu")
		(at 233.59999 -37.999924 90)
		(property "Reference" "TP203"
			(at 0 0 90)
			(layer "B.SilkS")
			(hide yes)
			(effects
				(font
					(size 1.27 1.27)
				)
				(justify mirror)
			)
		)
		(property "Value" "TPAD28-2-GP"
			(at 0.0127 -1.6637 90)
			(unlocked yes)
			(layer "B.Fab")
			(hide yes)
			(effects
				(font
					(size 1.016 1.016)
					(thickness 0.1524)
				)
				(justify mirror)
			)
		)
		(property "Device Type" "TPAD28"
			(at 0.0127 -3.1877 90)
			(unlocked yes)
			(layer "B.Fab")
			(hide yes)
			(effects
				(font
					(size 1.016 1.016)
					(thickness 0.1524)
				)
				(justify mirror)
			)
		)
		(duplicate_pad_numbers_are_jumpers no)
		(fp_poly
			(pts
				(arc
					(start 0 0.3556)
					(mid 0 -0.3556)
					(end 0 0.3556)
				)
			)
			(stroke
				(width 0)
				(type default)
			)
			(fill no)
			(layer "B.CrtYd")
		)
		(fp_poly
			(pts
				(arc
					(start 0 0.6096)
					(mid 0 -0.6096)
					(end 0 0.6096)
				)
			)
			(stroke
				(width 0)
				(type default)
			)
			(fill no)
			(layer "B.Fab")
		)
		(pad "1" smd circle
			(at 0 0 270)
			(size 0.7112 0.7112)
			(layers "B.Cu" "B.Mask" "B.Paste")
			(net "RMII_RXD_1")
		)
	)
	(footprint ""
		(layer "B.Cu")
		(at 228.6254 -59.9948 90)
		(property "Reference" "C539"
			(at 0 0 90)
			(layer "B.SilkS")
			(hide yes)
			(effects
				(font
					(size 1.27 1.27)
				)
				(justify mirror)
			)
		)
		(property "Value" "SCD1U16V1KX-1-GP"
			(at 2.8321 -1.7399 90)
			(unlocked yes)
			(layer "B.Fab")
			(hide yes)
			(effects
				(font
					(size 1.016 1.016)
					(thickness 0.1524)
				)
				(justify mirror)
			)
		)
		(property "Device Type" "C0201H13"
			(at 2.8321 -3.2639 90)
			(unlocked yes)
			(layer "B.Fab")
			(hide yes)
			(effects
				(font
					(size 1.016 1.016)
					(thickness 0.1524)
				)
				(justify mirror)
			)
		)
		(duplicate_pad_numbers_are_jumpers no)
		(fp_rect
			(start 0.2794 0.6477)
			(end -0.2794 -0.6477)
			(stroke
				(width 0)
				(type default)
			)
			(fill no)
			(layer "B.CrtYd")
		)
		(fp_rect
			(start 0.2794 0.6477)
			(end -0.2794 -0.6477)
			(stroke
				(width 0)
				(type default)
			)
			(fill no)
			(layer "B.Fab")
		)
		(pad "1" smd custom
			(at 0 -0.2794 270)
			(size 0.0762 0.0762)
			(layers "B.Cu" "B.Mask" "B.Paste")
			(net "DUT_AVD_PCIE")
			(options
				(clearance outline)
				(anchor circle)
			)
			(primitives
				(gr_poly
					(pts
						(arc
							(start 0.1524 0.127)
							(mid 0.137521 0.162921)
							(end 0.1016 0.1778)
						)
						(arc
							(start -0.1016 0.1778)
							(mid -0.137521 0.162921)
							(end -0.1524 0.127)
						)
						(arc
							(start -0.1524 -0.127)
							(mid -0.137521 -0.162921)
							(end -0.1016 -0.1778)
						)
						(arc
							(start 0.1016 -0.1778)
							(mid 0.137521 -0.162921)
							(end 0.1524 -0.127)
						)
					)
					(width 0)
					(fill yes)
				)
			)
		)
		(pad "2" smd custom
			(at 0 0.2794 270)
			(size 0.0762 0.0762)
			(layers "B.Cu" "B.Mask" "B.Paste")
			(net "GND")
			(options
				(clearance outline)
				(anchor circle)
			)
			(primitives
				(gr_poly
					(pts
						(arc
							(start 0.1524 0.127)
							(mid 0.137521 0.162921)
							(end 0.1016 0.1778)
						)
						(arc
							(start -0.1016 0.1778)
							(mid -0.137521 0.162921)
							(end -0.1524 0.127)
						)
						(arc
							(start -0.1524 -0.127)
							(mid -0.137521 -0.162921)
							(end -0.1016 -0.1778)
						)
						(arc
							(start 0.1016 -0.1778)
							(mid 0.137521 -0.162921)
							(end 0.1524 -0.127)
						)
					)
					(width 0)
					(fill yes)
				)
			)
		)
	)
	(footprint ""
		(layer "B.Cu")
		(at 228.6254 -53.992272 90)
		(property "Reference" "C538"
			(at 0 0 90)
			(layer "B.SilkS")
			(hide yes)
			(effects
				(font
					(size 1.27 1.27)
				)
				(justify mirror)
			)
		)
		(property "Value" "SCD1U16V1KX-1-GP"
			(at 2.8321 -1.7399 90)
			(unlocked yes)
			(layer "B.Fab")
			(hide yes)
			(effects
				(font
					(size 1.016 1.016)
					(thickness 0.1524)
				)
				(justify mirror)
			)
		)
		(property "Device Type" "C0201H13"
			(at 2.8321 -3.2639 90)
			(unlocked yes)
			(layer "B.Fab")
			(hide yes)
			(effects
				(font
					(size 1.016 1.016)
					(thickness 0.1524)
				)
				(justify mirror)
			)
		)
		(duplicate_pad_numbers_are_jumpers no)
		(fp_rect
			(start 0.2794 0.6477)
			(end -0.2794 -0.6477)
			(stroke
				(width 0)
				(type default)
			)
			(fill no)
			(layer "B.CrtYd")
		)
		(fp_rect
			(start 0.2794 0.6477)
			(end -0.2794 -0.6477)
			(stroke
				(width 0)
				(type default)
			)
			(fill no)
			(layer "B.Fab")
		)
		(pad "1" smd custom
			(at 0 -0.2794 270)
			(size 0.0762 0.0762)
			(layers "B.Cu" "B.Mask" "B.Paste")
			(net "DUT_AVD_PCIE")
			(options
				(clearance outline)
				(anchor circle)
			)
			(primitives
				(gr_poly
					(pts
						(arc
							(start 0.1524 0.127)
							(mid 0.137521 0.162921)
							(end 0.1016 0.1778)
						)
						(arc
							(start -0.1016 0.1778)
							(mid -0.137521 0.162921)
							(end -0.1524 0.127)
						)
						(arc
							(start -0.1524 -0.127)
							(mid -0.137521 -0.162921)
							(end -0.1016 -0.1778)
						)
						(arc
							(start 0.1016 -0.1778)
							(mid 0.137521 -0.162921)
							(end 0.1524 -0.127)
						)
					)
					(width 0)
					(fill yes)
				)
			)
		)
		(pad "2" smd custom
			(at 0 0.2794 270)
			(size 0.0762 0.0762)
			(layers "B.Cu" "B.Mask" "B.Paste")
			(net "GND")
			(options
				(clearance outline)
				(anchor circle)
			)
			(primitives
				(gr_poly
					(pts
						(arc
							(start 0.1524 0.127)
							(mid 0.137521 0.162921)
							(end 0.1016 0.1778)
						)
						(arc
							(start -0.1016 0.1778)
							(mid -0.137521 0.162921)
							(end -0.1524 0.127)
						)
						(arc
							(start -0.1524 -0.127)
							(mid -0.137521 -0.162921)
							(end -0.1016 -0.1778)
						)
						(arc
							(start 0.1016 -0.1778)
							(mid 0.137521 -0.162921)
							(end 0.1524 -0.127)
						)
					)
					(width 0)
					(fill yes)
				)
			)
		)
	)
	(footprint ""
		(layer "B.Cu")
		(at 228.6254 -47.997872 90)
		(property "Reference" "C492"
			(at 0 0 90)
			(layer "B.SilkS")
			(hide yes)
			(effects
				(font
					(size 1.27 1.27)
				)
				(justify mirror)
			)
		)
		(property "Value" "SCD1U16V1KX-1-GP"
			(at 2.8321 -1.7399 90)
			(unlocked yes)
			(layer "B.Fab")
			(hide yes)
			(effects
				(font
					(size 1.016 1.016)
					(thickness 0.1524)
				)
				(justify mirror)
			)
		)
		(property "Device Type" "C0201H13"
			(at 2.8321 -3.2639 90)
			(unlocked yes)
			(layer "B.Fab")
			(hide yes)
			(effects
				(font
					(size 1.016 1.016)
					(thickness 0.1524)
				)
				(justify mirror)
			)
		)
		(duplicate_pad_numbers_are_jumpers no)
		(fp_rect
			(start 0.2794 0.6477)
			(end -0.2794 -0.6477)
			(stroke
				(width 0)
				(type default)
			)
			(fill no)
			(layer "B.CrtYd")
		)
		(fp_rect
			(start 0.2794 0.6477)
			(end -0.2794 -0.6477)
			(stroke
				(width 0)
				(type default)
			)
			(fill no)
			(layer "B.Fab")
		)
		(pad "1" smd custom
			(at 0 -0.2794 270)
			(size 0.0762 0.0762)
			(layers "B.Cu" "B.Mask" "B.Paste")
			(net "DUT_AVD_PCIE")
			(options
				(clearance outline)
				(anchor circle)
			)
			(primitives
				(gr_poly
					(pts
						(arc
							(start 0.1524 0.127)
							(mid 0.137521 0.162921)
							(end 0.1016 0.1778)
						)
						(arc
							(start -0.1016 0.1778)
							(mid -0.137521 0.162921)
							(end -0.1524 0.127)
						)
						(arc
							(start -0.1524 -0.127)
							(mid -0.137521 -0.162921)
							(end -0.1016 -0.1778)
						)
						(arc
							(start 0.1016 -0.1778)
							(mid 0.137521 -0.162921)
							(end 0.1524 -0.127)
						)
					)
					(width 0)
					(fill yes)
				)
			)
		)
		(pad "2" smd custom
			(at 0 0.2794 270)
			(size 0.0762 0.0762)
			(layers "B.Cu" "B.Mask" "B.Paste")
			(net "GND")
			(options
				(clearance outline)
				(anchor circle)
			)
			(primitives
				(gr_poly
					(pts
						(arc
							(start 0.1524 0.127)
							(mid 0.137521 0.162921)
							(end 0.1016 0.1778)
						)
						(arc
							(start -0.1016 0.1778)
							(mid -0.137521 0.162921)
							(end -0.1524 0.127)
						)
						(arc
							(start -0.1524 -0.127)
							(mid -0.137521 -0.162921)
							(end -0.1016 -0.1778)
						)
						(arc
							(start 0.1016 -0.1778)
							(mid 0.137521 -0.162921)
							(end 0.1524 -0.127)
						)
					)
					(width 0)
					(fill yes)
				)
			)
		)
	)
	(footprint ""
		(layer "B.Cu")
		(at 211.2772 -44.7548 90)
		(property "Reference" "C730"
			(at 0 0 90)
			(layer "B.SilkS")
			(hide yes)
			(effects
				(font
					(size 1.27 1.27)
				)
				(justify mirror)
			)
		)
		(property "Value" "SCD22U10V2KX-1GP"
			(at -1.1811 -2.7051 90)
			(unlocked yes)
			(layer "B.Fab")
			(hide yes)
			(effects
				(font
					(size 1.016 1.016)
					(thickness 0.1524)
				)
				(justify mirror)
			)
		)
		(property "Device Type" "C402H22"
			(at -1.1811 -4.2291 90)
			(unlocked yes)
			(layer "B.Fab")
			(hide yes)
			(effects
				(font
					(size 1.016 1.016)
					(thickness 0.1524)
				)
				(justify mirror)
			)
		)
		(duplicate_pad_numbers_are_jumpers no)
		(fp_rect
			(start 0.4318 0.9525)
			(end -0.4318 -0.9525)
			(stroke
				(width 0)
				(type default)
			)
			(fill no)
			(layer "B.CrtYd")
		)
		(fp_rect
			(start 0.4318 0.9525)
			(end -0.4318 -0.9525)
			(stroke
				(width 0)
				(type default)
			)
			(fill no)
			(layer "B.Fab")
		)
		(pad "1" smd custom
			(at 0 -0.4445 270)
			(size 0.1524 0.1524)
			(layers "B.Cu" "B.Mask" "B.Paste")
			(net "BMC_PETXN")
			(options
				(clearance outline)
				(anchor circle)
			)
			(primitives
				(gr_poly
					(pts
						(arc
							(start 0.3048 0.2032)
							(mid 0.275042 0.275042)
							(end 0.2032 0.3048)
						)
						(arc
							(start -0.2032 0.3048)
							(mid -0.275042 0.275042)
							(end -0.3048 0.2032)
						)
						(arc
							(start -0.3048 -0.2032)
							(mid -0.275042 -0.275042)
							(end -0.2032 -0.3048)
						)
						(arc
							(start 0.2032 -0.3048)
							(mid 0.275042 -0.275042)
							(end 0.3048 -0.2032)
						)
					)
					(width 0)
					(fill yes)
				)
			)
		)
		(pad "2" smd custom
			(at 0 0.4445 270)
			(size 0.1524 0.1524)
			(layers "B.Cu" "B.Mask" "B.Paste")
			(net "PCIE_RX_N76")
			(options
				(clearance outline)
				(anchor circle)
			)
			(primitives
				(gr_poly
					(pts
						(arc
							(start 0.3048 0.2032)
							(mid 0.275042 0.275042)
							(end 0.2032 0.3048)
						)
						(arc
							(start -0.2032 0.3048)
							(mid -0.275042 0.275042)
							(end -0.3048 0.2032)
						)
						(arc
							(start -0.3048 -0.2032)
							(mid -0.275042 -0.275042)
							(end -0.2032 -0.3048)
						)
						(arc
							(start 0.2032 -0.3048)
							(mid 0.275042 -0.275042)
							(end 0.3048 -0.2032)
						)
					)
					(width 0)
					(fill yes)
				)
			)
		)
	)
	(footprint ""
		(layer "B.Cu")
		(at 237.1598 -41.995852 90)
		(property "Reference" "C435"
			(at 0 0 90)
			(layer "B.SilkS")
			(hide yes)
			(effects
				(font
					(size 1.27 1.27)
				)
				(justify mirror)
			)
		)
		(property "Value" "SCD1U16V1KX-1-GP"
			(at 2.8321 -1.7399 90)
			(unlocked yes)
			(layer "B.Fab")
			(hide yes)
			(effects
				(font
					(size 1.016 1.016)
					(thickness 0.1524)
				)
				(justify mirror)
			)
		)
		(property "Device Type" "C0201H13"
			(at 2.8321 -3.2639 90)
			(unlocked yes)
			(layer "B.Fab")
			(hide yes)
			(effects
				(font
					(size 1.016 1.016)
					(thickness 0.1524)
				)
				(justify mirror)
			)
		)
		(duplicate_pad_numbers_are_jumpers no)
		(fp_rect
			(start 0.2794 0.6477)
			(end -0.2794 -0.6477)
			(stroke
				(width 0)
				(type default)
			)
			(fill no)
			(layer "B.CrtYd")
		)
		(fp_rect
			(start 0.2794 0.6477)
			(end -0.2794 -0.6477)
			(stroke
				(width 0)
				(type default)
			)
			(fill no)
			(layer "B.Fab")
		)
		(pad "1" smd custom
			(at 0 -0.2794 270)
			(size 0.0762 0.0762)
			(layers "B.Cu" "B.Mask" "B.Paste")
			(net "DUT_VDD")
			(options
				(clearance outline)
				(anchor circle)
			)
			(primitives
				(gr_poly
					(pts
						(arc
							(start 0.1524 0.127)
							(mid 0.137521 0.162921)
							(end 0.1016 0.1778)
						)
						(arc
							(start -0.1016 0.1778)
							(mid -0.137521 0.162921)
							(end -0.1524 0.127)
						)
						(arc
							(start -0.1524 -0.127)
							(mid -0.137521 -0.162921)
							(end -0.1016 -0.1778)
						)
						(arc
							(start 0.1016 -0.1778)
							(mid 0.137521 -0.162921)
							(end 0.1524 -0.127)
						)
					)
					(width 0)
					(fill yes)
				)
			)
		)
		(pad "2" smd custom
			(at 0 0.2794 270)
			(size 0.0762 0.0762)
			(layers "B.Cu" "B.Mask" "B.Paste")
			(net "GND")
			(options
				(clearance outline)
				(anchor circle)
			)
			(primitives
				(gr_poly
					(pts
						(arc
							(start 0.1524 0.127)
							(mid 0.137521 0.162921)
							(end 0.1016 0.1778)
						)
						(arc
							(start -0.1016 0.1778)
							(mid -0.137521 0.162921)
							(end -0.1524 0.127)
						)
						(arc
							(start -0.1524 -0.127)
							(mid -0.137521 -0.162921)
							(end -0.1016 -0.1778)
						)
						(arc
							(start 0.1016 -0.1778)
							(mid 0.137521 -0.162921)
							(end 0.1524 -0.127)
						)
					)
					(width 0)
					(fill yes)
				)
			)
		)
	)
	(footprint ""
		(layer "B.Cu")
		(at 129.4384 -196.3928)
		(property "Reference" "R9030"
			(at 0 0 0)
			(layer "B.SilkS")
			(hide yes)
			(effects
				(font
					(size 1.27 1.27)
				)
				(justify mirror)
			)
		)
		(property "Value" "4K7R2F-GP"
			(at -0.064008 -3.993896 0)
			(unlocked yes)
			(layer "B.Fab")
			(hide yes)
			(effects
				(font
					(size 1.016 1.016)
					(thickness 0.1524)
				)
				(justify mirror)
			)
		)
		(property "Device Type" "R402H16"
			(at -0.064008 -5.517896 0)
			(unlocked yes)
			(layer "B.Fab")
			(hide yes)
			(effects
				(font
					(size 1.016 1.016)
					(thickness 0.1524)
				)
				(justify mirror)
			)
		)
		(duplicate_pad_numbers_are_jumpers no)
		(fp_line
			(start -0.508 -0.9398)
			(end 0.508 -0.9398)
			(stroke
				(width 0.1524)
				(type default)
			)
			(layer "B.SilkS")
		)
		(fp_line
			(start 0.508 -0.9398)
			(end 0.508 0.9398)
			(stroke
				(width 0.1524)
				(type default)
			)
			(layer "B.SilkS")
		)
		(fp_rect
			(start 0.508 0.9398)
			(end -0.508 -0.9398)
			(stroke
				(width 0)
				(type default)
			)
			(fill no)
			(layer "B.CrtYd")
		)
		(fp_rect
			(start 0.508 0.9398)
			(end -0.508 -0.9398)
			(stroke
				(width 0)
				(type default)
			)
			(fill no)
			(layer "B.Fab")
		)
		(pad "1" smd custom
			(at 0 -0.4445 180)
			(size 0.1397 0.1397)
			(layers "B.Cu" "B.Mask" "B.Paste")
			(net "SSD_PERST#1")
			(options
				(clearance outline)
				(anchor circle)
			)
			(primitives
				(gr_poly
					(pts
						(arc
							(start -0.1778 0.2794)
							(mid -0.249642 0.249642)
							(end -0.2794 0.1778)
						)
						(arc
							(start -0.2794 -0.1778)
							(mid -0.249642 -0.249642)
							(end -0.1778 -0.2794)
						)
						(arc
							(start 0.1778 -0.2794)
							(mid 0.249642 -0.249642)
							(end 0.2794 -0.1778)
						)
						(arc
							(start 0.2794 0.1778)
							(mid 0.249642 0.249642)
							(end 0.1778 0.2794)
						)
					)
					(width 0)
					(fill yes)
				)
			)
		)
		(pad "2" smd custom
			(at 0 0.4445 180)
			(size 0.1397 0.1397)
			(layers "B.Cu" "B.Mask" "B.Paste")
			(net "GND")
			(options
				(clearance outline)
				(anchor circle)
			)
			(primitives
				(gr_poly
					(pts
						(arc
							(start -0.1778 0.2794)
							(mid -0.249642 0.249642)
							(end -0.2794 0.1778)
						)
						(arc
							(start -0.2794 -0.1778)
							(mid -0.249642 -0.249642)
							(end -0.1778 -0.2794)
						)
						(arc
							(start 0.1778 -0.2794)
							(mid 0.249642 -0.249642)
							(end 0.2794 -0.1778)
						)
						(arc
							(start 0.2794 0.1778)
							(mid 0.249642 0.249642)
							(end 0.1778 0.2794)
						)
					)
					(width 0)
					(fill yes)
				)
			)
		)
	)
	(footprint ""
		(layer "B.Cu")
		(at 234.8865 -38.00348 -90)
		(property "Reference" "C481"
			(at 0 0 90)
			(layer "B.SilkS")
			(hide yes)
			(effects
				(font
					(size 1.27 1.27)
				)
				(justify mirror)
			)
		)
		(property "Value" "SCD1U16V1KX-1-GP"
			(at 2.8321 -1.7399 270)
			(unlocked yes)
			(layer "B.Fab")
			(hide yes)
			(effects
				(font
					(size 1.016 1.016)
					(thickness 0.1524)
				)
				(justify mirror)
			)
		)
		(property "Device Type" "C0201H13"
			(at 2.8321 -3.2639 270)
			(unlocked yes)
			(layer "B.Fab")
			(hide yes)
			(effects
				(font
					(size 1.016 1.016)
					(thickness 0.1524)
				)
				(justify mirror)
			)
		)
		(duplicate_pad_numbers_are_jumpers no)
		(fp_rect
			(start 0.2794 0.6477)
			(end -0.2794 -0.6477)
			(stroke
				(width 0)
				(type default)
			)
			(fill no)
			(layer "B.CrtYd")
		)
		(fp_rect
			(start 0.2794 0.6477)
			(end -0.2794 -0.6477)
			(stroke
				(width 0)
				(type default)
			)
			(fill no)
			(layer "B.Fab")
		)
		(pad "1" smd custom
			(at 0 -0.2794 90)
			(size 0.0762 0.0762)
			(layers "B.Cu" "B.Mask" "B.Paste")
			(net "DUT_VDDO")
			(options
				(clearance outline)
				(anchor circle)
			)
			(primitives
				(gr_poly
					(pts
						(arc
							(start 0.1524 0.127)
							(mid 0.137521 0.162921)
							(end 0.1016 0.1778)
						)
						(arc
							(start -0.1016 0.1778)
							(mid -0.137521 0.162921)
							(end -0.1524 0.127)
						)
						(arc
							(start -0.1524 -0.127)
							(mid -0.137521 -0.162921)
							(end -0.1016 -0.1778)
						)
						(arc
							(start 0.1016 -0.1778)
							(mid 0.137521 -0.162921)
							(end 0.1524 -0.127)
						)
					)
					(width 0)
					(fill yes)
				)
			)
		)
		(pad "2" smd custom
			(at 0 0.2794 90)
			(size 0.0762 0.0762)
			(layers "B.Cu" "B.Mask" "B.Paste")
			(net "GND")
			(options
				(clearance outline)
				(anchor circle)
			)
			(primitives
				(gr_poly
					(pts
						(arc
							(start 0.1524 0.127)
							(mid 0.137521 0.162921)
							(end 0.1016 0.1778)
						)
						(arc
							(start -0.1016 0.1778)
							(mid -0.137521 0.162921)
							(end -0.1524 0.127)
						)
						(arc
							(start -0.1524 -0.127)
							(mid -0.137521 -0.162921)
							(end -0.1016 -0.1778)
						)
						(arc
							(start 0.1016 -0.1778)
							(mid 0.137521 -0.162921)
							(end 0.1524 -0.127)
						)
					)
					(width 0)
					(fill yes)
				)
			)
		)
	)
	(footprint ""
		(layer "B.Cu")
		(at 78.486 -189.611)
		(property "Reference" "U69"
			(at 0 0 0)
			(layer "B.SilkS")
			(hide yes)
			(effects
				(font
					(size 1.27 1.27)
				)
				(justify mirror)
			)
		)
		(property "Value" "SN74LVC1G08DCKR-GP"
			(at 2.3368 -8.6868 0)
			(unlocked yes)
			(layer "B.Fab")
			(hide yes)
			(effects
				(font
					(size 1.016 1.016)
					(thickness 0.1524)
				)
				(justify mirror)
			)
		)
		(property "Device Type" "SC70-5H44"
			(at 2.3114 -10.414 0)
			(unlocked yes)
			(layer "B.Fab")
			(hide yes)
			(effects
				(font
					(size 1.016 1.016)
					(thickness 0.1524)
				)
				(justify mirror)
			)
		)
		(duplicate_pad_numbers_are_jumpers no)
		(fp_line
			(start -1.3843 -1.8034)
			(end -1.3843 -1.1176)
			(stroke
				(width 0.3302)
				(type default)
			)
			(layer "B.SilkS")
		)
		(fp_line
			(start -1.27 -1.7018)
			(end -1.27 1.7018)
			(stroke
				(width 0.1524)
				(type default)
			)
			(layer "B.SilkS")
		)
		(fp_line
			(start -1.27 1.7018)
			(end 1.27 1.7018)
			(stroke
				(width 0.1524)
				(type default)
			)
			(layer "B.SilkS")
		)
		(fp_line
			(start -0.6604 -1.8034)
			(end -1.3843 -1.8034)
			(stroke
				(width 0.3302)
				(type default)
			)
			(layer "B.SilkS")
		)
		(fp_line
			(start 1.27 -1.7018)
			(end -1.27 -1.7018)
			(stroke
				(width 0.1524)
				(type default)
			)
			(layer "B.SilkS")
		)
		(fp_line
			(start 1.27 1.7018)
			(end 1.27 -1.7018)
			(stroke
				(width 0.1524)
				(type default)
			)
			(layer "B.SilkS")
		)
		(fp_rect
			(start 1.524 1.9558)
			(end -1.524 -1.9558)
			(stroke
				(width 0)
				(type default)
			)
			(fill no)
			(layer "B.CrtYd")
		)
		(fp_poly
			(pts
				(xy 1.524 -1.9558) (xy -1.524 -1.9558) (xy -1.524 1.9558) (xy 1.524 1.9558)
			)
			(stroke
				(width 0)
				(type default)
			)
			(fill no)
			(layer "B.Fab")
		)
		(pad "1" smd rect
			(at -0.65024 -0.8255 180)
			(size 0.4064 1.2192)
			(layers "B.Cu" "B.Mask" "B.Paste")
			(net "BMC_SSD_RST#0_A5")
		)
		(pad "2" smd rect
			(at 0 -0.8255 180)
			(size 0.4064 1.2192)
			(layers "B.Cu" "B.Mask" "B.Paste")
			(net "SSD_PERST#0_B5")
		)
		(pad "3" smd rect
			(at 0.65024 -0.8255 180)
			(size 0.4064 1.2192)
			(layers "B.Cu" "B.Mask" "B.Paste")
			(net "GND")
		)
		(pad "4" smd rect
			(at 0.65024 0.8255 180)
			(size 0.4064 1.2192)
			(layers "B.Cu" "B.Mask" "B.Paste")
			(net "SSD_PERST_Y5")
		)
		(pad "5" smd rect
			(at -0.65024 0.8255 180)
			(size 0.4064 1.2192)
			(layers "B.Cu" "B.Mask" "B.Paste")
			(net "P3V3_STBY")
		)
	)
	(footprint ""
		(layer "B.Cu")
		(at 43.942 -137.795)
		(property "Reference" "TP229"
			(at 0 0 0)
			(layer "B.SilkS")
			(hide yes)
			(effects
				(font
					(size 1.27 1.27)
				)
				(justify mirror)
			)
		)
		(property "Value" "TPAD28-2-GP"
			(at 0.0127 -1.6637 0)
			(unlocked yes)
			(layer "B.Fab")
			(hide yes)
			(effects
				(font
					(size 1.016 1.016)
					(thickness 0.1524)
				)
				(justify mirror)
			)
		)
		(property "Device Type" "TPAD28"
			(at 0.0127 -3.1877 0)
			(unlocked yes)
			(layer "B.Fab")
			(hide yes)
			(effects
				(font
					(size 1.016 1.016)
					(thickness 0.1524)
				)
				(justify mirror)
			)
		)
		(duplicate_pad_numbers_are_jumpers no)
		(fp_poly
			(pts
				(arc
					(start 0.3556 0)
					(mid -0.3556 0)
					(end 0.3556 0)
				)
			)
			(stroke
				(width 0)
				(type default)
			)
			(fill no)
			(layer "B.CrtYd")
		)
		(fp_poly
			(pts
				(arc
					(start 0.6096 0)
					(mid -0.6096 0)
					(end 0.6096 0)
				)
			)
			(stroke
				(width 0)
				(type default)
			)
			(fill no)
			(layer "B.Fab")
		)
		(pad "1" smd circle
			(at 0 0 180)
			(size 0.7112 0.7112)
			(layers "B.Cu" "B.Mask" "B.Paste")
			(net "TP_GPIOO0")
		)
	)
	(footprint ""
		(layer "B.Cu")
		(at 237.1598 -54.0004 -90)
		(property "Reference" "C28"
			(at 0 0 90)
			(layer "B.SilkS")
			(hide yes)
			(effects
				(font
					(size 1.27 1.27)
				)
				(justify mirror)
			)
		)
		(property "Value" "SCD1U16V1KX-1-GP"
			(at 2.8321 -1.7399 270)
			(unlocked yes)
			(layer "B.Fab")
			(hide yes)
			(effects
				(font
					(size 1.016 1.016)
					(thickness 0.1524)
				)
				(justify mirror)
			)
		)
		(property "Device Type" "C0201H13"
			(at 2.8321 -3.2639 270)
			(unlocked yes)
			(layer "B.Fab")
			(hide yes)
			(effects
				(font
					(size 1.016 1.016)
					(thickness 0.1524)
				)
				(justify mirror)
			)
		)
		(duplicate_pad_numbers_are_jumpers no)
		(fp_rect
			(start 0.2794 0.6477)
			(end -0.2794 -0.6477)
			(stroke
				(width 0)
				(type default)
			)
			(fill no)
			(layer "B.CrtYd")
		)
		(fp_rect
			(start 0.2794 0.6477)
			(end -0.2794 -0.6477)
			(stroke
				(width 0)
				(type default)
			)
			(fill no)
			(layer "B.Fab")
		)
		(pad "1" smd custom
			(at 0 -0.2794 90)
			(size 0.0762 0.0762)
			(layers "B.Cu" "B.Mask" "B.Paste")
			(net "DUT_VDD")
			(options
				(clearance outline)
				(anchor circle)
			)
			(primitives
				(gr_poly
					(pts
						(arc
							(start 0.1524 0.127)
							(mid 0.137521 0.162921)
							(end 0.1016 0.1778)
						)
						(arc
							(start -0.1016 0.1778)
							(mid -0.137521 0.162921)
							(end -0.1524 0.127)
						)
						(arc
							(start -0.1524 -0.127)
							(mid -0.137521 -0.162921)
							(end -0.1016 -0.1778)
						)
						(arc
							(start 0.1016 -0.1778)
							(mid 0.137521 -0.162921)
							(end 0.1524 -0.127)
						)
					)
					(width 0)
					(fill yes)
				)
			)
		)
		(pad "2" smd custom
			(at 0 0.2794 90)
			(size 0.0762 0.0762)
			(layers "B.Cu" "B.Mask" "B.Paste")
			(net "GND")
			(options
				(clearance outline)
				(anchor circle)
			)
			(primitives
				(gr_poly
					(pts
						(arc
							(start 0.1524 0.127)
							(mid 0.137521 0.162921)
							(end 0.1016 0.1778)
						)
						(arc
							(start -0.1016 0.1778)
							(mid -0.137521 0.162921)
							(end -0.1524 0.127)
						)
						(arc
							(start -0.1524 -0.127)
							(mid -0.137521 -0.162921)
							(end -0.1016 -0.1778)
						)
						(arc
							(start 0.1016 -0.1778)
							(mid 0.137521 -0.162921)
							(end 0.1524 -0.127)
						)
					)
					(width 0)
					(fill yes)
				)
			)
		)
	)
	(footprint ""
		(layer "B.Cu")
		(at 248.59996 -38.999922 -90)
		(property "Reference" "TP281"
			(at 0 0 90)
			(layer "B.SilkS")
			(hide yes)
			(effects
				(font
					(size 1.27 1.27)
				)
				(justify mirror)
			)
		)
		(property "Value" "TPAD28-2-GP"
			(at 0.0127 -1.6637 270)
			(unlocked yes)
			(layer "B.Fab")
			(hide yes)
			(effects
				(font
					(size 1.016 1.016)
					(thickness 0.1524)
				)
				(justify mirror)
			)
		)
		(property "Device Type" "TPAD28"
			(at 0.0127 -3.1877 270)
			(unlocked yes)
			(layer "B.Fab")
			(hide yes)
			(effects
				(font
					(size 1.016 1.016)
					(thickness 0.1524)
				)
				(justify mirror)
			)
		)
		(duplicate_pad_numbers_are_jumpers no)
		(fp_poly
			(pts
				(arc
					(start 0 -0.3556)
					(mid 0 0.3556)
					(end 0 -0.3556)
				)
			)
			(stroke
				(width 0)
				(type default)
			)
			(fill no)
			(layer "B.CrtYd")
		)
		(fp_poly
			(pts
				(arc
					(start 0 -0.6096)
					(mid 0 0.6096)
					(end 0 -0.6096)
				)
			)
			(stroke
				(width 0)
				(type default)
			)
			(fill no)
			(layer "B.Fab")
		)
		(pad "1" smd circle
			(at 0 0 90)
			(size 0.7112 0.7112)
			(layers "B.Cu" "B.Mask" "B.Paste")
			(net "TWI_SRST#2")
		)
	)
	(footprint ""
		(layer "B.Cu")
		(at 43.434 -118.872)
		(property "Reference" "TP93"
			(at 0 0 0)
			(layer "B.SilkS")
			(hide yes)
			(effects
				(font
					(size 1.27 1.27)
				)
				(justify mirror)
			)
		)
		(property "Value" "TPAD28-2-GP"
			(at 0.0127 -1.6637 0)
			(unlocked yes)
			(layer "B.Fab")
			(hide yes)
			(effects
				(font
					(size 1.016 1.016)
					(thickness 0.1524)
				)
				(justify mirror)
			)
		)
		(property "Device Type" "TPAD28"
			(at 0.0127 -3.1877 0)
			(unlocked yes)
			(layer "B.Fab")
			(hide yes)
			(effects
				(font
					(size 1.016 1.016)
					(thickness 0.1524)
				)
				(justify mirror)
			)
		)
		(duplicate_pad_numbers_are_jumpers no)
		(fp_poly
			(pts
				(arc
					(start 0.3556 0)
					(mid -0.3556 0)
					(end 0.3556 0)
				)
			)
			(stroke
				(width 0)
				(type default)
			)
			(fill no)
			(layer "B.CrtYd")
		)
		(fp_poly
			(pts
				(arc
					(start 0.6096 0)
					(mid -0.6096 0)
					(end 0.6096 0)
				)
			)
			(stroke
				(width 0)
				(type default)
			)
			(fill no)
			(layer "B.Fab")
		)
		(pad "1" smd circle
			(at 0 0 180)
			(size 0.7112 0.7112)
			(layers "B.Cu" "B.Mask" "B.Paste")
			(net "TP_GPIOH4")
		)
	)
	(footprint ""
		(layer "B.Cu")
		(at 227.6856 -37.004752 -90)
		(property "Reference" "C569"
			(at 0 0 90)
			(layer "B.SilkS")
			(hide yes)
			(effects
				(font
					(size 1.27 1.27)
				)
				(justify mirror)
			)
		)
		(property "Value" "SCD1U16V1KX-1-GP"
			(at 2.8321 -1.7399 270)
			(unlocked yes)
			(layer "B.Fab")
			(hide yes)
			(effects
				(font
					(size 1.016 1.016)
					(thickness 0.1524)
				)
				(justify mirror)
			)
		)
		(property "Device Type" "C0201H13"
			(at 2.8321 -3.2639 270)
			(unlocked yes)
			(layer "B.Fab")
			(hide yes)
			(effects
				(font
					(size 1.016 1.016)
					(thickness 0.1524)
				)
				(justify mirror)
			)
		)
		(duplicate_pad_numbers_are_jumpers no)
		(fp_rect
			(start 0.2794 0.6477)
			(end -0.2794 -0.6477)
			(stroke
				(width 0)
				(type default)
			)
			(fill no)
			(layer "B.CrtYd")
		)
		(fp_rect
			(start 0.2794 0.6477)
			(end -0.2794 -0.6477)
			(stroke
				(width 0)
				(type default)
			)
			(fill no)
			(layer "B.Fab")
		)
		(pad "1" smd custom
			(at 0 -0.2794 90)
			(size 0.0762 0.0762)
			(layers "B.Cu" "B.Mask" "B.Paste")
			(net "DUT_AVD_PCIE")
			(options
				(clearance outline)
				(anchor circle)
			)
			(primitives
				(gr_poly
					(pts
						(arc
							(start 0.1524 0.127)
							(mid 0.137521 0.162921)
							(end 0.1016 0.1778)
						)
						(arc
							(start -0.1016 0.1778)
							(mid -0.137521 0.162921)
							(end -0.1524 0.127)
						)
						(arc
							(start -0.1524 -0.127)
							(mid -0.137521 -0.162921)
							(end -0.1016 -0.1778)
						)
						(arc
							(start 0.1016 -0.1778)
							(mid 0.137521 -0.162921)
							(end 0.1524 -0.127)
						)
					)
					(width 0)
					(fill yes)
				)
			)
		)
		(pad "2" smd custom
			(at 0 0.2794 90)
			(size 0.0762 0.0762)
			(layers "B.Cu" "B.Mask" "B.Paste")
			(net "GND")
			(options
				(clearance outline)
				(anchor circle)
			)
			(primitives
				(gr_poly
					(pts
						(arc
							(start 0.1524 0.127)
							(mid 0.137521 0.162921)
							(end 0.1016 0.1778)
						)
						(arc
							(start -0.1016 0.1778)
							(mid -0.137521 0.162921)
							(end -0.1524 0.127)
						)
						(arc
							(start -0.1524 -0.127)
							(mid -0.137521 -0.162921)
							(end -0.1016 -0.1778)
						)
						(arc
							(start 0.1016 -0.1778)
							(mid 0.137521 -0.162921)
							(end 0.1524 -0.127)
						)
					)
					(width 0)
					(fill yes)
				)
			)
		)
	)
	(footprint ""
		(layer "B.Cu")
		(at 19.9136 -185.2422 -90)
		(property "Reference" "R2122"
			(at 0 0 90)
			(layer "B.SilkS")
			(hide yes)
			(effects
				(font
					(size 1.27 1.27)
				)
				(justify mirror)
			)
		)
		(property "Value" "10R2F-L-GP"
			(at -0.064008 -3.993896 270)
			(unlocked yes)
			(layer "B.Fab")
			(hide yes)
			(effects
				(font
					(size 1.016 1.016)
					(thickness 0.1524)
				)
				(justify mirror)
			)
		)
		(property "Device Type" "R402H14"
			(at -0.064008 -5.517896 270)
			(unlocked yes)
			(layer "B.Fab")
			(hide yes)
			(effects
				(font
					(size 1.016 1.016)
					(thickness 0.1524)
				)
				(justify mirror)
			)
		)
		(duplicate_pad_numbers_are_jumpers no)
		(fp_line
			(start -0.508 -0.9398)
			(end 0.508 -0.9398)
			(stroke
				(width 0.1524)
				(type default)
			)
			(layer "B.SilkS")
		)
		(fp_line
			(start 0.508 -0.9398)
			(end 0.508 0.9398)
			(stroke
				(width 0.1524)
				(type default)
			)
			(layer "B.SilkS")
		)
		(fp_rect
			(start 0.508 0.9398)
			(end -0.508 -0.9398)
			(stroke
				(width 0)
				(type default)
			)
			(fill no)
			(layer "B.CrtYd")
		)
		(fp_rect
			(start 0.508 0.9398)
			(end -0.508 -0.9398)
			(stroke
				(width 0)
				(type default)
			)
			(fill no)
			(layer "B.Fab")
		)
		(pad "1" smd custom
			(at 0 -0.4445 90)
			(size 0.1397 0.1397)
			(layers "B.Cu" "B.Mask" "B.Paste")
			(net "MB0_CM_SENSE_R1_N")
			(options
				(clearance outline)
				(anchor circle)
			)
			(primitives
				(gr_poly
					(pts
						(arc
							(start -0.1778 0.2794)
							(mid -0.249642 0.249642)
							(end -0.2794 0.1778)
						)
						(arc
							(start -0.2794 -0.1778)
							(mid -0.249642 -0.249642)
							(end -0.1778 -0.2794)
						)
						(arc
							(start 0.1778 -0.2794)
							(mid 0.249642 -0.249642)
							(end 0.2794 -0.1778)
						)
						(arc
							(start 0.2794 0.1778)
							(mid 0.249642 0.249642)
							(end 0.1778 0.2794)
						)
					)
					(width 0)
					(fill yes)
				)
			)
		)
		(pad "2" smd custom
			(at 0 0.4445 90)
			(size 0.1397 0.1397)
			(layers "B.Cu" "B.Mask" "B.Paste")
			(net "MB0_CM_SENSE_N")
			(options
				(clearance outline)
				(anchor circle)
			)
			(primitives
				(gr_poly
					(pts
						(arc
							(start -0.1778 0.2794)
							(mid -0.249642 0.249642)
							(end -0.2794 0.1778)
						)
						(arc
							(start -0.2794 -0.1778)
							(mid -0.249642 -0.249642)
							(end -0.1778 -0.2794)
						)
						(arc
							(start 0.1778 -0.2794)
							(mid 0.249642 -0.249642)
							(end 0.2794 -0.1778)
						)
						(arc
							(start 0.2794 0.1778)
							(mid 0.249642 0.249642)
							(end 0.1778 0.2794)
						)
					)
					(width 0)
					(fill yes)
				)
			)
		)
	)
	(footprint ""
		(layer "B.Cu")
		(at 253.746 -26.1112 180)
		(property "Reference" "R760"
			(at 0 0 0)
			(layer "B.SilkS")
			(hide yes)
			(effects
				(font
					(size 1.27 1.27)
				)
				(justify mirror)
			)
		)
		(property "Value" "3K3R2F-2-GP"
			(at -0.064008 -3.993896 180)
			(unlocked yes)
			(layer "B.Fab")
			(hide yes)
			(effects
				(font
					(size 1.016 1.016)
					(thickness 0.1524)
				)
				(justify mirror)
			)
		)
		(property "Device Type" "R402H16"
			(at -0.064008 -5.517896 180)
			(unlocked yes)
			(layer "B.Fab")
			(hide yes)
			(effects
				(font
					(size 1.016 1.016)
					(thickness 0.1524)
				)
				(justify mirror)
			)
		)
		(duplicate_pad_numbers_are_jumpers no)
		(fp_line
			(start 0.508 -0.9398)
			(end 0.508 0.9398)
			(stroke
				(width 0.1524)
				(type default)
			)
			(layer "B.SilkS")
		)
		(fp_line
			(start -0.508 -0.9398)
			(end 0.508 -0.9398)
			(stroke
				(width 0.1524)
				(type default)
			)
			(layer "B.SilkS")
		)
		(fp_rect
			(start 0.508 0.9398)
			(end -0.508 -0.9398)
			(stroke
				(width 0)
				(type default)
			)
			(fill no)
			(layer "B.CrtYd")
		)
		(fp_rect
			(start 0.508 0.9398)
			(end -0.508 -0.9398)
			(stroke
				(width 0)
				(type default)
			)
			(fill no)
			(layer "B.Fab")
		)
		(pad "1" smd custom
			(at 0 -0.4445)
			(size 0.1397 0.1397)
			(layers "B.Cu" "B.Mask" "B.Paste")
			(net "P3V3_GPIO")
			(options
				(clearance outline)
				(anchor circle)
			)
			(primitives
				(gr_poly
					(pts
						(arc
							(start -0.1778 0.2794)
							(mid -0.249642 0.249642)
							(end -0.2794 0.1778)
						)
						(arc
							(start -0.2794 -0.1778)
							(mid -0.249642 -0.249642)
							(end -0.1778 -0.2794)
						)
						(arc
							(start 0.1778 -0.2794)
							(mid 0.249642 -0.249642)
							(end 0.2794 -0.1778)
						)
						(arc
							(start 0.2794 0.1778)
							(mid 0.249642 0.249642)
							(end 0.1778 0.2794)
						)
					)
					(width 0)
					(fill yes)
				)
			)
		)
		(pad "2" smd custom
			(at 0 0.4445)
			(size 0.1397 0.1397)
			(layers "B.Cu" "B.Mask" "B.Paste")
			(net "TWI_SDA0")
			(options
				(clearance outline)
				(anchor circle)
			)
			(primitives
				(gr_poly
					(pts
						(arc
							(start -0.1778 0.2794)
							(mid -0.249642 0.249642)
							(end -0.2794 0.1778)
						)
						(arc
							(start -0.2794 -0.1778)
							(mid -0.249642 -0.249642)
							(end -0.1778 -0.2794)
						)
						(arc
							(start 0.1778 -0.2794)
							(mid 0.249642 -0.249642)
							(end 0.2794 -0.1778)
						)
						(arc
							(start 0.2794 0.1778)
							(mid 0.249642 0.249642)
							(end 0.1778 0.2794)
						)
					)
					(width 0)
					(fill yes)
				)
			)
		)
	)
	(footprint ""
		(layer "B.Cu")
		(at 252.603 -44.010072 -90)
		(property "Reference" "C614"
			(at 0 0 90)
			(layer "B.SilkS")
			(hide yes)
			(effects
				(font
					(size 1.27 1.27)
				)
				(justify mirror)
			)
		)
		(property "Value" "SCD1U16V1KX-1-GP"
			(at 2.8321 -1.7399 270)
			(unlocked yes)
			(layer "B.Fab")
			(hide yes)
			(effects
				(font
					(size 1.016 1.016)
					(thickness 0.1524)
				)
				(justify mirror)
			)
		)
		(property "Device Type" "C0201H13"
			(at 2.8321 -3.2639 270)
			(unlocked yes)
			(layer "B.Fab")
			(hide yes)
			(effects
				(font
					(size 1.016 1.016)
					(thickness 0.1524)
				)
				(justify mirror)
			)
		)
		(duplicate_pad_numbers_are_jumpers no)
		(fp_rect
			(start 0.2794 0.6477)
			(end -0.2794 -0.6477)
			(stroke
				(width 0)
				(type default)
			)
			(fill no)
			(layer "B.CrtYd")
		)
		(fp_rect
			(start 0.2794 0.6477)
			(end -0.2794 -0.6477)
			(stroke
				(width 0)
				(type default)
			)
			(fill no)
			(layer "B.Fab")
		)
		(pad "1" smd custom
			(at 0 -0.2794 90)
			(size 0.0762 0.0762)
			(layers "B.Cu" "B.Mask" "B.Paste")
			(net "DUT_AVD_PCIE")
			(options
				(clearance outline)
				(anchor circle)
			)
			(primitives
				(gr_poly
					(pts
						(arc
							(start 0.1524 0.127)
							(mid 0.137521 0.162921)
							(end 0.1016 0.1778)
						)
						(arc
							(start -0.1016 0.1778)
							(mid -0.137521 0.162921)
							(end -0.1524 0.127)
						)
						(arc
							(start -0.1524 -0.127)
							(mid -0.137521 -0.162921)
							(end -0.1016 -0.1778)
						)
						(arc
							(start 0.1016 -0.1778)
							(mid 0.137521 -0.162921)
							(end 0.1524 -0.127)
						)
					)
					(width 0)
					(fill yes)
				)
			)
		)
		(pad "2" smd custom
			(at 0 0.2794 90)
			(size 0.0762 0.0762)
			(layers "B.Cu" "B.Mask" "B.Paste")
			(net "GND")
			(options
				(clearance outline)
				(anchor circle)
			)
			(primitives
				(gr_poly
					(pts
						(arc
							(start 0.1524 0.127)
							(mid 0.137521 0.162921)
							(end 0.1016 0.1778)
						)
						(arc
							(start -0.1016 0.1778)
							(mid -0.137521 0.162921)
							(end -0.1524 0.127)
						)
						(arc
							(start -0.1524 -0.127)
							(mid -0.137521 -0.162921)
							(end -0.1016 -0.1778)
						)
						(arc
							(start 0.1016 -0.1778)
							(mid 0.137521 -0.162921)
							(end 0.1524 -0.127)
						)
					)
					(width 0)
					(fill yes)
				)
			)
		)
	)
	(footprint ""
		(layer "B.Cu")
		(at 67.945 -190.627)
		(property "Reference" "R210"
			(at 0 0 0)
			(layer "B.SilkS")
			(hide yes)
			(effects
				(font
					(size 1.27 1.27)
				)
				(justify mirror)
			)
		)
		(property "Value" "4K7R2F-GP"
			(at -0.064008 -3.993896 0)
			(unlocked yes)
			(layer "B.Fab")
			(hide yes)
			(effects
				(font
					(size 1.016 1.016)
					(thickness 0.1524)
				)
				(justify mirror)
			)
		)
		(property "Device Type" "R402H16"
			(at -0.064008 -5.517896 0)
			(unlocked yes)
			(layer "B.Fab")
			(hide yes)
			(effects
				(font
					(size 1.016 1.016)
					(thickness 0.1524)
				)
				(justify mirror)
			)
		)
		(duplicate_pad_numbers_are_jumpers no)
		(fp_line
			(start -0.508 -0.9398)
			(end 0.508 -0.9398)
			(stroke
				(width 0.1524)
				(type default)
			)
			(layer "B.SilkS")
		)
		(fp_line
			(start 0.508 -0.9398)
			(end 0.508 0.9398)
			(stroke
				(width 0.1524)
				(type default)
			)
			(layer "B.SilkS")
		)
		(fp_rect
			(start 0.508 0.9398)
			(end -0.508 -0.9398)
			(stroke
				(width 0)
				(type default)
			)
			(fill no)
			(layer "B.CrtYd")
		)
		(fp_rect
			(start 0.508 0.9398)
			(end -0.508 -0.9398)
			(stroke
				(width 0)
				(type default)
			)
			(fill no)
			(layer "B.Fab")
		)
		(pad "1" smd custom
			(at 0 -0.4445 180)
			(size 0.1397 0.1397)
			(layers "B.Cu" "B.Mask" "B.Paste")
			(net "BMC_SSD_RST#0_A11")
			(options
				(clearance outline)
				(anchor circle)
			)
			(primitives
				(gr_poly
					(pts
						(arc
							(start -0.1778 0.2794)
							(mid -0.249642 0.249642)
							(end -0.2794 0.1778)
						)
						(arc
							(start -0.2794 -0.1778)
							(mid -0.249642 -0.249642)
							(end -0.1778 -0.2794)
						)
						(arc
							(start 0.1778 -0.2794)
							(mid 0.249642 -0.249642)
							(end 0.2794 -0.1778)
						)
						(arc
							(start 0.2794 0.1778)
							(mid 0.249642 0.249642)
							(end 0.1778 0.2794)
						)
					)
					(width 0)
					(fill yes)
				)
			)
		)
		(pad "2" smd custom
			(at 0 0.4445 180)
			(size 0.1397 0.1397)
			(layers "B.Cu" "B.Mask" "B.Paste")
			(net "P3V3_STBY")
			(options
				(clearance outline)
				(anchor circle)
			)
			(primitives
				(gr_poly
					(pts
						(arc
							(start -0.1778 0.2794)
							(mid -0.249642 0.249642)
							(end -0.2794 0.1778)
						)
						(arc
							(start -0.2794 -0.1778)
							(mid -0.249642 -0.249642)
							(end -0.1778 -0.2794)
						)
						(arc
							(start 0.1778 -0.2794)
							(mid 0.249642 -0.249642)
							(end 0.2794 -0.1778)
						)
						(arc
							(start 0.2794 0.1778)
							(mid 0.249642 0.249642)
							(end 0.1778 0.2794)
						)
					)
					(width 0)
					(fill yes)
				)
			)
		)
	)
	(footprint ""
		(layer "B.Cu")
		(at 230.63708 -38.94836 -90)
		(property "Reference" "TP278"
			(at 0 0 90)
			(layer "B.SilkS")
			(hide yes)
			(effects
				(font
					(size 1.27 1.27)
				)
				(justify mirror)
			)
		)
		(property "Value" "TPAD28-2-GP"
			(at 0.0127 -1.6637 270)
			(unlocked yes)
			(layer "B.Fab")
			(hide yes)
			(effects
				(font
					(size 1.016 1.016)
					(thickness 0.1524)
				)
				(justify mirror)
			)
		)
		(property "Device Type" "TPAD28"
			(at 0.0127 -3.1877 270)
			(unlocked yes)
			(layer "B.Fab")
			(hide yes)
			(effects
				(font
					(size 1.016 1.016)
					(thickness 0.1524)
				)
				(justify mirror)
			)
		)
		(duplicate_pad_numbers_are_jumpers no)
		(fp_poly
			(pts
				(arc
					(start 0 -0.3556)
					(mid 0 0.3556)
					(end 0 -0.3556)
				)
			)
			(stroke
				(width 0)
				(type default)
			)
			(fill no)
			(layer "B.CrtYd")
		)
		(fp_poly
			(pts
				(arc
					(start 0 -0.6096)
					(mid 0 0.6096)
					(end 0 -0.6096)
				)
			)
			(stroke
				(width 0)
				(type default)
			)
			(fill no)
			(layer "B.Fab")
		)
		(pad "1" smd circle
			(at 0 0 90)
			(size 0.7112 0.7112)
			(layers "B.Cu" "B.Mask" "B.Paste")
			(net "SPI_CSB0_1")
		)
	)
	(footprint ""
		(layer "B.Cu")
		(at 22.987 -69.58076 90)
		(property "Reference" "R396"
			(at 0 0 90)
			(layer "B.SilkS")
			(hide yes)
			(effects
				(font
					(size 1.27 1.27)
				)
				(justify mirror)
			)
		)
		(property "Value" "100KR2J-1-GP"
			(at -0.064008 -3.993896 90)
			(unlocked yes)
			(layer "B.Fab")
			(hide yes)
			(effects
				(font
					(size 1.016 1.016)
					(thickness 0.1524)
				)
				(justify mirror)
			)
		)
		(property "Device Type" "R402H16"
			(at -0.064008 -5.517896 90)
			(unlocked yes)
			(layer "B.Fab")
			(hide yes)
			(effects
				(font
					(size 1.016 1.016)
					(thickness 0.1524)
				)
				(justify mirror)
			)
		)
		(duplicate_pad_numbers_are_jumpers no)
		(fp_line
			(start 0.508 -0.9398)
			(end 0.508 0.9398)
			(stroke
				(width 0.1524)
				(type default)
			)
			(layer "B.SilkS")
		)
		(fp_line
			(start -0.508 -0.9398)
			(end 0.508 -0.9398)
			(stroke
				(width 0.1524)
				(type default)
			)
			(layer "B.SilkS")
		)
		(fp_rect
			(start 0.508 0.9398)
			(end -0.508 -0.9398)
			(stroke
				(width 0)
				(type default)
			)
			(fill no)
			(layer "B.CrtYd")
		)
		(fp_rect
			(start 0.508 0.9398)
			(end -0.508 -0.9398)
			(stroke
				(width 0)
				(type default)
			)
			(fill no)
			(layer "B.Fab")
		)
		(pad "1" smd custom
			(at 0 -0.4445 270)
			(size 0.1397 0.1397)
			(layers "B.Cu" "B.Mask" "B.Paste")
			(net "P3V3_STBY")
			(options
				(clearance outline)
				(anchor circle)
			)
			(primitives
				(gr_poly
					(pts
						(arc
							(start -0.1778 0.2794)
							(mid -0.249642 0.249642)
							(end -0.2794 0.1778)
						)
						(arc
							(start -0.2794 -0.1778)
							(mid -0.249642 -0.249642)
							(end -0.1778 -0.2794)
						)
						(arc
							(start 0.1778 -0.2794)
							(mid 0.249642 -0.249642)
							(end 0.2794 -0.1778)
						)
						(arc
							(start 0.2794 0.1778)
							(mid 0.249642 0.249642)
							(end 0.1778 0.2794)
						)
					)
					(width 0)
					(fill yes)
				)
			)
		)
		(pad "2" smd custom
			(at 0 0.4445 270)
			(size 0.1397 0.1397)
			(layers "B.Cu" "B.Mask" "B.Paste")
			(net "PHY_RESET_N")
			(options
				(clearance outline)
				(anchor circle)
			)
			(primitives
				(gr_poly
					(pts
						(arc
							(start -0.1778 0.2794)
							(mid -0.249642 0.249642)
							(end -0.2794 0.1778)
						)
						(arc
							(start -0.2794 -0.1778)
							(mid -0.249642 -0.249642)
							(end -0.1778 -0.2794)
						)
						(arc
							(start 0.1778 -0.2794)
							(mid 0.249642 -0.249642)
							(end 0.2794 -0.1778)
						)
						(arc
							(start 0.2794 0.1778)
							(mid 0.249642 0.249642)
							(end 0.1778 0.2794)
						)
					)
					(width 0)
					(fill yes)
				)
			)
		)
	)
	(footprint ""
		(layer "B.Cu")
		(at 20.955 -129.667 90)
		(property "Reference" "R340"
			(at 0 0 90)
			(layer "B.SilkS")
			(hide yes)
			(effects
				(font
					(size 1.27 1.27)
				)
				(justify mirror)
			)
		)
		(property "Value" "3K3R2F-2-GP"
			(at -0.064008 -3.993896 90)
			(unlocked yes)
			(layer "B.Fab")
			(hide yes)
			(effects
				(font
					(size 1.016 1.016)
					(thickness 0.1524)
				)
				(justify mirror)
			)
		)
		(property "Device Type" "R402H16"
			(at -0.064008 -5.517896 90)
			(unlocked yes)
			(layer "B.Fab")
			(hide yes)
			(effects
				(font
					(size 1.016 1.016)
					(thickness 0.1524)
				)
				(justify mirror)
			)
		)
		(duplicate_pad_numbers_are_jumpers no)
		(fp_line
			(start 0.508 -0.9398)
			(end 0.508 0.9398)
			(stroke
				(width 0.1524)
				(type default)
			)
			(layer "B.SilkS")
		)
		(fp_line
			(start -0.508 -0.9398)
			(end 0.508 -0.9398)
			(stroke
				(width 0.1524)
				(type default)
			)
			(layer "B.SilkS")
		)
		(fp_rect
			(start 0.508 0.9398)
			(end -0.508 -0.9398)
			(stroke
				(width 0)
				(type default)
			)
			(fill no)
			(layer "B.CrtYd")
		)
		(fp_rect
			(start 0.508 0.9398)
			(end -0.508 -0.9398)
			(stroke
				(width 0)
				(type default)
			)
			(fill no)
			(layer "B.Fab")
		)
		(pad "1" smd custom
			(at 0 -0.4445 270)
			(size 0.1397 0.1397)
			(layers "B.Cu" "B.Mask" "B.Paste")
			(net "P3V3_STBY")
			(options
				(clearance outline)
				(anchor circle)
			)
			(primitives
				(gr_poly
					(pts
						(arc
							(start -0.1778 0.2794)
							(mid -0.249642 0.249642)
							(end -0.2794 0.1778)
						)
						(arc
							(start -0.2794 -0.1778)
							(mid -0.249642 -0.249642)
							(end -0.1778 -0.2794)
						)
						(arc
							(start 0.1778 -0.2794)
							(mid 0.249642 -0.249642)
							(end 0.2794 -0.1778)
						)
						(arc
							(start 0.2794 0.1778)
							(mid 0.249642 0.249642)
							(end 0.1778 0.2794)
						)
					)
					(width 0)
					(fill yes)
				)
			)
		)
		(pad "2" smd custom
			(at 0 0.4445 270)
			(size 0.1397 0.1397)
			(layers "B.Cu" "B.Mask" "B.Paste")
			(net "ROMA8")
			(options
				(clearance outline)
				(anchor circle)
			)
			(primitives
				(gr_poly
					(pts
						(arc
							(start -0.1778 0.2794)
							(mid -0.249642 0.249642)
							(end -0.2794 0.1778)
						)
						(arc
							(start -0.2794 -0.1778)
							(mid -0.249642 -0.249642)
							(end -0.1778 -0.2794)
						)
						(arc
							(start 0.1778 -0.2794)
							(mid 0.249642 -0.249642)
							(end 0.2794 -0.1778)
						)
						(arc
							(start 0.2794 0.1778)
							(mid 0.249642 0.249642)
							(end 0.1778 0.2794)
						)
					)
					(width 0)
					(fill yes)
				)
			)
		)
	)
	(footprint ""
		(layer "B.Cu")
		(at 41.656 -116.713 180)
		(property "Reference" "R672"
			(at 0 0 0)
			(layer "B.SilkS")
			(hide yes)
			(effects
				(font
					(size 1.27 1.27)
				)
				(justify mirror)
			)
		)
		(property "Value" "0R2J-2-GP"
			(at -0.064008 -3.993896 180)
			(unlocked yes)
			(layer "B.Fab")
			(hide yes)
			(effects
				(font
					(size 1.016 1.016)
					(thickness 0.1524)
				)
				(justify mirror)
			)
		)
		(property "Device Type" "R402H16"
			(at -0.064008 -5.517896 180)
			(unlocked yes)
			(layer "B.Fab")
			(hide yes)
			(effects
				(font
					(size 1.016 1.016)
					(thickness 0.1524)
				)
				(justify mirror)
			)
		)
		(duplicate_pad_numbers_are_jumpers no)
		(fp_line
			(start 0.508 -0.9398)
			(end 0.508 0.9398)
			(stroke
				(width 0.1524)
				(type default)
			)
			(layer "B.SilkS")
		)
		(fp_line
			(start -0.508 -0.9398)
			(end 0.508 -0.9398)
			(stroke
				(width 0.1524)
				(type default)
			)
			(layer "B.SilkS")
		)
		(fp_rect
			(start 0.508 0.9398)
			(end -0.508 -0.9398)
			(stroke
				(width 0)
				(type default)
			)
			(fill no)
			(layer "B.CrtYd")
		)
		(fp_rect
			(start 0.508 0.9398)
			(end -0.508 -0.9398)
			(stroke
				(width 0)
				(type default)
			)
			(fill no)
			(layer "B.Fab")
		)
		(pad "1" smd custom
			(at 0 -0.4445)
			(size 0.1397 0.1397)
			(layers "B.Cu" "B.Mask" "B.Paste")
			(net "CLK_50M_BMC_NCSI")
			(options
				(clearance outline)
				(anchor circle)
			)
			(primitives
				(gr_poly
					(pts
						(arc
							(start -0.1778 0.2794)
							(mid -0.249642 0.249642)
							(end -0.2794 0.1778)
						)
						(arc
							(start -0.2794 -0.1778)
							(mid -0.249642 -0.249642)
							(end -0.1778 -0.2794)
						)
						(arc
							(start 0.1778 -0.2794)
							(mid 0.249642 -0.249642)
							(end 0.2794 -0.1778)
						)
						(arc
							(start 0.2794 0.1778)
							(mid 0.249642 0.249642)
							(end 0.1778 0.2794)
						)
					)
					(width 0)
					(fill yes)
				)
			)
		)
		(pad "2" smd custom
			(at 0 0.4445)
			(size 0.1397 0.1397)
			(layers "B.Cu" "B.Mask" "B.Paste")
			(net "CLK_50M_BMC_NCSI_R")
			(options
				(clearance outline)
				(anchor circle)
			)
			(primitives
				(gr_poly
					(pts
						(arc
							(start -0.1778 0.2794)
							(mid -0.249642 0.249642)
							(end -0.2794 0.1778)
						)
						(arc
							(start -0.2794 -0.1778)
							(mid -0.249642 -0.249642)
							(end -0.1778 -0.2794)
						)
						(arc
							(start 0.1778 -0.2794)
							(mid 0.249642 -0.249642)
							(end 0.2794 -0.1778)
						)
						(arc
							(start 0.2794 0.1778)
							(mid 0.249642 0.249642)
							(end 0.1778 0.2794)
						)
					)
					(width 0)
					(fill yes)
				)
			)
		)
	)
	(footprint ""
		(layer "B.Cu")
		(at 226.740212 -193.911474)
		(property "Reference" "C3205"
			(at 0 0 0)
			(layer "B.SilkS")
			(hide yes)
			(effects
				(font
					(size 1.27 1.27)
				)
				(justify mirror)
			)
		)
		(property "Value" "SCD1U25V2KX-2-GP"
			(at -1.1811 -2.7051 0)
			(unlocked yes)
			(layer "B.Fab")
			(hide yes)
			(effects
				(font
					(size 1.016 1.016)
					(thickness 0.1524)
				)
				(justify mirror)
			)
		)
		(property "Device Type" "C402H22"
			(at -1.1811 -4.2291 0)
			(unlocked yes)
			(layer "B.Fab")
			(hide yes)
			(effects
				(font
					(size 1.016 1.016)
					(thickness 0.1524)
				)
				(justify mirror)
			)
		)
		(duplicate_pad_numbers_are_jumpers no)
		(fp_rect
			(start 0.4318 0.9525)
			(end -0.4318 -0.9525)
			(stroke
				(width 0)
				(type default)
			)
			(fill no)
			(layer "B.CrtYd")
		)
		(fp_rect
			(start 0.4318 0.9525)
			(end -0.4318 -0.9525)
			(stroke
				(width 0)
				(type default)
			)
			(fill no)
			(layer "B.Fab")
		)
		(pad "1" smd custom
			(at 0 -0.4445 180)
			(size 0.1524 0.1524)
			(layers "B.Cu" "B.Mask" "B.Paste")
			(net "P3V3_STBY")
			(options
				(clearance outline)
				(anchor circle)
			)
			(primitives
				(gr_poly
					(pts
						(arc
							(start 0.3048 0.2032)
							(mid 0.275042 0.275042)
							(end 0.2032 0.3048)
						)
						(arc
							(start -0.2032 0.3048)
							(mid -0.275042 0.275042)
							(end -0.3048 0.2032)
						)
						(arc
							(start -0.3048 -0.2032)
							(mid -0.275042 -0.275042)
							(end -0.2032 -0.3048)
						)
						(arc
							(start 0.2032 -0.3048)
							(mid 0.275042 -0.275042)
							(end 0.3048 -0.2032)
						)
					)
					(width 0)
					(fill yes)
				)
			)
		)
		(pad "2" smd custom
			(at 0 0.4445 180)
			(size 0.1524 0.1524)
			(layers "B.Cu" "B.Mask" "B.Paste")
			(net "GND")
			(options
				(clearance outline)
				(anchor circle)
			)
			(primitives
				(gr_poly
					(pts
						(arc
							(start 0.3048 0.2032)
							(mid 0.275042 0.275042)
							(end 0.2032 0.3048)
						)
						(arc
							(start -0.2032 0.3048)
							(mid -0.275042 0.275042)
							(end -0.3048 0.2032)
						)
						(arc
							(start -0.3048 -0.2032)
							(mid -0.275042 -0.275042)
							(end -0.2032 -0.3048)
						)
						(arc
							(start 0.2032 -0.3048)
							(mid 0.275042 -0.275042)
							(end 0.3048 -0.2032)
						)
					)
					(width 0)
					(fill yes)
				)
			)
		)
	)
	(footprint ""
		(layer "B.Cu")
		(at 146.414236 -61.79058 90)
		(property "Reference" "PR177"
			(at 0 0 90)
			(layer "B.SilkS")
			(hide yes)
			(effects
				(font
					(size 1.27 1.27)
				)
				(justify mirror)
			)
		)
		(property "Value" "0R3J-0-U-GP"
			(at 0.0254 -2.5146 90)
			(unlocked yes)
			(layer "B.Fab")
			(hide yes)
			(effects
				(font
					(size 1.016 1.016)
					(thickness 0.1524)
				)
				(justify mirror)
			)
		)
		(property "Device Type" "R603H22"
			(at 0.0254 -4.0386 90)
			(unlocked yes)
			(layer "B.Fab")
			(hide yes)
			(effects
				(font
					(size 1.016 1.016)
					(thickness 0.1524)
				)
				(justify mirror)
			)
		)
		(duplicate_pad_numbers_are_jumpers no)
		(fp_line
			(start 0.4826 0)
			(end 0.2032 0)
			(stroke
				(width 0.2032)
				(type default)
			)
			(layer "B.SilkS")
		)
		(fp_line
			(start -0.2032 0)
			(end -0.4826 0)
			(stroke
				(width 0.2032)
				(type default)
			)
			(layer "B.SilkS")
		)
		(fp_rect
			(start 0.5842 1.3335)
			(end -0.5842 -1.3335)
			(stroke
				(width 0)
				(type default)
			)
			(fill no)
			(layer "B.CrtYd")
		)
		(fp_rect
			(start 0.5842 1.3335)
			(end -0.5842 -1.3335)
			(stroke
				(width 0)
				(type default)
			)
			(fill no)
			(layer "B.Fab")
		)
		(pad "1" smd custom
			(at 0 -0.762 270)
			(size 0.2159 0.2159)
			(layers "B.Cu" "B.Mask" "B.Paste")
			(net "P12V")
			(options
				(clearance outline)
				(anchor circle)
			)
			(primitives
				(gr_poly
					(pts
						(arc
							(start -0.3302 0.4318)
							(mid -0.402042 0.402042)
							(end -0.4318 0.3302)
						)
						(arc
							(start -0.4318 -0.3302)
							(mid -0.402042 -0.402042)
							(end -0.3302 -0.4318)
						)
						(arc
							(start 0.3302 -0.4318)
							(mid 0.402042 -0.402042)
							(end 0.4318 -0.3302)
						)
						(arc
							(start 0.4318 0.3302)
							(mid 0.402042 0.402042)
							(end 0.3302 0.4318)
						)
					)
					(width 0)
					(fill yes)
				)
			)
		)
		(pad "2" smd custom
			(at 0 0.762 270)
			(size 0.2159 0.2159)
			(layers "B.Cu" "B.Mask" "B.Paste")
			(net "P0V9_VDD")
			(options
				(clearance outline)
				(anchor circle)
			)
			(primitives
				(gr_poly
					(pts
						(arc
							(start -0.3302 0.4318)
							(mid -0.402042 0.402042)
							(end -0.4318 0.3302)
						)
						(arc
							(start -0.4318 -0.3302)
							(mid -0.402042 -0.402042)
							(end -0.3302 -0.4318)
						)
						(arc
							(start 0.3302 -0.4318)
							(mid 0.402042 -0.402042)
							(end 0.4318 -0.3302)
						)
						(arc
							(start 0.4318 0.3302)
							(mid 0.402042 0.402042)
							(end 0.3302 0.4318)
						)
					)
					(width 0)
					(fill yes)
				)
			)
		)
	)
	(footprint ""
		(layer "B.Cu")
		(at 224.409 -10.287 180)
		(property "Reference" "PQ22"
			(at 0 0 0)
			(layer "B.SilkS")
			(hide yes)
			(effects
				(font
					(size 1.27 1.27)
				)
				(justify mirror)
			)
		)
		(property "Value" "AO3400-GP-U"
			(at -0.0254 -12.3444 180)
			(unlocked yes)
			(layer "B.Fab")
			(hide yes)
			(effects
				(font
					(size 1.016 1.016)
					(thickness 0.1524)
				)
				(justify mirror)
			)
		)
		(property "Device Type" "SOT23DGS2D8H50"
			(at -0.0254 -14.2494 180)
			(unlocked yes)
			(layer "B.Fab")
			(hide yes)
			(effects
				(font
					(size 1.016 1.016)
					(thickness 0.1524)
				)
				(justify mirror)
			)
		)
		(duplicate_pad_numbers_are_jumpers no)
		(fp_line
			(start 1.7018 0.254)
			(end 1.7018 -0.254)
			(stroke
				(width 0.1524)
				(type default)
			)
			(layer "B.SilkS")
		)
		(fp_line
			(start 1.7018 -0.254)
			(end -1.7018 -0.254)
			(stroke
				(width 0.1524)
				(type default)
			)
			(layer "B.SilkS")
		)
		(fp_line
			(start -1.7018 0.254)
			(end 1.7018 0.254)
			(stroke
				(width 0.1524)
				(type default)
			)
			(layer "B.SilkS")
		)
		(fp_line
			(start -1.7018 -0.254)
			(end -1.7018 0.254)
			(stroke
				(width 0.1524)
				(type default)
			)
			(layer "B.SilkS")
		)
		(fp_rect
			(start 1.778 1.9812)
			(end -1.778 -1.9812)
			(stroke
				(width 0)
				(type default)
			)
			(fill no)
			(layer "B.CrtYd")
		)
		(fp_poly
			(pts
				(xy 1.778 -1.9812) (xy -1.778 -1.9812) (xy -1.778 1.9812) (xy 1.778 1.9812)
			)
			(stroke
				(width 0)
				(type default)
			)
			(fill no)
			(layer "B.Fab")
		)
		(pad "D" smd custom
			(at 0 -1.1176)
			(size 0.254 0.254)
			(layers "B.Cu" "B.Mask" "B.Paste")
			(net "U81_B")
			(options
				(clearance outline)
				(anchor circle)
			)
			(primitives
				(gr_poly
					(pts
						(arc
							(start -0.508 0.4064)
							(mid -0.448484 0.550084)
							(end -0.3048 0.6096)
						)
						(arc
							(start 0.3048 0.6096)
							(mid 0.448484 0.550084)
							(end 0.508 0.4064)
						)
						(arc
							(start 0.508 -0.4064)
							(mid 0.448484 -0.550084)
							(end 0.3048 -0.6096)
						)
						(arc
							(start -0.3048 -0.6096)
							(mid -0.448484 -0.550084)
							(end -0.508 -0.4064)
						)
					)
					(width 0)
					(fill yes)
				)
			)
		)
		(pad "G" smd custom
			(at 1.016 1.1176)
			(size 0.254 0.254)
			(layers "B.Cu" "B.Mask" "B.Paste")
			(net "PQ22_G")
			(options
				(clearance outline)
				(anchor circle)
			)
			(primitives
				(gr_poly
					(pts
						(arc
							(start -0.508 0.4064)
							(mid -0.448484 0.550084)
							(end -0.3048 0.6096)
						)
						(arc
							(start 0.3048 0.6096)
							(mid 0.448484 0.550084)
							(end 0.508 0.4064)
						)
						(arc
							(start 0.508 -0.4064)
							(mid 0.448484 -0.550084)
							(end 0.3048 -0.6096)
						)
						(arc
							(start -0.3048 -0.6096)
							(mid -0.448484 -0.550084)
							(end -0.508 -0.4064)
						)
					)
					(width 0)
					(fill yes)
				)
			)
		)
		(pad "S" smd custom
			(at -1.016 1.1176)
			(size 0.254 0.254)
			(layers "B.Cu" "B.Mask" "B.Paste")
			(net "GND")
			(options
				(clearance outline)
				(anchor circle)
			)
			(primitives
				(gr_poly
					(pts
						(arc
							(start -0.508 0.4064)
							(mid -0.448484 0.550084)
							(end -0.3048 0.6096)
						)
						(arc
							(start 0.3048 0.6096)
							(mid 0.448484 0.550084)
							(end 0.508 0.4064)
						)
						(arc
							(start 0.508 -0.4064)
							(mid 0.448484 -0.550084)
							(end 0.3048 -0.6096)
						)
						(arc
							(start -0.3048 -0.6096)
							(mid -0.448484 -0.550084)
							(end -0.508 -0.4064)
						)
					)
					(width 0)
					(fill yes)
				)
			)
		)
	)
	(footprint ""
		(layer "B.Cu")
		(at 338.868512 -184.878218 180)
		(property "Reference" "R4152"
			(at 0 0 0)
			(layer "B.SilkS")
			(hide yes)
			(effects
				(font
					(size 1.27 1.27)
				)
				(justify mirror)
			)
		)
		(property "Value" "4K7R2F-GP"
			(at -0.064008 -3.993896 180)
			(unlocked yes)
			(layer "B.Fab")
			(hide yes)
			(effects
				(font
					(size 1.016 1.016)
					(thickness 0.1524)
				)
				(justify mirror)
			)
		)
		(property "Device Type" "R402H16"
			(at -0.064008 -5.517896 180)
			(unlocked yes)
			(layer "B.Fab")
			(hide yes)
			(effects
				(font
					(size 1.016 1.016)
					(thickness 0.1524)
				)
				(justify mirror)
			)
		)
		(duplicate_pad_numbers_are_jumpers no)
		(fp_line
			(start 0.508 -0.9398)
			(end 0.508 0.9398)
			(stroke
				(width 0.1524)
				(type default)
			)
			(layer "B.SilkS")
		)
		(fp_line
			(start -0.508 -0.9398)
			(end 0.508 -0.9398)
			(stroke
				(width 0.1524)
				(type default)
			)
			(layer "B.SilkS")
		)
		(fp_rect
			(start 0.508 0.9398)
			(end -0.508 -0.9398)
			(stroke
				(width 0)
				(type default)
			)
			(fill no)
			(layer "B.CrtYd")
		)
		(fp_rect
			(start 0.508 0.9398)
			(end -0.508 -0.9398)
			(stroke
				(width 0)
				(type default)
			)
			(fill no)
			(layer "B.Fab")
		)
		(pad "1" smd custom
			(at 0 -0.4445)
			(size 0.1397 0.1397)
			(layers "B.Cu" "B.Mask" "B.Paste")
			(net "SSD_ATNLED#14")
			(options
				(clearance outline)
				(anchor circle)
			)
			(primitives
				(gr_poly
					(pts
						(arc
							(start -0.1778 0.2794)
							(mid -0.249642 0.249642)
							(end -0.2794 0.1778)
						)
						(arc
							(start -0.2794 -0.1778)
							(mid -0.249642 -0.249642)
							(end -0.1778 -0.2794)
						)
						(arc
							(start 0.1778 -0.2794)
							(mid 0.249642 -0.249642)
							(end 0.2794 -0.1778)
						)
						(arc
							(start 0.2794 0.1778)
							(mid 0.249642 0.249642)
							(end 0.1778 0.2794)
						)
					)
					(width 0)
					(fill yes)
				)
			)
		)
		(pad "2" smd custom
			(at 0 0.4445)
			(size 0.1397 0.1397)
			(layers "B.Cu" "B.Mask" "B.Paste")
			(net "P3V3_STBY")
			(options
				(clearance outline)
				(anchor circle)
			)
			(primitives
				(gr_poly
					(pts
						(arc
							(start -0.1778 0.2794)
							(mid -0.249642 0.249642)
							(end -0.2794 0.1778)
						)
						(arc
							(start -0.2794 -0.1778)
							(mid -0.249642 -0.249642)
							(end -0.1778 -0.2794)
						)
						(arc
							(start 0.1778 -0.2794)
							(mid 0.249642 -0.249642)
							(end 0.2794 -0.1778)
						)
						(arc
							(start 0.2794 0.1778)
							(mid 0.249642 0.249642)
							(end 0.1778 0.2794)
						)
					)
					(width 0)
					(fill yes)
				)
			)
		)
	)
	(footprint ""
		(layer "B.Cu")
		(at 40.005 -117.602)
		(property "Reference" "TP327"
			(at 0 0 0)
			(layer "B.SilkS")
			(hide yes)
			(effects
				(font
					(size 1.27 1.27)
				)
				(justify mirror)
			)
		)
		(property "Value" "TPAD28-2-GP"
			(at 0.0127 -1.6637 0)
			(unlocked yes)
			(layer "B.Fab")
			(hide yes)
			(effects
				(font
					(size 1.016 1.016)
					(thickness 0.1524)
				)
				(justify mirror)
			)
		)
		(property "Device Type" "TPAD28"
			(at 0.0127 -3.1877 0)
			(unlocked yes)
			(layer "B.Fab")
			(hide yes)
			(effects
				(font
					(size 1.016 1.016)
					(thickness 0.1524)
				)
				(justify mirror)
			)
		)
		(duplicate_pad_numbers_are_jumpers no)
		(fp_poly
			(pts
				(arc
					(start 0.3556 0)
					(mid -0.3556 0)
					(end 0.3556 0)
				)
			)
			(stroke
				(width 0)
				(type default)
			)
			(fill no)
			(layer "B.CrtYd")
		)
		(fp_poly
			(pts
				(arc
					(start 0.6096 0)
					(mid -0.6096 0)
					(end 0.6096 0)
				)
			)
			(stroke
				(width 0)
				(type default)
			)
			(fill no)
			(layer "B.Fab")
		)
		(pad "1" smd circle
			(at 0 0 180)
			(size 0.7112 0.7112)
			(layers "B.Cu" "B.Mask" "B.Paste")
			(net "TP_GPIOU2")
		)
	)
	(footprint ""
		(layer "B.Cu")
		(at 124.262388 -202.811126)
		(property "Reference" "U71"
			(at 0 0 0)
			(layer "B.SilkS")
			(hide yes)
			(effects
				(font
					(size 1.27 1.27)
				)
				(justify mirror)
			)
		)
		(property "Value" "SN74LVC1G08DCKR-GP"
			(at 2.3368 -8.6868 0)
			(unlocked yes)
			(layer "B.Fab")
			(hide yes)
			(effects
				(font
					(size 1.016 1.016)
					(thickness 0.1524)
				)
				(justify mirror)
			)
		)
		(property "Device Type" "SC70-5H44"
			(at 2.3114 -10.414 0)
			(unlocked yes)
			(layer "B.Fab")
			(hide yes)
			(effects
				(font
					(size 1.016 1.016)
					(thickness 0.1524)
				)
				(justify mirror)
			)
		)
		(duplicate_pad_numbers_are_jumpers no)
		(fp_line
			(start -1.3843 -1.8034)
			(end -1.3843 -1.1176)
			(stroke
				(width 0.3302)
				(type default)
			)
			(layer "B.SilkS")
		)
		(fp_line
			(start -1.27 -1.7018)
			(end -1.27 1.7018)
			(stroke
				(width 0.1524)
				(type default)
			)
			(layer "B.SilkS")
		)
		(fp_line
			(start -1.27 1.7018)
			(end 1.27 1.7018)
			(stroke
				(width 0.1524)
				(type default)
			)
			(layer "B.SilkS")
		)
		(fp_line
			(start -0.6604 -1.8034)
			(end -1.3843 -1.8034)
			(stroke
				(width 0.3302)
				(type default)
			)
			(layer "B.SilkS")
		)
		(fp_line
			(start 1.27 -1.7018)
			(end -1.27 -1.7018)
			(stroke
				(width 0.1524)
				(type default)
			)
			(layer "B.SilkS")
		)
		(fp_line
			(start 1.27 1.7018)
			(end 1.27 -1.7018)
			(stroke
				(width 0.1524)
				(type default)
			)
			(layer "B.SilkS")
		)
		(fp_rect
			(start 1.524 1.9558)
			(end -1.524 -1.9558)
			(stroke
				(width 0)
				(type default)
			)
			(fill no)
			(layer "B.CrtYd")
		)
		(fp_poly
			(pts
				(xy 1.524 -1.9558) (xy -1.524 -1.9558) (xy -1.524 1.9558) (xy 1.524 1.9558)
			)
			(stroke
				(width 0)
				(type default)
			)
			(fill no)
			(layer "B.Fab")
		)
		(pad "1" smd rect
			(at -0.65024 -0.8255 180)
			(size 0.4064 1.2192)
			(layers "B.Cu" "B.Mask" "B.Paste")
			(net "BMC_SSD_RST#0_A7")
		)
		(pad "2" smd rect
			(at 0 -0.8255 180)
			(size 0.4064 1.2192)
			(layers "B.Cu" "B.Mask" "B.Paste")
			(net "SSD_PERST#0_B7")
		)
		(pad "3" smd rect
			(at 0.65024 -0.8255 180)
			(size 0.4064 1.2192)
			(layers "B.Cu" "B.Mask" "B.Paste")
			(net "GND")
		)
		(pad "4" smd rect
			(at 0.65024 0.8255 180)
			(size 0.4064 1.2192)
			(layers "B.Cu" "B.Mask" "B.Paste")
			(net "SSD_PERST_Y7")
		)
		(pad "5" smd rect
			(at -0.65024 0.8255 180)
			(size 0.4064 1.2192)
			(layers "B.Cu" "B.Mask" "B.Paste")
			(net "P3V3_STBY")
		)
	)
	(footprint ""
		(layer "B.Cu")
		(at 243.1288 -48.9966 -90)
		(property "Reference" "C447"
			(at 0 0 90)
			(layer "B.SilkS")
			(hide yes)
			(effects
				(font
					(size 1.27 1.27)
				)
				(justify mirror)
			)
		)
		(property "Value" "SCD1U16V1KX-1-GP"
			(at 2.8321 -1.7399 270)
			(unlocked yes)
			(layer "B.Fab")
			(hide yes)
			(effects
				(font
					(size 1.016 1.016)
					(thickness 0.1524)
				)
				(justify mirror)
			)
		)
		(property "Device Type" "C0201H13"
			(at 2.8321 -3.2639 270)
			(unlocked yes)
			(layer "B.Fab")
			(hide yes)
			(effects
				(font
					(size 1.016 1.016)
					(thickness 0.1524)
				)
				(justify mirror)
			)
		)
		(duplicate_pad_numbers_are_jumpers no)
		(fp_rect
			(start 0.2794 0.6477)
			(end -0.2794 -0.6477)
			(stroke
				(width 0)
				(type default)
			)
			(fill no)
			(layer "B.CrtYd")
		)
		(fp_rect
			(start 0.2794 0.6477)
			(end -0.2794 -0.6477)
			(stroke
				(width 0)
				(type default)
			)
			(fill no)
			(layer "B.Fab")
		)
		(pad "1" smd custom
			(at 0 -0.2794 90)
			(size 0.0762 0.0762)
			(layers "B.Cu" "B.Mask" "B.Paste")
			(net "DUT_VDD")
			(options
				(clearance outline)
				(anchor circle)
			)
			(primitives
				(gr_poly
					(pts
						(arc
							(start 0.1524 0.127)
							(mid 0.137521 0.162921)
							(end 0.1016 0.1778)
						)
						(arc
							(start -0.1016 0.1778)
							(mid -0.137521 0.162921)
							(end -0.1524 0.127)
						)
						(arc
							(start -0.1524 -0.127)
							(mid -0.137521 -0.162921)
							(end -0.1016 -0.1778)
						)
						(arc
							(start 0.1016 -0.1778)
							(mid 0.137521 -0.162921)
							(end 0.1524 -0.127)
						)
					)
					(width 0)
					(fill yes)
				)
			)
		)
		(pad "2" smd custom
			(at 0 0.2794 90)
			(size 0.0762 0.0762)
			(layers "B.Cu" "B.Mask" "B.Paste")
			(net "GND")
			(options
				(clearance outline)
				(anchor circle)
			)
			(primitives
				(gr_poly
					(pts
						(arc
							(start 0.1524 0.127)
							(mid 0.137521 0.162921)
							(end 0.1016 0.1778)
						)
						(arc
							(start -0.1016 0.1778)
							(mid -0.137521 0.162921)
							(end -0.1524 0.127)
						)
						(arc
							(start -0.1524 -0.127)
							(mid -0.137521 -0.162921)
							(end -0.1016 -0.1778)
						)
						(arc
							(start 0.1016 -0.1778)
							(mid 0.137521 -0.162921)
							(end 0.1524 -0.127)
						)
					)
					(width 0)
					(fill yes)
				)
			)
		)
	)
	(footprint ""
		(layer "B.Cu")
		(at 337.241388 -178.808126)
		(property "Reference" "U73"
			(at 0 0 0)
			(layer "B.SilkS")
			(hide yes)
			(effects
				(font
					(size 1.27 1.27)
				)
				(justify mirror)
			)
		)
		(property "Value" "SN74LVC1G08DCKR-GP"
			(at 2.3368 -8.6868 0)
			(unlocked yes)
			(layer "B.Fab")
			(hide yes)
			(effects
				(font
					(size 1.016 1.016)
					(thickness 0.1524)
				)
				(justify mirror)
			)
		)
		(property "Device Type" "SC70-5H44"
			(at 2.3114 -10.414 0)
			(unlocked yes)
			(layer "B.Fab")
			(hide yes)
			(effects
				(font
					(size 1.016 1.016)
					(thickness 0.1524)
				)
				(justify mirror)
			)
		)
		(duplicate_pad_numbers_are_jumpers no)
		(fp_line
			(start -1.3843 -1.8034)
			(end -1.3843 -1.1176)
			(stroke
				(width 0.3302)
				(type default)
			)
			(layer "B.SilkS")
		)
		(fp_line
			(start -1.27 -1.7018)
			(end -1.27 1.7018)
			(stroke
				(width 0.1524)
				(type default)
			)
			(layer "B.SilkS")
		)
		(fp_line
			(start -1.27 1.7018)
			(end 1.27 1.7018)
			(stroke
				(width 0.1524)
				(type default)
			)
			(layer "B.SilkS")
		)
		(fp_line
			(start -0.6604 -1.8034)
			(end -1.3843 -1.8034)
			(stroke
				(width 0.3302)
				(type default)
			)
			(layer "B.SilkS")
		)
		(fp_line
			(start 1.27 -1.7018)
			(end -1.27 -1.7018)
			(stroke
				(width 0.1524)
				(type default)
			)
			(layer "B.SilkS")
		)
		(fp_line
			(start 1.27 1.7018)
			(end 1.27 -1.7018)
			(stroke
				(width 0.1524)
				(type default)
			)
			(layer "B.SilkS")
		)
		(fp_rect
			(start 1.524 1.9558)
			(end -1.524 -1.9558)
			(stroke
				(width 0)
				(type default)
			)
			(fill no)
			(layer "B.CrtYd")
		)
		(fp_poly
			(pts
				(xy 1.524 -1.9558) (xy -1.524 -1.9558) (xy -1.524 1.9558) (xy 1.524 1.9558)
			)
			(stroke
				(width 0)
				(type default)
			)
			(fill no)
			(layer "B.Fab")
		)
		(pad "1" smd rect
			(at -0.65024 -0.8255 180)
			(size 0.4064 1.2192)
			(layers "B.Cu" "B.Mask" "B.Paste")
			(net "BMC_SSD_RST#0_A9")
		)
		(pad "2" smd rect
			(at 0 -0.8255 180)
			(size 0.4064 1.2192)
			(layers "B.Cu" "B.Mask" "B.Paste")
			(net "SSD_PERST#0_B9")
		)
		(pad "3" smd rect
			(at 0.65024 -0.8255 180)
			(size 0.4064 1.2192)
			(layers "B.Cu" "B.Mask" "B.Paste")
			(net "GND")
		)
		(pad "4" smd rect
			(at 0.65024 0.8255 180)
			(size 0.4064 1.2192)
			(layers "B.Cu" "B.Mask" "B.Paste")
			(net "SSD_PERST_Y9")
		)
		(pad "5" smd rect
			(at -0.65024 0.8255 180)
			(size 0.4064 1.2192)
			(layers "B.Cu" "B.Mask" "B.Paste")
			(net "P3V3_STBY")
		)
	)
	(footprint ""
		(layer "B.Cu")
		(at 58.166 -132.08 180)
		(property "Reference" "R5768"
			(at 0 0 0)
			(layer "B.SilkS")
			(hide yes)
			(effects
				(font
					(size 1.27 1.27)
				)
				(justify mirror)
			)
		)
		(property "Value" "1KR2F-3-GP"
			(at -0.064008 -3.993896 180)
			(unlocked yes)
			(layer "B.Fab")
			(hide yes)
			(effects
				(font
					(size 1.016 1.016)
					(thickness 0.1524)
				)
				(justify mirror)
			)
		)
		(property "Device Type" "R402H16"
			(at -0.064008 -5.517896 180)
			(unlocked yes)
			(layer "B.Fab")
			(hide yes)
			(effects
				(font
					(size 1.016 1.016)
					(thickness 0.1524)
				)
				(justify mirror)
			)
		)
		(duplicate_pad_numbers_are_jumpers no)
		(fp_line
			(start 0.508 -0.9398)
			(end 0.508 0.9398)
			(stroke
				(width 0.1524)
				(type default)
			)
			(layer "B.SilkS")
		)
		(fp_line
			(start -0.508 -0.9398)
			(end 0.508 -0.9398)
			(stroke
				(width 0.1524)
				(type default)
			)
			(layer "B.SilkS")
		)
		(fp_rect
			(start 0.508 0.9398)
			(end -0.508 -0.9398)
			(stroke
				(width 0)
				(type default)
			)
			(fill no)
			(layer "B.CrtYd")
		)
		(fp_rect
			(start 0.508 0.9398)
			(end -0.508 -0.9398)
			(stroke
				(width 0)
				(type default)
			)
			(fill no)
			(layer "B.Fab")
		)
		(pad "1" smd custom
			(at 0 -0.4445)
			(size 0.1397 0.1397)
			(layers "B.Cu" "B.Mask" "B.Paste")
			(net "P3V3_STBY")
			(options
				(clearance outline)
				(anchor circle)
			)
			(primitives
				(gr_poly
					(pts
						(arc
							(start -0.1778 0.2794)
							(mid -0.249642 0.249642)
							(end -0.2794 0.1778)
						)
						(arc
							(start -0.2794 -0.1778)
							(mid -0.249642 -0.249642)
							(end -0.1778 -0.2794)
						)
						(arc
							(start 0.1778 -0.2794)
							(mid 0.249642 -0.249642)
							(end 0.2794 -0.1778)
						)
						(arc
							(start 0.2794 0.1778)
							(mid 0.249642 0.249642)
							(end 0.1778 0.2794)
						)
					)
					(width 0)
					(fill yes)
				)
			)
		)
		(pad "2" smd custom
			(at 0 0.4445)
			(size 0.1397 0.1397)
			(layers "B.Cu" "B.Mask" "B.Paste")
			(net "ADC_P3V3_STBY")
			(options
				(clearance outline)
				(anchor circle)
			)
			(primitives
				(gr_poly
					(pts
						(arc
							(start -0.1778 0.2794)
							(mid -0.249642 0.249642)
							(end -0.2794 0.1778)
						)
						(arc
							(start -0.2794 -0.1778)
							(mid -0.249642 -0.249642)
							(end -0.1778 -0.2794)
						)
						(arc
							(start 0.1778 -0.2794)
							(mid 0.249642 -0.249642)
							(end 0.2794 -0.1778)
						)
						(arc
							(start 0.2794 0.1778)
							(mid 0.249642 0.249642)
							(end 0.1778 0.2794)
						)
					)
					(width 0)
					(fill yes)
				)
			)
		)
	)
	(footprint ""
		(layer "B.Cu")
		(at 239.1664 -43.997372 90)
		(property "Reference" "C429"
			(at 0 0 90)
			(layer "B.SilkS")
			(hide yes)
			(effects
				(font
					(size 1.27 1.27)
				)
				(justify mirror)
			)
		)
		(property "Value" "SCD1U16V1KX-1-GP"
			(at 2.8321 -1.7399 90)
			(unlocked yes)
			(layer "B.Fab")
			(hide yes)
			(effects
				(font
					(size 1.016 1.016)
					(thickness 0.1524)
				)
				(justify mirror)
			)
		)
		(property "Device Type" "C0201H13"
			(at 2.8321 -3.2639 90)
			(unlocked yes)
			(layer "B.Fab")
			(hide yes)
			(effects
				(font
					(size 1.016 1.016)
					(thickness 0.1524)
				)
				(justify mirror)
			)
		)
		(duplicate_pad_numbers_are_jumpers no)
		(fp_rect
			(start 0.2794 0.6477)
			(end -0.2794 -0.6477)
			(stroke
				(width 0)
				(type default)
			)
			(fill no)
			(layer "B.CrtYd")
		)
		(fp_rect
			(start 0.2794 0.6477)
			(end -0.2794 -0.6477)
			(stroke
				(width 0)
				(type default)
			)
			(fill no)
			(layer "B.Fab")
		)
		(pad "1" smd custom
			(at 0 -0.2794 270)
			(size 0.0762 0.0762)
			(layers "B.Cu" "B.Mask" "B.Paste")
			(net "DUT_VDD")
			(options
				(clearance outline)
				(anchor circle)
			)
			(primitives
				(gr_poly
					(pts
						(arc
							(start 0.1524 0.127)
							(mid 0.137521 0.162921)
							(end 0.1016 0.1778)
						)
						(arc
							(start -0.1016 0.1778)
							(mid -0.137521 0.162921)
							(end -0.1524 0.127)
						)
						(arc
							(start -0.1524 -0.127)
							(mid -0.137521 -0.162921)
							(end -0.1016 -0.1778)
						)
						(arc
							(start 0.1016 -0.1778)
							(mid 0.137521 -0.162921)
							(end 0.1524 -0.127)
						)
					)
					(width 0)
					(fill yes)
				)
			)
		)
		(pad "2" smd custom
			(at 0 0.2794 270)
			(size 0.0762 0.0762)
			(layers "B.Cu" "B.Mask" "B.Paste")
			(net "GND")
			(options
				(clearance outline)
				(anchor circle)
			)
			(primitives
				(gr_poly
					(pts
						(arc
							(start 0.1524 0.127)
							(mid 0.137521 0.162921)
							(end 0.1016 0.1778)
						)
						(arc
							(start -0.1016 0.1778)
							(mid -0.137521 0.162921)
							(end -0.1524 0.127)
						)
						(arc
							(start -0.1524 -0.127)
							(mid -0.137521 -0.162921)
							(end -0.1016 -0.1778)
						)
						(arc
							(start 0.1016 -0.1778)
							(mid 0.137521 -0.162921)
							(end 0.1524 -0.127)
						)
					)
					(width 0)
					(fill yes)
				)
			)
		)
	)
	(footprint ""
		(layer "B.Cu")
		(at 333.788512 -172.432218)
		(property "Reference" "R4151"
			(at 0 0 0)
			(layer "B.SilkS")
			(hide yes)
			(effects
				(font
					(size 1.27 1.27)
				)
				(justify mirror)
			)
		)
		(property "Value" "4K7R2F-GP"
			(at -0.064008 -3.993896 0)
			(unlocked yes)
			(layer "B.Fab")
			(hide yes)
			(effects
				(font
					(size 1.016 1.016)
					(thickness 0.1524)
				)
				(justify mirror)
			)
		)
		(property "Device Type" "R402H16"
			(at -0.064008 -5.517896 0)
			(unlocked yes)
			(layer "B.Fab")
			(hide yes)
			(effects
				(font
					(size 1.016 1.016)
					(thickness 0.1524)
				)
				(justify mirror)
			)
		)
		(duplicate_pad_numbers_are_jumpers no)
		(fp_line
			(start -0.508 -0.9398)
			(end 0.508 -0.9398)
			(stroke
				(width 0.1524)
				(type default)
			)
			(layer "B.SilkS")
		)
		(fp_line
			(start 0.508 -0.9398)
			(end 0.508 0.9398)
			(stroke
				(width 0.1524)
				(type default)
			)
			(layer "B.SilkS")
		)
		(fp_rect
			(start 0.508 0.9398)
			(end -0.508 -0.9398)
			(stroke
				(width 0)
				(type default)
			)
			(fill no)
			(layer "B.CrtYd")
		)
		(fp_rect
			(start 0.508 0.9398)
			(end -0.508 -0.9398)
			(stroke
				(width 0)
				(type default)
			)
			(fill no)
			(layer "B.Fab")
		)
		(pad "1" smd custom
			(at 0 -0.4445 180)
			(size 0.1397 0.1397)
			(layers "B.Cu" "B.Mask" "B.Paste")
			(net "SSD_ATNLED#4")
			(options
				(clearance outline)
				(anchor circle)
			)
			(primitives
				(gr_poly
					(pts
						(arc
							(start -0.1778 0.2794)
							(mid -0.249642 0.249642)
							(end -0.2794 0.1778)
						)
						(arc
							(start -0.2794 -0.1778)
							(mid -0.249642 -0.249642)
							(end -0.1778 -0.2794)
						)
						(arc
							(start 0.1778 -0.2794)
							(mid 0.249642 -0.249642)
							(end 0.2794 -0.1778)
						)
						(arc
							(start 0.2794 0.1778)
							(mid 0.249642 0.249642)
							(end 0.1778 0.2794)
						)
					)
					(width 0)
					(fill yes)
				)
			)
		)
		(pad "2" smd custom
			(at 0 0.4445 180)
			(size 0.1397 0.1397)
			(layers "B.Cu" "B.Mask" "B.Paste")
			(net "P3V3_STBY")
			(options
				(clearance outline)
				(anchor circle)
			)
			(primitives
				(gr_poly
					(pts
						(arc
							(start -0.1778 0.2794)
							(mid -0.249642 0.249642)
							(end -0.2794 0.1778)
						)
						(arc
							(start -0.2794 -0.1778)
							(mid -0.249642 -0.249642)
							(end -0.1778 -0.2794)
						)
						(arc
							(start 0.1778 -0.2794)
							(mid 0.249642 -0.249642)
							(end 0.2794 -0.1778)
						)
						(arc
							(start 0.2794 0.1778)
							(mid 0.249642 0.249642)
							(end 0.1778 0.2794)
						)
					)
					(width 0)
					(fill yes)
				)
			)
		)
	)
	(footprint ""
		(layer "B.Cu")
		(at 70.1548 -39.8526 180)
		(property "Reference" "PC28"
			(at 0 0 0)
			(layer "B.SilkS")
			(hide yes)
			(effects
				(font
					(size 1.27 1.27)
				)
				(justify mirror)
			)
		)
		(property "Value" "SC2K2P50V3KX-GP"
			(at 0 -2.8194 180)
			(unlocked yes)
			(layer "B.Fab")
			(hide yes)
			(effects
				(font
					(size 1.016 1.016)
					(thickness 0.1524)
				)
				(justify mirror)
			)
		)
		(property "Device Type" "C603"
			(at 0 -4.3434 180)
			(unlocked yes)
			(layer "B.Fab")
			(hide yes)
			(effects
				(font
					(size 1.016 1.016)
					(thickness 0.1524)
				)
				(justify mirror)
			)
		)
		(duplicate_pad_numbers_are_jumpers no)
		(fp_line
			(start -0.508 0)
			(end 0.508 0)
			(stroke
				(width 0.2032)
				(type default)
			)
			(layer "B.SilkS")
		)
		(fp_rect
			(start 0.5842 1.3335)
			(end -0.5842 -1.3335)
			(stroke
				(width 0)
				(type default)
			)
			(fill no)
			(layer "B.CrtYd")
		)
		(fp_rect
			(start 0.5842 1.3335)
			(end -0.5842 -1.3335)
			(stroke
				(width 0)
				(type default)
			)
			(fill no)
			(layer "B.Fab")
		)
		(pad "1" smd custom
			(at 0 -0.762)
			(size 0.2159 0.2159)
			(layers "B.Cu" "B.Mask" "B.Paste")
			(net "P3V3_STBY_LL")
			(options
				(clearance outline)
				(anchor circle)
			)
			(primitives
				(gr_poly
					(pts
						(arc
							(start -0.3302 0.4318)
							(mid -0.402042 0.402042)
							(end -0.4318 0.3302)
						)
						(arc
							(start -0.4318 -0.3302)
							(mid -0.402042 -0.402042)
							(end -0.3302 -0.4318)
						)
						(arc
							(start 0.3302 -0.4318)
							(mid 0.402042 -0.402042)
							(end 0.4318 -0.3302)
						)
						(arc
							(start 0.4318 0.3302)
							(mid 0.402042 0.402042)
							(end 0.3302 0.4318)
						)
					)
					(width 0)
					(fill yes)
				)
			)
		)
		(pad "2" smd custom
			(at 0 0.762)
			(size 0.2159 0.2159)
			(layers "B.Cu" "B.Mask" "B.Paste")
			(net "P3V3_STBY_SNB")
			(options
				(clearance outline)
				(anchor circle)
			)
			(primitives
				(gr_poly
					(pts
						(arc
							(start -0.3302 0.4318)
							(mid -0.402042 0.402042)
							(end -0.4318 0.3302)
						)
						(arc
							(start -0.4318 -0.3302)
							(mid -0.402042 -0.402042)
							(end -0.3302 -0.4318)
						)
						(arc
							(start 0.3302 -0.4318)
							(mid 0.402042 -0.402042)
							(end 0.4318 -0.3302)
						)
						(arc
							(start 0.4318 0.3302)
							(mid 0.402042 0.402042)
							(end 0.3302 0.4318)
						)
					)
					(width 0)
					(fill yes)
				)
			)
		)
	)
	(footprint ""
		(layer "B.Cu")
		(at 238.4044 -25.273 90)
		(property "Reference" "TP207"
			(at 0 0 90)
			(layer "B.SilkS")
			(hide yes)
			(effects
				(font
					(size 1.27 1.27)
				)
				(justify mirror)
			)
		)
		(property "Value" "TPAD28-2-GP"
			(at 0.0127 -1.6637 90)
			(unlocked yes)
			(layer "B.Fab")
			(hide yes)
			(effects
				(font
					(size 1.016 1.016)
					(thickness 0.1524)
				)
				(justify mirror)
			)
		)
		(property "Device Type" "TPAD28"
			(at 0.0127 -3.1877 90)
			(unlocked yes)
			(layer "B.Fab")
			(hide yes)
			(effects
				(font
					(size 1.016 1.016)
					(thickness 0.1524)
				)
				(justify mirror)
			)
		)
		(duplicate_pad_numbers_are_jumpers no)
		(fp_poly
			(pts
				(arc
					(start 0 0.3556)
					(mid 0 -0.3556)
					(end 0 0.3556)
				)
			)
			(stroke
				(width 0)
				(type default)
			)
			(fill no)
			(layer "B.CrtYd")
		)
		(fp_poly
			(pts
				(arc
					(start 0 0.6096)
					(mid 0 -0.6096)
					(end 0 0.6096)
				)
			)
			(stroke
				(width 0)
				(type default)
			)
			(fill no)
			(layer "B.Fab")
		)
		(pad "1" smd circle
			(at 0 0 270)
			(size 0.7112 0.7112)
			(layers "B.Cu" "B.Mask" "B.Paste")
			(net "LBI_DATA15")
		)
	)
	(footprint ""
		(layer "B.Cu")
		(at 228.6254 -55.998872 90)
		(property "Reference" "C536"
			(at 0 0 90)
			(layer "B.SilkS")
			(hide yes)
			(effects
				(font
					(size 1.27 1.27)
				)
				(justify mirror)
			)
		)
		(property "Value" "SCD1U16V1KX-1-GP"
			(at 2.8321 -1.7399 90)
			(unlocked yes)
			(layer "B.Fab")
			(hide yes)
			(effects
				(font
					(size 1.016 1.016)
					(thickness 0.1524)
				)
				(justify mirror)
			)
		)
		(property "Device Type" "C0201H13"
			(at 2.8321 -3.2639 90)
			(unlocked yes)
			(layer "B.Fab")
			(hide yes)
			(effects
				(font
					(size 1.016 1.016)
					(thickness 0.1524)
				)
				(justify mirror)
			)
		)
		(duplicate_pad_numbers_are_jumpers no)
		(fp_rect
			(start 0.2794 0.6477)
			(end -0.2794 -0.6477)
			(stroke
				(width 0)
				(type default)
			)
			(fill no)
			(layer "B.CrtYd")
		)
		(fp_rect
			(start 0.2794 0.6477)
			(end -0.2794 -0.6477)
			(stroke
				(width 0)
				(type default)
			)
			(fill no)
			(layer "B.Fab")
		)
		(pad "1" smd custom
			(at 0 -0.2794 270)
			(size 0.0762 0.0762)
			(layers "B.Cu" "B.Mask" "B.Paste")
			(net "DUT_AVD_PCIE")
			(options
				(clearance outline)
				(anchor circle)
			)
			(primitives
				(gr_poly
					(pts
						(arc
							(start 0.1524 0.127)
							(mid 0.137521 0.162921)
							(end 0.1016 0.1778)
						)
						(arc
							(start -0.1016 0.1778)
							(mid -0.137521 0.162921)
							(end -0.1524 0.127)
						)
						(arc
							(start -0.1524 -0.127)
							(mid -0.137521 -0.162921)
							(end -0.1016 -0.1778)
						)
						(arc
							(start 0.1016 -0.1778)
							(mid 0.137521 -0.162921)
							(end 0.1524 -0.127)
						)
					)
					(width 0)
					(fill yes)
				)
			)
		)
		(pad "2" smd custom
			(at 0 0.2794 270)
			(size 0.0762 0.0762)
			(layers "B.Cu" "B.Mask" "B.Paste")
			(net "GND")
			(options
				(clearance outline)
				(anchor circle)
			)
			(primitives
				(gr_poly
					(pts
						(arc
							(start 0.1524 0.127)
							(mid 0.137521 0.162921)
							(end 0.1016 0.1778)
						)
						(arc
							(start -0.1016 0.1778)
							(mid -0.137521 0.162921)
							(end -0.1524 0.127)
						)
						(arc
							(start -0.1524 -0.127)
							(mid -0.137521 -0.162921)
							(end -0.1016 -0.1778)
						)
						(arc
							(start 0.1016 -0.1778)
							(mid 0.137521 -0.162921)
							(end 0.1524 -0.127)
						)
					)
					(width 0)
					(fill yes)
				)
			)
		)
	)
	(footprint ""
		(layer "B.Cu")
		(at 131.52628 -33.54578)
		(property "Reference" "R2917"
			(at 0 0 0)
			(layer "B.SilkS")
			(hide yes)
			(effects
				(font
					(size 1.27 1.27)
				)
				(justify mirror)
			)
		)
		(property "Value" "0R2J-2-GP"
			(at -0.064008 -3.993896 0)
			(unlocked yes)
			(layer "B.Fab")
			(hide yes)
			(effects
				(font
					(size 1.016 1.016)
					(thickness 0.1524)
				)
				(justify mirror)
			)
		)
		(property "Device Type" "R402H16"
			(at -0.064008 -5.517896 0)
			(unlocked yes)
			(layer "B.Fab")
			(hide yes)
			(effects
				(font
					(size 1.016 1.016)
					(thickness 0.1524)
				)
				(justify mirror)
			)
		)
		(duplicate_pad_numbers_are_jumpers no)
		(fp_line
			(start -0.508 -0.9398)
			(end 0.508 -0.9398)
			(stroke
				(width 0.1524)
				(type default)
			)
			(layer "B.SilkS")
		)
		(fp_line
			(start 0.508 -0.9398)
			(end 0.508 0.9398)
			(stroke
				(width 0.1524)
				(type default)
			)
			(layer "B.SilkS")
		)
		(fp_rect
			(start 0.508 0.9398)
			(end -0.508 -0.9398)
			(stroke
				(width 0)
				(type default)
			)
			(fill no)
			(layer "B.CrtYd")
		)
		(fp_rect
			(start 0.508 0.9398)
			(end -0.508 -0.9398)
			(stroke
				(width 0)
				(type default)
			)
			(fill no)
			(layer "B.Fab")
		)
		(pad "1" smd custom
			(at 0 -0.4445 180)
			(size 0.1397 0.1397)
			(layers "B.Cu" "B.Mask" "B.Paste")
			(net "BMC_I2C1_MINI1_SDA")
			(options
				(clearance outline)
				(anchor circle)
			)
			(primitives
				(gr_poly
					(pts
						(arc
							(start -0.1778 0.2794)
							(mid -0.249642 0.249642)
							(end -0.2794 0.1778)
						)
						(arc
							(start -0.2794 -0.1778)
							(mid -0.249642 -0.249642)
							(end -0.1778 -0.2794)
						)
						(arc
							(start 0.1778 -0.2794)
							(mid 0.249642 -0.249642)
							(end 0.2794 -0.1778)
						)
						(arc
							(start 0.2794 0.1778)
							(mid 0.249642 0.249642)
							(end 0.1778 0.2794)
						)
					)
					(width 0)
					(fill yes)
				)
			)
		)
		(pad "2" smd custom
			(at 0 0.4445 180)
			(size 0.1397 0.1397)
			(layers "B.Cu" "B.Mask" "B.Paste")
			(net "8644_SDA_R_1")
			(options
				(clearance outline)
				(anchor circle)
			)
			(primitives
				(gr_poly
					(pts
						(arc
							(start -0.1778 0.2794)
							(mid -0.249642 0.249642)
							(end -0.2794 0.1778)
						)
						(arc
							(start -0.2794 -0.1778)
							(mid -0.249642 -0.249642)
							(end -0.1778 -0.2794)
						)
						(arc
							(start 0.1778 -0.2794)
							(mid 0.249642 -0.249642)
							(end 0.2794 -0.1778)
						)
						(arc
							(start 0.2794 0.1778)
							(mid 0.249642 0.249642)
							(end 0.1778 0.2794)
						)
					)
					(width 0)
					(fill yes)
				)
			)
		)
	)
	(footprint ""
		(layer "B.Cu")
		(at 245.5672 -56.007 90)
		(property "Reference" "C523"
			(at 0 0 90)
			(layer "B.SilkS")
			(hide yes)
			(effects
				(font
					(size 1.27 1.27)
				)
				(justify mirror)
			)
		)
		(property "Value" "SCD1U16V1KX-1-GP"
			(at 2.8321 -1.7399 90)
			(unlocked yes)
			(layer "B.Fab")
			(hide yes)
			(effects
				(font
					(size 1.016 1.016)
					(thickness 0.1524)
				)
				(justify mirror)
			)
		)
		(property "Device Type" "C0201H13"
			(at 2.8321 -3.2639 90)
			(unlocked yes)
			(layer "B.Fab")
			(hide yes)
			(effects
				(font
					(size 1.016 1.016)
					(thickness 0.1524)
				)
				(justify mirror)
			)
		)
		(duplicate_pad_numbers_are_jumpers no)
		(fp_rect
			(start 0.2794 0.6477)
			(end -0.2794 -0.6477)
			(stroke
				(width 0)
				(type default)
			)
			(fill no)
			(layer "B.CrtYd")
		)
		(fp_rect
			(start 0.2794 0.6477)
			(end -0.2794 -0.6477)
			(stroke
				(width 0)
				(type default)
			)
			(fill no)
			(layer "B.Fab")
		)
		(pad "1" smd custom
			(at 0 -0.2794 270)
			(size 0.0762 0.0762)
			(layers "B.Cu" "B.Mask" "B.Paste")
			(net "DUT_AVD_TX")
			(options
				(clearance outline)
				(anchor circle)
			)
			(primitives
				(gr_poly
					(pts
						(arc
							(start 0.1524 0.127)
							(mid 0.137521 0.162921)
							(end 0.1016 0.1778)
						)
						(arc
							(start -0.1016 0.1778)
							(mid -0.137521 0.162921)
							(end -0.1524 0.127)
						)
						(arc
							(start -0.1524 -0.127)
							(mid -0.137521 -0.162921)
							(end -0.1016 -0.1778)
						)
						(arc
							(start 0.1016 -0.1778)
							(mid 0.137521 -0.162921)
							(end 0.1524 -0.127)
						)
					)
					(width 0)
					(fill yes)
				)
			)
		)
		(pad "2" smd custom
			(at 0 0.2794 270)
			(size 0.0762 0.0762)
			(layers "B.Cu" "B.Mask" "B.Paste")
			(net "GND")
			(options
				(clearance outline)
				(anchor circle)
			)
			(primitives
				(gr_poly
					(pts
						(arc
							(start 0.1524 0.127)
							(mid 0.137521 0.162921)
							(end 0.1016 0.1778)
						)
						(arc
							(start -0.1016 0.1778)
							(mid -0.137521 0.162921)
							(end -0.1524 0.127)
						)
						(arc
							(start -0.1524 -0.127)
							(mid -0.137521 -0.162921)
							(end -0.1016 -0.1778)
						)
						(arc
							(start 0.1016 -0.1778)
							(mid 0.137521 -0.162921)
							(end 0.1524 -0.127)
						)
					)
					(width 0)
					(fill yes)
				)
			)
		)
	)
	(footprint ""
		(layer "B.Cu")
		(at 224.867724 -190.601092)
		(property "Reference" "R4141"
			(at 0 0 0)
			(layer "B.SilkS")
			(hide yes)
			(effects
				(font
					(size 1.27 1.27)
				)
				(justify mirror)
			)
		)
		(property "Value" "4K7R2F-GP"
			(at -0.064008 -3.993896 0)
			(unlocked yes)
			(layer "B.Fab")
			(hide yes)
			(effects
				(font
					(size 1.016 1.016)
					(thickness 0.1524)
				)
				(justify mirror)
			)
		)
		(property "Device Type" "R402H16"
			(at -0.064008 -5.517896 0)
			(unlocked yes)
			(layer "B.Fab")
			(hide yes)
			(effects
				(font
					(size 1.016 1.016)
					(thickness 0.1524)
				)
				(justify mirror)
			)
		)
		(duplicate_pad_numbers_are_jumpers no)
		(fp_line
			(start -0.508 -0.9398)
			(end 0.508 -0.9398)
			(stroke
				(width 0.1524)
				(type default)
			)
			(layer "B.SilkS")
		)
		(fp_line
			(start 0.508 -0.9398)
			(end 0.508 0.9398)
			(stroke
				(width 0.1524)
				(type default)
			)
			(layer "B.SilkS")
		)
		(fp_rect
			(start 0.508 0.9398)
			(end -0.508 -0.9398)
			(stroke
				(width 0)
				(type default)
			)
			(fill no)
			(layer "B.CrtYd")
		)
		(fp_rect
			(start 0.508 0.9398)
			(end -0.508 -0.9398)
			(stroke
				(width 0)
				(type default)
			)
			(fill no)
			(layer "B.Fab")
		)
		(pad "1" smd custom
			(at 0 -0.4445 180)
			(size 0.1397 0.1397)
			(layers "B.Cu" "B.Mask" "B.Paste")
			(net "SSD_PRSNT#8")
			(options
				(clearance outline)
				(anchor circle)
			)
			(primitives
				(gr_poly
					(pts
						(arc
							(start -0.1778 0.2794)
							(mid -0.249642 0.249642)
							(end -0.2794 0.1778)
						)
						(arc
							(start -0.2794 -0.1778)
							(mid -0.249642 -0.249642)
							(end -0.1778 -0.2794)
						)
						(arc
							(start 0.1778 -0.2794)
							(mid 0.249642 -0.249642)
							(end 0.2794 -0.1778)
						)
						(arc
							(start 0.2794 0.1778)
							(mid 0.249642 0.249642)
							(end 0.1778 0.2794)
						)
					)
					(width 0)
					(fill yes)
				)
			)
		)
		(pad "2" smd custom
			(at 0 0.4445 180)
			(size 0.1397 0.1397)
			(layers "B.Cu" "B.Mask" "B.Paste")
			(net "P3V3_STBY")
			(options
				(clearance outline)
				(anchor circle)
			)
			(primitives
				(gr_poly
					(pts
						(arc
							(start -0.1778 0.2794)
							(mid -0.249642 0.249642)
							(end -0.2794 0.1778)
						)
						(arc
							(start -0.2794 -0.1778)
							(mid -0.249642 -0.249642)
							(end -0.1778 -0.2794)
						)
						(arc
							(start 0.1778 -0.2794)
							(mid 0.249642 -0.249642)
							(end 0.2794 -0.1778)
						)
						(arc
							(start 0.2794 0.1778)
							(mid 0.249642 0.249642)
							(end 0.1778 0.2794)
						)
					)
					(width 0)
					(fill yes)
				)
			)
		)
	)
	(footprint ""
		(layer "B.Cu")
		(at 181.64302 -13.9446)
		(property "Reference" "R273"
			(at 0 0 0)
			(layer "B.SilkS")
			(hide yes)
			(effects
				(font
					(size 1.27 1.27)
				)
				(justify mirror)
			)
		)
		(property "Value" "0R2J-2-GP"
			(at -0.064008 -3.993896 0)
			(unlocked yes)
			(layer "B.Fab")
			(hide yes)
			(effects
				(font
					(size 1.016 1.016)
					(thickness 0.1524)
				)
				(justify mirror)
			)
		)
		(property "Device Type" "R402H16"
			(at -0.064008 -5.517896 0)
			(unlocked yes)
			(layer "B.Fab")
			(hide yes)
			(effects
				(font
					(size 1.016 1.016)
					(thickness 0.1524)
				)
				(justify mirror)
			)
		)
		(duplicate_pad_numbers_are_jumpers no)
		(fp_line
			(start -0.508 -0.9398)
			(end 0.508 -0.9398)
			(stroke
				(width 0.1524)
				(type default)
			)
			(layer "B.SilkS")
		)
		(fp_line
			(start 0.508 -0.9398)
			(end 0.508 0.9398)
			(stroke
				(width 0.1524)
				(type default)
			)
			(layer "B.SilkS")
		)
		(fp_rect
			(start 0.508 0.9398)
			(end -0.508 -0.9398)
			(stroke
				(width 0)
				(type default)
			)
			(fill no)
			(layer "B.CrtYd")
		)
		(fp_rect
			(start 0.508 0.9398)
			(end -0.508 -0.9398)
			(stroke
				(width 0)
				(type default)
			)
			(fill no)
			(layer "B.Fab")
		)
		(pad "1" smd custom
			(at 0 -0.4445 180)
			(size 0.1397 0.1397)
			(layers "B.Cu" "B.Mask" "B.Paste")
			(net "MINISAS_CN15_C_I2C_INT#")
			(options
				(clearance outline)
				(anchor circle)
			)
			(primitives
				(gr_poly
					(pts
						(arc
							(start -0.1778 0.2794)
							(mid -0.249642 0.249642)
							(end -0.2794 0.1778)
						)
						(arc
							(start -0.2794 -0.1778)
							(mid -0.249642 -0.249642)
							(end -0.1778 -0.2794)
						)
						(arc
							(start 0.1778 -0.2794)
							(mid 0.249642 -0.249642)
							(end 0.2794 -0.1778)
						)
						(arc
							(start 0.2794 0.1778)
							(mid 0.249642 0.249642)
							(end 0.1778 0.2794)
						)
					)
					(width 0)
					(fill yes)
				)
			)
		)
		(pad "2" smd custom
			(at 0 0.4445 180)
			(size 0.1397 0.1397)
			(layers "B.Cu" "B.Mask" "B.Paste")
			(net "PCIE_REFCLK_H3_N_R")
			(options
				(clearance outline)
				(anchor circle)
			)
			(primitives
				(gr_poly
					(pts
						(arc
							(start -0.1778 0.2794)
							(mid -0.249642 0.249642)
							(end -0.2794 0.1778)
						)
						(arc
							(start -0.2794 -0.1778)
							(mid -0.249642 -0.249642)
							(end -0.1778 -0.2794)
						)
						(arc
							(start 0.1778 -0.2794)
							(mid 0.249642 -0.249642)
							(end 0.2794 -0.1778)
						)
						(arc
							(start 0.2794 0.1778)
							(mid 0.249642 0.249642)
							(end 0.1778 0.2794)
						)
					)
					(width 0)
					(fill yes)
				)
			)
		)
	)
	(footprint ""
		(layer "B.Cu")
		(at 182.648098 -51.293268 90)
		(property "Reference" "R43"
			(at 0 0 90)
			(layer "B.SilkS")
			(hide yes)
			(effects
				(font
					(size 1.27 1.27)
				)
				(justify mirror)
			)
		)
		(property "Value" "1KR3F-GP"
			(at 0.0254 -2.5146 90)
			(unlocked yes)
			(layer "B.Fab")
			(hide yes)
			(effects
				(font
					(size 1.016 1.016)
					(thickness 0.1524)
				)
				(justify mirror)
			)
		)
		(property "Device Type" "R603H22"
			(at 0.0254 -4.0386 90)
			(unlocked yes)
			(layer "B.Fab")
			(hide yes)
			(effects
				(font
					(size 1.016 1.016)
					(thickness 0.1524)
				)
				(justify mirror)
			)
		)
		(duplicate_pad_numbers_are_jumpers no)
		(fp_line
			(start 0.4826 0)
			(end 0.2032 0)
			(stroke
				(width 0.2032)
				(type default)
			)
			(layer "B.SilkS")
		)
		(fp_line
			(start -0.2032 0)
			(end -0.4826 0)
			(stroke
				(width 0.2032)
				(type default)
			)
			(layer "B.SilkS")
		)
		(fp_rect
			(start 0.5842 1.3335)
			(end -0.5842 -1.3335)
			(stroke
				(width 0)
				(type default)
			)
			(fill no)
			(layer "B.CrtYd")
		)
		(fp_rect
			(start 0.5842 1.3335)
			(end -0.5842 -1.3335)
			(stroke
				(width 0)
				(type default)
			)
			(fill no)
			(layer "B.Fab")
		)
		(pad "1" smd custom
			(at 0 -0.762 270)
			(size 0.2159 0.2159)
			(layers "B.Cu" "B.Mask" "B.Paste")
			(net "DUT_AVD_PCIE")
			(options
				(clearance outline)
				(anchor circle)
			)
			(primitives
				(gr_poly
					(pts
						(arc
							(start -0.3302 0.4318)
							(mid -0.402042 0.402042)
							(end -0.4318 0.3302)
						)
						(arc
							(start -0.4318 -0.3302)
							(mid -0.402042 -0.402042)
							(end -0.3302 -0.4318)
						)
						(arc
							(start 0.3302 -0.4318)
							(mid 0.402042 -0.402042)
							(end 0.4318 -0.3302)
						)
						(arc
							(start 0.4318 0.3302)
							(mid 0.402042 0.402042)
							(end 0.3302 0.4318)
						)
					)
					(width 0)
					(fill yes)
				)
			)
		)
		(pad "2" smd custom
			(at 0 0.762 270)
			(size 0.2159 0.2159)
			(layers "B.Cu" "B.Mask" "B.Paste")
			(net "DUT_AVD_PCIE_Q")
			(options
				(clearance outline)
				(anchor circle)
			)
			(primitives
				(gr_poly
					(pts
						(arc
							(start -0.3302 0.4318)
							(mid -0.402042 0.402042)
							(end -0.4318 0.3302)
						)
						(arc
							(start -0.4318 -0.3302)
							(mid -0.402042 -0.402042)
							(end -0.3302 -0.4318)
						)
						(arc
							(start 0.3302 -0.4318)
							(mid 0.402042 -0.402042)
							(end 0.4318 -0.3302)
						)
						(arc
							(start 0.4318 0.3302)
							(mid 0.402042 0.402042)
							(end 0.3302 0.4318)
						)
					)
					(width 0)
					(fill yes)
				)
			)
		)
	)
	(footprint ""
		(layer "B.Cu")
		(at 340.5886 -181.8386)
		(property "Reference" "R3244"
			(at 0 0 0)
			(layer "B.SilkS")
			(hide yes)
			(effects
				(font
					(size 1.27 1.27)
				)
				(justify mirror)
			)
		)
		(property "Value" "0R2J-2-GP"
			(at -0.064008 -3.993896 0)
			(unlocked yes)
			(layer "B.Fab")
			(hide yes)
			(effects
				(font
					(size 1.016 1.016)
					(thickness 0.1524)
				)
				(justify mirror)
			)
		)
		(property "Device Type" "R402H16"
			(at -0.064008 -5.517896 0)
			(unlocked yes)
			(layer "B.Fab")
			(hide yes)
			(effects
				(font
					(size 1.016 1.016)
					(thickness 0.1524)
				)
				(justify mirror)
			)
		)
		(duplicate_pad_numbers_are_jumpers no)
		(fp_line
			(start -0.508 -0.9398)
			(end 0.508 -0.9398)
			(stroke
				(width 0.1524)
				(type default)
			)
			(layer "B.SilkS")
		)
		(fp_line
			(start 0.508 -0.9398)
			(end 0.508 0.9398)
			(stroke
				(width 0.1524)
				(type default)
			)
			(layer "B.SilkS")
		)
		(fp_rect
			(start 0.508 0.9398)
			(end -0.508 -0.9398)
			(stroke
				(width 0)
				(type default)
			)
			(fill no)
			(layer "B.CrtYd")
		)
		(fp_rect
			(start 0.508 0.9398)
			(end -0.508 -0.9398)
			(stroke
				(width 0)
				(type default)
			)
			(fill no)
			(layer "B.Fab")
		)
		(pad "1" smd custom
			(at 0 -0.4445 180)
			(size 0.1397 0.1397)
			(layers "B.Cu" "B.Mask" "B.Paste")
			(net "BMC_SSD_RST#14")
			(options
				(clearance outline)
				(anchor circle)
			)
			(primitives
				(gr_poly
					(pts
						(arc
							(start -0.1778 0.2794)
							(mid -0.249642 0.249642)
							(end -0.2794 0.1778)
						)
						(arc
							(start -0.2794 -0.1778)
							(mid -0.249642 -0.249642)
							(end -0.1778 -0.2794)
						)
						(arc
							(start 0.1778 -0.2794)
							(mid 0.249642 -0.249642)
							(end 0.2794 -0.1778)
						)
						(arc
							(start 0.2794 0.1778)
							(mid 0.249642 0.249642)
							(end 0.1778 0.2794)
						)
					)
					(width 0)
					(fill yes)
				)
			)
		)
		(pad "2" smd custom
			(at 0 0.4445 180)
			(size 0.1397 0.1397)
			(layers "B.Cu" "B.Mask" "B.Paste")
			(net "BMC_SSD_RST#0_A14")
			(options
				(clearance outline)
				(anchor circle)
			)
			(primitives
				(gr_poly
					(pts
						(arc
							(start -0.1778 0.2794)
							(mid -0.249642 0.249642)
							(end -0.2794 0.1778)
						)
						(arc
							(start -0.2794 -0.1778)
							(mid -0.249642 -0.249642)
							(end -0.1778 -0.2794)
						)
						(arc
							(start 0.1778 -0.2794)
							(mid 0.249642 -0.249642)
							(end 0.2794 -0.1778)
						)
						(arc
							(start 0.2794 0.1778)
							(mid 0.249642 0.249642)
							(end 0.1778 0.2794)
						)
					)
					(width 0)
					(fill yes)
				)
			)
		)
	)
	(footprint ""
		(layer "B.Cu")
		(at 66.548 -149.479 -90)
		(property "Reference" "R208"
			(at 0 0 90)
			(layer "B.SilkS")
			(hide yes)
			(effects
				(font
					(size 1.27 1.27)
				)
				(justify mirror)
			)
		)
		(property "Value" "0R2J-2-GP"
			(at -0.064008 -3.993896 270)
			(unlocked yes)
			(layer "B.Fab")
			(hide yes)
			(effects
				(font
					(size 1.016 1.016)
					(thickness 0.1524)
				)
				(justify mirror)
			)
		)
		(property "Device Type" "R402H16"
			(at -0.064008 -5.517896 270)
			(unlocked yes)
			(layer "B.Fab")
			(hide yes)
			(effects
				(font
					(size 1.016 1.016)
					(thickness 0.1524)
				)
				(justify mirror)
			)
		)
		(duplicate_pad_numbers_are_jumpers no)
		(fp_line
			(start -0.508 -0.9398)
			(end 0.508 -0.9398)
			(stroke
				(width 0.1524)
				(type default)
			)
			(layer "B.SilkS")
		)
		(fp_line
			(start 0.508 -0.9398)
			(end 0.508 0.9398)
			(stroke
				(width 0.1524)
				(type default)
			)
			(layer "B.SilkS")
		)
		(fp_rect
			(start 0.508 0.9398)
			(end -0.508 -0.9398)
			(stroke
				(width 0)
				(type default)
			)
			(fill no)
			(layer "B.CrtYd")
		)
		(fp_rect
			(start 0.508 0.9398)
			(end -0.508 -0.9398)
			(stroke
				(width 0)
				(type default)
			)
			(fill no)
			(layer "B.Fab")
		)
		(pad "1" smd custom
			(at 0 -0.4445 90)
			(size 0.1397 0.1397)
			(layers "B.Cu" "B.Mask" "B.Paste")
			(net "EEPROM_SCL")
			(options
				(clearance outline)
				(anchor circle)
			)
			(primitives
				(gr_poly
					(pts
						(arc
							(start -0.1778 0.2794)
							(mid -0.249642 0.249642)
							(end -0.2794 0.1778)
						)
						(arc
							(start -0.2794 -0.1778)
							(mid -0.249642 -0.249642)
							(end -0.1778 -0.2794)
						)
						(arc
							(start 0.1778 -0.2794)
							(mid 0.249642 -0.249642)
							(end 0.2794 -0.1778)
						)
						(arc
							(start 0.2794 0.1778)
							(mid 0.249642 0.249642)
							(end 0.1778 0.2794)
						)
					)
					(width 0)
					(fill yes)
				)
			)
		)
		(pad "2" smd custom
			(at 0 0.4445 90)
			(size 0.1397 0.1397)
			(layers "B.Cu" "B.Mask" "B.Paste")
			(net "BMC_I2C5_D_PEB_SCL")
			(options
				(clearance outline)
				(anchor circle)
			)
			(primitives
				(gr_poly
					(pts
						(arc
							(start -0.1778 0.2794)
							(mid -0.249642 0.249642)
							(end -0.2794 0.1778)
						)
						(arc
							(start -0.2794 -0.1778)
							(mid -0.249642 -0.249642)
							(end -0.1778 -0.2794)
						)
						(arc
							(start 0.1778 -0.2794)
							(mid 0.249642 -0.249642)
							(end 0.2794 -0.1778)
						)
						(arc
							(start 0.2794 0.1778)
							(mid 0.249642 0.249642)
							(end 0.1778 0.2794)
						)
					)
					(width 0)
					(fill yes)
				)
			)
		)
	)
	(footprint ""
		(layer "B.Cu")
		(at 23.796498 -126.005336 90)
		(property "Reference" "R356"
			(at 0 0 90)
			(layer "B.SilkS")
			(hide yes)
			(effects
				(font
					(size 1.27 1.27)
				)
				(justify mirror)
			)
		)
		(property "Value" "3K3R2F-2-GP"
			(at -0.064008 -3.993896 90)
			(unlocked yes)
			(layer "B.Fab")
			(hide yes)
			(effects
				(font
					(size 1.016 1.016)
					(thickness 0.1524)
				)
				(justify mirror)
			)
		)
		(property "Device Type" "R402H16"
			(at -0.064008 -5.517896 90)
			(unlocked yes)
			(layer "B.Fab")
			(hide yes)
			(effects
				(font
					(size 1.016 1.016)
					(thickness 0.1524)
				)
				(justify mirror)
			)
		)
		(duplicate_pad_numbers_are_jumpers no)
		(fp_line
			(start 0.508 -0.9398)
			(end 0.508 0.9398)
			(stroke
				(width 0.1524)
				(type default)
			)
			(layer "B.SilkS")
		)
		(fp_line
			(start -0.508 -0.9398)
			(end 0.508 -0.9398)
			(stroke
				(width 0.1524)
				(type default)
			)
			(layer "B.SilkS")
		)
		(fp_rect
			(start 0.508 0.9398)
			(end -0.508 -0.9398)
			(stroke
				(width 0)
				(type default)
			)
			(fill no)
			(layer "B.CrtYd")
		)
		(fp_rect
			(start 0.508 0.9398)
			(end -0.508 -0.9398)
			(stroke
				(width 0)
				(type default)
			)
			(fill no)
			(layer "B.Fab")
		)
		(pad "1" smd custom
			(at 0 -0.4445 270)
			(size 0.1397 0.1397)
			(layers "B.Cu" "B.Mask" "B.Paste")
			(net "P3V3_STBY")
			(options
				(clearance outline)
				(anchor circle)
			)
			(primitives
				(gr_poly
					(pts
						(arc
							(start -0.1778 0.2794)
							(mid -0.249642 0.249642)
							(end -0.2794 0.1778)
						)
						(arc
							(start -0.2794 -0.1778)
							(mid -0.249642 -0.249642)
							(end -0.1778 -0.2794)
						)
						(arc
							(start 0.1778 -0.2794)
							(mid 0.249642 -0.249642)
							(end 0.2794 -0.1778)
						)
						(arc
							(start 0.2794 0.1778)
							(mid 0.249642 0.249642)
							(end 0.1778 0.2794)
						)
					)
					(width 0)
					(fill yes)
				)
			)
		)
		(pad "2" smd custom
			(at 0 0.4445 270)
			(size 0.1397 0.1397)
			(layers "B.Cu" "B.Mask" "B.Paste")
			(net "ROMA12")
			(options
				(clearance outline)
				(anchor circle)
			)
			(primitives
				(gr_poly
					(pts
						(arc
							(start -0.1778 0.2794)
							(mid -0.249642 0.249642)
							(end -0.2794 0.1778)
						)
						(arc
							(start -0.2794 -0.1778)
							(mid -0.249642 -0.249642)
							(end -0.1778 -0.2794)
						)
						(arc
							(start 0.1778 -0.2794)
							(mid 0.249642 -0.249642)
							(end 0.2794 -0.1778)
						)
						(arc
							(start 0.2794 0.1778)
							(mid 0.249642 0.249642)
							(end 0.1778 0.2794)
						)
					)
					(width 0)
					(fill yes)
				)
			)
		)
	)
	(footprint ""
		(layer "B.Cu")
		(at 310.007 -56.261 180)
		(property "Reference" "PG61"
			(at 0 0 0)
			(layer "B.SilkS")
			(hide yes)
			(effects
				(font
					(size 1.27 1.27)
				)
				(justify mirror)
			)
		)
		(property "Value" "GAP-CLOSE-PWR-3-GP"
			(at -0.0254 -6.5786 180)
			(unlocked yes)
			(layer "B.Fab")
			(hide yes)
			(effects
				(font
					(size 1.016 1.016)
					(thickness 0.1524)
				)
				(justify mirror)
			)
		)
		(property "Device Type" "GAP-CLOSE-PWR-3"
			(at -0.0254 -8.255 180)
			(unlocked yes)
			(layer "B.Fab")
			(hide yes)
			(effects
				(font
					(size 1.016 1.016)
					(thickness 0.1524)
				)
				(justify mirror)
			)
		)
		(duplicate_pad_numbers_are_jumpers no)
		(fp_rect
			(start 0.7112 0.4572)
			(end -0.7112 -0.4572)
			(stroke
				(width 0)
				(type default)
			)
			(fill no)
			(layer "B.CrtYd")
		)
		(fp_poly
			(pts
				(xy 0.7112 -0.4572) (xy -0.7112 -0.4572) (xy -0.7112 0.4572) (xy 0.7112 0.4572)
			)
			(stroke
				(width 0)
				(type default)
			)
			(fill no)
			(layer "B.Fab")
		)
		(pad "1" smd rect
			(at 0.3048 0)
			(size 0.6604 0.762)
			(layers "B.Cu" "B.Mask" "B.Paste")
			(net "DUT_VDD")
		)
		(pad "2" smd rect
			(at -0.3048 0)
			(size 0.6604 0.762)
			(layers "B.Cu" "B.Mask" "B.Paste")
			(net "P0V9_E")
		)
	)
	(footprint ""
		(layer "B.Cu")
		(at 158.508192 -33.589976)
		(property "Reference" "R2924"
			(at 0 0 0)
			(layer "B.SilkS")
			(hide yes)
			(effects
				(font
					(size 1.27 1.27)
				)
				(justify mirror)
			)
		)
		(property "Value" "0R2J-2-GP"
			(at -0.064008 -3.993896 0)
			(unlocked yes)
			(layer "B.Fab")
			(hide yes)
			(effects
				(font
					(size 1.016 1.016)
					(thickness 0.1524)
				)
				(justify mirror)
			)
		)
		(property "Device Type" "R402H16"
			(at -0.064008 -5.517896 0)
			(unlocked yes)
			(layer "B.Fab")
			(hide yes)
			(effects
				(font
					(size 1.016 1.016)
					(thickness 0.1524)
				)
				(justify mirror)
			)
		)
		(duplicate_pad_numbers_are_jumpers no)
		(fp_line
			(start -0.508 -0.9398)
			(end 0.508 -0.9398)
			(stroke
				(width 0.1524)
				(type default)
			)
			(layer "B.SilkS")
		)
		(fp_line
			(start 0.508 -0.9398)
			(end 0.508 0.9398)
			(stroke
				(width 0.1524)
				(type default)
			)
			(layer "B.SilkS")
		)
		(fp_rect
			(start 0.508 0.9398)
			(end -0.508 -0.9398)
			(stroke
				(width 0)
				(type default)
			)
			(fill no)
			(layer "B.CrtYd")
		)
		(fp_rect
			(start 0.508 0.9398)
			(end -0.508 -0.9398)
			(stroke
				(width 0)
				(type default)
			)
			(fill no)
			(layer "B.Fab")
		)
		(pad "1" smd custom
			(at 0 -0.4445 180)
			(size 0.1397 0.1397)
			(layers "B.Cu" "B.Mask" "B.Paste")
			(net "CBL_PRSNT_N_3")
			(options
				(clearance outline)
				(anchor circle)
			)
			(primitives
				(gr_poly
					(pts
						(arc
							(start -0.1778 0.2794)
							(mid -0.249642 0.249642)
							(end -0.2794 0.1778)
						)
						(arc
							(start -0.2794 -0.1778)
							(mid -0.249642 -0.249642)
							(end -0.1778 -0.2794)
						)
						(arc
							(start 0.1778 -0.2794)
							(mid 0.249642 -0.249642)
							(end 0.2794 -0.1778)
						)
						(arc
							(start 0.2794 0.1778)
							(mid 0.249642 0.249642)
							(end 0.1778 0.2794)
						)
					)
					(width 0)
					(fill yes)
				)
			)
		)
		(pad "2" smd custom
			(at 0 0.4445 180)
			(size 0.1397 0.1397)
			(layers "B.Cu" "B.Mask" "B.Paste")
			(net "8644_CBL_PRSNT_R_3")
			(options
				(clearance outline)
				(anchor circle)
			)
			(primitives
				(gr_poly
					(pts
						(arc
							(start -0.1778 0.2794)
							(mid -0.249642 0.249642)
							(end -0.2794 0.1778)
						)
						(arc
							(start -0.2794 -0.1778)
							(mid -0.249642 -0.249642)
							(end -0.1778 -0.2794)
						)
						(arc
							(start 0.1778 -0.2794)
							(mid 0.249642 -0.249642)
							(end 0.2794 -0.1778)
						)
						(arc
							(start 0.2794 0.1778)
							(mid 0.249642 0.249642)
							(end 0.1778 0.2794)
						)
					)
					(width 0)
					(fill yes)
				)
			)
		)
	)
	(footprint ""
		(layer "B.Cu")
		(at 235.331 -71.882 -90)
		(property "Reference" "C496"
			(at 0 0 90)
			(layer "B.SilkS")
			(hide yes)
			(effects
				(font
					(size 1.27 1.27)
				)
				(justify mirror)
			)
		)
		(property "Value" "SC4D7U16V5KX-1-GP"
			(at 0.0762 -6.1214 270)
			(unlocked yes)
			(layer "B.Fab")
			(hide yes)
			(effects
				(font
					(size 1.016 1.016)
					(thickness 0.1524)
				)
				(justify mirror)
			)
		)
		(property "Device Type" "C805H56"
			(at 0.0762 -8.1534 270)
			(unlocked yes)
			(layer "B.Fab")
			(hide yes)
			(effects
				(font
					(size 1.016 1.016)
					(thickness 0.1524)
				)
				(justify mirror)
			)
		)
		(duplicate_pad_numbers_are_jumpers no)
		(fp_line
			(start -0.635 0)
			(end 0.635 0)
			(stroke
				(width 0.508)
				(type default)
			)
			(layer "B.SilkS")
		)
		(fp_rect
			(start 0.9652 1.778)
			(end -0.9652 -1.778)
			(stroke
				(width 0)
				(type default)
			)
			(fill no)
			(layer "B.CrtYd")
		)
		(fp_poly
			(pts
				(xy 0.9652 -1.778) (xy -0.9652 -1.778) (xy -0.9652 1.778) (xy 0.9652 1.778)
			)
			(stroke
				(width 0)
				(type default)
			)
			(fill no)
			(layer "B.Fab")
		)
		(pad "1" smd rect
			(at 0 -0.9652 90)
			(size 1.397 1.143)
			(layers "B.Cu" "B.Mask" "B.Paste")
			(net "DUT_AVD_TX")
		)
		(pad "2" smd rect
			(at 0 0.9652 90)
			(size 1.397 1.143)
			(layers "B.Cu" "B.Mask" "B.Paste")
			(net "GND")
		)
	)
	(footprint ""
		(layer "B.Cu")
		(at 20.955 -138.811 -90)
		(property "Reference" "R659"
			(at 0 0 90)
			(layer "B.SilkS")
			(hide yes)
			(effects
				(font
					(size 1.27 1.27)
				)
				(justify mirror)
			)
		)
		(property "Value" "0R2J-2-GP"
			(at -0.064008 -3.993896 270)
			(unlocked yes)
			(layer "B.Fab")
			(hide yes)
			(effects
				(font
					(size 1.016 1.016)
					(thickness 0.1524)
				)
				(justify mirror)
			)
		)
		(property "Device Type" "R402H16"
			(at -0.064008 -5.517896 270)
			(unlocked yes)
			(layer "B.Fab")
			(hide yes)
			(effects
				(font
					(size 1.016 1.016)
					(thickness 0.1524)
				)
				(justify mirror)
			)
		)
		(duplicate_pad_numbers_are_jumpers no)
		(fp_line
			(start -0.508 -0.9398)
			(end 0.508 -0.9398)
			(stroke
				(width 0.1524)
				(type default)
			)
			(layer "B.SilkS")
		)
		(fp_line
			(start 0.508 -0.9398)
			(end 0.508 0.9398)
			(stroke
				(width 0.1524)
				(type default)
			)
			(layer "B.SilkS")
		)
		(fp_rect
			(start 0.508 0.9398)
			(end -0.508 -0.9398)
			(stroke
				(width 0)
				(type default)
			)
			(fill no)
			(layer "B.CrtYd")
		)
		(fp_rect
			(start 0.508 0.9398)
			(end -0.508 -0.9398)
			(stroke
				(width 0)
				(type default)
			)
			(fill no)
			(layer "B.Fab")
		)
		(pad "1" smd custom
			(at 0 -0.4445 90)
			(size 0.1397 0.1397)
			(layers "B.Cu" "B.Mask" "B.Paste")
			(net "GPIOR3_R")
			(options
				(clearance outline)
				(anchor circle)
			)
			(primitives
				(gr_poly
					(pts
						(arc
							(start -0.1778 0.2794)
							(mid -0.249642 0.249642)
							(end -0.2794 0.1778)
						)
						(arc
							(start -0.2794 -0.1778)
							(mid -0.249642 -0.249642)
							(end -0.1778 -0.2794)
						)
						(arc
							(start 0.1778 -0.2794)
							(mid 0.249642 -0.249642)
							(end 0.2794 -0.1778)
						)
						(arc
							(start 0.2794 0.1778)
							(mid 0.249642 0.249642)
							(end 0.1778 0.2794)
						)
					)
					(width 0)
					(fill yes)
				)
			)
		)
		(pad "2" smd custom
			(at 0 0.4445 90)
			(size 0.1397 0.1397)
			(layers "B.Cu" "B.Mask" "B.Paste")
			(net "BP_PRSNT_N")
			(options
				(clearance outline)
				(anchor circle)
			)
			(primitives
				(gr_poly
					(pts
						(arc
							(start -0.1778 0.2794)
							(mid -0.249642 0.249642)
							(end -0.2794 0.1778)
						)
						(arc
							(start -0.2794 -0.1778)
							(mid -0.249642 -0.249642)
							(end -0.1778 -0.2794)
						)
						(arc
							(start 0.1778 -0.2794)
							(mid 0.249642 -0.249642)
							(end 0.2794 -0.1778)
						)
						(arc
							(start 0.2794 0.1778)
							(mid 0.249642 0.249642)
							(end 0.1778 0.2794)
						)
					)
					(width 0)
					(fill yes)
				)
			)
		)
	)
	(footprint ""
		(layer "B.Cu")
		(at 252.5776 -40.005 -90)
		(property "Reference" "C590"
			(at 0 0 90)
			(layer "B.SilkS")
			(hide yes)
			(effects
				(font
					(size 1.27 1.27)
				)
				(justify mirror)
			)
		)
		(property "Value" "SCD1U16V1KX-1-GP"
			(at 2.8321 -1.7399 270)
			(unlocked yes)
			(layer "B.Fab")
			(hide yes)
			(effects
				(font
					(size 1.016 1.016)
					(thickness 0.1524)
				)
				(justify mirror)
			)
		)
		(property "Device Type" "C0201H13"
			(at 2.8321 -3.2639 270)
			(unlocked yes)
			(layer "B.Fab")
			(hide yes)
			(effects
				(font
					(size 1.016 1.016)
					(thickness 0.1524)
				)
				(justify mirror)
			)
		)
		(duplicate_pad_numbers_are_jumpers no)
		(fp_rect
			(start 0.2794 0.6477)
			(end -0.2794 -0.6477)
			(stroke
				(width 0)
				(type default)
			)
			(fill no)
			(layer "B.CrtYd")
		)
		(fp_rect
			(start 0.2794 0.6477)
			(end -0.2794 -0.6477)
			(stroke
				(width 0)
				(type default)
			)
			(fill no)
			(layer "B.Fab")
		)
		(pad "1" smd custom
			(at 0 -0.2794 90)
			(size 0.0762 0.0762)
			(layers "B.Cu" "B.Mask" "B.Paste")
			(net "DUT_AVD_PCIE")
			(options
				(clearance outline)
				(anchor circle)
			)
			(primitives
				(gr_poly
					(pts
						(arc
							(start 0.1524 0.127)
							(mid 0.137521 0.162921)
							(end 0.1016 0.1778)
						)
						(arc
							(start -0.1016 0.1778)
							(mid -0.137521 0.162921)
							(end -0.1524 0.127)
						)
						(arc
							(start -0.1524 -0.127)
							(mid -0.137521 -0.162921)
							(end -0.1016 -0.1778)
						)
						(arc
							(start 0.1016 -0.1778)
							(mid 0.137521 -0.162921)
							(end 0.1524 -0.127)
						)
					)
					(width 0)
					(fill yes)
				)
			)
		)
		(pad "2" smd custom
			(at 0 0.2794 90)
			(size 0.0762 0.0762)
			(layers "B.Cu" "B.Mask" "B.Paste")
			(net "GND")
			(options
				(clearance outline)
				(anchor circle)
			)
			(primitives
				(gr_poly
					(pts
						(arc
							(start 0.1524 0.127)
							(mid 0.137521 0.162921)
							(end 0.1016 0.1778)
						)
						(arc
							(start -0.1016 0.1778)
							(mid -0.137521 0.162921)
							(end -0.1524 0.127)
						)
						(arc
							(start -0.1524 -0.127)
							(mid -0.137521 -0.162921)
							(end -0.1016 -0.1778)
						)
						(arc
							(start 0.1016 -0.1778)
							(mid 0.137521 -0.162921)
							(end 0.1524 -0.127)
						)
					)
					(width 0)
					(fill yes)
				)
			)
		)
	)
	(footprint ""
		(layer "B.Cu")
		(at 20.955 -130.683 90)
		(property "Reference" "R345"
			(at 0 0 90)
			(layer "B.SilkS")
			(hide yes)
			(effects
				(font
					(size 1.27 1.27)
				)
				(justify mirror)
			)
		)
		(property "Value" "3K3R2F-2-GP"
			(at -0.064008 -3.993896 90)
			(unlocked yes)
			(layer "B.Fab")
			(hide yes)
			(effects
				(font
					(size 1.016 1.016)
					(thickness 0.1524)
				)
				(justify mirror)
			)
		)
		(property "Device Type" "R402H16"
			(at -0.064008 -5.517896 90)
			(unlocked yes)
			(layer "B.Fab")
			(hide yes)
			(effects
				(font
					(size 1.016 1.016)
					(thickness 0.1524)
				)
				(justify mirror)
			)
		)
		(duplicate_pad_numbers_are_jumpers no)
		(fp_line
			(start 0.508 -0.9398)
			(end 0.508 0.9398)
			(stroke
				(width 0.1524)
				(type default)
			)
			(layer "B.SilkS")
		)
		(fp_line
			(start -0.508 -0.9398)
			(end 0.508 -0.9398)
			(stroke
				(width 0.1524)
				(type default)
			)
			(layer "B.SilkS")
		)
		(fp_rect
			(start 0.508 0.9398)
			(end -0.508 -0.9398)
			(stroke
				(width 0)
				(type default)
			)
			(fill no)
			(layer "B.CrtYd")
		)
		(fp_rect
			(start 0.508 0.9398)
			(end -0.508 -0.9398)
			(stroke
				(width 0)
				(type default)
			)
			(fill no)
			(layer "B.Fab")
		)
		(pad "1" smd custom
			(at 0 -0.4445 270)
			(size 0.1397 0.1397)
			(layers "B.Cu" "B.Mask" "B.Paste")
			(net "P3V3_STBY")
			(options
				(clearance outline)
				(anchor circle)
			)
			(primitives
				(gr_poly
					(pts
						(arc
							(start -0.1778 0.2794)
							(mid -0.249642 0.249642)
							(end -0.2794 0.1778)
						)
						(arc
							(start -0.2794 -0.1778)
							(mid -0.249642 -0.249642)
							(end -0.1778 -0.2794)
						)
						(arc
							(start 0.1778 -0.2794)
							(mid 0.249642 -0.249642)
							(end 0.2794 -0.1778)
						)
						(arc
							(start 0.2794 0.1778)
							(mid 0.249642 0.249642)
							(end 0.1778 0.2794)
						)
					)
					(width 0)
					(fill yes)
				)
			)
		)
		(pad "2" smd custom
			(at 0 0.4445 270)
			(size 0.1397 0.1397)
			(layers "B.Cu" "B.Mask" "B.Paste")
			(net "ROMA17")
			(options
				(clearance outline)
				(anchor circle)
			)
			(primitives
				(gr_poly
					(pts
						(arc
							(start -0.1778 0.2794)
							(mid -0.249642 0.249642)
							(end -0.2794 0.1778)
						)
						(arc
							(start -0.2794 -0.1778)
							(mid -0.249642 -0.249642)
							(end -0.1778 -0.2794)
						)
						(arc
							(start 0.1778 -0.2794)
							(mid 0.249642 -0.249642)
							(end 0.2794 -0.1778)
						)
						(arc
							(start 0.2794 0.1778)
							(mid 0.249642 0.249642)
							(end 0.1778 0.2794)
						)
					)
					(width 0)
					(fill yes)
				)
			)
		)
	)
	(footprint ""
		(layer "B.Cu")
		(at 181.70652 -6.04012 180)
		(property "Reference" "R329"
			(at 0 0 0)
			(layer "B.SilkS")
			(hide yes)
			(effects
				(font
					(size 1.27 1.27)
				)
				(justify mirror)
			)
		)
		(property "Value" "0R2J-2-GP"
			(at -0.064008 -3.993896 180)
			(unlocked yes)
			(layer "B.Fab")
			(hide yes)
			(effects
				(font
					(size 1.016 1.016)
					(thickness 0.1524)
				)
				(justify mirror)
			)
		)
		(property "Device Type" "R402H16"
			(at -0.064008 -5.517896 180)
			(unlocked yes)
			(layer "B.Fab")
			(hide yes)
			(effects
				(font
					(size 1.016 1.016)
					(thickness 0.1524)
				)
				(justify mirror)
			)
		)
		(duplicate_pad_numbers_are_jumpers no)
		(fp_line
			(start 0.508 -0.9398)
			(end 0.508 0.9398)
			(stroke
				(width 0.1524)
				(type default)
			)
			(layer "B.SilkS")
		)
		(fp_line
			(start -0.508 -0.9398)
			(end 0.508 -0.9398)
			(stroke
				(width 0.1524)
				(type default)
			)
			(layer "B.SilkS")
		)
		(fp_rect
			(start 0.508 0.9398)
			(end -0.508 -0.9398)
			(stroke
				(width 0)
				(type default)
			)
			(fill no)
			(layer "B.CrtYd")
		)
		(fp_rect
			(start 0.508 0.9398)
			(end -0.508 -0.9398)
			(stroke
				(width 0)
				(type default)
			)
			(fill no)
			(layer "B.Fab")
		)
		(pad "1" smd custom
			(at 0 -0.4445)
			(size 0.1397 0.1397)
			(layers "B.Cu" "B.Mask" "B.Paste")
			(net "CLK_P_1_R")
			(options
				(clearance outline)
				(anchor circle)
			)
			(primitives
				(gr_poly
					(pts
						(arc
							(start -0.1778 0.2794)
							(mid -0.249642 0.249642)
							(end -0.2794 0.1778)
						)
						(arc
							(start -0.2794 -0.1778)
							(mid -0.249642 -0.249642)
							(end -0.1778 -0.2794)
						)
						(arc
							(start 0.1778 -0.2794)
							(mid 0.249642 -0.249642)
							(end 0.2794 -0.1778)
						)
						(arc
							(start 0.2794 0.1778)
							(mid 0.249642 0.249642)
							(end 0.1778 0.2794)
						)
					)
					(width 0)
					(fill yes)
				)
			)
		)
		(pad "2" smd custom
			(at 0 0.4445)
			(size 0.1397 0.1397)
			(layers "B.Cu" "B.Mask" "B.Paste")
			(net "PCIE_REFCLK_H2_P_R")
			(options
				(clearance outline)
				(anchor circle)
			)
			(primitives
				(gr_poly
					(pts
						(arc
							(start -0.1778 0.2794)
							(mid -0.249642 0.249642)
							(end -0.2794 0.1778)
						)
						(arc
							(start -0.2794 -0.1778)
							(mid -0.249642 -0.249642)
							(end -0.1778 -0.2794)
						)
						(arc
							(start 0.1778 -0.2794)
							(mid 0.249642 -0.249642)
							(end 0.2794 -0.1778)
						)
						(arc
							(start 0.2794 0.1778)
							(mid 0.249642 0.249642)
							(end 0.1778 0.2794)
						)
					)
					(width 0)
					(fill yes)
				)
			)
		)
	)
	(footprint ""
		(layer "B.Cu")
		(at 46.3042 -104.0384 180)
		(property "Reference" "R408"
			(at 0 0 0)
			(layer "B.SilkS")
			(hide yes)
			(effects
				(font
					(size 1.27 1.27)
				)
				(justify mirror)
			)
		)
		(property "Value" "4K7R2F-GP"
			(at -0.064008 -3.993896 180)
			(unlocked yes)
			(layer "B.Fab")
			(hide yes)
			(effects
				(font
					(size 1.016 1.016)
					(thickness 0.1524)
				)
				(justify mirror)
			)
		)
		(property "Device Type" "R402H16"
			(at -0.064008 -5.517896 180)
			(unlocked yes)
			(layer "B.Fab")
			(hide yes)
			(effects
				(font
					(size 1.016 1.016)
					(thickness 0.1524)
				)
				(justify mirror)
			)
		)
		(duplicate_pad_numbers_are_jumpers no)
		(fp_line
			(start 0.508 -0.9398)
			(end 0.508 0.9398)
			(stroke
				(width 0.1524)
				(type default)
			)
			(layer "B.SilkS")
		)
		(fp_line
			(start -0.508 -0.9398)
			(end 0.508 -0.9398)
			(stroke
				(width 0.1524)
				(type default)
			)
			(layer "B.SilkS")
		)
		(fp_rect
			(start 0.508 0.9398)
			(end -0.508 -0.9398)
			(stroke
				(width 0)
				(type default)
			)
			(fill no)
			(layer "B.CrtYd")
		)
		(fp_rect
			(start 0.508 0.9398)
			(end -0.508 -0.9398)
			(stroke
				(width 0)
				(type default)
			)
			(fill no)
			(layer "B.Fab")
		)
		(pad "1" smd custom
			(at 0 -0.4445)
			(size 0.1397 0.1397)
			(layers "B.Cu" "B.Mask" "B.Paste")
			(net "P3V3_STBY")
			(options
				(clearance outline)
				(anchor circle)
			)
			(primitives
				(gr_poly
					(pts
						(arc
							(start -0.1778 0.2794)
							(mid -0.249642 0.249642)
							(end -0.2794 0.1778)
						)
						(arc
							(start -0.2794 -0.1778)
							(mid -0.249642 -0.249642)
							(end -0.1778 -0.2794)
						)
						(arc
							(start 0.1778 -0.2794)
							(mid 0.249642 -0.249642)
							(end 0.2794 -0.1778)
						)
						(arc
							(start 0.2794 0.1778)
							(mid 0.249642 0.249642)
							(end 0.1778 0.2794)
						)
					)
					(width 0)
					(fill yes)
				)
			)
		)
		(pad "2" smd custom
			(at 0 0.4445)
			(size 0.1397 0.1397)
			(layers "B.Cu" "B.Mask" "B.Paste")
			(net "I2C8_LS_G1")
			(options
				(clearance outline)
				(anchor circle)
			)
			(primitives
				(gr_poly
					(pts
						(arc
							(start -0.1778 0.2794)
							(mid -0.249642 0.249642)
							(end -0.2794 0.1778)
						)
						(arc
							(start -0.2794 -0.1778)
							(mid -0.249642 -0.249642)
							(end -0.1778 -0.2794)
						)
						(arc
							(start 0.1778 -0.2794)
							(mid 0.249642 -0.249642)
							(end 0.2794 -0.1778)
						)
						(arc
							(start 0.2794 0.1778)
							(mid 0.249642 0.249642)
							(end 0.1778 0.2794)
						)
					)
					(width 0)
					(fill yes)
				)
			)
		)
	)
	(footprint ""
		(layer "B.Cu")
		(at 24.139144 -134.687564 90)
		(property "Reference" "R341"
			(at 0 0 90)
			(layer "B.SilkS")
			(hide yes)
			(effects
				(font
					(size 1.27 1.27)
				)
				(justify mirror)
			)
		)
		(property "Value" "3K3R2F-2-GP"
			(at -0.064008 -3.993896 90)
			(unlocked yes)
			(layer "B.Fab")
			(hide yes)
			(effects
				(font
					(size 1.016 1.016)
					(thickness 0.1524)
				)
				(justify mirror)
			)
		)
		(property "Device Type" "R402H16"
			(at -0.064008 -5.517896 90)
			(unlocked yes)
			(layer "B.Fab")
			(hide yes)
			(effects
				(font
					(size 1.016 1.016)
					(thickness 0.1524)
				)
				(justify mirror)
			)
		)
		(duplicate_pad_numbers_are_jumpers no)
		(fp_line
			(start 0.508 -0.9398)
			(end 0.508 0.9398)
			(stroke
				(width 0.1524)
				(type default)
			)
			(layer "B.SilkS")
		)
		(fp_line
			(start -0.508 -0.9398)
			(end 0.508 -0.9398)
			(stroke
				(width 0.1524)
				(type default)
			)
			(layer "B.SilkS")
		)
		(fp_rect
			(start 0.508 0.9398)
			(end -0.508 -0.9398)
			(stroke
				(width 0)
				(type default)
			)
			(fill no)
			(layer "B.CrtYd")
		)
		(fp_rect
			(start 0.508 0.9398)
			(end -0.508 -0.9398)
			(stroke
				(width 0)
				(type default)
			)
			(fill no)
			(layer "B.Fab")
		)
		(pad "1" smd custom
			(at 0 -0.4445 270)
			(size 0.1397 0.1397)
			(layers "B.Cu" "B.Mask" "B.Paste")
			(net "P3V3_STBY")
			(options
				(clearance outline)
				(anchor circle)
			)
			(primitives
				(gr_poly
					(pts
						(arc
							(start -0.1778 0.2794)
							(mid -0.249642 0.249642)
							(end -0.2794 0.1778)
						)
						(arc
							(start -0.2794 -0.1778)
							(mid -0.249642 -0.249642)
							(end -0.1778 -0.2794)
						)
						(arc
							(start 0.1778 -0.2794)
							(mid 0.249642 -0.249642)
							(end 0.2794 -0.1778)
						)
						(arc
							(start 0.2794 0.1778)
							(mid 0.249642 0.249642)
							(end 0.1778 0.2794)
						)
					)
					(width 0)
					(fill yes)
				)
			)
		)
		(pad "2" smd custom
			(at 0 0.4445 270)
			(size 0.1397 0.1397)
			(layers "B.Cu" "B.Mask" "B.Paste")
			(net "ROMA16")
			(options
				(clearance outline)
				(anchor circle)
			)
			(primitives
				(gr_poly
					(pts
						(arc
							(start -0.1778 0.2794)
							(mid -0.249642 0.249642)
							(end -0.2794 0.1778)
						)
						(arc
							(start -0.2794 -0.1778)
							(mid -0.249642 -0.249642)
							(end -0.1778 -0.2794)
						)
						(arc
							(start 0.1778 -0.2794)
							(mid 0.249642 -0.249642)
							(end 0.2794 -0.1778)
						)
						(arc
							(start 0.2794 0.1778)
							(mid 0.249642 0.249642)
							(end 0.1778 0.2794)
						)
					)
					(width 0)
					(fill yes)
				)
			)
		)
	)
	(footprint ""
		(layer "B.Cu")
		(at 44.958 -118.364)
		(property "Reference" "TP216"
			(at 0 0 0)
			(layer "B.SilkS")
			(hide yes)
			(effects
				(font
					(size 1.27 1.27)
				)
				(justify mirror)
			)
		)
		(property "Value" "TPAD28-2-GP"
			(at 0.0127 -1.6637 0)
			(unlocked yes)
			(layer "B.Fab")
			(hide yes)
			(effects
				(font
					(size 1.016 1.016)
					(thickness 0.1524)
				)
				(justify mirror)
			)
		)
		(property "Device Type" "TPAD28"
			(at 0.0127 -3.1877 0)
			(unlocked yes)
			(layer "B.Fab")
			(hide yes)
			(effects
				(font
					(size 1.016 1.016)
					(thickness 0.1524)
				)
				(justify mirror)
			)
		)
		(duplicate_pad_numbers_are_jumpers no)
		(fp_poly
			(pts
				(arc
					(start 0.3556 0)
					(mid -0.3556 0)
					(end 0.3556 0)
				)
			)
			(stroke
				(width 0)
				(type default)
			)
			(fill no)
			(layer "B.CrtYd")
		)
		(fp_poly
			(pts
				(arc
					(start 0.6096 0)
					(mid -0.6096 0)
					(end 0.6096 0)
				)
			)
			(stroke
				(width 0)
				(type default)
			)
			(fill no)
			(layer "B.Fab")
		)
		(pad "1" smd circle
			(at 0 0 180)
			(size 0.7112 0.7112)
			(layers "B.Cu" "B.Mask" "B.Paste")
			(net "TP_GPIOA3")
		)
	)
	(footprint ""
		(layer "B.Cu")
		(at 145.761202 -64.416432 -90)
		(property "Reference" "PC197"
			(at 0 0 90)
			(layer "B.SilkS")
			(hide yes)
			(effects
				(font
					(size 1.27 1.27)
				)
				(justify mirror)
			)
		)
		(property "Value" "SC10U25V5KX-GP"
			(at 0.0762 -6.1214 270)
			(unlocked yes)
			(layer "B.Fab")
			(hide yes)
			(effects
				(font
					(size 1.016 1.016)
					(thickness 0.1524)
				)
				(justify mirror)
			)
		)
		(property "Device Type" "C805H56"
			(at 0.0762 -8.1534 270)
			(unlocked yes)
			(layer "B.Fab")
			(hide yes)
			(effects
				(font
					(size 1.016 1.016)
					(thickness 0.1524)
				)
				(justify mirror)
			)
		)
		(duplicate_pad_numbers_are_jumpers no)
		(fp_line
			(start -0.635 0)
			(end 0.635 0)
			(stroke
				(width 0.508)
				(type default)
			)
			(layer "B.SilkS")
		)
		(fp_rect
			(start 0.9652 1.778)
			(end -0.9652 -1.778)
			(stroke
				(width 0)
				(type default)
			)
			(fill no)
			(layer "B.CrtYd")
		)
		(fp_poly
			(pts
				(xy 0.9652 -1.778) (xy -0.9652 -1.778) (xy -0.9652 1.778) (xy 0.9652 1.778)
			)
			(stroke
				(width 0)
				(type default)
			)
			(fill no)
			(layer "B.Fab")
		)
		(pad "1" smd rect
			(at 0 -0.9652 90)
			(size 1.397 1.143)
			(layers "B.Cu" "B.Mask" "B.Paste")
			(net "P0V9_VIN")
		)
		(pad "2" smd rect
			(at 0 0.9652 90)
			(size 1.397 1.143)
			(layers "B.Cu" "B.Mask" "B.Paste")
			(net "GND")
		)
	)
	(footprint ""
		(layer "B.Cu")
		(at 243.5606 -56.007 90)
		(property "Reference" "C510"
			(at 0 0 90)
			(layer "B.SilkS")
			(hide yes)
			(effects
				(font
					(size 1.27 1.27)
				)
				(justify mirror)
			)
		)
		(property "Value" "SCD1U16V1KX-1-GP"
			(at 2.8321 -1.7399 90)
			(unlocked yes)
			(layer "B.Fab")
			(hide yes)
			(effects
				(font
					(size 1.016 1.016)
					(thickness 0.1524)
				)
				(justify mirror)
			)
		)
		(property "Device Type" "C0201H13"
			(at 2.8321 -3.2639 90)
			(unlocked yes)
			(layer "B.Fab")
			(hide yes)
			(effects
				(font
					(size 1.016 1.016)
					(thickness 0.1524)
				)
				(justify mirror)
			)
		)
		(duplicate_pad_numbers_are_jumpers no)
		(fp_rect
			(start 0.2794 0.6477)
			(end -0.2794 -0.6477)
			(stroke
				(width 0)
				(type default)
			)
			(fill no)
			(layer "B.CrtYd")
		)
		(fp_rect
			(start 0.2794 0.6477)
			(end -0.2794 -0.6477)
			(stroke
				(width 0)
				(type default)
			)
			(fill no)
			(layer "B.Fab")
		)
		(pad "1" smd custom
			(at 0 -0.2794 270)
			(size 0.0762 0.0762)
			(layers "B.Cu" "B.Mask" "B.Paste")
			(net "DUT_AVD_TX")
			(options
				(clearance outline)
				(anchor circle)
			)
			(primitives
				(gr_poly
					(pts
						(arc
							(start 0.1524 0.127)
							(mid 0.137521 0.162921)
							(end 0.1016 0.1778)
						)
						(arc
							(start -0.1016 0.1778)
							(mid -0.137521 0.162921)
							(end -0.1524 0.127)
						)
						(arc
							(start -0.1524 -0.127)
							(mid -0.137521 -0.162921)
							(end -0.1016 -0.1778)
						)
						(arc
							(start 0.1016 -0.1778)
							(mid 0.137521 -0.162921)
							(end 0.1524 -0.127)
						)
					)
					(width 0)
					(fill yes)
				)
			)
		)
		(pad "2" smd custom
			(at 0 0.2794 270)
			(size 0.0762 0.0762)
			(layers "B.Cu" "B.Mask" "B.Paste")
			(net "GND")
			(options
				(clearance outline)
				(anchor circle)
			)
			(primitives
				(gr_poly
					(pts
						(arc
							(start 0.1524 0.127)
							(mid 0.137521 0.162921)
							(end 0.1016 0.1778)
						)
						(arc
							(start -0.1016 0.1778)
							(mid -0.137521 0.162921)
							(end -0.1524 0.127)
						)
						(arc
							(start -0.1524 -0.127)
							(mid -0.137521 -0.162921)
							(end -0.1016 -0.1778)
						)
						(arc
							(start 0.1016 -0.1778)
							(mid 0.137521 -0.162921)
							(end 0.1524 -0.127)
						)
					)
					(width 0)
					(fill yes)
				)
			)
		)
	)
	(footprint ""
		(layer "B.Cu")
		(at 182.07482 -12.4714 -90)
		(property "Reference" "R2937"
			(at 0 0 90)
			(layer "B.SilkS")
			(hide yes)
			(effects
				(font
					(size 1.27 1.27)
				)
				(justify mirror)
			)
		)
		(property "Value" "0R2J-2-GP"
			(at -0.064008 -3.993896 270)
			(unlocked yes)
			(layer "B.Fab")
			(hide yes)
			(effects
				(font
					(size 1.016 1.016)
					(thickness 0.1524)
				)
				(justify mirror)
			)
		)
		(property "Device Type" "R402H16"
			(at -0.064008 -5.517896 270)
			(unlocked yes)
			(layer "B.Fab")
			(hide yes)
			(effects
				(font
					(size 1.016 1.016)
					(thickness 0.1524)
				)
				(justify mirror)
			)
		)
		(duplicate_pad_numbers_are_jumpers no)
		(fp_line
			(start -0.508 -0.9398)
			(end 0.508 -0.9398)
			(stroke
				(width 0.1524)
				(type default)
			)
			(layer "B.SilkS")
		)
		(fp_line
			(start 0.508 -0.9398)
			(end 0.508 0.9398)
			(stroke
				(width 0.1524)
				(type default)
			)
			(layer "B.SilkS")
		)
		(fp_rect
			(start 0.508 0.9398)
			(end -0.508 -0.9398)
			(stroke
				(width 0)
				(type default)
			)
			(fill no)
			(layer "B.CrtYd")
		)
		(fp_rect
			(start 0.508 0.9398)
			(end -0.508 -0.9398)
			(stroke
				(width 0)
				(type default)
			)
			(fill no)
			(layer "B.Fab")
		)
		(pad "1" smd custom
			(at 0 -0.4445 90)
			(size 0.1397 0.1397)
			(layers "B.Cu" "B.Mask" "B.Paste")
			(net "PCIE_REFCLK_H3_P")
			(options
				(clearance outline)
				(anchor circle)
			)
			(primitives
				(gr_poly
					(pts
						(arc
							(start -0.1778 0.2794)
							(mid -0.249642 0.249642)
							(end -0.2794 0.1778)
						)
						(arc
							(start -0.2794 -0.1778)
							(mid -0.249642 -0.249642)
							(end -0.1778 -0.2794)
						)
						(arc
							(start 0.1778 -0.2794)
							(mid 0.249642 -0.249642)
							(end 0.2794 -0.1778)
						)
						(arc
							(start 0.2794 0.1778)
							(mid 0.249642 0.249642)
							(end 0.1778 0.2794)
						)
					)
					(width 0)
					(fill yes)
				)
			)
		)
		(pad "2" smd custom
			(at 0 0.4445 90)
			(size 0.1397 0.1397)
			(layers "B.Cu" "B.Mask" "B.Paste")
			(net "PCIE_REFCLK_H3_P_R")
			(options
				(clearance outline)
				(anchor circle)
			)
			(primitives
				(gr_poly
					(pts
						(arc
							(start -0.1778 0.2794)
							(mid -0.249642 0.249642)
							(end -0.2794 0.1778)
						)
						(arc
							(start -0.2794 -0.1778)
							(mid -0.249642 -0.249642)
							(end -0.1778 -0.2794)
						)
						(arc
							(start 0.1778 -0.2794)
							(mid 0.249642 -0.249642)
							(end 0.2794 -0.1778)
						)
						(arc
							(start 0.2794 0.1778)
							(mid 0.249642 0.249642)
							(end 0.1778 0.2794)
						)
					)
					(width 0)
					(fill yes)
				)
			)
		)
	)
	(footprint ""
		(layer "B.Cu")
		(at 79.166212 -186.545474)
		(property "Reference" "R3218"
			(at 0 0 0)
			(layer "B.SilkS")
			(hide yes)
			(effects
				(font
					(size 1.27 1.27)
				)
				(justify mirror)
			)
		)
		(property "Value" "0R2J-2-GP"
			(at -0.064008 -3.993896 0)
			(unlocked yes)
			(layer "B.Fab")
			(hide yes)
			(effects
				(font
					(size 1.016 1.016)
					(thickness 0.1524)
				)
				(justify mirror)
			)
		)
		(property "Device Type" "R402H16"
			(at -0.064008 -5.517896 0)
			(unlocked yes)
			(layer "B.Fab")
			(hide yes)
			(effects
				(font
					(size 1.016 1.016)
					(thickness 0.1524)
				)
				(justify mirror)
			)
		)
		(duplicate_pad_numbers_are_jumpers no)
		(fp_line
			(start -0.508 -0.9398)
			(end 0.508 -0.9398)
			(stroke
				(width 0.1524)
				(type default)
			)
			(layer "B.SilkS")
		)
		(fp_line
			(start 0.508 -0.9398)
			(end 0.508 0.9398)
			(stroke
				(width 0.1524)
				(type default)
			)
			(layer "B.SilkS")
		)
		(fp_rect
			(start 0.508 0.9398)
			(end -0.508 -0.9398)
			(stroke
				(width 0)
				(type default)
			)
			(fill no)
			(layer "B.CrtYd")
		)
		(fp_rect
			(start 0.508 0.9398)
			(end -0.508 -0.9398)
			(stroke
				(width 0)
				(type default)
			)
			(fill no)
			(layer "B.Fab")
		)
		(pad "1" smd custom
			(at 0 -0.4445 180)
			(size 0.1397 0.1397)
			(layers "B.Cu" "B.Mask" "B.Paste")
			(net "SSD_PERST_Y5")
			(options
				(clearance outline)
				(anchor circle)
			)
			(primitives
				(gr_poly
					(pts
						(arc
							(start -0.1778 0.2794)
							(mid -0.249642 0.249642)
							(end -0.2794 0.1778)
						)
						(arc
							(start -0.2794 -0.1778)
							(mid -0.249642 -0.249642)
							(end -0.1778 -0.2794)
						)
						(arc
							(start 0.1778 -0.2794)
							(mid 0.249642 -0.249642)
							(end 0.2794 -0.1778)
						)
						(arc
							(start 0.2794 0.1778)
							(mid 0.249642 0.249642)
							(end 0.1778 0.2794)
						)
					)
					(width 0)
					(fill yes)
				)
			)
		)
		(pad "2" smd custom
			(at 0 0.4445 180)
			(size 0.1397 0.1397)
			(layers "B.Cu" "B.Mask" "B.Paste")
			(net "SSD_PERST#5_R")
			(options
				(clearance outline)
				(anchor circle)
			)
			(primitives
				(gr_poly
					(pts
						(arc
							(start -0.1778 0.2794)
							(mid -0.249642 0.249642)
							(end -0.2794 0.1778)
						)
						(arc
							(start -0.2794 -0.1778)
							(mid -0.249642 -0.249642)
							(end -0.1778 -0.2794)
						)
						(arc
							(start 0.1778 -0.2794)
							(mid 0.249642 -0.249642)
							(end 0.2794 -0.1778)
						)
						(arc
							(start 0.2794 0.1778)
							(mid 0.249642 0.249642)
							(end 0.1778 0.2794)
						)
					)
					(width 0)
					(fill yes)
				)
			)
		)
	)
	(footprint ""
		(layer "B.Cu")
		(at 41.91 -118.872)
		(property "Reference" "TP296"
			(at 0 0 0)
			(layer "B.SilkS")
			(hide yes)
			(effects
				(font
					(size 1.27 1.27)
				)
				(justify mirror)
			)
		)
		(property "Value" "TPAD28-2-GP"
			(at 0.0127 -1.6637 0)
			(unlocked yes)
			(layer "B.Fab")
			(hide yes)
			(effects
				(font
					(size 1.016 1.016)
					(thickness 0.1524)
				)
				(justify mirror)
			)
		)
		(property "Device Type" "TPAD28"
			(at 0.0127 -3.1877 0)
			(unlocked yes)
			(layer "B.Fab")
			(hide yes)
			(effects
				(font
					(size 1.016 1.016)
					(thickness 0.1524)
				)
				(justify mirror)
			)
		)
		(duplicate_pad_numbers_are_jumpers no)
		(fp_poly
			(pts
				(arc
					(start 0.3556 0)
					(mid -0.3556 0)
					(end 0.3556 0)
				)
			)
			(stroke
				(width 0)
				(type default)
			)
			(fill no)
			(layer "B.CrtYd")
		)
		(fp_poly
			(pts
				(arc
					(start 0.6096 0)
					(mid -0.6096 0)
					(end 0.6096 0)
				)
			)
			(stroke
				(width 0)
				(type default)
			)
			(fill no)
			(layer "B.Fab")
		)
		(pad "1" smd circle
			(at 0 0 180)
			(size 0.7112 0.7112)
			(layers "B.Cu" "B.Mask" "B.Paste")
			(net "TP_GPIOV6")
		)
	)
	(footprint ""
		(layer "B.Cu")
		(at 48.6156 -106.6292 -90)
		(property "Reference" "R67"
			(at 0 0 90)
			(layer "B.SilkS")
			(hide yes)
			(effects
				(font
					(size 1.27 1.27)
				)
				(justify mirror)
			)
		)
		(property "Value" "0R2J-2-GP"
			(at -0.064008 -3.993896 270)
			(unlocked yes)
			(layer "B.Fab")
			(hide yes)
			(effects
				(font
					(size 1.016 1.016)
					(thickness 0.1524)
				)
				(justify mirror)
			)
		)
		(property "Device Type" "R402H16"
			(at -0.064008 -5.517896 270)
			(unlocked yes)
			(layer "B.Fab")
			(hide yes)
			(effects
				(font
					(size 1.016 1.016)
					(thickness 0.1524)
				)
				(justify mirror)
			)
		)
		(duplicate_pad_numbers_are_jumpers no)
		(fp_line
			(start -0.508 -0.9398)
			(end 0.508 -0.9398)
			(stroke
				(width 0.1524)
				(type default)
			)
			(layer "B.SilkS")
		)
		(fp_line
			(start 0.508 -0.9398)
			(end 0.508 0.9398)
			(stroke
				(width 0.1524)
				(type default)
			)
			(layer "B.SilkS")
		)
		(fp_rect
			(start 0.508 0.9398)
			(end -0.508 -0.9398)
			(stroke
				(width 0)
				(type default)
			)
			(fill no)
			(layer "B.CrtYd")
		)
		(fp_rect
			(start 0.508 0.9398)
			(end -0.508 -0.9398)
			(stroke
				(width 0)
				(type default)
			)
			(fill no)
			(layer "B.Fab")
		)
		(pad "1" smd custom
			(at 0 -0.4445 90)
			(size 0.1397 0.1397)
			(layers "B.Cu" "B.Mask" "B.Paste")
			(net "BMC_I2C14_MINI8_SCL_S")
			(options
				(clearance outline)
				(anchor circle)
			)
			(primitives
				(gr_poly
					(pts
						(arc
							(start -0.1778 0.2794)
							(mid -0.249642 0.249642)
							(end -0.2794 0.1778)
						)
						(arc
							(start -0.2794 -0.1778)
							(mid -0.249642 -0.249642)
							(end -0.1778 -0.2794)
						)
						(arc
							(start 0.1778 -0.2794)
							(mid 0.249642 -0.249642)
							(end 0.2794 -0.1778)
						)
						(arc
							(start 0.2794 0.1778)
							(mid 0.249642 0.249642)
							(end 0.1778 0.2794)
						)
					)
					(width 0)
					(fill yes)
				)
			)
		)
		(pad "2" smd custom
			(at 0 0.4445 90)
			(size 0.1397 0.1397)
			(layers "B.Cu" "B.Mask" "B.Paste")
			(net "BMC_I2C14_MINI8_SCL")
			(options
				(clearance outline)
				(anchor circle)
			)
			(primitives
				(gr_poly
					(pts
						(arc
							(start -0.1778 0.2794)
							(mid -0.249642 0.249642)
							(end -0.2794 0.1778)
						)
						(arc
							(start -0.2794 -0.1778)
							(mid -0.249642 -0.249642)
							(end -0.1778 -0.2794)
						)
						(arc
							(start 0.1778 -0.2794)
							(mid 0.249642 -0.249642)
							(end 0.2794 -0.1778)
						)
						(arc
							(start 0.2794 0.1778)
							(mid 0.249642 0.249642)
							(end 0.1778 0.2794)
						)
					)
					(width 0)
					(fill yes)
				)
			)
		)
	)
	(footprint ""
		(layer "B.Cu")
		(at 299.353732 -34.624772 180)
		(property "Reference" "C277"
			(at 0 0 0)
			(layer "B.SilkS")
			(hide yes)
			(effects
				(font
					(size 1.27 1.27)
				)
				(justify mirror)
			)
		)
		(property "Value" "SCD1U10V2KX-5GP"
			(at -1.1811 -2.7051 180)
			(unlocked yes)
			(layer "B.Fab")
			(hide yes)
			(effects
				(font
					(size 1.016 1.016)
					(thickness 0.1524)
				)
				(justify mirror)
			)
		)
		(property "Device Type" "C402H22"
			(at -1.1811 -4.2291 180)
			(unlocked yes)
			(layer "B.Fab")
			(hide yes)
			(effects
				(font
					(size 1.016 1.016)
					(thickness 0.1524)
				)
				(justify mirror)
			)
		)
		(duplicate_pad_numbers_are_jumpers no)
		(fp_rect
			(start 0.4318 0.9525)
			(end -0.4318 -0.9525)
			(stroke
				(width 0)
				(type default)
			)
			(fill no)
			(layer "B.CrtYd")
		)
		(fp_rect
			(start 0.4318 0.9525)
			(end -0.4318 -0.9525)
			(stroke
				(width 0)
				(type default)
			)
			(fill no)
			(layer "B.Fab")
		)
		(pad "1" smd custom
			(at 0 -0.4445)
			(size 0.1524 0.1524)
			(layers "B.Cu" "B.Mask" "B.Paste")
			(net "GND")
			(options
				(clearance outline)
				(anchor circle)
			)
			(primitives
				(gr_poly
					(pts
						(arc
							(start 0.3048 0.2032)
							(mid 0.275042 0.275042)
							(end 0.2032 0.3048)
						)
						(arc
							(start -0.2032 0.3048)
							(mid -0.275042 0.275042)
							(end -0.3048 0.2032)
						)
						(arc
							(start -0.3048 -0.2032)
							(mid -0.275042 -0.275042)
							(end -0.2032 -0.3048)
						)
						(arc
							(start 0.2032 -0.3048)
							(mid 0.275042 -0.275042)
							(end 0.3048 -0.2032)
						)
					)
					(width 0)
					(fill yes)
				)
			)
		)
		(pad "2" smd custom
			(at 0 0.4445)
			(size 0.1524 0.1524)
			(layers "B.Cu" "B.Mask" "B.Paste")
			(net "P3V3_STBY")
			(options
				(clearance outline)
				(anchor circle)
			)
			(primitives
				(gr_poly
					(pts
						(arc
							(start 0.3048 0.2032)
							(mid 0.275042 0.275042)
							(end 0.2032 0.3048)
						)
						(arc
							(start -0.2032 0.3048)
							(mid -0.275042 0.275042)
							(end -0.3048 0.2032)
						)
						(arc
							(start -0.3048 -0.2032)
							(mid -0.275042 -0.275042)
							(end -0.2032 -0.3048)
						)
						(arc
							(start 0.2032 -0.3048)
							(mid 0.275042 -0.275042)
							(end 0.3048 -0.2032)
						)
					)
					(width 0)
					(fill yes)
				)
			)
		)
	)
	(footprint ""
		(layer "B.Cu")
		(at 178.0794 -68.453)
		(property "Reference" "PG26"
			(at 0 0 0)
			(layer "B.SilkS")
			(hide yes)
			(effects
				(font
					(size 1.27 1.27)
				)
				(justify mirror)
			)
		)
		(property "Value" "GAP-CLOSE-PWR-3-GP"
			(at -0.0254 -6.5786 0)
			(unlocked yes)
			(layer "B.Fab")
			(hide yes)
			(effects
				(font
					(size 1.016 1.016)
					(thickness 0.1524)
				)
				(justify mirror)
			)
		)
		(property "Device Type" "GAP-CLOSE-PWR-3"
			(at -0.0254 -8.255 0)
			(unlocked yes)
			(layer "B.Fab")
			(hide yes)
			(effects
				(font
					(size 1.016 1.016)
					(thickness 0.1524)
				)
				(justify mirror)
			)
		)
		(duplicate_pad_numbers_are_jumpers no)
		(fp_rect
			(start 0.7112 0.4572)
			(end -0.7112 -0.4572)
			(stroke
				(width 0)
				(type default)
			)
			(fill no)
			(layer "B.CrtYd")
		)
		(fp_poly
			(pts
				(xy 0.7112 -0.4572) (xy -0.7112 -0.4572) (xy -0.7112 0.4572) (xy 0.7112 0.4572)
			)
			(stroke
				(width 0)
				(type default)
			)
			(fill no)
			(layer "B.Fab")
		)
		(pad "1" smd rect
			(at 0.3048 0 180)
			(size 0.6604 0.762)
			(layers "B.Cu" "B.Mask" "B.Paste")
			(net "DUT_AVD_PCIE")
		)
		(pad "2" smd rect
			(at -0.3048 0 180)
			(size 0.6604 0.762)
			(layers "B.Cu" "B.Mask" "B.Paste")
			(net "P0V9")
		)
	)
	(footprint ""
		(layer "B.Cu")
		(at 250.5964 -60.071)
		(property "Reference" "C599"
			(at 0 0 0)
			(layer "B.SilkS")
			(hide yes)
			(effects
				(font
					(size 1.27 1.27)
				)
				(justify mirror)
			)
		)
		(property "Value" "SCD1U16V1KX-1-GP"
			(at 2.8321 -1.7399 0)
			(unlocked yes)
			(layer "B.Fab")
			(hide yes)
			(effects
				(font
					(size 1.016 1.016)
					(thickness 0.1524)
				)
				(justify mirror)
			)
		)
		(property "Device Type" "C0201H13"
			(at 2.8321 -3.2639 0)
			(unlocked yes)
			(layer "B.Fab")
			(hide yes)
			(effects
				(font
					(size 1.016 1.016)
					(thickness 0.1524)
				)
				(justify mirror)
			)
		)
		(duplicate_pad_numbers_are_jumpers no)
		(fp_rect
			(start 0.2794 0.6477)
			(end -0.2794 -0.6477)
			(stroke
				(width 0)
				(type default)
			)
			(fill no)
			(layer "B.CrtYd")
		)
		(fp_rect
			(start 0.2794 0.6477)
			(end -0.2794 -0.6477)
			(stroke
				(width 0)
				(type default)
			)
			(fill no)
			(layer "B.Fab")
		)
		(pad "1" smd custom
			(at 0 -0.2794 180)
			(size 0.0762 0.0762)
			(layers "B.Cu" "B.Mask" "B.Paste")
			(net "DUT_AVD_PCIE")
			(options
				(clearance outline)
				(anchor circle)
			)
			(primitives
				(gr_poly
					(pts
						(arc
							(start 0.1524 0.127)
							(mid 0.137521 0.162921)
							(end 0.1016 0.1778)
						)
						(arc
							(start -0.1016 0.1778)
							(mid -0.137521 0.162921)
							(end -0.1524 0.127)
						)
						(arc
							(start -0.1524 -0.127)
							(mid -0.137521 -0.162921)
							(end -0.1016 -0.1778)
						)
						(arc
							(start 0.1016 -0.1778)
							(mid 0.137521 -0.162921)
							(end 0.1524 -0.127)
						)
					)
					(width 0)
					(fill yes)
				)
			)
		)
		(pad "2" smd custom
			(at 0 0.2794 180)
			(size 0.0762 0.0762)
			(layers "B.Cu" "B.Mask" "B.Paste")
			(net "GND")
			(options
				(clearance outline)
				(anchor circle)
			)
			(primitives
				(gr_poly
					(pts
						(arc
							(start 0.1524 0.127)
							(mid 0.137521 0.162921)
							(end 0.1016 0.1778)
						)
						(arc
							(start -0.1016 0.1778)
							(mid -0.137521 0.162921)
							(end -0.1524 0.127)
						)
						(arc
							(start -0.1524 -0.127)
							(mid -0.137521 -0.162921)
							(end -0.1016 -0.1778)
						)
						(arc
							(start 0.1016 -0.1778)
							(mid 0.137521 -0.162921)
							(end 0.1524 -0.127)
						)
					)
					(width 0)
					(fill yes)
				)
			)
		)
	)
	(footprint ""
		(layer "B.Cu")
		(at 270.18615 -12.401042 90)
		(property "Reference" "R2962"
			(at 0 0 90)
			(layer "B.SilkS")
			(hide yes)
			(effects
				(font
					(size 1.27 1.27)
				)
				(justify mirror)
			)
		)
		(property "Value" "0R2J-2-GP"
			(at -0.064008 -3.993896 90)
			(unlocked yes)
			(layer "B.Fab")
			(hide yes)
			(effects
				(font
					(size 1.016 1.016)
					(thickness 0.1524)
				)
				(justify mirror)
			)
		)
		(property "Device Type" "R402H16"
			(at -0.064008 -5.517896 90)
			(unlocked yes)
			(layer "B.Fab")
			(hide yes)
			(effects
				(font
					(size 1.016 1.016)
					(thickness 0.1524)
				)
				(justify mirror)
			)
		)
		(duplicate_pad_numbers_are_jumpers no)
		(fp_line
			(start 0.508 -0.9398)
			(end 0.508 0.9398)
			(stroke
				(width 0.1524)
				(type default)
			)
			(layer "B.SilkS")
		)
		(fp_line
			(start -0.508 -0.9398)
			(end 0.508 -0.9398)
			(stroke
				(width 0.1524)
				(type default)
			)
			(layer "B.SilkS")
		)
		(fp_rect
			(start 0.508 0.9398)
			(end -0.508 -0.9398)
			(stroke
				(width 0)
				(type default)
			)
			(fill no)
			(layer "B.CrtYd")
		)
		(fp_rect
			(start 0.508 0.9398)
			(end -0.508 -0.9398)
			(stroke
				(width 0)
				(type default)
			)
			(fill no)
			(layer "B.Fab")
		)
		(pad "1" smd custom
			(at 0 -0.4445 270)
			(size 0.1397 0.1397)
			(layers "B.Cu" "B.Mask" "B.Paste")
			(net "HOST5_RST_N")
			(options
				(clearance outline)
				(anchor circle)
			)
			(primitives
				(gr_poly
					(pts
						(arc
							(start -0.1778 0.2794)
							(mid -0.249642 0.249642)
							(end -0.2794 0.1778)
						)
						(arc
							(start -0.2794 -0.1778)
							(mid -0.249642 -0.249642)
							(end -0.1778 -0.2794)
						)
						(arc
							(start 0.1778 -0.2794)
							(mid 0.249642 -0.249642)
							(end 0.2794 -0.1778)
						)
						(arc
							(start 0.2794 0.1778)
							(mid 0.249642 0.249642)
							(end 0.1778 0.2794)
						)
					)
					(width 0)
					(fill yes)
				)
			)
		)
		(pad "2" smd custom
			(at 0 0.4445 270)
			(size 0.1397 0.1397)
			(layers "B.Cu" "B.Mask" "B.Paste")
			(net "HOST5_RST_N_C")
			(options
				(clearance outline)
				(anchor circle)
			)
			(primitives
				(gr_poly
					(pts
						(arc
							(start -0.1778 0.2794)
							(mid -0.249642 0.249642)
							(end -0.2794 0.1778)
						)
						(arc
							(start -0.2794 -0.1778)
							(mid -0.249642 -0.249642)
							(end -0.1778 -0.2794)
						)
						(arc
							(start 0.1778 -0.2794)
							(mid 0.249642 -0.249642)
							(end 0.2794 -0.1778)
						)
						(arc
							(start 0.2794 0.1778)
							(mid 0.249642 0.249642)
							(end 0.1778 0.2794)
						)
					)
					(width 0)
					(fill yes)
				)
			)
		)
	)
	(footprint ""
		(layer "B.Cu")
		(at 179.9844 -61.595)
		(property "Reference" "C586"
			(at 0 0 0)
			(layer "B.SilkS")
			(hide yes)
			(effects
				(font
					(size 1.27 1.27)
				)
				(justify mirror)
			)
		)
		(property "Value" "SC4D7U16V5KX-1-GP"
			(at 0.0762 -6.1214 0)
			(unlocked yes)
			(layer "B.Fab")
			(hide yes)
			(effects
				(font
					(size 1.016 1.016)
					(thickness 0.1524)
				)
				(justify mirror)
			)
		)
		(property "Device Type" "C805H56"
			(at 0.0762 -8.1534 0)
			(unlocked yes)
			(layer "B.Fab")
			(hide yes)
			(effects
				(font
					(size 1.016 1.016)
					(thickness 0.1524)
				)
				(justify mirror)
			)
		)
		(duplicate_pad_numbers_are_jumpers no)
		(fp_line
			(start -0.635 0)
			(end 0.635 0)
			(stroke
				(width 0.508)
				(type default)
			)
			(layer "B.SilkS")
		)
		(fp_rect
			(start 0.9652 1.778)
			(end -0.9652 -1.778)
			(stroke
				(width 0)
				(type default)
			)
			(fill no)
			(layer "B.CrtYd")
		)
		(fp_poly
			(pts
				(xy 0.9652 -1.778) (xy -0.9652 -1.778) (xy -0.9652 1.778) (xy 0.9652 1.778)
			)
			(stroke
				(width 0)
				(type default)
			)
			(fill no)
			(layer "B.Fab")
		)
		(pad "1" smd rect
			(at 0 -0.9652 180)
			(size 1.397 1.143)
			(layers "B.Cu" "B.Mask" "B.Paste")
			(net "DUT_AVD_PCIE")
		)
		(pad "2" smd rect
			(at 0 0.9652 180)
			(size 1.397 1.143)
			(layers "B.Cu" "B.Mask" "B.Paste")
			(net "GND")
		)
	)
	(footprint ""
		(layer "B.Cu")
		(at 310.007 -60.071 180)
		(property "Reference" "PG58"
			(at 0 0 0)
			(layer "B.SilkS")
			(hide yes)
			(effects
				(font
					(size 1.27 1.27)
				)
				(justify mirror)
			)
		)
		(property "Value" "GAP-CLOSE-PWR-3-GP"
			(at -0.0254 -6.5786 180)
			(unlocked yes)
			(layer "B.Fab")
			(hide yes)
			(effects
				(font
					(size 1.016 1.016)
					(thickness 0.1524)
				)
				(justify mirror)
			)
		)
		(property "Device Type" "GAP-CLOSE-PWR-3"
			(at -0.0254 -8.255 180)
			(unlocked yes)
			(layer "B.Fab")
			(hide yes)
			(effects
				(font
					(size 1.016 1.016)
					(thickness 0.1524)
				)
				(justify mirror)
			)
		)
		(duplicate_pad_numbers_are_jumpers no)
		(fp_rect
			(start 0.7112 0.4572)
			(end -0.7112 -0.4572)
			(stroke
				(width 0)
				(type default)
			)
			(fill no)
			(layer "B.CrtYd")
		)
		(fp_poly
			(pts
				(xy 0.7112 -0.4572) (xy -0.7112 -0.4572) (xy -0.7112 0.4572) (xy 0.7112 0.4572)
			)
			(stroke
				(width 0)
				(type default)
			)
			(fill no)
			(layer "B.Fab")
		)
		(pad "1" smd rect
			(at 0.3048 0)
			(size 0.6604 0.762)
			(layers "B.Cu" "B.Mask" "B.Paste")
			(net "DUT_VDD")
		)
		(pad "2" smd rect
			(at -0.3048 0)
			(size 0.6604 0.762)
			(layers "B.Cu" "B.Mask" "B.Paste")
			(net "P0V9_E")
		)
	)
	(footprint ""
		(layer "B.Cu")
		(at 249.6058 -37.9984 -90)
		(property "Reference" "TP297"
			(at 0 0 90)
			(layer "B.SilkS")
			(hide yes)
			(effects
				(font
					(size 1.27 1.27)
				)
				(justify mirror)
			)
		)
		(property "Value" "TPAD28-2-GP"
			(at 0.0127 -1.6637 270)
			(unlocked yes)
			(layer "B.Fab")
			(hide yes)
			(effects
				(font
					(size 1.016 1.016)
					(thickness 0.1524)
				)
				(justify mirror)
			)
		)
		(property "Device Type" "TPAD28"
			(at 0.0127 -3.1877 270)
			(unlocked yes)
			(layer "B.Fab")
			(hide yes)
			(effects
				(font
					(size 1.016 1.016)
					(thickness 0.1524)
				)
				(justify mirror)
			)
		)
		(duplicate_pad_numbers_are_jumpers no)
		(fp_poly
			(pts
				(arc
					(start 0 -0.3556)
					(mid 0 0.3556)
					(end 0 -0.3556)
				)
			)
			(stroke
				(width 0)
				(type default)
			)
			(fill no)
			(layer "B.CrtYd")
		)
		(fp_poly
			(pts
				(arc
					(start 0 -0.6096)
					(mid 0 0.6096)
					(end 0 -0.6096)
				)
			)
			(stroke
				(width 0)
				(type default)
			)
			(fill no)
			(layer "B.Fab")
		)
		(pad "1" smd circle
			(at 0 0 90)
			(size 0.7112 0.7112)
			(layers "B.Cu" "B.Mask" "B.Paste")
			(net "TWI_SRST#8")
		)
	)
	(footprint ""
		(layer "B.Cu")
		(at 124.079 -205.74)
		(property "Reference" "C8094"
			(at 0 0 0)
			(layer "B.SilkS")
			(hide yes)
			(effects
				(font
					(size 1.27 1.27)
				)
				(justify mirror)
			)
		)
		(property "Value" "SCD047U25V2KX-GP"
			(at -1.1811 -2.7051 0)
			(unlocked yes)
			(layer "B.Fab")
			(hide yes)
			(effects
				(font
					(size 1.016 1.016)
					(thickness 0.1524)
				)
				(justify mirror)
			)
		)
		(property "Device Type" "C402H22"
			(at -1.1811 -4.2291 0)
			(unlocked yes)
			(layer "B.Fab")
			(hide yes)
			(effects
				(font
					(size 1.016 1.016)
					(thickness 0.1524)
				)
				(justify mirror)
			)
		)
		(duplicate_pad_numbers_are_jumpers no)
		(fp_rect
			(start 0.4318 0.9525)
			(end -0.4318 -0.9525)
			(stroke
				(width 0)
				(type default)
			)
			(fill no)
			(layer "B.CrtYd")
		)
		(fp_rect
			(start 0.4318 0.9525)
			(end -0.4318 -0.9525)
			(stroke
				(width 0)
				(type default)
			)
			(fill no)
			(layer "B.Fab")
		)
		(pad "1" smd custom
			(at 0 -0.4445 180)
			(size 0.1524 0.1524)
			(layers "B.Cu" "B.Mask" "B.Paste")
			(net "P3V3_STBY")
			(options
				(clearance outline)
				(anchor circle)
			)
			(primitives
				(gr_poly
					(pts
						(arc
							(start 0.3048 0.2032)
							(mid 0.275042 0.275042)
							(end 0.2032 0.3048)
						)
						(arc
							(start -0.2032 0.3048)
							(mid -0.275042 0.275042)
							(end -0.3048 0.2032)
						)
						(arc
							(start -0.3048 -0.2032)
							(mid -0.275042 -0.275042)
							(end -0.2032 -0.3048)
						)
						(arc
							(start 0.2032 -0.3048)
							(mid 0.275042 -0.275042)
							(end 0.3048 -0.2032)
						)
					)
					(width 0)
					(fill yes)
				)
			)
		)
		(pad "2" smd custom
			(at 0 0.4445 180)
			(size 0.1524 0.1524)
			(layers "B.Cu" "B.Mask" "B.Paste")
			(net "GND")
			(options
				(clearance outline)
				(anchor circle)
			)
			(primitives
				(gr_poly
					(pts
						(arc
							(start 0.3048 0.2032)
							(mid 0.275042 0.275042)
							(end 0.2032 0.3048)
						)
						(arc
							(start -0.2032 0.3048)
							(mid -0.275042 0.275042)
							(end -0.3048 0.2032)
						)
						(arc
							(start -0.3048 -0.2032)
							(mid -0.275042 -0.275042)
							(end -0.2032 -0.3048)
						)
						(arc
							(start 0.2032 -0.3048)
							(mid 0.275042 -0.275042)
							(end 0.3048 -0.2032)
						)
					)
					(width 0)
					(fill yes)
				)
			)
		)
	)
	(footprint ""
		(layer "B.Cu")
		(at 63.754 -126.9746)
		(property "Reference" "R420"
			(at 0 0 0)
			(layer "B.SilkS")
			(hide yes)
			(effects
				(font
					(size 1.27 1.27)
				)
				(justify mirror)
			)
		)
		(property "Value" "10KR2F-2-GP"
			(at -0.064008 -3.993896 0)
			(unlocked yes)
			(layer "B.Fab")
			(hide yes)
			(effects
				(font
					(size 1.016 1.016)
					(thickness 0.1524)
				)
				(justify mirror)
			)
		)
		(property "Device Type" "R402H16"
			(at -0.064008 -5.517896 0)
			(unlocked yes)
			(layer "B.Fab")
			(hide yes)
			(effects
				(font
					(size 1.016 1.016)
					(thickness 0.1524)
				)
				(justify mirror)
			)
		)
		(duplicate_pad_numbers_are_jumpers no)
		(fp_line
			(start -0.508 -0.9398)
			(end 0.508 -0.9398)
			(stroke
				(width 0.1524)
				(type default)
			)
			(layer "B.SilkS")
		)
		(fp_line
			(start 0.508 -0.9398)
			(end 0.508 0.9398)
			(stroke
				(width 0.1524)
				(type default)
			)
			(layer "B.SilkS")
		)
		(fp_rect
			(start 0.508 0.9398)
			(end -0.508 -0.9398)
			(stroke
				(width 0)
				(type default)
			)
			(fill no)
			(layer "B.CrtYd")
		)
		(fp_rect
			(start 0.508 0.9398)
			(end -0.508 -0.9398)
			(stroke
				(width 0)
				(type default)
			)
			(fill no)
			(layer "B.Fab")
		)
		(pad "1" smd custom
			(at 0 -0.4445 180)
			(size 0.1397 0.1397)
			(layers "B.Cu" "B.Mask" "B.Paste")
			(net "P3V3_STBY")
			(options
				(clearance outline)
				(anchor circle)
			)
			(primitives
				(gr_poly
					(pts
						(arc
							(start -0.1778 0.2794)
							(mid -0.249642 0.249642)
							(end -0.2794 0.1778)
						)
						(arc
							(start -0.2794 -0.1778)
							(mid -0.249642 -0.249642)
							(end -0.1778 -0.2794)
						)
						(arc
							(start 0.1778 -0.2794)
							(mid 0.249642 -0.249642)
							(end 0.2794 -0.1778)
						)
						(arc
							(start 0.2794 0.1778)
							(mid 0.249642 0.249642)
							(end 0.1778 0.2794)
						)
					)
					(width 0)
					(fill yes)
				)
			)
		)
		(pad "2" smd custom
			(at 0 0.4445 180)
			(size 0.1397 0.1397)
			(layers "B.Cu" "B.Mask" "B.Paste")
			(net "BMC_TXD5")
			(options
				(clearance outline)
				(anchor circle)
			)
			(primitives
				(gr_poly
					(pts
						(arc
							(start -0.1778 0.2794)
							(mid -0.249642 0.249642)
							(end -0.2794 0.1778)
						)
						(arc
							(start -0.2794 -0.1778)
							(mid -0.249642 -0.249642)
							(end -0.1778 -0.2794)
						)
						(arc
							(start 0.1778 -0.2794)
							(mid 0.249642 -0.249642)
							(end 0.2794 -0.1778)
						)
						(arc
							(start 0.2794 0.1778)
							(mid 0.249642 0.249642)
							(end 0.1778 0.2794)
						)
					)
					(width 0)
					(fill yes)
				)
			)
		)
	)
	(footprint ""
		(layer "B.Cu")
		(at 20.955 -128.651 90)
		(property "Reference" "R361"
			(at 0 0 90)
			(layer "B.SilkS")
			(hide yes)
			(effects
				(font
					(size 1.27 1.27)
				)
				(justify mirror)
			)
		)
		(property "Value" "3K3R2F-2-GP"
			(at -0.064008 -3.993896 90)
			(unlocked yes)
			(layer "B.Fab")
			(hide yes)
			(effects
				(font
					(size 1.016 1.016)
					(thickness 0.1524)
				)
				(justify mirror)
			)
		)
		(property "Device Type" "R402H16"
			(at -0.064008 -5.517896 90)
			(unlocked yes)
			(layer "B.Fab")
			(hide yes)
			(effects
				(font
					(size 1.016 1.016)
					(thickness 0.1524)
				)
				(justify mirror)
			)
		)
		(duplicate_pad_numbers_are_jumpers no)
		(fp_line
			(start 0.508 -0.9398)
			(end 0.508 0.9398)
			(stroke
				(width 0.1524)
				(type default)
			)
			(layer "B.SilkS")
		)
		(fp_line
			(start -0.508 -0.9398)
			(end 0.508 -0.9398)
			(stroke
				(width 0.1524)
				(type default)
			)
			(layer "B.SilkS")
		)
		(fp_rect
			(start 0.508 0.9398)
			(end -0.508 -0.9398)
			(stroke
				(width 0)
				(type default)
			)
			(fill no)
			(layer "B.CrtYd")
		)
		(fp_rect
			(start 0.508 0.9398)
			(end -0.508 -0.9398)
			(stroke
				(width 0)
				(type default)
			)
			(fill no)
			(layer "B.Fab")
		)
		(pad "1" smd custom
			(at 0 -0.4445 270)
			(size 0.1397 0.1397)
			(layers "B.Cu" "B.Mask" "B.Paste")
			(net "P3V3_STBY")
			(options
				(clearance outline)
				(anchor circle)
			)
			(primitives
				(gr_poly
					(pts
						(arc
							(start -0.1778 0.2794)
							(mid -0.249642 0.249642)
							(end -0.2794 0.1778)
						)
						(arc
							(start -0.2794 -0.1778)
							(mid -0.249642 -0.249642)
							(end -0.1778 -0.2794)
						)
						(arc
							(start 0.1778 -0.2794)
							(mid 0.249642 -0.249642)
							(end 0.2794 -0.1778)
						)
						(arc
							(start 0.2794 0.1778)
							(mid 0.249642 0.249642)
							(end 0.1778 0.2794)
						)
					)
					(width 0)
					(fill yes)
				)
			)
		)
		(pad "2" smd custom
			(at 0 0.4445 270)
			(size 0.1397 0.1397)
			(layers "B.Cu" "B.Mask" "B.Paste")
			(net "ROMA21")
			(options
				(clearance outline)
				(anchor circle)
			)
			(primitives
				(gr_poly
					(pts
						(arc
							(start -0.1778 0.2794)
							(mid -0.249642 0.249642)
							(end -0.2794 0.1778)
						)
						(arc
							(start -0.2794 -0.1778)
							(mid -0.249642 -0.249642)
							(end -0.1778 -0.2794)
						)
						(arc
							(start 0.1778 -0.2794)
							(mid 0.249642 -0.249642)
							(end 0.2794 -0.1778)
						)
						(arc
							(start 0.2794 0.1778)
							(mid 0.249642 0.249642)
							(end 0.1778 0.2794)
						)
					)
					(width 0)
					(fill yes)
				)
			)
		)
	)
	(footprint ""
		(layer "B.Cu")
		(at 252.603 -42.994072 -90)
		(property "Reference" "C615"
			(at 0 0 90)
			(layer "B.SilkS")
			(hide yes)
			(effects
				(font
					(size 1.27 1.27)
				)
				(justify mirror)
			)
		)
		(property "Value" "SCD1U16V1KX-1-GP"
			(at 2.8321 -1.7399 270)
			(unlocked yes)
			(layer "B.Fab")
			(hide yes)
			(effects
				(font
					(size 1.016 1.016)
					(thickness 0.1524)
				)
				(justify mirror)
			)
		)
		(property "Device Type" "C0201H13"
			(at 2.8321 -3.2639 270)
			(unlocked yes)
			(layer "B.Fab")
			(hide yes)
			(effects
				(font
					(size 1.016 1.016)
					(thickness 0.1524)
				)
				(justify mirror)
			)
		)
		(duplicate_pad_numbers_are_jumpers no)
		(fp_rect
			(start 0.2794 0.6477)
			(end -0.2794 -0.6477)
			(stroke
				(width 0)
				(type default)
			)
			(fill no)
			(layer "B.CrtYd")
		)
		(fp_rect
			(start 0.2794 0.6477)
			(end -0.2794 -0.6477)
			(stroke
				(width 0)
				(type default)
			)
			(fill no)
			(layer "B.Fab")
		)
		(pad "1" smd custom
			(at 0 -0.2794 90)
			(size 0.0762 0.0762)
			(layers "B.Cu" "B.Mask" "B.Paste")
			(net "DUT_AVD_PCIE")
			(options
				(clearance outline)
				(anchor circle)
			)
			(primitives
				(gr_poly
					(pts
						(arc
							(start 0.1524 0.127)
							(mid 0.137521 0.162921)
							(end 0.1016 0.1778)
						)
						(arc
							(start -0.1016 0.1778)
							(mid -0.137521 0.162921)
							(end -0.1524 0.127)
						)
						(arc
							(start -0.1524 -0.127)
							(mid -0.137521 -0.162921)
							(end -0.1016 -0.1778)
						)
						(arc
							(start 0.1016 -0.1778)
							(mid 0.137521 -0.162921)
							(end 0.1524 -0.127)
						)
					)
					(width 0)
					(fill yes)
				)
			)
		)
		(pad "2" smd custom
			(at 0 0.2794 90)
			(size 0.0762 0.0762)
			(layers "B.Cu" "B.Mask" "B.Paste")
			(net "GND")
			(options
				(clearance outline)
				(anchor circle)
			)
			(primitives
				(gr_poly
					(pts
						(arc
							(start 0.1524 0.127)
							(mid 0.137521 0.162921)
							(end 0.1016 0.1778)
						)
						(arc
							(start -0.1016 0.1778)
							(mid -0.137521 0.162921)
							(end -0.1524 0.127)
						)
						(arc
							(start -0.1524 -0.127)
							(mid -0.137521 -0.162921)
							(end -0.1016 -0.1778)
						)
						(arc
							(start 0.1016 -0.1778)
							(mid 0.137521 -0.162921)
							(end 0.1524 -0.127)
						)
					)
					(width 0)
					(fill yes)
				)
			)
		)
	)
	(footprint ""
		(layer "B.Cu")
		(at 130.556 -202.565)
		(property "Reference" "R140"
			(at 0 0 0)
			(layer "B.SilkS")
			(hide yes)
			(effects
				(font
					(size 1.27 1.27)
				)
				(justify mirror)
			)
		)
		(property "Value" "4K7R2F-GP"
			(at -0.064008 -3.993896 0)
			(unlocked yes)
			(layer "B.Fab")
			(hide yes)
			(effects
				(font
					(size 1.016 1.016)
					(thickness 0.1524)
				)
				(justify mirror)
			)
		)
		(property "Device Type" "R402H16"
			(at -0.064008 -5.517896 0)
			(unlocked yes)
			(layer "B.Fab")
			(hide yes)
			(effects
				(font
					(size 1.016 1.016)
					(thickness 0.1524)
				)
				(justify mirror)
			)
		)
		(duplicate_pad_numbers_are_jumpers no)
		(fp_line
			(start -0.508 -0.9398)
			(end 0.508 -0.9398)
			(stroke
				(width 0.1524)
				(type default)
			)
			(layer "B.SilkS")
		)
		(fp_line
			(start 0.508 -0.9398)
			(end 0.508 0.9398)
			(stroke
				(width 0.1524)
				(type default)
			)
			(layer "B.SilkS")
		)
		(fp_rect
			(start 0.508 0.9398)
			(end -0.508 -0.9398)
			(stroke
				(width 0)
				(type default)
			)
			(fill no)
			(layer "B.CrtYd")
		)
		(fp_rect
			(start 0.508 0.9398)
			(end -0.508 -0.9398)
			(stroke
				(width 0)
				(type default)
			)
			(fill no)
			(layer "B.Fab")
		)
		(pad "1" smd custom
			(at 0 -0.4445 180)
			(size 0.1397 0.1397)
			(layers "B.Cu" "B.Mask" "B.Paste")
			(net "BMC_SSD_RST#0_A2")
			(options
				(clearance outline)
				(anchor circle)
			)
			(primitives
				(gr_poly
					(pts
						(arc
							(start -0.1778 0.2794)
							(mid -0.249642 0.249642)
							(end -0.2794 0.1778)
						)
						(arc
							(start -0.2794 -0.1778)
							(mid -0.249642 -0.249642)
							(end -0.1778 -0.2794)
						)
						(arc
							(start 0.1778 -0.2794)
							(mid 0.249642 -0.249642)
							(end 0.2794 -0.1778)
						)
						(arc
							(start 0.2794 0.1778)
							(mid 0.249642 0.249642)
							(end 0.1778 0.2794)
						)
					)
					(width 0)
					(fill yes)
				)
			)
		)
		(pad "2" smd custom
			(at 0 0.4445 180)
			(size 0.1397 0.1397)
			(layers "B.Cu" "B.Mask" "B.Paste")
			(net "P3V3_STBY")
			(options
				(clearance outline)
				(anchor circle)
			)
			(primitives
				(gr_poly
					(pts
						(arc
							(start -0.1778 0.2794)
							(mid -0.249642 0.249642)
							(end -0.2794 0.1778)
						)
						(arc
							(start -0.2794 -0.1778)
							(mid -0.249642 -0.249642)
							(end -0.1778 -0.2794)
						)
						(arc
							(start 0.1778 -0.2794)
							(mid 0.249642 -0.249642)
							(end 0.2794 -0.1778)
						)
						(arc
							(start 0.2794 0.1778)
							(mid 0.249642 0.249642)
							(end 0.1778 0.2794)
						)
					)
					(width 0)
					(fill yes)
				)
			)
		)
	)
	(footprint ""
		(layer "B.Cu")
		(at 50.165 -145.415 180)
		(property "Reference" "SR847"
			(at 0 0 0)
			(layer "B.SilkS")
			(hide yes)
			(effects
				(font
					(size 1.27 1.27)
				)
				(justify mirror)
			)
		)
		(property "Value" "4K75R2F-1-GP"
			(at -0.064008 -3.993896 180)
			(unlocked yes)
			(layer "B.Fab")
			(hide yes)
			(effects
				(font
					(size 1.016 1.016)
					(thickness 0.1524)
				)
				(justify mirror)
			)
		)
		(property "Device Type" "R402H16"
			(at -0.064008 -5.517896 180)
			(unlocked yes)
			(layer "B.Fab")
			(hide yes)
			(effects
				(font
					(size 1.016 1.016)
					(thickness 0.1524)
				)
				(justify mirror)
			)
		)
		(duplicate_pad_numbers_are_jumpers no)
		(fp_line
			(start 0.508 -0.9398)
			(end 0.508 0.9398)
			(stroke
				(width 0.1524)
				(type default)
			)
			(layer "B.SilkS")
		)
		(fp_line
			(start -0.508 -0.9398)
			(end 0.508 -0.9398)
			(stroke
				(width 0.1524)
				(type default)
			)
			(layer "B.SilkS")
		)
		(fp_rect
			(start 0.508 0.9398)
			(end -0.508 -0.9398)
			(stroke
				(width 0)
				(type default)
			)
			(fill no)
			(layer "B.CrtYd")
		)
		(fp_rect
			(start 0.508 0.9398)
			(end -0.508 -0.9398)
			(stroke
				(width 0)
				(type default)
			)
			(fill no)
			(layer "B.Fab")
		)
		(pad "1" smd custom
			(at 0 -0.4445)
			(size 0.1397 0.1397)
			(layers "B.Cu" "B.Mask" "B.Paste")
			(net "BMC_FW_DET_BOARD_VER_2")
			(options
				(clearance outline)
				(anchor circle)
			)
			(primitives
				(gr_poly
					(pts
						(arc
							(start -0.1778 0.2794)
							(mid -0.249642 0.249642)
							(end -0.2794 0.1778)
						)
						(arc
							(start -0.2794 -0.1778)
							(mid -0.249642 -0.249642)
							(end -0.1778 -0.2794)
						)
						(arc
							(start 0.1778 -0.2794)
							(mid 0.249642 -0.249642)
							(end 0.2794 -0.1778)
						)
						(arc
							(start 0.2794 0.1778)
							(mid 0.249642 0.249642)
							(end 0.1778 0.2794)
						)
					)
					(width 0)
					(fill yes)
				)
			)
		)
		(pad "2" smd custom
			(at 0 0.4445)
			(size 0.1397 0.1397)
			(layers "B.Cu" "B.Mask" "B.Paste")
			(net "GND")
			(options
				(clearance outline)
				(anchor circle)
			)
			(primitives
				(gr_poly
					(pts
						(arc
							(start -0.1778 0.2794)
							(mid -0.249642 0.249642)
							(end -0.2794 0.1778)
						)
						(arc
							(start -0.2794 -0.1778)
							(mid -0.249642 -0.249642)
							(end -0.1778 -0.2794)
						)
						(arc
							(start 0.1778 -0.2794)
							(mid 0.249642 -0.249642)
							(end 0.2794 -0.1778)
						)
						(arc
							(start 0.2794 0.1778)
							(mid 0.249642 0.249642)
							(end 0.1778 0.2794)
						)
					)
					(width 0)
					(fill yes)
				)
			)
		)
	)
	(footprint ""
		(layer "B.Cu")
		(at 59.218322 -124.441966 90)
		(property "Reference" "R421"
			(at 0 0 90)
			(layer "B.SilkS")
			(hide yes)
			(effects
				(font
					(size 1.27 1.27)
				)
				(justify mirror)
			)
		)
		(property "Value" "4K7R2F-GP"
			(at -0.064008 -3.993896 90)
			(unlocked yes)
			(layer "B.Fab")
			(hide yes)
			(effects
				(font
					(size 1.016 1.016)
					(thickness 0.1524)
				)
				(justify mirror)
			)
		)
		(property "Device Type" "R402H16"
			(at -0.064008 -5.517896 90)
			(unlocked yes)
			(layer "B.Fab")
			(hide yes)
			(effects
				(font
					(size 1.016 1.016)
					(thickness 0.1524)
				)
				(justify mirror)
			)
		)
		(duplicate_pad_numbers_are_jumpers no)
		(fp_line
			(start 0.508 -0.9398)
			(end 0.508 0.9398)
			(stroke
				(width 0.1524)
				(type default)
			)
			(layer "B.SilkS")
		)
		(fp_line
			(start -0.508 -0.9398)
			(end 0.508 -0.9398)
			(stroke
				(width 0.1524)
				(type default)
			)
			(layer "B.SilkS")
		)
		(fp_rect
			(start 0.508 0.9398)
			(end -0.508 -0.9398)
			(stroke
				(width 0)
				(type default)
			)
			(fill no)
			(layer "B.CrtYd")
		)
		(fp_rect
			(start 0.508 0.9398)
			(end -0.508 -0.9398)
			(stroke
				(width 0)
				(type default)
			)
			(fill no)
			(layer "B.Fab")
		)
		(pad "1" smd custom
			(at 0 -0.4445 270)
			(size 0.1397 0.1397)
			(layers "B.Cu" "B.Mask" "B.Paste")
			(net "BMC_I2C8_CLKBUF1_SCL")
			(options
				(clearance outline)
				(anchor circle)
			)
			(primitives
				(gr_poly
					(pts
						(arc
							(start -0.1778 0.2794)
							(mid -0.249642 0.249642)
							(end -0.2794 0.1778)
						)
						(arc
							(start -0.2794 -0.1778)
							(mid -0.249642 -0.249642)
							(end -0.1778 -0.2794)
						)
						(arc
							(start 0.1778 -0.2794)
							(mid 0.249642 -0.249642)
							(end 0.2794 -0.1778)
						)
						(arc
							(start 0.2794 0.1778)
							(mid 0.249642 0.249642)
							(end 0.1778 0.2794)
						)
					)
					(width 0)
					(fill yes)
				)
			)
		)
		(pad "2" smd custom
			(at 0 0.4445 270)
			(size 0.1397 0.1397)
			(layers "B.Cu" "B.Mask" "B.Paste")
			(net "P3V3_STBY")
			(options
				(clearance outline)
				(anchor circle)
			)
			(primitives
				(gr_poly
					(pts
						(arc
							(start -0.1778 0.2794)
							(mid -0.249642 0.249642)
							(end -0.2794 0.1778)
						)
						(arc
							(start -0.2794 -0.1778)
							(mid -0.249642 -0.249642)
							(end -0.1778 -0.2794)
						)
						(arc
							(start 0.1778 -0.2794)
							(mid 0.249642 -0.249642)
							(end 0.2794 -0.1778)
						)
						(arc
							(start 0.2794 0.1778)
							(mid 0.249642 0.249642)
							(end 0.1778 0.2794)
						)
					)
					(width 0)
					(fill yes)
				)
			)
		)
	)
	(footprint ""
		(layer "B.Cu")
		(at 336.7786 -181.8386)
		(property "Reference" "R3229"
			(at 0 0 0)
			(layer "B.SilkS")
			(hide yes)
			(effects
				(font
					(size 1.27 1.27)
				)
				(justify mirror)
			)
		)
		(property "Value" "0R2J-2-GP"
			(at -0.064008 -3.993896 0)
			(unlocked yes)
			(layer "B.Fab")
			(hide yes)
			(effects
				(font
					(size 1.016 1.016)
					(thickness 0.1524)
				)
				(justify mirror)
			)
		)
		(property "Device Type" "R402H16"
			(at -0.064008 -5.517896 0)
			(unlocked yes)
			(layer "B.Fab")
			(hide yes)
			(effects
				(font
					(size 1.016 1.016)
					(thickness 0.1524)
				)
				(justify mirror)
			)
		)
		(duplicate_pad_numbers_are_jumpers no)
		(fp_line
			(start -0.508 -0.9398)
			(end 0.508 -0.9398)
			(stroke
				(width 0.1524)
				(type default)
			)
			(layer "B.SilkS")
		)
		(fp_line
			(start 0.508 -0.9398)
			(end 0.508 0.9398)
			(stroke
				(width 0.1524)
				(type default)
			)
			(layer "B.SilkS")
		)
		(fp_rect
			(start 0.508 0.9398)
			(end -0.508 -0.9398)
			(stroke
				(width 0)
				(type default)
			)
			(fill no)
			(layer "B.CrtYd")
		)
		(fp_rect
			(start 0.508 0.9398)
			(end -0.508 -0.9398)
			(stroke
				(width 0)
				(type default)
			)
			(fill no)
			(layer "B.Fab")
		)
		(pad "1" smd custom
			(at 0 -0.4445 180)
			(size 0.1397 0.1397)
			(layers "B.Cu" "B.Mask" "B.Paste")
			(net "BMC_SSD_RST#9")
			(options
				(clearance outline)
				(anchor circle)
			)
			(primitives
				(gr_poly
					(pts
						(arc
							(start -0.1778 0.2794)
							(mid -0.249642 0.249642)
							(end -0.2794 0.1778)
						)
						(arc
							(start -0.2794 -0.1778)
							(mid -0.249642 -0.249642)
							(end -0.1778 -0.2794)
						)
						(arc
							(start 0.1778 -0.2794)
							(mid 0.249642 -0.249642)
							(end 0.2794 -0.1778)
						)
						(arc
							(start 0.2794 0.1778)
							(mid 0.249642 0.249642)
							(end 0.1778 0.2794)
						)
					)
					(width 0)
					(fill yes)
				)
			)
		)
		(pad "2" smd custom
			(at 0 0.4445 180)
			(size 0.1397 0.1397)
			(layers "B.Cu" "B.Mask" "B.Paste")
			(net "BMC_SSD_RST#0_A9")
			(options
				(clearance outline)
				(anchor circle)
			)
			(primitives
				(gr_poly
					(pts
						(arc
							(start -0.1778 0.2794)
							(mid -0.249642 0.249642)
							(end -0.2794 0.1778)
						)
						(arc
							(start -0.2794 -0.1778)
							(mid -0.249642 -0.249642)
							(end -0.1778 -0.2794)
						)
						(arc
							(start 0.1778 -0.2794)
							(mid 0.249642 -0.249642)
							(end 0.2794 -0.1778)
						)
						(arc
							(start 0.2794 0.1778)
							(mid 0.249642 0.249642)
							(end 0.1778 0.2794)
						)
					)
					(width 0)
					(fill yes)
				)
			)
		)
	)
	(footprint ""
		(layer "B.Cu")
		(at 270.63065 -10.813542)
		(property "Reference" "R723"
			(at 0 0 0)
			(layer "B.SilkS")
			(hide yes)
			(effects
				(font
					(size 1.27 1.27)
				)
				(justify mirror)
			)
		)
		(property "Value" "0R2J-2-GP"
			(at -0.064008 -3.993896 0)
			(unlocked yes)
			(layer "B.Fab")
			(hide yes)
			(effects
				(font
					(size 1.016 1.016)
					(thickness 0.1524)
				)
				(justify mirror)
			)
		)
		(property "Device Type" "R402H16"
			(at -0.064008 -5.517896 0)
			(unlocked yes)
			(layer "B.Fab")
			(hide yes)
			(effects
				(font
					(size 1.016 1.016)
					(thickness 0.1524)
				)
				(justify mirror)
			)
		)
		(duplicate_pad_numbers_are_jumpers no)
		(fp_line
			(start -0.508 -0.9398)
			(end 0.508 -0.9398)
			(stroke
				(width 0.1524)
				(type default)
			)
			(layer "B.SilkS")
		)
		(fp_line
			(start 0.508 -0.9398)
			(end 0.508 0.9398)
			(stroke
				(width 0.1524)
				(type default)
			)
			(layer "B.SilkS")
		)
		(fp_rect
			(start 0.508 0.9398)
			(end -0.508 -0.9398)
			(stroke
				(width 0)
				(type default)
			)
			(fill no)
			(layer "B.CrtYd")
		)
		(fp_rect
			(start 0.508 0.9398)
			(end -0.508 -0.9398)
			(stroke
				(width 0)
				(type default)
			)
			(fill no)
			(layer "B.Fab")
		)
		(pad "1" smd custom
			(at 0 -0.4445 180)
			(size 0.1397 0.1397)
			(layers "B.Cu" "B.Mask" "B.Paste")
			(net "HOST6_RST_N_C")
			(options
				(clearance outline)
				(anchor circle)
			)
			(primitives
				(gr_poly
					(pts
						(arc
							(start -0.1778 0.2794)
							(mid -0.249642 0.249642)
							(end -0.2794 0.1778)
						)
						(arc
							(start -0.2794 -0.1778)
							(mid -0.249642 -0.249642)
							(end -0.1778 -0.2794)
						)
						(arc
							(start 0.1778 -0.2794)
							(mid 0.249642 -0.249642)
							(end 0.2794 -0.1778)
						)
						(arc
							(start 0.2794 0.1778)
							(mid 0.249642 0.249642)
							(end 0.1778 0.2794)
						)
					)
					(width 0)
					(fill yes)
				)
			)
		)
		(pad "2" smd custom
			(at 0 0.4445 180)
			(size 0.1397 0.1397)
			(layers "B.Cu" "B.Mask" "B.Paste")
			(net "P3V3_STBY")
			(options
				(clearance outline)
				(anchor circle)
			)
			(primitives
				(gr_poly
					(pts
						(arc
							(start -0.1778 0.2794)
							(mid -0.249642 0.249642)
							(end -0.2794 0.1778)
						)
						(arc
							(start -0.2794 -0.1778)
							(mid -0.249642 -0.249642)
							(end -0.1778 -0.2794)
						)
						(arc
							(start 0.1778 -0.2794)
							(mid 0.249642 -0.249642)
							(end 0.2794 -0.1778)
						)
						(arc
							(start 0.2794 0.1778)
							(mid 0.249642 0.249642)
							(end 0.1778 0.2794)
						)
					)
					(width 0)
					(fill yes)
				)
			)
		)
	)
	(footprint ""
		(layer "B.Cu")
		(at 298.489624 -34.625026 180)
		(property "Reference" "C131"
			(at 0 0 0)
			(layer "B.SilkS")
			(hide yes)
			(effects
				(font
					(size 1.27 1.27)
				)
				(justify mirror)
			)
		)
		(property "Value" "SCD1U10V2KX-5GP"
			(at -1.1811 -2.7051 180)
			(unlocked yes)
			(layer "B.Fab")
			(hide yes)
			(effects
				(font
					(size 1.016 1.016)
					(thickness 0.1524)
				)
				(justify mirror)
			)
		)
		(property "Device Type" "C402H22"
			(at -1.1811 -4.2291 180)
			(unlocked yes)
			(layer "B.Fab")
			(hide yes)
			(effects
				(font
					(size 1.016 1.016)
					(thickness 0.1524)
				)
				(justify mirror)
			)
		)
		(duplicate_pad_numbers_are_jumpers no)
		(fp_rect
			(start 0.4318 0.9525)
			(end -0.4318 -0.9525)
			(stroke
				(width 0)
				(type default)
			)
			(fill no)
			(layer "B.CrtYd")
		)
		(fp_rect
			(start 0.4318 0.9525)
			(end -0.4318 -0.9525)
			(stroke
				(width 0)
				(type default)
			)
			(fill no)
			(layer "B.Fab")
		)
		(pad "1" smd custom
			(at 0 -0.4445)
			(size 0.1524 0.1524)
			(layers "B.Cu" "B.Mask" "B.Paste")
			(net "GND")
			(options
				(clearance outline)
				(anchor circle)
			)
			(primitives
				(gr_poly
					(pts
						(arc
							(start 0.3048 0.2032)
							(mid 0.275042 0.275042)
							(end 0.2032 0.3048)
						)
						(arc
							(start -0.2032 0.3048)
							(mid -0.275042 0.275042)
							(end -0.3048 0.2032)
						)
						(arc
							(start -0.3048 -0.2032)
							(mid -0.275042 -0.275042)
							(end -0.2032 -0.3048)
						)
						(arc
							(start 0.2032 -0.3048)
							(mid 0.275042 -0.275042)
							(end 0.3048 -0.2032)
						)
					)
					(width 0)
					(fill yes)
				)
			)
		)
		(pad "2" smd custom
			(at 0 0.4445)
			(size 0.1524 0.1524)
			(layers "B.Cu" "B.Mask" "B.Paste")
			(net "P3V3_STBY")
			(options
				(clearance outline)
				(anchor circle)
			)
			(primitives
				(gr_poly
					(pts
						(arc
							(start 0.3048 0.2032)
							(mid 0.275042 0.275042)
							(end 0.2032 0.3048)
						)
						(arc
							(start -0.2032 0.3048)
							(mid -0.275042 0.275042)
							(end -0.3048 0.2032)
						)
						(arc
							(start -0.3048 -0.2032)
							(mid -0.275042 -0.275042)
							(end -0.2032 -0.3048)
						)
						(arc
							(start 0.2032 -0.3048)
							(mid 0.275042 -0.275042)
							(end 0.3048 -0.2032)
						)
					)
					(width 0)
					(fill yes)
				)
			)
		)
	)
	(footprint ""
		(layer "B.Cu")
		(at 131.294124 -208.889092 180)
		(property "Reference" "R4122"
			(at 0 0 0)
			(layer "B.SilkS")
			(hide yes)
			(effects
				(font
					(size 1.27 1.27)
				)
				(justify mirror)
			)
		)
		(property "Value" "4K7R2F-GP"
			(at -0.064008 -3.993896 180)
			(unlocked yes)
			(layer "B.Fab")
			(hide yes)
			(effects
				(font
					(size 1.016 1.016)
					(thickness 0.1524)
				)
				(justify mirror)
			)
		)
		(property "Device Type" "R402H16"
			(at -0.064008 -5.517896 180)
			(unlocked yes)
			(layer "B.Fab")
			(hide yes)
			(effects
				(font
					(size 1.016 1.016)
					(thickness 0.1524)
				)
				(justify mirror)
			)
		)
		(duplicate_pad_numbers_are_jumpers no)
		(fp_line
			(start 0.508 -0.9398)
			(end 0.508 0.9398)
			(stroke
				(width 0.1524)
				(type default)
			)
			(layer "B.SilkS")
		)
		(fp_line
			(start -0.508 -0.9398)
			(end 0.508 -0.9398)
			(stroke
				(width 0.1524)
				(type default)
			)
			(layer "B.SilkS")
		)
		(fp_rect
			(start 0.508 0.9398)
			(end -0.508 -0.9398)
			(stroke
				(width 0)
				(type default)
			)
			(fill no)
			(layer "B.CrtYd")
		)
		(fp_rect
			(start 0.508 0.9398)
			(end -0.508 -0.9398)
			(stroke
				(width 0)
				(type default)
			)
			(fill no)
			(layer "B.Fab")
		)
		(pad "1" smd custom
			(at 0 -0.4445)
			(size 0.1397 0.1397)
			(layers "B.Cu" "B.Mask" "B.Paste")
			(net "SSD_PERST#6")
			(options
				(clearance outline)
				(anchor circle)
			)
			(primitives
				(gr_poly
					(pts
						(arc
							(start -0.1778 0.2794)
							(mid -0.249642 0.249642)
							(end -0.2794 0.1778)
						)
						(arc
							(start -0.2794 -0.1778)
							(mid -0.249642 -0.249642)
							(end -0.1778 -0.2794)
						)
						(arc
							(start 0.1778 -0.2794)
							(mid 0.249642 -0.249642)
							(end 0.2794 -0.1778)
						)
						(arc
							(start 0.2794 0.1778)
							(mid 0.249642 0.249642)
							(end 0.1778 0.2794)
						)
					)
					(width 0)
					(fill yes)
				)
			)
		)
		(pad "2" smd custom
			(at 0 0.4445)
			(size 0.1397 0.1397)
			(layers "B.Cu" "B.Mask" "B.Paste")
			(net "P3V3_STBY")
			(options
				(clearance outline)
				(anchor circle)
			)
			(primitives
				(gr_poly
					(pts
						(arc
							(start -0.1778 0.2794)
							(mid -0.249642 0.249642)
							(end -0.2794 0.1778)
						)
						(arc
							(start -0.2794 -0.1778)
							(mid -0.249642 -0.249642)
							(end -0.1778 -0.2794)
						)
						(arc
							(start 0.1778 -0.2794)
							(mid 0.249642 -0.249642)
							(end 0.2794 -0.1778)
						)
						(arc
							(start 0.2794 0.1778)
							(mid 0.249642 0.249642)
							(end 0.1778 0.2794)
						)
					)
					(width 0)
					(fill yes)
				)
			)
		)
	)
	(footprint ""
		(layer "B.Cu")
		(at 330.740512 -172.432218 180)
		(property "Reference" "R577"
			(at 0 0 0)
			(layer "B.SilkS")
			(hide yes)
			(effects
				(font
					(size 1.27 1.27)
				)
				(justify mirror)
			)
		)
		(property "Value" "10KR2F-2-GP"
			(at -0.064008 -3.993896 180)
			(unlocked yes)
			(layer "B.Fab")
			(hide yes)
			(effects
				(font
					(size 1.016 1.016)
					(thickness 0.1524)
				)
				(justify mirror)
			)
		)
		(property "Device Type" "R402H16"
			(at -0.064008 -5.517896 180)
			(unlocked yes)
			(layer "B.Fab")
			(hide yes)
			(effects
				(font
					(size 1.016 1.016)
					(thickness 0.1524)
				)
				(justify mirror)
			)
		)
		(duplicate_pad_numbers_are_jumpers no)
		(fp_line
			(start 0.508 -0.9398)
			(end 0.508 0.9398)
			(stroke
				(width 0.1524)
				(type default)
			)
			(layer "B.SilkS")
		)
		(fp_line
			(start -0.508 -0.9398)
			(end 0.508 -0.9398)
			(stroke
				(width 0.1524)
				(type default)
			)
			(layer "B.SilkS")
		)
		(fp_rect
			(start 0.508 0.9398)
			(end -0.508 -0.9398)
			(stroke
				(width 0)
				(type default)
			)
			(fill no)
			(layer "B.CrtYd")
		)
		(fp_rect
			(start 0.508 0.9398)
			(end -0.508 -0.9398)
			(stroke
				(width 0)
				(type default)
			)
			(fill no)
			(layer "B.Fab")
		)
		(pad "1" smd custom
			(at 0 -0.4445)
			(size 0.1397 0.1397)
			(layers "B.Cu" "B.Mask" "B.Paste")
			(net "P3V3_STBY")
			(options
				(clearance outline)
				(anchor circle)
			)
			(primitives
				(gr_poly
					(pts
						(arc
							(start -0.1778 0.2794)
							(mid -0.249642 0.249642)
							(end -0.2794 0.1778)
						)
						(arc
							(start -0.2794 -0.1778)
							(mid -0.249642 -0.249642)
							(end -0.1778 -0.2794)
						)
						(arc
							(start 0.1778 -0.2794)
							(mid 0.249642 -0.249642)
							(end 0.2794 -0.1778)
						)
						(arc
							(start 0.2794 0.1778)
							(mid 0.249642 0.249642)
							(end 0.1778 0.2794)
						)
					)
					(width 0)
					(fill yes)
				)
			)
		)
		(pad "2" smd custom
			(at 0 0.4445)
			(size 0.1397 0.1397)
			(layers "B.Cu" "B.Mask" "B.Paste")
			(net "IOEXP4_AD1")
			(options
				(clearance outline)
				(anchor circle)
			)
			(primitives
				(gr_poly
					(pts
						(arc
							(start -0.1778 0.2794)
							(mid -0.249642 0.249642)
							(end -0.2794 0.1778)
						)
						(arc
							(start -0.2794 -0.1778)
							(mid -0.249642 -0.249642)
							(end -0.1778 -0.2794)
						)
						(arc
							(start 0.1778 -0.2794)
							(mid 0.249642 -0.249642)
							(end 0.2794 -0.1778)
						)
						(arc
							(start 0.2794 0.1778)
							(mid 0.249642 0.249642)
							(end 0.1778 0.2794)
						)
					)
					(width 0)
					(fill yes)
				)
			)
		)
	)
	(footprint ""
		(layer "B.Cu")
		(at 243.1288 -51.9938 90)
		(property "Reference" "C444"
			(at 0 0 90)
			(layer "B.SilkS")
			(hide yes)
			(effects
				(font
					(size 1.27 1.27)
				)
				(justify mirror)
			)
		)
		(property "Value" "SCD1U16V1KX-1-GP"
			(at 2.8321 -1.7399 90)
			(unlocked yes)
			(layer "B.Fab")
			(hide yes)
			(effects
				(font
					(size 1.016 1.016)
					(thickness 0.1524)
				)
				(justify mirror)
			)
		)
		(property "Device Type" "C0201H13"
			(at 2.8321 -3.2639 90)
			(unlocked yes)
			(layer "B.Fab")
			(hide yes)
			(effects
				(font
					(size 1.016 1.016)
					(thickness 0.1524)
				)
				(justify mirror)
			)
		)
		(duplicate_pad_numbers_are_jumpers no)
		(fp_rect
			(start 0.2794 0.6477)
			(end -0.2794 -0.6477)
			(stroke
				(width 0)
				(type default)
			)
			(fill no)
			(layer "B.CrtYd")
		)
		(fp_rect
			(start 0.2794 0.6477)
			(end -0.2794 -0.6477)
			(stroke
				(width 0)
				(type default)
			)
			(fill no)
			(layer "B.Fab")
		)
		(pad "1" smd custom
			(at 0 -0.2794 270)
			(size 0.0762 0.0762)
			(layers "B.Cu" "B.Mask" "B.Paste")
			(net "DUT_VDD")
			(options
				(clearance outline)
				(anchor circle)
			)
			(primitives
				(gr_poly
					(pts
						(arc
							(start 0.1524 0.127)
							(mid 0.137521 0.162921)
							(end 0.1016 0.1778)
						)
						(arc
							(start -0.1016 0.1778)
							(mid -0.137521 0.162921)
							(end -0.1524 0.127)
						)
						(arc
							(start -0.1524 -0.127)
							(mid -0.137521 -0.162921)
							(end -0.1016 -0.1778)
						)
						(arc
							(start 0.1016 -0.1778)
							(mid 0.137521 -0.162921)
							(end 0.1524 -0.127)
						)
					)
					(width 0)
					(fill yes)
				)
			)
		)
		(pad "2" smd custom
			(at 0 0.2794 270)
			(size 0.0762 0.0762)
			(layers "B.Cu" "B.Mask" "B.Paste")
			(net "GND")
			(options
				(clearance outline)
				(anchor circle)
			)
			(primitives
				(gr_poly
					(pts
						(arc
							(start 0.1524 0.127)
							(mid 0.137521 0.162921)
							(end 0.1016 0.1778)
						)
						(arc
							(start -0.1016 0.1778)
							(mid -0.137521 0.162921)
							(end -0.1524 0.127)
						)
						(arc
							(start -0.1524 -0.127)
							(mid -0.137521 -0.162921)
							(end -0.1016 -0.1778)
						)
						(arc
							(start 0.1016 -0.1778)
							(mid 0.137521 -0.162921)
							(end 0.1524 -0.127)
						)
					)
					(width 0)
					(fill yes)
				)
			)
		)
	)
	(footprint ""
		(layer "B.Cu")
		(at 233.6038 -40.005)
		(property "Reference" "TP200"
			(at 0 0 0)
			(layer "B.SilkS")
			(hide yes)
			(effects
				(font
					(size 1.27 1.27)
				)
				(justify mirror)
			)
		)
		(property "Value" "TPAD28-2-GP"
			(at 0.0127 -1.6637 0)
			(unlocked yes)
			(layer "B.Fab")
			(hide yes)
			(effects
				(font
					(size 1.016 1.016)
					(thickness 0.1524)
				)
				(justify mirror)
			)
		)
		(property "Device Type" "TPAD28"
			(at 0.0127 -3.1877 0)
			(unlocked yes)
			(layer "B.Fab")
			(hide yes)
			(effects
				(font
					(size 1.016 1.016)
					(thickness 0.1524)
				)
				(justify mirror)
			)
		)
		(duplicate_pad_numbers_are_jumpers no)
		(fp_poly
			(pts
				(arc
					(start 0.3556 0)
					(mid -0.3556 0)
					(end 0.3556 0)
				)
			)
			(stroke
				(width 0)
				(type default)
			)
			(fill no)
			(layer "B.CrtYd")
		)
		(fp_poly
			(pts
				(arc
					(start 0.6096 0)
					(mid -0.6096 0)
					(end 0.6096 0)
				)
			)
			(stroke
				(width 0)
				(type default)
			)
			(fill no)
			(layer "B.Fab")
		)
		(pad "1" smd circle
			(at 0 0 180)
			(size 0.7112 0.7112)
			(layers "B.Cu" "B.Mask" "B.Paste")
			(net "RMII_TX_EN")
		)
	)
	(footprint ""
		(layer "B.Cu")
		(at 61.341 -123.444 -90)
		(property "Reference" "R579"
			(at 0 0 90)
			(layer "B.SilkS")
			(hide yes)
			(effects
				(font
					(size 1.27 1.27)
				)
				(justify mirror)
			)
		)
		(property "Value" "4K7R2F-GP"
			(at -0.064008 -3.993896 270)
			(unlocked yes)
			(layer "B.Fab")
			(hide yes)
			(effects
				(font
					(size 1.016 1.016)
					(thickness 0.1524)
				)
				(justify mirror)
			)
		)
		(property "Device Type" "R402H16"
			(at -0.064008 -5.517896 270)
			(unlocked yes)
			(layer "B.Fab")
			(hide yes)
			(effects
				(font
					(size 1.016 1.016)
					(thickness 0.1524)
				)
				(justify mirror)
			)
		)
		(duplicate_pad_numbers_are_jumpers no)
		(fp_line
			(start -0.508 -0.9398)
			(end 0.508 -0.9398)
			(stroke
				(width 0.1524)
				(type default)
			)
			(layer "B.SilkS")
		)
		(fp_line
			(start 0.508 -0.9398)
			(end 0.508 0.9398)
			(stroke
				(width 0.1524)
				(type default)
			)
			(layer "B.SilkS")
		)
		(fp_rect
			(start 0.508 0.9398)
			(end -0.508 -0.9398)
			(stroke
				(width 0)
				(type default)
			)
			(fill no)
			(layer "B.CrtYd")
		)
		(fp_rect
			(start 0.508 0.9398)
			(end -0.508 -0.9398)
			(stroke
				(width 0)
				(type default)
			)
			(fill no)
			(layer "B.Fab")
		)
		(pad "1" smd custom
			(at 0 -0.4445 90)
			(size 0.1397 0.1397)
			(layers "B.Cu" "B.Mask" "B.Paste")
			(net "BMC_I2C6_C_FCB_SCL")
			(options
				(clearance outline)
				(anchor circle)
			)
			(primitives
				(gr_poly
					(pts
						(arc
							(start -0.1778 0.2794)
							(mid -0.249642 0.249642)
							(end -0.2794 0.1778)
						)
						(arc
							(start -0.2794 -0.1778)
							(mid -0.249642 -0.249642)
							(end -0.1778 -0.2794)
						)
						(arc
							(start 0.1778 -0.2794)
							(mid 0.249642 -0.249642)
							(end 0.2794 -0.1778)
						)
						(arc
							(start 0.2794 0.1778)
							(mid 0.249642 0.249642)
							(end 0.1778 0.2794)
						)
					)
					(width 0)
					(fill yes)
				)
			)
		)
		(pad "2" smd custom
			(at 0 0.4445 90)
			(size 0.1397 0.1397)
			(layers "B.Cu" "B.Mask" "B.Paste")
			(net "P3V3_STBY")
			(options
				(clearance outline)
				(anchor circle)
			)
			(primitives
				(gr_poly
					(pts
						(arc
							(start -0.1778 0.2794)
							(mid -0.249642 0.249642)
							(end -0.2794 0.1778)
						)
						(arc
							(start -0.2794 -0.1778)
							(mid -0.249642 -0.249642)
							(end -0.1778 -0.2794)
						)
						(arc
							(start 0.1778 -0.2794)
							(mid 0.249642 -0.249642)
							(end 0.2794 -0.1778)
						)
						(arc
							(start 0.2794 0.1778)
							(mid 0.249642 0.249642)
							(end 0.1778 0.2794)
						)
					)
					(width 0)
					(fill yes)
				)
			)
		)
	)
	(footprint ""
		(layer "B.Cu")
		(at 243.1288 -54.0004 90)
		(property "Reference" "C440"
			(at 0 0 90)
			(layer "B.SilkS")
			(hide yes)
			(effects
				(font
					(size 1.27 1.27)
				)
				(justify mirror)
			)
		)
		(property "Value" "SCD1U16V1KX-1-GP"
			(at 2.8321 -1.7399 90)
			(unlocked yes)
			(layer "B.Fab")
			(hide yes)
			(effects
				(font
					(size 1.016 1.016)
					(thickness 0.1524)
				)
				(justify mirror)
			)
		)
		(property "Device Type" "C0201H13"
			(at 2.8321 -3.2639 90)
			(unlocked yes)
			(layer "B.Fab")
			(hide yes)
			(effects
				(font
					(size 1.016 1.016)
					(thickness 0.1524)
				)
				(justify mirror)
			)
		)
		(duplicate_pad_numbers_are_jumpers no)
		(fp_rect
			(start 0.2794 0.6477)
			(end -0.2794 -0.6477)
			(stroke
				(width 0)
				(type default)
			)
			(fill no)
			(layer "B.CrtYd")
		)
		(fp_rect
			(start 0.2794 0.6477)
			(end -0.2794 -0.6477)
			(stroke
				(width 0)
				(type default)
			)
			(fill no)
			(layer "B.Fab")
		)
		(pad "1" smd custom
			(at 0 -0.2794 270)
			(size 0.0762 0.0762)
			(layers "B.Cu" "B.Mask" "B.Paste")
			(net "DUT_VDD")
			(options
				(clearance outline)
				(anchor circle)
			)
			(primitives
				(gr_poly
					(pts
						(arc
							(start 0.1524 0.127)
							(mid 0.137521 0.162921)
							(end 0.1016 0.1778)
						)
						(arc
							(start -0.1016 0.1778)
							(mid -0.137521 0.162921)
							(end -0.1524 0.127)
						)
						(arc
							(start -0.1524 -0.127)
							(mid -0.137521 -0.162921)
							(end -0.1016 -0.1778)
						)
						(arc
							(start 0.1016 -0.1778)
							(mid 0.137521 -0.162921)
							(end 0.1524 -0.127)
						)
					)
					(width 0)
					(fill yes)
				)
			)
		)
		(pad "2" smd custom
			(at 0 0.2794 270)
			(size 0.0762 0.0762)
			(layers "B.Cu" "B.Mask" "B.Paste")
			(net "GND")
			(options
				(clearance outline)
				(anchor circle)
			)
			(primitives
				(gr_poly
					(pts
						(arc
							(start 0.1524 0.127)
							(mid 0.137521 0.162921)
							(end 0.1016 0.1778)
						)
						(arc
							(start -0.1016 0.1778)
							(mid -0.137521 0.162921)
							(end -0.1524 0.127)
						)
						(arc
							(start -0.1524 -0.127)
							(mid -0.137521 -0.162921)
							(end -0.1016 -0.1778)
						)
						(arc
							(start 0.1016 -0.1778)
							(mid 0.137521 -0.162921)
							(end 0.1524 -0.127)
						)
					)
					(width 0)
					(fill yes)
				)
			)
		)
	)
	(footprint ""
		(layer "B.Cu")
		(at 238.5822 -35.9918 90)
		(property "Reference" "C466"
			(at 0 0 90)
			(layer "B.SilkS")
			(hide yes)
			(effects
				(font
					(size 1.27 1.27)
				)
				(justify mirror)
			)
		)
		(property "Value" "SCD1U16V1KX-1-GP"
			(at 2.8321 -1.7399 90)
			(unlocked yes)
			(layer "B.Fab")
			(hide yes)
			(effects
				(font
					(size 1.016 1.016)
					(thickness 0.1524)
				)
				(justify mirror)
			)
		)
		(property "Device Type" "C0201H13"
			(at 2.8321 -3.2639 90)
			(unlocked yes)
			(layer "B.Fab")
			(hide yes)
			(effects
				(font
					(size 1.016 1.016)
					(thickness 0.1524)
				)
				(justify mirror)
			)
		)
		(duplicate_pad_numbers_are_jumpers no)
		(fp_rect
			(start 0.2794 0.6477)
			(end -0.2794 -0.6477)
			(stroke
				(width 0)
				(type default)
			)
			(fill no)
			(layer "B.CrtYd")
		)
		(fp_rect
			(start 0.2794 0.6477)
			(end -0.2794 -0.6477)
			(stroke
				(width 0)
				(type default)
			)
			(fill no)
			(layer "B.Fab")
		)
		(pad "1" smd custom
			(at 0 -0.2794 270)
			(size 0.0762 0.0762)
			(layers "B.Cu" "B.Mask" "B.Paste")
			(net "DUT_VDDO_REF")
			(options
				(clearance outline)
				(anchor circle)
			)
			(primitives
				(gr_poly
					(pts
						(arc
							(start 0.1524 0.127)
							(mid 0.137521 0.162921)
							(end 0.1016 0.1778)
						)
						(arc
							(start -0.1016 0.1778)
							(mid -0.137521 0.162921)
							(end -0.1524 0.127)
						)
						(arc
							(start -0.1524 -0.127)
							(mid -0.137521 -0.162921)
							(end -0.1016 -0.1778)
						)
						(arc
							(start 0.1016 -0.1778)
							(mid 0.137521 -0.162921)
							(end 0.1524 -0.127)
						)
					)
					(width 0)
					(fill yes)
				)
			)
		)
		(pad "2" smd custom
			(at 0 0.2794 270)
			(size 0.0762 0.0762)
			(layers "B.Cu" "B.Mask" "B.Paste")
			(net "GND")
			(options
				(clearance outline)
				(anchor circle)
			)
			(primitives
				(gr_poly
					(pts
						(arc
							(start 0.1524 0.127)
							(mid 0.137521 0.162921)
							(end 0.1016 0.1778)
						)
						(arc
							(start -0.1016 0.1778)
							(mid -0.137521 0.162921)
							(end -0.1524 0.127)
						)
						(arc
							(start -0.1524 -0.127)
							(mid -0.137521 -0.162921)
							(end -0.1016 -0.1778)
						)
						(arc
							(start 0.1016 -0.1778)
							(mid 0.137521 -0.162921)
							(end 0.1524 -0.127)
						)
					)
					(width 0)
					(fill yes)
				)
			)
		)
	)
	(footprint ""
		(layer "B.Cu")
		(at 243.1288 -41.995852 -90)
		(property "Reference" "C438"
			(at 0 0 90)
			(layer "B.SilkS")
			(hide yes)
			(effects
				(font
					(size 1.27 1.27)
				)
				(justify mirror)
			)
		)
		(property "Value" "SCD1U16V1KX-1-GP"
			(at 2.8321 -1.7399 270)
			(unlocked yes)
			(layer "B.Fab")
			(hide yes)
			(effects
				(font
					(size 1.016 1.016)
					(thickness 0.1524)
				)
				(justify mirror)
			)
		)
		(property "Device Type" "C0201H13"
			(at 2.8321 -3.2639 270)
			(unlocked yes)
			(layer "B.Fab")
			(hide yes)
			(effects
				(font
					(size 1.016 1.016)
					(thickness 0.1524)
				)
				(justify mirror)
			)
		)
		(duplicate_pad_numbers_are_jumpers no)
		(fp_rect
			(start 0.2794 0.6477)
			(end -0.2794 -0.6477)
			(stroke
				(width 0)
				(type default)
			)
			(fill no)
			(layer "B.CrtYd")
		)
		(fp_rect
			(start 0.2794 0.6477)
			(end -0.2794 -0.6477)
			(stroke
				(width 0)
				(type default)
			)
			(fill no)
			(layer "B.Fab")
		)
		(pad "1" smd custom
			(at 0 -0.2794 90)
			(size 0.0762 0.0762)
			(layers "B.Cu" "B.Mask" "B.Paste")
			(net "DUT_VDD")
			(options
				(clearance outline)
				(anchor circle)
			)
			(primitives
				(gr_poly
					(pts
						(arc
							(start 0.1524 0.127)
							(mid 0.137521 0.162921)
							(end 0.1016 0.1778)
						)
						(arc
							(start -0.1016 0.1778)
							(mid -0.137521 0.162921)
							(end -0.1524 0.127)
						)
						(arc
							(start -0.1524 -0.127)
							(mid -0.137521 -0.162921)
							(end -0.1016 -0.1778)
						)
						(arc
							(start 0.1016 -0.1778)
							(mid 0.137521 -0.162921)
							(end 0.1524 -0.127)
						)
					)
					(width 0)
					(fill yes)
				)
			)
		)
		(pad "2" smd custom
			(at 0 0.2794 90)
			(size 0.0762 0.0762)
			(layers "B.Cu" "B.Mask" "B.Paste")
			(net "GND")
			(options
				(clearance outline)
				(anchor circle)
			)
			(primitives
				(gr_poly
					(pts
						(arc
							(start 0.1524 0.127)
							(mid 0.137521 0.162921)
							(end 0.1016 0.1778)
						)
						(arc
							(start -0.1016 0.1778)
							(mid -0.137521 0.162921)
							(end -0.1524 0.127)
						)
						(arc
							(start -0.1524 -0.127)
							(mid -0.137521 -0.162921)
							(end -0.1016 -0.1778)
						)
						(arc
							(start 0.1016 -0.1778)
							(mid 0.137521 -0.162921)
							(end 0.1524 -0.127)
						)
					)
					(width 0)
					(fill yes)
				)
			)
		)
	)
	(footprint ""
		(layer "B.Cu")
		(at 252.603 -56.989472 -90)
		(property "Reference" "C607"
			(at 0 0 90)
			(layer "B.SilkS")
			(hide yes)
			(effects
				(font
					(size 1.27 1.27)
				)
				(justify mirror)
			)
		)
		(property "Value" "SCD1U16V1KX-1-GP"
			(at 2.8321 -1.7399 270)
			(unlocked yes)
			(layer "B.Fab")
			(hide yes)
			(effects
				(font
					(size 1.016 1.016)
					(thickness 0.1524)
				)
				(justify mirror)
			)
		)
		(property "Device Type" "C0201H13"
			(at 2.8321 -3.2639 270)
			(unlocked yes)
			(layer "B.Fab")
			(hide yes)
			(effects
				(font
					(size 1.016 1.016)
					(thickness 0.1524)
				)
				(justify mirror)
			)
		)
		(duplicate_pad_numbers_are_jumpers no)
		(fp_rect
			(start 0.2794 0.6477)
			(end -0.2794 -0.6477)
			(stroke
				(width 0)
				(type default)
			)
			(fill no)
			(layer "B.CrtYd")
		)
		(fp_rect
			(start 0.2794 0.6477)
			(end -0.2794 -0.6477)
			(stroke
				(width 0)
				(type default)
			)
			(fill no)
			(layer "B.Fab")
		)
		(pad "1" smd custom
			(at 0 -0.2794 90)
			(size 0.0762 0.0762)
			(layers "B.Cu" "B.Mask" "B.Paste")
			(net "DUT_AVD_PCIE")
			(options
				(clearance outline)
				(anchor circle)
			)
			(primitives
				(gr_poly
					(pts
						(arc
							(start 0.1524 0.127)
							(mid 0.137521 0.162921)
							(end 0.1016 0.1778)
						)
						(arc
							(start -0.1016 0.1778)
							(mid -0.137521 0.162921)
							(end -0.1524 0.127)
						)
						(arc
							(start -0.1524 -0.127)
							(mid -0.137521 -0.162921)
							(end -0.1016 -0.1778)
						)
						(arc
							(start 0.1016 -0.1778)
							(mid 0.137521 -0.162921)
							(end 0.1524 -0.127)
						)
					)
					(width 0)
					(fill yes)
				)
			)
		)
		(pad "2" smd custom
			(at 0 0.2794 90)
			(size 0.0762 0.0762)
			(layers "B.Cu" "B.Mask" "B.Paste")
			(net "GND")
			(options
				(clearance outline)
				(anchor circle)
			)
			(primitives
				(gr_poly
					(pts
						(arc
							(start 0.1524 0.127)
							(mid 0.137521 0.162921)
							(end 0.1016 0.1778)
						)
						(arc
							(start -0.1016 0.1778)
							(mid -0.137521 0.162921)
							(end -0.1524 0.127)
						)
						(arc
							(start -0.1524 -0.127)
							(mid -0.137521 -0.162921)
							(end -0.1016 -0.1778)
						)
						(arc
							(start 0.1016 -0.1778)
							(mid 0.137521 -0.162921)
							(end 0.1524 -0.127)
						)
					)
					(width 0)
					(fill yes)
				)
			)
		)
	)
	(footprint ""
		(layer "B.Cu")
		(at 243.967 -25.4 90)
		(property "Reference" "TP190"
			(at 0 0 90)
			(layer "B.SilkS")
			(hide yes)
			(effects
				(font
					(size 1.27 1.27)
				)
				(justify mirror)
			)
		)
		(property "Value" "TPAD28-2-GP"
			(at 0.0127 -1.6637 90)
			(unlocked yes)
			(layer "B.Fab")
			(hide yes)
			(effects
				(font
					(size 1.016 1.016)
					(thickness 0.1524)
				)
				(justify mirror)
			)
		)
		(property "Device Type" "TPAD28"
			(at 0.0127 -3.1877 90)
			(unlocked yes)
			(layer "B.Fab")
			(hide yes)
			(effects
				(font
					(size 1.016 1.016)
					(thickness 0.1524)
				)
				(justify mirror)
			)
		)
		(duplicate_pad_numbers_are_jumpers no)
		(fp_poly
			(pts
				(arc
					(start 0 0.3556)
					(mid 0 -0.3556)
					(end 0 0.3556)
				)
			)
			(stroke
				(width 0)
				(type default)
			)
			(fill no)
			(layer "B.CrtYd")
		)
		(fp_poly
			(pts
				(arc
					(start 0 0.6096)
					(mid 0 -0.6096)
					(end 0 0.6096)
				)
			)
			(stroke
				(width 0)
				(type default)
			)
			(fill no)
			(layer "B.Fab")
		)
		(pad "1" smd circle
			(at 0 0 270)
			(size 0.7112 0.7112)
			(layers "B.Cu" "B.Mask" "B.Paste")
			(net "LBI_OE#")
		)
	)
	(footprint ""
		(layer "B.Cu")
		(at 247.599962 -33.999932)
		(property "Reference" "TP299"
			(at 0 0 0)
			(layer "B.SilkS")
			(hide yes)
			(effects
				(font
					(size 1.27 1.27)
				)
				(justify mirror)
			)
		)
		(property "Value" "TPAD28-2-GP"
			(at 0.0127 -1.6637 0)
			(unlocked yes)
			(layer "B.Fab")
			(hide yes)
			(effects
				(font
					(size 1.016 1.016)
					(thickness 0.1524)
				)
				(justify mirror)
			)
		)
		(property "Device Type" "TPAD28"
			(at 0.0127 -3.1877 0)
			(unlocked yes)
			(layer "B.Fab")
			(hide yes)
			(effects
				(font
					(size 1.016 1.016)
					(thickness 0.1524)
				)
				(justify mirror)
			)
		)
		(duplicate_pad_numbers_are_jumpers no)
		(fp_poly
			(pts
				(arc
					(start 0.3556 0)
					(mid -0.3556 0)
					(end 0.3556 0)
				)
			)
			(stroke
				(width 0)
				(type default)
			)
			(fill no)
			(layer "B.CrtYd")
		)
		(fp_poly
			(pts
				(arc
					(start 0.6096 0)
					(mid -0.6096 0)
					(end 0.6096 0)
				)
			)
			(stroke
				(width 0)
				(type default)
			)
			(fill no)
			(layer "B.Fab")
		)
		(pad "1" smd circle
			(at 0 0 180)
			(size 0.7112 0.7112)
			(layers "B.Cu" "B.Mask" "B.Paste")
			(net "TWI_SDA9")
		)
	)
	(footprint ""
		(layer "B.Cu")
		(at 269.150084 -18.3896 90)
		(property "Reference" "R2977"
			(at 0 0 90)
			(layer "B.SilkS")
			(hide yes)
			(effects
				(font
					(size 1.27 1.27)
				)
				(justify mirror)
			)
		)
		(property "Value" "0R2J-2-GP"
			(at -0.064008 -3.993896 90)
			(unlocked yes)
			(layer "B.Fab")
			(hide yes)
			(effects
				(font
					(size 1.016 1.016)
					(thickness 0.1524)
				)
				(justify mirror)
			)
		)
		(property "Device Type" "R402H16"
			(at -0.064008 -5.517896 90)
			(unlocked yes)
			(layer "B.Fab")
			(hide yes)
			(effects
				(font
					(size 1.016 1.016)
					(thickness 0.1524)
				)
				(justify mirror)
			)
		)
		(duplicate_pad_numbers_are_jumpers no)
		(fp_line
			(start 0.508 -0.9398)
			(end 0.508 0.9398)
			(stroke
				(width 0.1524)
				(type default)
			)
			(layer "B.SilkS")
		)
		(fp_line
			(start -0.508 -0.9398)
			(end 0.508 -0.9398)
			(stroke
				(width 0.1524)
				(type default)
			)
			(layer "B.SilkS")
		)
		(fp_rect
			(start 0.508 0.9398)
			(end -0.508 -0.9398)
			(stroke
				(width 0)
				(type default)
			)
			(fill no)
			(layer "B.CrtYd")
		)
		(fp_rect
			(start 0.508 0.9398)
			(end -0.508 -0.9398)
			(stroke
				(width 0)
				(type default)
			)
			(fill no)
			(layer "B.Fab")
		)
		(pad "1" smd custom
			(at 0 -0.4445 270)
			(size 0.1397 0.1397)
			(layers "B.Cu" "B.Mask" "B.Paste")
			(net "USB_P4_DN_BMC")
			(options
				(clearance outline)
				(anchor circle)
			)
			(primitives
				(gr_poly
					(pts
						(arc
							(start -0.1778 0.2794)
							(mid -0.249642 0.249642)
							(end -0.2794 0.1778)
						)
						(arc
							(start -0.2794 -0.1778)
							(mid -0.249642 -0.249642)
							(end -0.1778 -0.2794)
						)
						(arc
							(start 0.1778 -0.2794)
							(mid 0.249642 -0.249642)
							(end 0.2794 -0.1778)
						)
						(arc
							(start 0.2794 0.1778)
							(mid 0.249642 0.249642)
							(end 0.1778 0.2794)
						)
					)
					(width 0)
					(fill yes)
				)
			)
		)
		(pad "2" smd custom
			(at 0 0.4445 270)
			(size 0.1397 0.1397)
			(layers "B.Cu" "B.Mask" "B.Paste")
			(net "8644_USB_DN5")
			(options
				(clearance outline)
				(anchor circle)
			)
			(primitives
				(gr_poly
					(pts
						(arc
							(start -0.1778 0.2794)
							(mid -0.249642 0.249642)
							(end -0.2794 0.1778)
						)
						(arc
							(start -0.2794 -0.1778)
							(mid -0.249642 -0.249642)
							(end -0.1778 -0.2794)
						)
						(arc
							(start 0.1778 -0.2794)
							(mid 0.249642 -0.249642)
							(end 0.2794 -0.1778)
						)
						(arc
							(start 0.2794 0.1778)
							(mid 0.249642 0.249642)
							(end 0.1778 0.2794)
						)
					)
					(width 0)
					(fill yes)
				)
			)
		)
	)
	(footprint ""
		(layer "B.Cu")
		(at 237.617 -57.995058 -90)
		(property "Reference" "C524"
			(at 0 0 90)
			(layer "B.SilkS")
			(hide yes)
			(effects
				(font
					(size 1.27 1.27)
				)
				(justify mirror)
			)
		)
		(property "Value" "SCD1U16V1KX-1-GP"
			(at 2.8321 -1.7399 270)
			(unlocked yes)
			(layer "B.Fab")
			(hide yes)
			(effects
				(font
					(size 1.016 1.016)
					(thickness 0.1524)
				)
				(justify mirror)
			)
		)
		(property "Device Type" "C0201H13"
			(at 2.8321 -3.2639 270)
			(unlocked yes)
			(layer "B.Fab")
			(hide yes)
			(effects
				(font
					(size 1.016 1.016)
					(thickness 0.1524)
				)
				(justify mirror)
			)
		)
		(duplicate_pad_numbers_are_jumpers no)
		(fp_rect
			(start 0.2794 0.6477)
			(end -0.2794 -0.6477)
			(stroke
				(width 0)
				(type default)
			)
			(fill no)
			(layer "B.CrtYd")
		)
		(fp_rect
			(start 0.2794 0.6477)
			(end -0.2794 -0.6477)
			(stroke
				(width 0)
				(type default)
			)
			(fill no)
			(layer "B.Fab")
		)
		(pad "1" smd custom
			(at 0 -0.2794 90)
			(size 0.0762 0.0762)
			(layers "B.Cu" "B.Mask" "B.Paste")
			(net "DUT_AVD_TX")
			(options
				(clearance outline)
				(anchor circle)
			)
			(primitives
				(gr_poly
					(pts
						(arc
							(start 0.1524 0.127)
							(mid 0.137521 0.162921)
							(end 0.1016 0.1778)
						)
						(arc
							(start -0.1016 0.1778)
							(mid -0.137521 0.162921)
							(end -0.1524 0.127)
						)
						(arc
							(start -0.1524 -0.127)
							(mid -0.137521 -0.162921)
							(end -0.1016 -0.1778)
						)
						(arc
							(start 0.1016 -0.1778)
							(mid 0.137521 -0.162921)
							(end 0.1524 -0.127)
						)
					)
					(width 0)
					(fill yes)
				)
			)
		)
		(pad "2" smd custom
			(at 0 0.2794 90)
			(size 0.0762 0.0762)
			(layers "B.Cu" "B.Mask" "B.Paste")
			(net "GND")
			(options
				(clearance outline)
				(anchor circle)
			)
			(primitives
				(gr_poly
					(pts
						(arc
							(start 0.1524 0.127)
							(mid 0.137521 0.162921)
							(end 0.1016 0.1778)
						)
						(arc
							(start -0.1016 0.1778)
							(mid -0.137521 0.162921)
							(end -0.1524 0.127)
						)
						(arc
							(start -0.1524 -0.127)
							(mid -0.137521 -0.162921)
							(end -0.1016 -0.1778)
						)
						(arc
							(start 0.1016 -0.1778)
							(mid 0.137521 -0.162921)
							(end 0.1524 -0.127)
						)
					)
					(width 0)
					(fill yes)
				)
			)
		)
	)
	(footprint ""
		(layer "B.Cu")
		(at 35.306 -129.667 90)
		(property "Reference" "C213"
			(at 0 0 90)
			(layer "B.SilkS")
			(hide yes)
			(effects
				(font
					(size 1.27 1.27)
				)
				(justify mirror)
			)
		)
		(property "Value" "SC1U10V2KX-4-GP"
			(at -1.1811 -2.7051 90)
			(unlocked yes)
			(layer "B.Fab")
			(hide yes)
			(effects
				(font
					(size 1.016 1.016)
					(thickness 0.1524)
				)
				(justify mirror)
			)
		)
		(property "Device Type" "C402H22"
			(at -1.1811 -4.2291 90)
			(unlocked yes)
			(layer "B.Fab")
			(hide yes)
			(effects
				(font
					(size 1.016 1.016)
					(thickness 0.1524)
				)
				(justify mirror)
			)
		)
		(duplicate_pad_numbers_are_jumpers no)
		(fp_rect
			(start 0.4318 0.9525)
			(end -0.4318 -0.9525)
			(stroke
				(width 0)
				(type default)
			)
			(fill no)
			(layer "B.CrtYd")
		)
		(fp_rect
			(start 0.4318 0.9525)
			(end -0.4318 -0.9525)
			(stroke
				(width 0)
				(type default)
			)
			(fill no)
			(layer "B.Fab")
		)
		(pad "1" smd custom
			(at 0 -0.4445 270)
			(size 0.1524 0.1524)
			(layers "B.Cu" "B.Mask" "B.Paste")
			(net "P1V26_STBY")
			(options
				(clearance outline)
				(anchor circle)
			)
			(primitives
				(gr_poly
					(pts
						(arc
							(start 0.3048 0.2032)
							(mid 0.275042 0.275042)
							(end 0.2032 0.3048)
						)
						(arc
							(start -0.2032 0.3048)
							(mid -0.275042 0.275042)
							(end -0.3048 0.2032)
						)
						(arc
							(start -0.3048 -0.2032)
							(mid -0.275042 -0.275042)
							(end -0.2032 -0.3048)
						)
						(arc
							(start 0.2032 -0.3048)
							(mid 0.275042 -0.275042)
							(end 0.3048 -0.2032)
						)
					)
					(width 0)
					(fill yes)
				)
			)
		)
		(pad "2" smd custom
			(at 0 0.4445 270)
			(size 0.1524 0.1524)
			(layers "B.Cu" "B.Mask" "B.Paste")
			(net "GND")
			(options
				(clearance outline)
				(anchor circle)
			)
			(primitives
				(gr_poly
					(pts
						(arc
							(start 0.3048 0.2032)
							(mid 0.275042 0.275042)
							(end 0.2032 0.3048)
						)
						(arc
							(start -0.2032 0.3048)
							(mid -0.275042 0.275042)
							(end -0.3048 0.2032)
						)
						(arc
							(start -0.3048 -0.2032)
							(mid -0.275042 -0.275042)
							(end -0.2032 -0.3048)
						)
						(arc
							(start 0.2032 -0.3048)
							(mid 0.275042 -0.275042)
							(end 0.3048 -0.2032)
						)
					)
					(width 0)
					(fill yes)
				)
			)
		)
	)
	(footprint ""
		(layer "B.Cu")
		(at 150.783544 -33.545272 180)
		(property "Reference" "C228"
			(at 0 0 0)
			(layer "B.SilkS")
			(hide yes)
			(effects
				(font
					(size 1.27 1.27)
				)
				(justify mirror)
			)
		)
		(property "Value" "SCD1U10V2KX-5GP"
			(at -1.1811 -2.7051 180)
			(unlocked yes)
			(layer "B.Fab")
			(hide yes)
			(effects
				(font
					(size 1.016 1.016)
					(thickness 0.1524)
				)
				(justify mirror)
			)
		)
		(property "Device Type" "C402H22"
			(at -1.1811 -4.2291 180)
			(unlocked yes)
			(layer "B.Fab")
			(hide yes)
			(effects
				(font
					(size 1.016 1.016)
					(thickness 0.1524)
				)
				(justify mirror)
			)
		)
		(duplicate_pad_numbers_are_jumpers no)
		(fp_rect
			(start 0.4318 0.9525)
			(end -0.4318 -0.9525)
			(stroke
				(width 0)
				(type default)
			)
			(fill no)
			(layer "B.CrtYd")
		)
		(fp_rect
			(start 0.4318 0.9525)
			(end -0.4318 -0.9525)
			(stroke
				(width 0)
				(type default)
			)
			(fill no)
			(layer "B.Fab")
		)
		(pad "1" smd custom
			(at 0 -0.4445)
			(size 0.1524 0.1524)
			(layers "B.Cu" "B.Mask" "B.Paste")
			(net "GND")
			(options
				(clearance outline)
				(anchor circle)
			)
			(primitives
				(gr_poly
					(pts
						(arc
							(start 0.3048 0.2032)
							(mid 0.275042 0.275042)
							(end 0.2032 0.3048)
						)
						(arc
							(start -0.2032 0.3048)
							(mid -0.275042 0.275042)
							(end -0.3048 0.2032)
						)
						(arc
							(start -0.3048 -0.2032)
							(mid -0.275042 -0.275042)
							(end -0.2032 -0.3048)
						)
						(arc
							(start 0.2032 -0.3048)
							(mid 0.275042 -0.275042)
							(end 0.3048 -0.2032)
						)
					)
					(width 0)
					(fill yes)
				)
			)
		)
		(pad "2" smd custom
			(at 0 0.4445)
			(size 0.1524 0.1524)
			(layers "B.Cu" "B.Mask" "B.Paste")
			(net "P3V3_STBY")
			(options
				(clearance outline)
				(anchor circle)
			)
			(primitives
				(gr_poly
					(pts
						(arc
							(start 0.3048 0.2032)
							(mid 0.275042 0.275042)
							(end 0.2032 0.3048)
						)
						(arc
							(start -0.2032 0.3048)
							(mid -0.275042 0.275042)
							(end -0.3048 0.2032)
						)
						(arc
							(start -0.3048 -0.2032)
							(mid -0.275042 -0.275042)
							(end -0.2032 -0.3048)
						)
						(arc
							(start 0.2032 -0.3048)
							(mid 0.275042 -0.275042)
							(end 0.3048 -0.2032)
						)
					)
					(width 0)
					(fill yes)
				)
			)
		)
	)
	(footprint ""
		(layer "B.Cu")
		(at 56.134 -136.271 180)
		(property "Reference" "R3100"
			(at 0 0 0)
			(layer "B.SilkS")
			(hide yes)
			(effects
				(font
					(size 1.27 1.27)
				)
				(justify mirror)
			)
		)
		(property "Value" "1KR2F-3-GP"
			(at -0.064008 -3.993896 180)
			(unlocked yes)
			(layer "B.Fab")
			(hide yes)
			(effects
				(font
					(size 1.016 1.016)
					(thickness 0.1524)
				)
				(justify mirror)
			)
		)
		(property "Device Type" "R402H16"
			(at -0.064008 -5.517896 180)
			(unlocked yes)
			(layer "B.Fab")
			(hide yes)
			(effects
				(font
					(size 1.016 1.016)
					(thickness 0.1524)
				)
				(justify mirror)
			)
		)
		(duplicate_pad_numbers_are_jumpers no)
		(fp_line
			(start 0.508 -0.9398)
			(end 0.508 0.9398)
			(stroke
				(width 0.1524)
				(type default)
			)
			(layer "B.SilkS")
		)
		(fp_line
			(start -0.508 -0.9398)
			(end 0.508 -0.9398)
			(stroke
				(width 0.1524)
				(type default)
			)
			(layer "B.SilkS")
		)
		(fp_rect
			(start 0.508 0.9398)
			(end -0.508 -0.9398)
			(stroke
				(width 0)
				(type default)
			)
			(fill no)
			(layer "B.CrtYd")
		)
		(fp_rect
			(start 0.508 0.9398)
			(end -0.508 -0.9398)
			(stroke
				(width 0)
				(type default)
			)
			(fill no)
			(layer "B.Fab")
		)
		(pad "1" smd custom
			(at 0 -0.4445)
			(size 0.1397 0.1397)
			(layers "B.Cu" "B.Mask" "B.Paste")
			(net "ADC_P0V9_E")
			(options
				(clearance outline)
				(anchor circle)
			)
			(primitives
				(gr_poly
					(pts
						(arc
							(start -0.1778 0.2794)
							(mid -0.249642 0.249642)
							(end -0.2794 0.1778)
						)
						(arc
							(start -0.2794 -0.1778)
							(mid -0.249642 -0.249642)
							(end -0.1778 -0.2794)
						)
						(arc
							(start 0.1778 -0.2794)
							(mid 0.249642 -0.249642)
							(end 0.2794 -0.1778)
						)
						(arc
							(start 0.2794 0.1778)
							(mid 0.249642 0.249642)
							(end 0.1778 0.2794)
						)
					)
					(width 0)
					(fill yes)
				)
			)
		)
		(pad "2" smd custom
			(at 0 0.4445)
			(size 0.1397 0.1397)
			(layers "B.Cu" "B.Mask" "B.Paste")
			(net "GND")
			(options
				(clearance outline)
				(anchor circle)
			)
			(primitives
				(gr_poly
					(pts
						(arc
							(start -0.1778 0.2794)
							(mid -0.249642 0.249642)
							(end -0.2794 0.1778)
						)
						(arc
							(start -0.2794 -0.1778)
							(mid -0.249642 -0.249642)
							(end -0.1778 -0.2794)
						)
						(arc
							(start 0.1778 -0.2794)
							(mid 0.249642 -0.249642)
							(end 0.2794 -0.1778)
						)
						(arc
							(start 0.2794 0.1778)
							(mid 0.249642 0.249642)
							(end 0.1778 0.2794)
						)
					)
					(width 0)
					(fill yes)
				)
			)
		)
	)
	(footprint ""
		(layer "B.Cu")
		(at 222.541592 -194.284092 -90)
		(property "Reference" "C3203"
			(at 0 0 90)
			(layer "B.SilkS")
			(hide yes)
			(effects
				(font
					(size 1.27 1.27)
				)
				(justify mirror)
			)
		)
		(property "Value" "SCD1U25V2KX-2-GP"
			(at -1.1811 -2.7051 270)
			(unlocked yes)
			(layer "B.Fab")
			(hide yes)
			(effects
				(font
					(size 1.016 1.016)
					(thickness 0.1524)
				)
				(justify mirror)
			)
		)
		(property "Device Type" "C402H22"
			(at -1.1811 -4.2291 270)
			(unlocked yes)
			(layer "B.Fab")
			(hide yes)
			(effects
				(font
					(size 1.016 1.016)
					(thickness 0.1524)
				)
				(justify mirror)
			)
		)
		(duplicate_pad_numbers_are_jumpers no)
		(fp_rect
			(start 0.4318 0.9525)
			(end -0.4318 -0.9525)
			(stroke
				(width 0)
				(type default)
			)
			(fill no)
			(layer "B.CrtYd")
		)
		(fp_rect
			(start 0.4318 0.9525)
			(end -0.4318 -0.9525)
			(stroke
				(width 0)
				(type default)
			)
			(fill no)
			(layer "B.Fab")
		)
		(pad "1" smd custom
			(at 0 -0.4445 90)
			(size 0.1524 0.1524)
			(layers "B.Cu" "B.Mask" "B.Paste")
			(net "P3V3_STBY")
			(options
				(clearance outline)
				(anchor circle)
			)
			(primitives
				(gr_poly
					(pts
						(arc
							(start 0.3048 0.2032)
							(mid 0.275042 0.275042)
							(end 0.2032 0.3048)
						)
						(arc
							(start -0.2032 0.3048)
							(mid -0.275042 0.275042)
							(end -0.3048 0.2032)
						)
						(arc
							(start -0.3048 -0.2032)
							(mid -0.275042 -0.275042)
							(end -0.2032 -0.3048)
						)
						(arc
							(start 0.2032 -0.3048)
							(mid 0.275042 -0.275042)
							(end 0.3048 -0.2032)
						)
					)
					(width 0)
					(fill yes)
				)
			)
		)
		(pad "2" smd custom
			(at 0 0.4445 90)
			(size 0.1524 0.1524)
			(layers "B.Cu" "B.Mask" "B.Paste")
			(net "GND")
			(options
				(clearance outline)
				(anchor circle)
			)
			(primitives
				(gr_poly
					(pts
						(arc
							(start 0.3048 0.2032)
							(mid 0.275042 0.275042)
							(end 0.2032 0.3048)
						)
						(arc
							(start -0.2032 0.3048)
							(mid -0.275042 0.275042)
							(end -0.3048 0.2032)
						)
						(arc
							(start -0.3048 -0.2032)
							(mid -0.275042 -0.275042)
							(end -0.2032 -0.3048)
						)
						(arc
							(start 0.2032 -0.3048)
							(mid 0.275042 -0.275042)
							(end 0.3048 -0.2032)
						)
					)
					(width 0)
					(fill yes)
				)
			)
		)
	)
	(footprint ""
		(layer "B.Cu")
		(at 81.833212 -186.545474)
		(property "Reference" "C3211"
			(at 0 0 0)
			(layer "B.SilkS")
			(hide yes)
			(effects
				(font
					(size 1.27 1.27)
				)
				(justify mirror)
			)
		)
		(property "Value" "SCD1U25V2KX-2-GP"
			(at -1.1811 -2.7051 0)
			(unlocked yes)
			(layer "B.Fab")
			(hide yes)
			(effects
				(font
					(size 1.016 1.016)
					(thickness 0.1524)
				)
				(justify mirror)
			)
		)
		(property "Device Type" "C402H22"
			(at -1.1811 -4.2291 0)
			(unlocked yes)
			(layer "B.Fab")
			(hide yes)
			(effects
				(font
					(size 1.016 1.016)
					(thickness 0.1524)
				)
				(justify mirror)
			)
		)
		(duplicate_pad_numbers_are_jumpers no)
		(fp_rect
			(start 0.4318 0.9525)
			(end -0.4318 -0.9525)
			(stroke
				(width 0)
				(type default)
			)
			(fill no)
			(layer "B.CrtYd")
		)
		(fp_rect
			(start 0.4318 0.9525)
			(end -0.4318 -0.9525)
			(stroke
				(width 0)
				(type default)
			)
			(fill no)
			(layer "B.Fab")
		)
		(pad "1" smd custom
			(at 0 -0.4445 180)
			(size 0.1524 0.1524)
			(layers "B.Cu" "B.Mask" "B.Paste")
			(net "P3V3_STBY")
			(options
				(clearance outline)
				(anchor circle)
			)
			(primitives
				(gr_poly
					(pts
						(arc
							(start 0.3048 0.2032)
							(mid 0.275042 0.275042)
							(end 0.2032 0.3048)
						)
						(arc
							(start -0.2032 0.3048)
							(mid -0.275042 0.275042)
							(end -0.3048 0.2032)
						)
						(arc
							(start -0.3048 -0.2032)
							(mid -0.275042 -0.275042)
							(end -0.2032 -0.3048)
						)
						(arc
							(start 0.2032 -0.3048)
							(mid 0.275042 -0.275042)
							(end 0.3048 -0.2032)
						)
					)
					(width 0)
					(fill yes)
				)
			)
		)
		(pad "2" smd custom
			(at 0 0.4445 180)
			(size 0.1524 0.1524)
			(layers "B.Cu" "B.Mask" "B.Paste")
			(net "GND")
			(options
				(clearance outline)
				(anchor circle)
			)
			(primitives
				(gr_poly
					(pts
						(arc
							(start 0.3048 0.2032)
							(mid 0.275042 0.275042)
							(end 0.2032 0.3048)
						)
						(arc
							(start -0.2032 0.3048)
							(mid -0.275042 0.275042)
							(end -0.3048 0.2032)
						)
						(arc
							(start -0.3048 -0.2032)
							(mid -0.275042 -0.275042)
							(end -0.2032 -0.3048)
						)
						(arc
							(start 0.2032 -0.3048)
							(mid 0.275042 -0.275042)
							(end 0.3048 -0.2032)
						)
					)
					(width 0)
					(fill yes)
				)
			)
		)
	)
	(footprint ""
		(layer "B.Cu")
		(at 53.721 -136.779 90)
		(property "Reference" "R152"
			(at 0 0 90)
			(layer "B.SilkS")
			(hide yes)
			(effects
				(font
					(size 1.27 1.27)
				)
				(justify mirror)
			)
		)
		(property "Value" "4K7R2F-GP"
			(at -0.064008 -3.993896 90)
			(unlocked yes)
			(layer "B.Fab")
			(hide yes)
			(effects
				(font
					(size 1.016 1.016)
					(thickness 0.1524)
				)
				(justify mirror)
			)
		)
		(property "Device Type" "R402H16"
			(at -0.064008 -5.517896 90)
			(unlocked yes)
			(layer "B.Fab")
			(hide yes)
			(effects
				(font
					(size 1.016 1.016)
					(thickness 0.1524)
				)
				(justify mirror)
			)
		)
		(duplicate_pad_numbers_are_jumpers no)
		(fp_line
			(start 0.508 -0.9398)
			(end 0.508 0.9398)
			(stroke
				(width 0.1524)
				(type default)
			)
			(layer "B.SilkS")
		)
		(fp_line
			(start -0.508 -0.9398)
			(end 0.508 -0.9398)
			(stroke
				(width 0.1524)
				(type default)
			)
			(layer "B.SilkS")
		)
		(fp_rect
			(start 0.508 0.9398)
			(end -0.508 -0.9398)
			(stroke
				(width 0)
				(type default)
			)
			(fill no)
			(layer "B.CrtYd")
		)
		(fp_rect
			(start 0.508 0.9398)
			(end -0.508 -0.9398)
			(stroke
				(width 0)
				(type default)
			)
			(fill no)
			(layer "B.Fab")
		)
		(pad "1" smd custom
			(at 0 -0.4445 270)
			(size 0.1397 0.1397)
			(layers "B.Cu" "B.Mask" "B.Paste")
			(net "CBL_PRSNT_N_2")
			(options
				(clearance outline)
				(anchor circle)
			)
			(primitives
				(gr_poly
					(pts
						(arc
							(start -0.1778 0.2794)
							(mid -0.249642 0.249642)
							(end -0.2794 0.1778)
						)
						(arc
							(start -0.2794 -0.1778)
							(mid -0.249642 -0.249642)
							(end -0.1778 -0.2794)
						)
						(arc
							(start 0.1778 -0.2794)
							(mid 0.249642 -0.249642)
							(end 0.2794 -0.1778)
						)
						(arc
							(start 0.2794 0.1778)
							(mid 0.249642 0.249642)
							(end 0.1778 0.2794)
						)
					)
					(width 0)
					(fill yes)
				)
			)
		)
		(pad "2" smd custom
			(at 0 0.4445 270)
			(size 0.1397 0.1397)
			(layers "B.Cu" "B.Mask" "B.Paste")
			(net "P3V3_STBY")
			(options
				(clearance outline)
				(anchor circle)
			)
			(primitives
				(gr_poly
					(pts
						(arc
							(start -0.1778 0.2794)
							(mid -0.249642 0.249642)
							(end -0.2794 0.1778)
						)
						(arc
							(start -0.2794 -0.1778)
							(mid -0.249642 -0.249642)
							(end -0.1778 -0.2794)
						)
						(arc
							(start 0.1778 -0.2794)
							(mid 0.249642 -0.249642)
							(end 0.2794 -0.1778)
						)
						(arc
							(start 0.2794 0.1778)
							(mid 0.249642 0.249642)
							(end 0.1778 0.2794)
						)
					)
					(width 0)
					(fill yes)
				)
			)
		)
	)
	(footprint ""
		(layer "B.Cu")
		(at 128.524 -202.819)
		(property "Reference" "U65"
			(at 0 0 0)
			(layer "B.SilkS")
			(hide yes)
			(effects
				(font
					(size 1.27 1.27)
				)
				(justify mirror)
			)
		)
		(property "Value" "SN74LVC1G08DCKR-GP"
			(at 2.3368 -8.6868 0)
			(unlocked yes)
			(layer "B.Fab")
			(hide yes)
			(effects
				(font
					(size 1.016 1.016)
					(thickness 0.1524)
				)
				(justify mirror)
			)
		)
		(property "Device Type" "SC70-5H44"
			(at 2.3114 -10.414 0)
			(unlocked yes)
			(layer "B.Fab")
			(hide yes)
			(effects
				(font
					(size 1.016 1.016)
					(thickness 0.1524)
				)
				(justify mirror)
			)
		)
		(duplicate_pad_numbers_are_jumpers no)
		(fp_line
			(start -1.3843 -1.8034)
			(end -1.3843 -1.1176)
			(stroke
				(width 0.3302)
				(type default)
			)
			(layer "B.SilkS")
		)
		(fp_line
			(start -1.27 -1.7018)
			(end -1.27 1.7018)
			(stroke
				(width 0.1524)
				(type default)
			)
			(layer "B.SilkS")
		)
		(fp_line
			(start -1.27 1.7018)
			(end 1.27 1.7018)
			(stroke
				(width 0.1524)
				(type default)
			)
			(layer "B.SilkS")
		)
		(fp_line
			(start -0.6604 -1.8034)
			(end -1.3843 -1.8034)
			(stroke
				(width 0.3302)
				(type default)
			)
			(layer "B.SilkS")
		)
		(fp_line
			(start 1.27 -1.7018)
			(end -1.27 -1.7018)
			(stroke
				(width 0.1524)
				(type default)
			)
			(layer "B.SilkS")
		)
		(fp_line
			(start 1.27 1.7018)
			(end 1.27 -1.7018)
			(stroke
				(width 0.1524)
				(type default)
			)
			(layer "B.SilkS")
		)
		(fp_rect
			(start 1.524 1.9558)
			(end -1.524 -1.9558)
			(stroke
				(width 0)
				(type default)
			)
			(fill no)
			(layer "B.CrtYd")
		)
		(fp_poly
			(pts
				(xy 1.524 -1.9558) (xy -1.524 -1.9558) (xy -1.524 1.9558) (xy 1.524 1.9558)
			)
			(stroke
				(width 0)
				(type default)
			)
			(fill no)
			(layer "B.Fab")
		)
		(pad "1" smd rect
			(at -0.65024 -0.8255 180)
			(size 0.4064 1.2192)
			(layers "B.Cu" "B.Mask" "B.Paste")
			(net "BMC_SSD_RST#0_A1")
		)
		(pad "2" smd rect
			(at 0 -0.8255 180)
			(size 0.4064 1.2192)
			(layers "B.Cu" "B.Mask" "B.Paste")
			(net "SSD_PERST#0_B1")
		)
		(pad "3" smd rect
			(at 0.65024 -0.8255 180)
			(size 0.4064 1.2192)
			(layers "B.Cu" "B.Mask" "B.Paste")
			(net "GND")
		)
		(pad "4" smd rect
			(at 0.65024 0.8255 180)
			(size 0.4064 1.2192)
			(layers "B.Cu" "B.Mask" "B.Paste")
			(net "SSD_PERST_Y1")
		)
		(pad "5" smd rect
			(at -0.65024 0.8255 180)
			(size 0.4064 1.2192)
			(layers "B.Cu" "B.Mask" "B.Paste")
			(net "P3V3_STBY")
		)
	)
	(footprint ""
		(layer "B.Cu")
		(at 265.216894 -4.970272)
		(property "Reference" "R189"
			(at 0 0 0)
			(layer "B.SilkS")
			(hide yes)
			(effects
				(font
					(size 1.27 1.27)
				)
				(justify mirror)
			)
		)
		(property "Value" "4K7R2F-GP"
			(at -0.064008 -3.993896 0)
			(unlocked yes)
			(layer "B.Fab")
			(hide yes)
			(effects
				(font
					(size 1.016 1.016)
					(thickness 0.1524)
				)
				(justify mirror)
			)
		)
		(property "Device Type" "R402H16"
			(at -0.064008 -5.517896 0)
			(unlocked yes)
			(layer "B.Fab")
			(hide yes)
			(effects
				(font
					(size 1.016 1.016)
					(thickness 0.1524)
				)
				(justify mirror)
			)
		)
		(duplicate_pad_numbers_are_jumpers no)
		(fp_line
			(start -0.508 -0.9398)
			(end 0.508 -0.9398)
			(stroke
				(width 0.1524)
				(type default)
			)
			(layer "B.SilkS")
		)
		(fp_line
			(start 0.508 -0.9398)
			(end 0.508 0.9398)
			(stroke
				(width 0.1524)
				(type default)
			)
			(layer "B.SilkS")
		)
		(fp_rect
			(start 0.508 0.9398)
			(end -0.508 -0.9398)
			(stroke
				(width 0)
				(type default)
			)
			(fill no)
			(layer "B.CrtYd")
		)
		(fp_rect
			(start 0.508 0.9398)
			(end -0.508 -0.9398)
			(stroke
				(width 0)
				(type default)
			)
			(fill no)
			(layer "B.Fab")
		)
		(pad "1" smd custom
			(at 0 -0.4445 180)
			(size 0.1397 0.1397)
			(layers "B.Cu" "B.Mask" "B.Paste")
			(net "P3V3_STBY")
			(options
				(clearance outline)
				(anchor circle)
			)
			(primitives
				(gr_poly
					(pts
						(arc
							(start -0.1778 0.2794)
							(mid -0.249642 0.249642)
							(end -0.2794 0.1778)
						)
						(arc
							(start -0.2794 -0.1778)
							(mid -0.249642 -0.249642)
							(end -0.1778 -0.2794)
						)
						(arc
							(start 0.1778 -0.2794)
							(mid 0.249642 -0.249642)
							(end 0.2794 -0.1778)
						)
						(arc
							(start 0.2794 0.1778)
							(mid 0.249642 0.249642)
							(end 0.1778 0.2794)
						)
					)
					(width 0)
					(fill yes)
				)
			)
		)
		(pad "2" smd custom
			(at 0 0.4445 180)
			(size 0.1397 0.1397)
			(layers "B.Cu" "B.Mask" "B.Paste")
			(net "TEMP_1_A1")
			(options
				(clearance outline)
				(anchor circle)
			)
			(primitives
				(gr_poly
					(pts
						(arc
							(start -0.1778 0.2794)
							(mid -0.249642 0.249642)
							(end -0.2794 0.1778)
						)
						(arc
							(start -0.2794 -0.1778)
							(mid -0.249642 -0.249642)
							(end -0.1778 -0.2794)
						)
						(arc
							(start 0.1778 -0.2794)
							(mid 0.249642 -0.249642)
							(end 0.2794 -0.1778)
						)
						(arc
							(start 0.2794 0.1778)
							(mid 0.249642 0.249642)
							(end 0.1778 0.2794)
						)
					)
					(width 0)
					(fill yes)
				)
			)
		)
	)
	(footprint ""
		(layer "B.Cu")
		(at 235.331 -67.818 -90)
		(property "Reference" "C516"
			(at 0 0 90)
			(layer "B.SilkS")
			(hide yes)
			(effects
				(font
					(size 1.27 1.27)
				)
				(justify mirror)
			)
		)
		(property "Value" "SC4D7U16V5KX-1-GP"
			(at 0.0762 -6.1214 270)
			(unlocked yes)
			(layer "B.Fab")
			(hide yes)
			(effects
				(font
					(size 1.016 1.016)
					(thickness 0.1524)
				)
				(justify mirror)
			)
		)
		(property "Device Type" "C805H56"
			(at 0.0762 -8.1534 270)
			(unlocked yes)
			(layer "B.Fab")
			(hide yes)
			(effects
				(font
					(size 1.016 1.016)
					(thickness 0.1524)
				)
				(justify mirror)
			)
		)
		(duplicate_pad_numbers_are_jumpers no)
		(fp_line
			(start -0.635 0)
			(end 0.635 0)
			(stroke
				(width 0.508)
				(type default)
			)
			(layer "B.SilkS")
		)
		(fp_rect
			(start 0.9652 1.778)
			(end -0.9652 -1.778)
			(stroke
				(width 0)
				(type default)
			)
			(fill no)
			(layer "B.CrtYd")
		)
		(fp_poly
			(pts
				(xy 0.9652 -1.778) (xy -0.9652 -1.778) (xy -0.9652 1.778) (xy 0.9652 1.778)
			)
			(stroke
				(width 0)
				(type default)
			)
			(fill no)
			(layer "B.Fab")
		)
		(pad "1" smd rect
			(at 0 -0.9652 90)
			(size 1.397 1.143)
			(layers "B.Cu" "B.Mask" "B.Paste")
			(net "DUT_AVD_TX")
		)
		(pad "2" smd rect
			(at 0 0.9652 90)
			(size 1.397 1.143)
			(layers "B.Cu" "B.Mask" "B.Paste")
			(net "GND")
		)
	)
	(footprint ""
		(layer "B.Cu")
		(at 247.65 -44.9961 -90)
		(property "Reference" "C595"
			(at 0 0 90)
			(layer "B.SilkS")
			(hide yes)
			(effects
				(font
					(size 1.27 1.27)
				)
				(justify mirror)
			)
		)
		(property "Value" "SCD1U16V1KX-1-GP"
			(at 2.8321 -1.7399 270)
			(unlocked yes)
			(layer "B.Fab")
			(hide yes)
			(effects
				(font
					(size 1.016 1.016)
					(thickness 0.1524)
				)
				(justify mirror)
			)
		)
		(property "Device Type" "C0201H13"
			(at 2.8321 -3.2639 270)
			(unlocked yes)
			(layer "B.Fab")
			(hide yes)
			(effects
				(font
					(size 1.016 1.016)
					(thickness 0.1524)
				)
				(justify mirror)
			)
		)
		(duplicate_pad_numbers_are_jumpers no)
		(fp_rect
			(start 0.2794 0.6477)
			(end -0.2794 -0.6477)
			(stroke
				(width 0)
				(type default)
			)
			(fill no)
			(layer "B.CrtYd")
		)
		(fp_rect
			(start 0.2794 0.6477)
			(end -0.2794 -0.6477)
			(stroke
				(width 0)
				(type default)
			)
			(fill no)
			(layer "B.Fab")
		)
		(pad "1" smd custom
			(at 0 -0.2794 90)
			(size 0.0762 0.0762)
			(layers "B.Cu" "B.Mask" "B.Paste")
			(net "DUT_AVD_PCIE")
			(options
				(clearance outline)
				(anchor circle)
			)
			(primitives
				(gr_poly
					(pts
						(arc
							(start 0.1524 0.127)
							(mid 0.137521 0.162921)
							(end 0.1016 0.1778)
						)
						(arc
							(start -0.1016 0.1778)
							(mid -0.137521 0.162921)
							(end -0.1524 0.127)
						)
						(arc
							(start -0.1524 -0.127)
							(mid -0.137521 -0.162921)
							(end -0.1016 -0.1778)
						)
						(arc
							(start 0.1016 -0.1778)
							(mid 0.137521 -0.162921)
							(end 0.1524 -0.127)
						)
					)
					(width 0)
					(fill yes)
				)
			)
		)
		(pad "2" smd custom
			(at 0 0.2794 90)
			(size 0.0762 0.0762)
			(layers "B.Cu" "B.Mask" "B.Paste")
			(net "GND")
			(options
				(clearance outline)
				(anchor circle)
			)
			(primitives
				(gr_poly
					(pts
						(arc
							(start 0.1524 0.127)
							(mid 0.137521 0.162921)
							(end 0.1016 0.1778)
						)
						(arc
							(start -0.1016 0.1778)
							(mid -0.137521 0.162921)
							(end -0.1524 0.127)
						)
						(arc
							(start -0.1524 -0.127)
							(mid -0.137521 -0.162921)
							(end -0.1016 -0.1778)
						)
						(arc
							(start 0.1016 -0.1778)
							(mid 0.137521 -0.162921)
							(end 0.1524 -0.127)
						)
					)
					(width 0)
					(fill yes)
				)
			)
		)
	)
	(footprint ""
		(layer "B.Cu")
		(at 339.884512 -184.878218 180)
		(property "Reference" "R4150"
			(at 0 0 0)
			(layer "B.SilkS")
			(hide yes)
			(effects
				(font
					(size 1.27 1.27)
				)
				(justify mirror)
			)
		)
		(property "Value" "4K7R2F-GP"
			(at -0.064008 -3.993896 180)
			(unlocked yes)
			(layer "B.Fab")
			(hide yes)
			(effects
				(font
					(size 1.016 1.016)
					(thickness 0.1524)
				)
				(justify mirror)
			)
		)
		(property "Device Type" "R402H16"
			(at -0.064008 -5.517896 180)
			(unlocked yes)
			(layer "B.Fab")
			(hide yes)
			(effects
				(font
					(size 1.016 1.016)
					(thickness 0.1524)
				)
				(justify mirror)
			)
		)
		(duplicate_pad_numbers_are_jumpers no)
		(fp_line
			(start 0.508 -0.9398)
			(end 0.508 0.9398)
			(stroke
				(width 0.1524)
				(type default)
			)
			(layer "B.SilkS")
		)
		(fp_line
			(start -0.508 -0.9398)
			(end 0.508 -0.9398)
			(stroke
				(width 0.1524)
				(type default)
			)
			(layer "B.SilkS")
		)
		(fp_rect
			(start 0.508 0.9398)
			(end -0.508 -0.9398)
			(stroke
				(width 0)
				(type default)
			)
			(fill no)
			(layer "B.CrtYd")
		)
		(fp_rect
			(start 0.508 0.9398)
			(end -0.508 -0.9398)
			(stroke
				(width 0)
				(type default)
			)
			(fill no)
			(layer "B.Fab")
		)
		(pad "1" smd custom
			(at 0 -0.4445)
			(size 0.1397 0.1397)
			(layers "B.Cu" "B.Mask" "B.Paste")
			(net "SSD_PRSNT#14")
			(options
				(clearance outline)
				(anchor circle)
			)
			(primitives
				(gr_poly
					(pts
						(arc
							(start -0.1778 0.2794)
							(mid -0.249642 0.249642)
							(end -0.2794 0.1778)
						)
						(arc
							(start -0.2794 -0.1778)
							(mid -0.249642 -0.249642)
							(end -0.1778 -0.2794)
						)
						(arc
							(start 0.1778 -0.2794)
							(mid 0.249642 -0.249642)
							(end 0.2794 -0.1778)
						)
						(arc
							(start 0.2794 0.1778)
							(mid 0.249642 0.249642)
							(end 0.1778 0.2794)
						)
					)
					(width 0)
					(fill yes)
				)
			)
		)
		(pad "2" smd custom
			(at 0 0.4445)
			(size 0.1397 0.1397)
			(layers "B.Cu" "B.Mask" "B.Paste")
			(net "P3V3_STBY")
			(options
				(clearance outline)
				(anchor circle)
			)
			(primitives
				(gr_poly
					(pts
						(arc
							(start -0.1778 0.2794)
							(mid -0.249642 0.249642)
							(end -0.2794 0.1778)
						)
						(arc
							(start -0.2794 -0.1778)
							(mid -0.249642 -0.249642)
							(end -0.1778 -0.2794)
						)
						(arc
							(start 0.1778 -0.2794)
							(mid 0.249642 -0.249642)
							(end 0.2794 -0.1778)
						)
						(arc
							(start 0.2794 0.1778)
							(mid 0.249642 0.249642)
							(end 0.1778 0.2794)
						)
					)
					(width 0)
					(fill yes)
				)
			)
		)
	)
	(footprint ""
		(layer "B.Cu")
		(at 263.10082 -2.341626 180)
		(property "Reference" "R201"
			(at 0 0 0)
			(layer "B.SilkS")
			(hide yes)
			(effects
				(font
					(size 1.27 1.27)
				)
				(justify mirror)
			)
		)
		(property "Value" "49D9R2D-GP"
			(at -0.064008 -3.993896 180)
			(unlocked yes)
			(layer "B.Fab")
			(hide yes)
			(effects
				(font
					(size 1.016 1.016)
					(thickness 0.1524)
				)
				(justify mirror)
			)
		)
		(property "Device Type" "R402H16"
			(at -0.064008 -5.517896 180)
			(unlocked yes)
			(layer "B.Fab")
			(hide yes)
			(effects
				(font
					(size 1.016 1.016)
					(thickness 0.1524)
				)
				(justify mirror)
			)
		)
		(duplicate_pad_numbers_are_jumpers no)
		(fp_line
			(start 0.508 -0.9398)
			(end 0.508 0.9398)
			(stroke
				(width 0.1524)
				(type default)
			)
			(layer "B.SilkS")
		)
		(fp_line
			(start -0.508 -0.9398)
			(end 0.508 -0.9398)
			(stroke
				(width 0.1524)
				(type default)
			)
			(layer "B.SilkS")
		)
		(fp_rect
			(start 0.508 0.9398)
			(end -0.508 -0.9398)
			(stroke
				(width 0)
				(type default)
			)
			(fill no)
			(layer "B.CrtYd")
		)
		(fp_rect
			(start 0.508 0.9398)
			(end -0.508 -0.9398)
			(stroke
				(width 0)
				(type default)
			)
			(fill no)
			(layer "B.Fab")
		)
		(pad "1" smd custom
			(at 0 -0.4445)
			(size 0.1397 0.1397)
			(layers "B.Cu" "B.Mask" "B.Paste")
			(net "TEMP_SENSOR_DXP_R")
			(options
				(clearance outline)
				(anchor circle)
			)
			(primitives
				(gr_poly
					(pts
						(arc
							(start -0.1778 0.2794)
							(mid -0.249642 0.249642)
							(end -0.2794 0.1778)
						)
						(arc
							(start -0.2794 -0.1778)
							(mid -0.249642 -0.249642)
							(end -0.1778 -0.2794)
						)
						(arc
							(start 0.1778 -0.2794)
							(mid 0.249642 -0.249642)
							(end 0.2794 -0.1778)
						)
						(arc
							(start 0.2794 0.1778)
							(mid 0.249642 0.249642)
							(end 0.1778 0.2794)
						)
					)
					(width 0)
					(fill yes)
				)
			)
		)
		(pad "2" smd custom
			(at 0 0.4445)
			(size 0.1397 0.1397)
			(layers "B.Cu" "B.Mask" "B.Paste")
			(net "TEMP_SENSOR_DXP")
			(options
				(clearance outline)
				(anchor circle)
			)
			(primitives
				(gr_poly
					(pts
						(arc
							(start -0.1778 0.2794)
							(mid -0.249642 0.249642)
							(end -0.2794 0.1778)
						)
						(arc
							(start -0.2794 -0.1778)
							(mid -0.249642 -0.249642)
							(end -0.1778 -0.2794)
						)
						(arc
							(start 0.1778 -0.2794)
							(mid 0.249642 -0.249642)
							(end 0.2794 -0.1778)
						)
						(arc
							(start 0.2794 0.1778)
							(mid 0.249642 0.249642)
							(end 0.1778 0.2794)
						)
					)
					(width 0)
					(fill yes)
				)
			)
		)
	)
	(footprint ""
		(layer "B.Cu")
		(at 41.021 -127 180)
		(property "Reference" "R301"
			(at 0 0 0)
			(layer "B.SilkS")
			(hide yes)
			(effects
				(font
					(size 1.27 1.27)
				)
				(justify mirror)
			)
		)
		(property "Value" "10KR2F-2-GP"
			(at -0.064008 -3.993896 180)
			(unlocked yes)
			(layer "B.Fab")
			(hide yes)
			(effects
				(font
					(size 1.016 1.016)
					(thickness 0.1524)
				)
				(justify mirror)
			)
		)
		(property "Device Type" "R402H16"
			(at -0.064008 -5.517896 180)
			(unlocked yes)
			(layer "B.Fab")
			(hide yes)
			(effects
				(font
					(size 1.016 1.016)
					(thickness 0.1524)
				)
				(justify mirror)
			)
		)
		(duplicate_pad_numbers_are_jumpers no)
		(fp_line
			(start 0.508 -0.9398)
			(end 0.508 0.9398)
			(stroke
				(width 0.1524)
				(type default)
			)
			(layer "B.SilkS")
		)
		(fp_line
			(start -0.508 -0.9398)
			(end 0.508 -0.9398)
			(stroke
				(width 0.1524)
				(type default)
			)
			(layer "B.SilkS")
		)
		(fp_rect
			(start 0.508 0.9398)
			(end -0.508 -0.9398)
			(stroke
				(width 0)
				(type default)
			)
			(fill no)
			(layer "B.CrtYd")
		)
		(fp_rect
			(start 0.508 0.9398)
			(end -0.508 -0.9398)
			(stroke
				(width 0)
				(type default)
			)
			(fill no)
			(layer "B.Fab")
		)
		(pad "1" smd custom
			(at 0 -0.4445)
			(size 0.1397 0.1397)
			(layers "B.Cu" "B.Mask" "B.Paste")
			(net "BMC0_ENTEST1")
			(options
				(clearance outline)
				(anchor circle)
			)
			(primitives
				(gr_poly
					(pts
						(arc
							(start -0.1778 0.2794)
							(mid -0.249642 0.249642)
							(end -0.2794 0.1778)
						)
						(arc
							(start -0.2794 -0.1778)
							(mid -0.249642 -0.249642)
							(end -0.1778 -0.2794)
						)
						(arc
							(start 0.1778 -0.2794)
							(mid 0.249642 -0.249642)
							(end 0.2794 -0.1778)
						)
						(arc
							(start 0.2794 0.1778)
							(mid 0.249642 0.249642)
							(end 0.1778 0.2794)
						)
					)
					(width 0)
					(fill yes)
				)
			)
		)
		(pad "2" smd custom
			(at 0 0.4445)
			(size 0.1397 0.1397)
			(layers "B.Cu" "B.Mask" "B.Paste")
			(net "GND")
			(options
				(clearance outline)
				(anchor circle)
			)
			(primitives
				(gr_poly
					(pts
						(arc
							(start -0.1778 0.2794)
							(mid -0.249642 0.249642)
							(end -0.2794 0.1778)
						)
						(arc
							(start -0.2794 -0.1778)
							(mid -0.249642 -0.249642)
							(end -0.1778 -0.2794)
						)
						(arc
							(start 0.1778 -0.2794)
							(mid 0.249642 -0.249642)
							(end 0.2794 -0.1778)
						)
						(arc
							(start 0.2794 0.1778)
							(mid 0.249642 0.249642)
							(end 0.1778 0.2794)
						)
					)
					(width 0)
					(fill yes)
				)
			)
		)
	)
	(footprint ""
		(layer "B.Cu")
		(at 228.6254 -53.001672 90)
		(property "Reference" "C563"
			(at 0 0 90)
			(layer "B.SilkS")
			(hide yes)
			(effects
				(font
					(size 1.27 1.27)
				)
				(justify mirror)
			)
		)
		(property "Value" "SCD1U16V1KX-1-GP"
			(at 2.8321 -1.7399 90)
			(unlocked yes)
			(layer "B.Fab")
			(hide yes)
			(effects
				(font
					(size 1.016 1.016)
					(thickness 0.1524)
				)
				(justify mirror)
			)
		)
		(property "Device Type" "C0201H13"
			(at 2.8321 -3.2639 90)
			(unlocked yes)
			(layer "B.Fab")
			(hide yes)
			(effects
				(font
					(size 1.016 1.016)
					(thickness 0.1524)
				)
				(justify mirror)
			)
		)
		(duplicate_pad_numbers_are_jumpers no)
		(fp_rect
			(start 0.2794 0.6477)
			(end -0.2794 -0.6477)
			(stroke
				(width 0)
				(type default)
			)
			(fill no)
			(layer "B.CrtYd")
		)
		(fp_rect
			(start 0.2794 0.6477)
			(end -0.2794 -0.6477)
			(stroke
				(width 0)
				(type default)
			)
			(fill no)
			(layer "B.Fab")
		)
		(pad "1" smd custom
			(at 0 -0.2794 270)
			(size 0.0762 0.0762)
			(layers "B.Cu" "B.Mask" "B.Paste")
			(net "DUT_AVD_PCIE")
			(options
				(clearance outline)
				(anchor circle)
			)
			(primitives
				(gr_poly
					(pts
						(arc
							(start 0.1524 0.127)
							(mid 0.137521 0.162921)
							(end 0.1016 0.1778)
						)
						(arc
							(start -0.1016 0.1778)
							(mid -0.137521 0.162921)
							(end -0.1524 0.127)
						)
						(arc
							(start -0.1524 -0.127)
							(mid -0.137521 -0.162921)
							(end -0.1016 -0.1778)
						)
						(arc
							(start 0.1016 -0.1778)
							(mid 0.137521 -0.162921)
							(end 0.1524 -0.127)
						)
					)
					(width 0)
					(fill yes)
				)
			)
		)
		(pad "2" smd custom
			(at 0 0.2794 270)
			(size 0.0762 0.0762)
			(layers "B.Cu" "B.Mask" "B.Paste")
			(net "GND")
			(options
				(clearance outline)
				(anchor circle)
			)
			(primitives
				(gr_poly
					(pts
						(arc
							(start 0.1524 0.127)
							(mid 0.137521 0.162921)
							(end 0.1016 0.1778)
						)
						(arc
							(start -0.1016 0.1778)
							(mid -0.137521 0.162921)
							(end -0.1524 0.127)
						)
						(arc
							(start -0.1524 -0.127)
							(mid -0.137521 -0.162921)
							(end -0.1016 -0.1778)
						)
						(arc
							(start 0.1016 -0.1778)
							(mid 0.137521 -0.162921)
							(end 0.1524 -0.127)
						)
					)
					(width 0)
					(fill yes)
				)
			)
		)
	)
	(footprint ""
		(layer "B.Cu")
		(at 310.007 -62.357 180)
		(property "Reference" "PG54"
			(at 0 0 0)
			(layer "B.SilkS")
			(hide yes)
			(effects
				(font
					(size 1.27 1.27)
				)
				(justify mirror)
			)
		)
		(property "Value" "GAP-CLOSE-PWR-3-GP"
			(at -0.0254 -6.5786 180)
			(unlocked yes)
			(layer "B.Fab")
			(hide yes)
			(effects
				(font
					(size 1.016 1.016)
					(thickness 0.1524)
				)
				(justify mirror)
			)
		)
		(property "Device Type" "GAP-CLOSE-PWR-3"
			(at -0.0254 -8.255 180)
			(unlocked yes)
			(layer "B.Fab")
			(hide yes)
			(effects
				(font
					(size 1.016 1.016)
					(thickness 0.1524)
				)
				(justify mirror)
			)
		)
		(duplicate_pad_numbers_are_jumpers no)
		(fp_rect
			(start 0.7112 0.4572)
			(end -0.7112 -0.4572)
			(stroke
				(width 0)
				(type default)
			)
			(fill no)
			(layer "B.CrtYd")
		)
		(fp_poly
			(pts
				(xy 0.7112 -0.4572) (xy -0.7112 -0.4572) (xy -0.7112 0.4572) (xy 0.7112 0.4572)
			)
			(stroke
				(width 0)
				(type default)
			)
			(fill no)
			(layer "B.Fab")
		)
		(pad "1" smd rect
			(at 0.3048 0)
			(size 0.6604 0.762)
			(layers "B.Cu" "B.Mask" "B.Paste")
			(net "DUT_VDD")
		)
		(pad "2" smd rect
			(at -0.3048 0)
			(size 0.6604 0.762)
			(layers "B.Cu" "B.Mask" "B.Paste")
			(net "P0V9_E")
		)
	)
	(footprint ""
		(layer "B.Cu")
		(at 272.6055 -7.8105 180)
		(property "Reference" "R277"
			(at 0 0 0)
			(layer "B.SilkS")
			(hide yes)
			(effects
				(font
					(size 1.27 1.27)
				)
				(justify mirror)
			)
		)
		(property "Value" "0R2J-2-GP"
			(at -0.064008 -3.993896 180)
			(unlocked yes)
			(layer "B.Fab")
			(hide yes)
			(effects
				(font
					(size 1.016 1.016)
					(thickness 0.1524)
				)
				(justify mirror)
			)
		)
		(property "Device Type" "R402H16"
			(at -0.064008 -5.517896 180)
			(unlocked yes)
			(layer "B.Fab")
			(hide yes)
			(effects
				(font
					(size 1.016 1.016)
					(thickness 0.1524)
				)
				(justify mirror)
			)
		)
		(duplicate_pad_numbers_are_jumpers no)
		(fp_line
			(start 0.508 -0.9398)
			(end 0.508 0.9398)
			(stroke
				(width 0.1524)
				(type default)
			)
			(layer "B.SilkS")
		)
		(fp_line
			(start -0.508 -0.9398)
			(end 0.508 -0.9398)
			(stroke
				(width 0.1524)
				(type default)
			)
			(layer "B.SilkS")
		)
		(fp_rect
			(start 0.508 0.9398)
			(end -0.508 -0.9398)
			(stroke
				(width 0)
				(type default)
			)
			(fill no)
			(layer "B.CrtYd")
		)
		(fp_rect
			(start 0.508 0.9398)
			(end -0.508 -0.9398)
			(stroke
				(width 0)
				(type default)
			)
			(fill no)
			(layer "B.Fab")
		)
		(pad "1" smd custom
			(at 0 -0.4445)
			(size 0.1397 0.1397)
			(layers "B.Cu" "B.Mask" "B.Paste")
			(net "MINISAS_CN16_A_I2C_INT#")
			(options
				(clearance outline)
				(anchor circle)
			)
			(primitives
				(gr_poly
					(pts
						(arc
							(start -0.1778 0.2794)
							(mid -0.249642 0.249642)
							(end -0.2794 0.1778)
						)
						(arc
							(start -0.2794 -0.1778)
							(mid -0.249642 -0.249642)
							(end -0.1778 -0.2794)
						)
						(arc
							(start 0.1778 -0.2794)
							(mid 0.249642 -0.249642)
							(end 0.2794 -0.1778)
						)
						(arc
							(start 0.2794 0.1778)
							(mid 0.249642 0.249642)
							(end 0.1778 0.2794)
						)
					)
					(width 0)
					(fill yes)
				)
			)
		)
		(pad "2" smd custom
			(at 0 0.4445)
			(size 0.1397 0.1397)
			(layers "B.Cu" "B.Mask" "B.Paste")
			(net "PCIE_REFCLK_H0_N_R")
			(options
				(clearance outline)
				(anchor circle)
			)
			(primitives
				(gr_poly
					(pts
						(arc
							(start -0.1778 0.2794)
							(mid -0.249642 0.249642)
							(end -0.2794 0.1778)
						)
						(arc
							(start -0.2794 -0.1778)
							(mid -0.249642 -0.249642)
							(end -0.1778 -0.2794)
						)
						(arc
							(start 0.1778 -0.2794)
							(mid 0.249642 -0.249642)
							(end 0.2794 -0.1778)
						)
						(arc
							(start 0.2794 0.1778)
							(mid 0.249642 0.249642)
							(end 0.1778 0.2794)
						)
					)
					(width 0)
					(fill yes)
				)
			)
		)
	)
	(footprint ""
		(layer "B.Cu")
		(at 61.4426 -115.7224 90)
		(property "Reference" "R300"
			(at 0 0 90)
			(layer "B.SilkS")
			(hide yes)
			(effects
				(font
					(size 1.27 1.27)
				)
				(justify mirror)
			)
		)
		(property "Value" "4K7R2F-GP"
			(at -0.064008 -3.993896 90)
			(unlocked yes)
			(layer "B.Fab")
			(hide yes)
			(effects
				(font
					(size 1.016 1.016)
					(thickness 0.1524)
				)
				(justify mirror)
			)
		)
		(property "Device Type" "R402H16"
			(at -0.064008 -5.517896 90)
			(unlocked yes)
			(layer "B.Fab")
			(hide yes)
			(effects
				(font
					(size 1.016 1.016)
					(thickness 0.1524)
				)
				(justify mirror)
			)
		)
		(duplicate_pad_numbers_are_jumpers no)
		(fp_line
			(start 0.508 -0.9398)
			(end 0.508 0.9398)
			(stroke
				(width 0.1524)
				(type default)
			)
			(layer "B.SilkS")
		)
		(fp_line
			(start -0.508 -0.9398)
			(end 0.508 -0.9398)
			(stroke
				(width 0.1524)
				(type default)
			)
			(layer "B.SilkS")
		)
		(fp_rect
			(start 0.508 0.9398)
			(end -0.508 -0.9398)
			(stroke
				(width 0)
				(type default)
			)
			(fill no)
			(layer "B.CrtYd")
		)
		(fp_rect
			(start 0.508 0.9398)
			(end -0.508 -0.9398)
			(stroke
				(width 0)
				(type default)
			)
			(fill no)
			(layer "B.Fab")
		)
		(pad "1" smd custom
			(at 0 -0.4445 270)
			(size 0.1397 0.1397)
			(layers "B.Cu" "B.Mask" "B.Paste")
			(net "P3V3_STBY")
			(options
				(clearance outline)
				(anchor circle)
			)
			(primitives
				(gr_poly
					(pts
						(arc
							(start -0.1778 0.2794)
							(mid -0.249642 0.249642)
							(end -0.2794 0.1778)
						)
						(arc
							(start -0.2794 -0.1778)
							(mid -0.249642 -0.249642)
							(end -0.1778 -0.2794)
						)
						(arc
							(start 0.1778 -0.2794)
							(mid 0.249642 -0.249642)
							(end 0.2794 -0.1778)
						)
						(arc
							(start 0.2794 0.1778)
							(mid 0.249642 0.249642)
							(end 0.1778 0.2794)
						)
					)
					(width 0)
					(fill yes)
				)
			)
		)
		(pad "2" smd custom
			(at 0 0.4445 270)
			(size 0.1397 0.1397)
			(layers "B.Cu" "B.Mask" "B.Paste")
			(net "I2C3_LS_G2")
			(options
				(clearance outline)
				(anchor circle)
			)
			(primitives
				(gr_poly
					(pts
						(arc
							(start -0.1778 0.2794)
							(mid -0.249642 0.249642)
							(end -0.2794 0.1778)
						)
						(arc
							(start -0.2794 -0.1778)
							(mid -0.249642 -0.249642)
							(end -0.1778 -0.2794)
						)
						(arc
							(start 0.1778 -0.2794)
							(mid 0.249642 -0.249642)
							(end 0.2794 -0.1778)
						)
						(arc
							(start 0.2794 0.1778)
							(mid 0.249642 0.249642)
							(end 0.1778 0.2794)
						)
					)
					(width 0)
					(fill yes)
				)
			)
		)
	)
	(footprint ""
		(layer "B.Cu")
		(at 51.181 -145.415 180)
		(property "Reference" "SR849"
			(at 0 0 0)
			(layer "B.SilkS")
			(hide yes)
			(effects
				(font
					(size 1.27 1.27)
				)
				(justify mirror)
			)
		)
		(property "Value" "4K75R2F-1-GP"
			(at -0.064008 -3.993896 180)
			(unlocked yes)
			(layer "B.Fab")
			(hide yes)
			(effects
				(font
					(size 1.016 1.016)
					(thickness 0.1524)
				)
				(justify mirror)
			)
		)
		(property "Device Type" "R402H16"
			(at -0.064008 -5.517896 180)
			(unlocked yes)
			(layer "B.Fab")
			(hide yes)
			(effects
				(font
					(size 1.016 1.016)
					(thickness 0.1524)
				)
				(justify mirror)
			)
		)
		(duplicate_pad_numbers_are_jumpers no)
		(fp_line
			(start 0.508 -0.9398)
			(end 0.508 0.9398)
			(stroke
				(width 0.1524)
				(type default)
			)
			(layer "B.SilkS")
		)
		(fp_line
			(start -0.508 -0.9398)
			(end 0.508 -0.9398)
			(stroke
				(width 0.1524)
				(type default)
			)
			(layer "B.SilkS")
		)
		(fp_rect
			(start 0.508 0.9398)
			(end -0.508 -0.9398)
			(stroke
				(width 0)
				(type default)
			)
			(fill no)
			(layer "B.CrtYd")
		)
		(fp_rect
			(start 0.508 0.9398)
			(end -0.508 -0.9398)
			(stroke
				(width 0)
				(type default)
			)
			(fill no)
			(layer "B.Fab")
		)
		(pad "1" smd custom
			(at 0 -0.4445)
			(size 0.1397 0.1397)
			(layers "B.Cu" "B.Mask" "B.Paste")
			(net "BMC_FW_DET_BOARD_VER_1")
			(options
				(clearance outline)
				(anchor circle)
			)
			(primitives
				(gr_poly
					(pts
						(arc
							(start -0.1778 0.2794)
							(mid -0.249642 0.249642)
							(end -0.2794 0.1778)
						)
						(arc
							(start -0.2794 -0.1778)
							(mid -0.249642 -0.249642)
							(end -0.1778 -0.2794)
						)
						(arc
							(start 0.1778 -0.2794)
							(mid 0.249642 -0.249642)
							(end 0.2794 -0.1778)
						)
						(arc
							(start 0.2794 0.1778)
							(mid 0.249642 0.249642)
							(end 0.1778 0.2794)
						)
					)
					(width 0)
					(fill yes)
				)
			)
		)
		(pad "2" smd custom
			(at 0 0.4445)
			(size 0.1397 0.1397)
			(layers "B.Cu" "B.Mask" "B.Paste")
			(net "GND")
			(options
				(clearance outline)
				(anchor circle)
			)
			(primitives
				(gr_poly
					(pts
						(arc
							(start -0.1778 0.2794)
							(mid -0.249642 0.249642)
							(end -0.2794 0.1778)
						)
						(arc
							(start -0.2794 -0.1778)
							(mid -0.249642 -0.249642)
							(end -0.1778 -0.2794)
						)
						(arc
							(start 0.1778 -0.2794)
							(mid 0.249642 -0.249642)
							(end 0.2794 -0.1778)
						)
						(arc
							(start 0.2794 0.1778)
							(mid 0.249642 0.249642)
							(end 0.1778 0.2794)
						)
					)
					(width 0)
					(fill yes)
				)
			)
		)
	)
	(footprint ""
		(layer "B.Cu")
		(at 34.937954 -158.479744 180)
		(property "Reference" "C197"
			(at 0 0 0)
			(layer "B.SilkS")
			(hide yes)
			(effects
				(font
					(size 1.27 1.27)
				)
				(justify mirror)
			)
		)
		(property "Value" "SC1U10V2KX-4-GP"
			(at -1.1811 -2.7051 180)
			(unlocked yes)
			(layer "B.Fab")
			(hide yes)
			(effects
				(font
					(size 1.016 1.016)
					(thickness 0.1524)
				)
				(justify mirror)
			)
		)
		(property "Device Type" "C402H22"
			(at -1.1811 -4.2291 180)
			(unlocked yes)
			(layer "B.Fab")
			(hide yes)
			(effects
				(font
					(size 1.016 1.016)
					(thickness 0.1524)
				)
				(justify mirror)
			)
		)
		(duplicate_pad_numbers_are_jumpers no)
		(fp_rect
			(start 0.4318 0.9525)
			(end -0.4318 -0.9525)
			(stroke
				(width 0)
				(type default)
			)
			(fill no)
			(layer "B.CrtYd")
		)
		(fp_rect
			(start 0.4318 0.9525)
			(end -0.4318 -0.9525)
			(stroke
				(width 0)
				(type default)
			)
			(fill no)
			(layer "B.Fab")
		)
		(pad "1" smd custom
			(at 0 -0.4445)
			(size 0.1524 0.1524)
			(layers "B.Cu" "B.Mask" "B.Paste")
			(net "P1V53_STBY")
			(options
				(clearance outline)
				(anchor circle)
			)
			(primitives
				(gr_poly
					(pts
						(arc
							(start 0.3048 0.2032)
							(mid 0.275042 0.275042)
							(end 0.2032 0.3048)
						)
						(arc
							(start -0.2032 0.3048)
							(mid -0.275042 0.275042)
							(end -0.3048 0.2032)
						)
						(arc
							(start -0.3048 -0.2032)
							(mid -0.275042 -0.275042)
							(end -0.2032 -0.3048)
						)
						(arc
							(start 0.2032 -0.3048)
							(mid 0.275042 -0.275042)
							(end 0.3048 -0.2032)
						)
					)
					(width 0)
					(fill yes)
				)
			)
		)
		(pad "2" smd custom
			(at 0 0.4445)
			(size 0.1524 0.1524)
			(layers "B.Cu" "B.Mask" "B.Paste")
			(net "GND")
			(options
				(clearance outline)
				(anchor circle)
			)
			(primitives
				(gr_poly
					(pts
						(arc
							(start 0.3048 0.2032)
							(mid 0.275042 0.275042)
							(end 0.2032 0.3048)
						)
						(arc
							(start -0.2032 0.3048)
							(mid -0.275042 0.275042)
							(end -0.3048 0.2032)
						)
						(arc
							(start -0.3048 -0.2032)
							(mid -0.275042 -0.275042)
							(end -0.2032 -0.3048)
						)
						(arc
							(start 0.2032 -0.3048)
							(mid 0.275042 -0.275042)
							(end 0.3048 -0.2032)
						)
					)
					(width 0)
					(fill yes)
				)
			)
		)
	)
	(footprint ""
		(layer "B.Cu")
		(at 212.916008 -4.064)
		(property "Reference" "R3716"
			(at 0 0 0)
			(layer "B.SilkS")
			(hide yes)
			(effects
				(font
					(size 1.27 1.27)
				)
				(justify mirror)
			)
		)
		(property "Value" "1KR2F-3-GP"
			(at -0.064008 -3.993896 0)
			(unlocked yes)
			(layer "B.Fab")
			(hide yes)
			(effects
				(font
					(size 1.016 1.016)
					(thickness 0.1524)
				)
				(justify mirror)
			)
		)
		(property "Device Type" "R402H16"
			(at -0.064008 -5.517896 0)
			(unlocked yes)
			(layer "B.Fab")
			(hide yes)
			(effects
				(font
					(size 1.016 1.016)
					(thickness 0.1524)
				)
				(justify mirror)
			)
		)
		(duplicate_pad_numbers_are_jumpers no)
		(fp_line
			(start -0.508 -0.9398)
			(end 0.508 -0.9398)
			(stroke
				(width 0.1524)
				(type default)
			)
			(layer "B.SilkS")
		)
		(fp_line
			(start 0.508 -0.9398)
			(end 0.508 0.9398)
			(stroke
				(width 0.1524)
				(type default)
			)
			(layer "B.SilkS")
		)
		(fp_rect
			(start 0.508 0.9398)
			(end -0.508 -0.9398)
			(stroke
				(width 0)
				(type default)
			)
			(fill no)
			(layer "B.CrtYd")
		)
		(fp_rect
			(start 0.508 0.9398)
			(end -0.508 -0.9398)
			(stroke
				(width 0)
				(type default)
			)
			(fill no)
			(layer "B.Fab")
		)
		(pad "1" smd custom
			(at 0 -0.4445 180)
			(size 0.1397 0.1397)
			(layers "B.Cu" "B.Mask" "B.Paste")
			(net "HOST4_RST_N")
			(options
				(clearance outline)
				(anchor circle)
			)
			(primitives
				(gr_poly
					(pts
						(arc
							(start -0.1778 0.2794)
							(mid -0.249642 0.249642)
							(end -0.2794 0.1778)
						)
						(arc
							(start -0.2794 -0.1778)
							(mid -0.249642 -0.249642)
							(end -0.1778 -0.2794)
						)
						(arc
							(start 0.1778 -0.2794)
							(mid 0.249642 -0.249642)
							(end 0.2794 -0.1778)
						)
						(arc
							(start 0.2794 0.1778)
							(mid 0.249642 0.249642)
							(end 0.1778 0.2794)
						)
					)
					(width 0)
					(fill yes)
				)
			)
		)
		(pad "2" smd custom
			(at 0 0.4445 180)
			(size 0.1397 0.1397)
			(layers "B.Cu" "B.Mask" "B.Paste")
			(net "P3V3_STBY")
			(options
				(clearance outline)
				(anchor circle)
			)
			(primitives
				(gr_poly
					(pts
						(arc
							(start -0.1778 0.2794)
							(mid -0.249642 0.249642)
							(end -0.2794 0.1778)
						)
						(arc
							(start -0.2794 -0.1778)
							(mid -0.249642 -0.249642)
							(end -0.1778 -0.2794)
						)
						(arc
							(start 0.1778 -0.2794)
							(mid 0.249642 -0.249642)
							(end 0.2794 -0.1778)
						)
						(arc
							(start 0.2794 0.1778)
							(mid 0.249642 0.249642)
							(end 0.1778 0.2794)
						)
					)
					(width 0)
					(fill yes)
				)
			)
		)
	)
	(footprint ""
		(layer "B.Cu")
		(at 130.4798 -196.3928)
		(property "Reference" "R4123"
			(at 0 0 0)
			(layer "B.SilkS")
			(hide yes)
			(effects
				(font
					(size 1.27 1.27)
				)
				(justify mirror)
			)
		)
		(property "Value" "4K7R2F-GP"
			(at -0.064008 -3.993896 0)
			(unlocked yes)
			(layer "B.Fab")
			(hide yes)
			(effects
				(font
					(size 1.016 1.016)
					(thickness 0.1524)
				)
				(justify mirror)
			)
		)
		(property "Device Type" "R402H16"
			(at -0.064008 -5.517896 0)
			(unlocked yes)
			(layer "B.Fab")
			(hide yes)
			(effects
				(font
					(size 1.016 1.016)
					(thickness 0.1524)
				)
				(justify mirror)
			)
		)
		(duplicate_pad_numbers_are_jumpers no)
		(fp_line
			(start -0.508 -0.9398)
			(end 0.508 -0.9398)
			(stroke
				(width 0.1524)
				(type default)
			)
			(layer "B.SilkS")
		)
		(fp_line
			(start 0.508 -0.9398)
			(end 0.508 0.9398)
			(stroke
				(width 0.1524)
				(type default)
			)
			(layer "B.SilkS")
		)
		(fp_rect
			(start 0.508 0.9398)
			(end -0.508 -0.9398)
			(stroke
				(width 0)
				(type default)
			)
			(fill no)
			(layer "B.CrtYd")
		)
		(fp_rect
			(start 0.508 0.9398)
			(end -0.508 -0.9398)
			(stroke
				(width 0)
				(type default)
			)
			(fill no)
			(layer "B.Fab")
		)
		(pad "1" smd custom
			(at 0 -0.4445 180)
			(size 0.1397 0.1397)
			(layers "B.Cu" "B.Mask" "B.Paste")
			(net "SSD_PERST#1")
			(options
				(clearance outline)
				(anchor circle)
			)
			(primitives
				(gr_poly
					(pts
						(arc
							(start -0.1778 0.2794)
							(mid -0.249642 0.249642)
							(end -0.2794 0.1778)
						)
						(arc
							(start -0.2794 -0.1778)
							(mid -0.249642 -0.249642)
							(end -0.1778 -0.2794)
						)
						(arc
							(start 0.1778 -0.2794)
							(mid 0.249642 -0.249642)
							(end 0.2794 -0.1778)
						)
						(arc
							(start 0.2794 0.1778)
							(mid 0.249642 0.249642)
							(end 0.1778 0.2794)
						)
					)
					(width 0)
					(fill yes)
				)
			)
		)
		(pad "2" smd custom
			(at 0 0.4445 180)
			(size 0.1397 0.1397)
			(layers "B.Cu" "B.Mask" "B.Paste")
			(net "P3V3_STBY")
			(options
				(clearance outline)
				(anchor circle)
			)
			(primitives
				(gr_poly
					(pts
						(arc
							(start -0.1778 0.2794)
							(mid -0.249642 0.249642)
							(end -0.2794 0.1778)
						)
						(arc
							(start -0.2794 -0.1778)
							(mid -0.249642 -0.249642)
							(end -0.1778 -0.2794)
						)
						(arc
							(start 0.1778 -0.2794)
							(mid 0.249642 -0.249642)
							(end 0.2794 -0.1778)
						)
						(arc
							(start 0.2794 0.1778)
							(mid 0.249642 0.249642)
							(end 0.1778 0.2794)
						)
					)
					(width 0)
					(fill yes)
				)
			)
		)
	)
	(footprint ""
		(layer "B.Cu")
		(at 253.5936 -39.0144 90)
		(property "Reference" "C591"
			(at 0 0 90)
			(layer "B.SilkS")
			(hide yes)
			(effects
				(font
					(size 1.27 1.27)
				)
				(justify mirror)
			)
		)
		(property "Value" "SCD1U16V1KX-1-GP"
			(at 2.8321 -1.7399 90)
			(unlocked yes)
			(layer "B.Fab")
			(hide yes)
			(effects
				(font
					(size 1.016 1.016)
					(thickness 0.1524)
				)
				(justify mirror)
			)
		)
		(property "Device Type" "C0201H13"
			(at 2.8321 -3.2639 90)
			(unlocked yes)
			(layer "B.Fab")
			(hide yes)
			(effects
				(font
					(size 1.016 1.016)
					(thickness 0.1524)
				)
				(justify mirror)
			)
		)
		(duplicate_pad_numbers_are_jumpers no)
		(fp_rect
			(start 0.2794 0.6477)
			(end -0.2794 -0.6477)
			(stroke
				(width 0)
				(type default)
			)
			(fill no)
			(layer "B.CrtYd")
		)
		(fp_rect
			(start 0.2794 0.6477)
			(end -0.2794 -0.6477)
			(stroke
				(width 0)
				(type default)
			)
			(fill no)
			(layer "B.Fab")
		)
		(pad "1" smd custom
			(at 0 -0.2794 270)
			(size 0.0762 0.0762)
			(layers "B.Cu" "B.Mask" "B.Paste")
			(net "DUT_AVD_PCIE")
			(options
				(clearance outline)
				(anchor circle)
			)
			(primitives
				(gr_poly
					(pts
						(arc
							(start 0.1524 0.127)
							(mid 0.137521 0.162921)
							(end 0.1016 0.1778)
						)
						(arc
							(start -0.1016 0.1778)
							(mid -0.137521 0.162921)
							(end -0.1524 0.127)
						)
						(arc
							(start -0.1524 -0.127)
							(mid -0.137521 -0.162921)
							(end -0.1016 -0.1778)
						)
						(arc
							(start 0.1016 -0.1778)
							(mid 0.137521 -0.162921)
							(end 0.1524 -0.127)
						)
					)
					(width 0)
					(fill yes)
				)
			)
		)
		(pad "2" smd custom
			(at 0 0.2794 270)
			(size 0.0762 0.0762)
			(layers "B.Cu" "B.Mask" "B.Paste")
			(net "GND")
			(options
				(clearance outline)
				(anchor circle)
			)
			(primitives
				(gr_poly
					(pts
						(arc
							(start 0.1524 0.127)
							(mid 0.137521 0.162921)
							(end 0.1016 0.1778)
						)
						(arc
							(start -0.1016 0.1778)
							(mid -0.137521 0.162921)
							(end -0.1524 0.127)
						)
						(arc
							(start -0.1524 -0.127)
							(mid -0.137521 -0.162921)
							(end -0.1016 -0.1778)
						)
						(arc
							(start 0.1016 -0.1778)
							(mid 0.137521 -0.162921)
							(end 0.1524 -0.127)
						)
					)
					(width 0)
					(fill yes)
				)
			)
		)
	)
	(footprint ""
		(layer "B.Cu")
		(at 249.599958 -35.999928 -90)
		(property "Reference" "TP280"
			(at 0 0 90)
			(layer "B.SilkS")
			(hide yes)
			(effects
				(font
					(size 1.27 1.27)
				)
				(justify mirror)
			)
		)
		(property "Value" "TPAD28-2-GP"
			(at 0.0127 -1.6637 270)
			(unlocked yes)
			(layer "B.Fab")
			(hide yes)
			(effects
				(font
					(size 1.016 1.016)
					(thickness 0.1524)
				)
				(justify mirror)
			)
		)
		(property "Device Type" "TPAD28"
			(at 0.0127 -3.1877 270)
			(unlocked yes)
			(layer "B.Fab")
			(hide yes)
			(effects
				(font
					(size 1.016 1.016)
					(thickness 0.1524)
				)
				(justify mirror)
			)
		)
		(duplicate_pad_numbers_are_jumpers no)
		(fp_poly
			(pts
				(arc
					(start 0 -0.3556)
					(mid 0 0.3556)
					(end 0 -0.3556)
				)
			)
			(stroke
				(width 0)
				(type default)
			)
			(fill no)
			(layer "B.CrtYd")
		)
		(fp_poly
			(pts
				(arc
					(start 0 -0.6096)
					(mid 0 0.6096)
					(end 0 -0.6096)
				)
			)
			(stroke
				(width 0)
				(type default)
			)
			(fill no)
			(layer "B.Fab")
		)
		(pad "1" smd circle
			(at 0 0 90)
			(size 0.7112 0.7112)
			(layers "B.Cu" "B.Mask" "B.Paste")
			(net "TWI_SRST#1")
		)
	)
	(footprint ""
		(layer "B.Cu")
		(at 64.135 -46.99 90)
		(property "Reference" "PC22"
			(at 0 0 90)
			(layer "B.SilkS")
			(hide yes)
			(effects
				(font
					(size 1.27 1.27)
				)
				(justify mirror)
			)
		)
		(property "Value" "SC10U25V5KX-GP"
			(at 0.0762 -6.1214 90)
			(unlocked yes)
			(layer "B.Fab")
			(hide yes)
			(effects
				(font
					(size 1.016 1.016)
					(thickness 0.1524)
				)
				(justify mirror)
			)
		)
		(property "Device Type" "C805H56"
			(at 0.0762 -8.1534 90)
			(unlocked yes)
			(layer "B.Fab")
			(hide yes)
			(effects
				(font
					(size 1.016 1.016)
					(thickness 0.1524)
				)
				(justify mirror)
			)
		)
		(duplicate_pad_numbers_are_jumpers no)
		(fp_line
			(start -0.635 0)
			(end 0.635 0)
			(stroke
				(width 0.508)
				(type default)
			)
			(layer "B.SilkS")
		)
		(fp_rect
			(start 0.9652 1.778)
			(end -0.9652 -1.778)
			(stroke
				(width 0)
				(type default)
			)
			(fill no)
			(layer "B.CrtYd")
		)
		(fp_poly
			(pts
				(xy 0.9652 -1.778) (xy -0.9652 -1.778) (xy -0.9652 1.778) (xy 0.9652 1.778)
			)
			(stroke
				(width 0)
				(type default)
			)
			(fill no)
			(layer "B.Fab")
		)
		(pad "1" smd rect
			(at 0 -0.9652 270)
			(size 1.397 1.143)
			(layers "B.Cu" "B.Mask" "B.Paste")
			(net "P3V3_STBY_VIN")
		)
		(pad "2" smd rect
			(at 0 0.9652 270)
			(size 1.397 1.143)
			(layers "B.Cu" "B.Mask" "B.Paste")
			(net "GND")
		)
	)
	(footprint ""
		(layer "B.Cu")
		(at 161.417 -88.4174 180)
		(property "Reference" "C718"
			(at 0 0 0)
			(layer "B.SilkS")
			(hide yes)
			(effects
				(font
					(size 1.27 1.27)
				)
				(justify mirror)
			)
		)
		(property "Value" "SCD1U10V2KX-5GP"
			(at -1.1811 -2.7051 180)
			(unlocked yes)
			(layer "B.Fab")
			(hide yes)
			(effects
				(font
					(size 1.016 1.016)
					(thickness 0.1524)
				)
				(justify mirror)
			)
		)
		(property "Device Type" "C402H22"
			(at -1.1811 -4.2291 180)
			(unlocked yes)
			(layer "B.Fab")
			(hide yes)
			(effects
				(font
					(size 1.016 1.016)
					(thickness 0.1524)
				)
				(justify mirror)
			)
		)
		(duplicate_pad_numbers_are_jumpers no)
		(fp_rect
			(start 0.4318 0.9525)
			(end -0.4318 -0.9525)
			(stroke
				(width 0)
				(type default)
			)
			(fill no)
			(layer "B.CrtYd")
		)
		(fp_rect
			(start 0.4318 0.9525)
			(end -0.4318 -0.9525)
			(stroke
				(width 0)
				(type default)
			)
			(fill no)
			(layer "B.Fab")
		)
		(pad "1" smd custom
			(at 0 -0.4445)
			(size 0.1524 0.1524)
			(layers "B.Cu" "B.Mask" "B.Paste")
			(net "P1V8_CLKGEN")
			(options
				(clearance outline)
				(anchor circle)
			)
			(primitives
				(gr_poly
					(pts
						(arc
							(start 0.3048 0.2032)
							(mid 0.275042 0.275042)
							(end 0.2032 0.3048)
						)
						(arc
							(start -0.2032 0.3048)
							(mid -0.275042 0.275042)
							(end -0.3048 0.2032)
						)
						(arc
							(start -0.3048 -0.2032)
							(mid -0.275042 -0.275042)
							(end -0.2032 -0.3048)
						)
						(arc
							(start 0.2032 -0.3048)
							(mid 0.275042 -0.275042)
							(end 0.3048 -0.2032)
						)
					)
					(width 0)
					(fill yes)
				)
			)
		)
		(pad "2" smd custom
			(at 0 0.4445)
			(size 0.1524 0.1524)
			(layers "B.Cu" "B.Mask" "B.Paste")
			(net "GND")
			(options
				(clearance outline)
				(anchor circle)
			)
			(primitives
				(gr_poly
					(pts
						(arc
							(start 0.3048 0.2032)
							(mid 0.275042 0.275042)
							(end 0.2032 0.3048)
						)
						(arc
							(start -0.2032 0.3048)
							(mid -0.275042 0.275042)
							(end -0.3048 0.2032)
						)
						(arc
							(start -0.3048 -0.2032)
							(mid -0.275042 -0.275042)
							(end -0.2032 -0.3048)
						)
						(arc
							(start 0.2032 -0.3048)
							(mid 0.275042 -0.275042)
							(end 0.3048 -0.2032)
						)
					)
					(width 0)
					(fill yes)
				)
			)
		)
	)
	(footprint ""
		(layer "B.Cu")
		(at 340.995 -62.992 -90)
		(property "Reference" "PC174"
			(at 0 0 90)
			(layer "B.SilkS")
			(hide yes)
			(effects
				(font
					(size 1.27 1.27)
				)
				(justify mirror)
			)
		)
		(property "Value" "SC10U25V5KX-GP"
			(at 0.0762 -6.1214 270)
			(unlocked yes)
			(layer "B.Fab")
			(hide yes)
			(effects
				(font
					(size 1.016 1.016)
					(thickness 0.1524)
				)
				(justify mirror)
			)
		)
		(property "Device Type" "C805H56"
			(at 0.0762 -8.1534 270)
			(unlocked yes)
			(layer "B.Fab")
			(hide yes)
			(effects
				(font
					(size 1.016 1.016)
					(thickness 0.1524)
				)
				(justify mirror)
			)
		)
		(duplicate_pad_numbers_are_jumpers no)
		(fp_line
			(start -0.635 0)
			(end 0.635 0)
			(stroke
				(width 0.508)
				(type default)
			)
			(layer "B.SilkS")
		)
		(fp_rect
			(start 0.9652 1.778)
			(end -0.9652 -1.778)
			(stroke
				(width 0)
				(type default)
			)
			(fill no)
			(layer "B.CrtYd")
		)
		(fp_poly
			(pts
				(xy 0.9652 -1.778) (xy -0.9652 -1.778) (xy -0.9652 1.778) (xy 0.9652 1.778)
			)
			(stroke
				(width 0)
				(type default)
			)
			(fill no)
			(layer "B.Fab")
		)
		(pad "1" smd rect
			(at 0 -0.9652 90)
			(size 1.397 1.143)
			(layers "B.Cu" "B.Mask" "B.Paste")
			(net "P0V9_E_VIN")
		)
		(pad "2" smd rect
			(at 0 0.9652 90)
			(size 1.397 1.143)
			(layers "B.Cu" "B.Mask" "B.Paste")
			(net "GND")
		)
	)
	(footprint ""
		(layer "B.Cu")
		(at 132.125212 -205.849474)
		(property "Reference" "R3208"
			(at 0 0 0)
			(layer "B.SilkS")
			(hide yes)
			(effects
				(font
					(size 1.27 1.27)
				)
				(justify mirror)
			)
		)
		(property "Value" "0R2J-2-GP"
			(at -0.064008 -3.993896 0)
			(unlocked yes)
			(layer "B.Fab")
			(hide yes)
			(effects
				(font
					(size 1.016 1.016)
					(thickness 0.1524)
				)
				(justify mirror)
			)
		)
		(property "Device Type" "R402H16"
			(at -0.064008 -5.517896 0)
			(unlocked yes)
			(layer "B.Fab")
			(hide yes)
			(effects
				(font
					(size 1.016 1.016)
					(thickness 0.1524)
				)
				(justify mirror)
			)
		)
		(duplicate_pad_numbers_are_jumpers no)
		(fp_line
			(start -0.508 -0.9398)
			(end 0.508 -0.9398)
			(stroke
				(width 0.1524)
				(type default)
			)
			(layer "B.SilkS")
		)
		(fp_line
			(start 0.508 -0.9398)
			(end 0.508 0.9398)
			(stroke
				(width 0.1524)
				(type default)
			)
			(layer "B.SilkS")
		)
		(fp_rect
			(start 0.508 0.9398)
			(end -0.508 -0.9398)
			(stroke
				(width 0)
				(type default)
			)
			(fill no)
			(layer "B.CrtYd")
		)
		(fp_rect
			(start 0.508 0.9398)
			(end -0.508 -0.9398)
			(stroke
				(width 0)
				(type default)
			)
			(fill no)
			(layer "B.Fab")
		)
		(pad "1" smd custom
			(at 0 -0.4445 180)
			(size 0.1397 0.1397)
			(layers "B.Cu" "B.Mask" "B.Paste")
			(net "BMC_SSD_RST#2")
			(options
				(clearance outline)
				(anchor circle)
			)
			(primitives
				(gr_poly
					(pts
						(arc
							(start -0.1778 0.2794)
							(mid -0.249642 0.249642)
							(end -0.2794 0.1778)
						)
						(arc
							(start -0.2794 -0.1778)
							(mid -0.249642 -0.249642)
							(end -0.1778 -0.2794)
						)
						(arc
							(start 0.1778 -0.2794)
							(mid 0.249642 -0.249642)
							(end 0.2794 -0.1778)
						)
						(arc
							(start 0.2794 0.1778)
							(mid 0.249642 0.249642)
							(end 0.1778 0.2794)
						)
					)
					(width 0)
					(fill yes)
				)
			)
		)
		(pad "2" smd custom
			(at 0 0.4445 180)
			(size 0.1397 0.1397)
			(layers "B.Cu" "B.Mask" "B.Paste")
			(net "BMC_SSD_RST#0_A2")
			(options
				(clearance outline)
				(anchor circle)
			)
			(primitives
				(gr_poly
					(pts
						(arc
							(start -0.1778 0.2794)
							(mid -0.249642 0.249642)
							(end -0.2794 0.1778)
						)
						(arc
							(start -0.2794 -0.1778)
							(mid -0.249642 -0.249642)
							(end -0.1778 -0.2794)
						)
						(arc
							(start 0.1778 -0.2794)
							(mid 0.249642 -0.249642)
							(end 0.2794 -0.1778)
						)
						(arc
							(start 0.2794 0.1778)
							(mid 0.249642 0.249642)
							(end 0.1778 0.2794)
						)
					)
					(width 0)
					(fill yes)
				)
			)
		)
	)
	(footprint ""
		(layer "B.Cu")
		(at 162.306 -92.7354)
		(property "Reference" "C714"
			(at 0 0 0)
			(layer "B.SilkS")
			(hide yes)
			(effects
				(font
					(size 1.27 1.27)
				)
				(justify mirror)
			)
		)
		(property "Value" "SCD1U10V2KX-5GP"
			(at -1.1811 -2.7051 0)
			(unlocked yes)
			(layer "B.Fab")
			(hide yes)
			(effects
				(font
					(size 1.016 1.016)
					(thickness 0.1524)
				)
				(justify mirror)
			)
		)
		(property "Device Type" "C402H22"
			(at -1.1811 -4.2291 0)
			(unlocked yes)
			(layer "B.Fab")
			(hide yes)
			(effects
				(font
					(size 1.016 1.016)
					(thickness 0.1524)
				)
				(justify mirror)
			)
		)
		(duplicate_pad_numbers_are_jumpers no)
		(fp_rect
			(start 0.4318 0.9525)
			(end -0.4318 -0.9525)
			(stroke
				(width 0)
				(type default)
			)
			(fill no)
			(layer "B.CrtYd")
		)
		(fp_rect
			(start 0.4318 0.9525)
			(end -0.4318 -0.9525)
			(stroke
				(width 0)
				(type default)
			)
			(fill no)
			(layer "B.Fab")
		)
		(pad "1" smd custom
			(at 0 -0.4445 180)
			(size 0.1524 0.1524)
			(layers "B.Cu" "B.Mask" "B.Paste")
			(net "P1V8_CLKGEN")
			(options
				(clearance outline)
				(anchor circle)
			)
			(primitives
				(gr_poly
					(pts
						(arc
							(start 0.3048 0.2032)
							(mid 0.275042 0.275042)
							(end 0.2032 0.3048)
						)
						(arc
							(start -0.2032 0.3048)
							(mid -0.275042 0.275042)
							(end -0.3048 0.2032)
						)
						(arc
							(start -0.3048 -0.2032)
							(mid -0.275042 -0.275042)
							(end -0.2032 -0.3048)
						)
						(arc
							(start 0.2032 -0.3048)
							(mid 0.275042 -0.275042)
							(end 0.3048 -0.2032)
						)
					)
					(width 0)
					(fill yes)
				)
			)
		)
		(pad "2" smd custom
			(at 0 0.4445 180)
			(size 0.1524 0.1524)
			(layers "B.Cu" "B.Mask" "B.Paste")
			(net "GND")
			(options
				(clearance outline)
				(anchor circle)
			)
			(primitives
				(gr_poly
					(pts
						(arc
							(start 0.3048 0.2032)
							(mid 0.275042 0.275042)
							(end 0.2032 0.3048)
						)
						(arc
							(start -0.2032 0.3048)
							(mid -0.275042 0.275042)
							(end -0.3048 0.2032)
						)
						(arc
							(start -0.3048 -0.2032)
							(mid -0.275042 -0.275042)
							(end -0.2032 -0.3048)
						)
						(arc
							(start 0.2032 -0.3048)
							(mid 0.275042 -0.275042)
							(end 0.3048 -0.2032)
						)
					)
					(width 0)
					(fill yes)
				)
			)
		)
	)
	(footprint ""
		(layer "B.Cu")
		(at 35.774884 -109.319314 -90)
		(property "Reference" "R679"
			(at 0 0 90)
			(layer "B.SilkS")
			(hide yes)
			(effects
				(font
					(size 1.27 1.27)
				)
				(justify mirror)
			)
		)
		(property "Value" "0R2J-2-GP"
			(at -0.064008 -3.993896 270)
			(unlocked yes)
			(layer "B.Fab")
			(hide yes)
			(effects
				(font
					(size 1.016 1.016)
					(thickness 0.1524)
				)
				(justify mirror)
			)
		)
		(property "Device Type" "R402H16"
			(at -0.064008 -5.517896 270)
			(unlocked yes)
			(layer "B.Fab")
			(hide yes)
			(effects
				(font
					(size 1.016 1.016)
					(thickness 0.1524)
				)
				(justify mirror)
			)
		)
		(duplicate_pad_numbers_are_jumpers no)
		(fp_line
			(start -0.508 -0.9398)
			(end 0.508 -0.9398)
			(stroke
				(width 0.1524)
				(type default)
			)
			(layer "B.SilkS")
		)
		(fp_line
			(start 0.508 -0.9398)
			(end 0.508 0.9398)
			(stroke
				(width 0.1524)
				(type default)
			)
			(layer "B.SilkS")
		)
		(fp_rect
			(start 0.508 0.9398)
			(end -0.508 -0.9398)
			(stroke
				(width 0)
				(type default)
			)
			(fill no)
			(layer "B.CrtYd")
		)
		(fp_rect
			(start 0.508 0.9398)
			(end -0.508 -0.9398)
			(stroke
				(width 0)
				(type default)
			)
			(fill no)
			(layer "B.Fab")
		)
		(pad "1" smd custom
			(at 0 -0.4445 90)
			(size 0.1397 0.1397)
			(layers "B.Cu" "B.Mask" "B.Paste")
			(net "BMC_RXCK_R")
			(options
				(clearance outline)
				(anchor circle)
			)
			(primitives
				(gr_poly
					(pts
						(arc
							(start -0.1778 0.2794)
							(mid -0.249642 0.249642)
							(end -0.2794 0.1778)
						)
						(arc
							(start -0.2794 -0.1778)
							(mid -0.249642 -0.249642)
							(end -0.1778 -0.2794)
						)
						(arc
							(start 0.1778 -0.2794)
							(mid 0.249642 -0.249642)
							(end 0.2794 -0.1778)
						)
						(arc
							(start 0.2794 0.1778)
							(mid 0.249642 0.249642)
							(end 0.1778 0.2794)
						)
					)
					(width 0)
					(fill yes)
				)
			)
		)
		(pad "2" smd custom
			(at 0 0.4445 90)
			(size 0.1397 0.1397)
			(layers "B.Cu" "B.Mask" "B.Paste")
			(net "CLK_50M_BMC0")
			(options
				(clearance outline)
				(anchor circle)
			)
			(primitives
				(gr_poly
					(pts
						(arc
							(start -0.1778 0.2794)
							(mid -0.249642 0.249642)
							(end -0.2794 0.1778)
						)
						(arc
							(start -0.2794 -0.1778)
							(mid -0.249642 -0.249642)
							(end -0.1778 -0.2794)
						)
						(arc
							(start 0.1778 -0.2794)
							(mid 0.249642 -0.249642)
							(end 0.2794 -0.1778)
						)
						(arc
							(start 0.2794 0.1778)
							(mid 0.249642 0.249642)
							(end 0.1778 0.2794)
						)
					)
					(width 0)
					(fill yes)
				)
			)
		)
	)
	(footprint ""
		(layer "B.Cu")
		(at 310.007 -63.119 180)
		(property "Reference" "PG53"
			(at 0 0 0)
			(layer "B.SilkS")
			(hide yes)
			(effects
				(font
					(size 1.27 1.27)
				)
				(justify mirror)
			)
		)
		(property "Value" "GAP-CLOSE-PWR-3-GP"
			(at -0.0254 -6.5786 180)
			(unlocked yes)
			(layer "B.Fab")
			(hide yes)
			(effects
				(font
					(size 1.016 1.016)
					(thickness 0.1524)
				)
				(justify mirror)
			)
		)
		(property "Device Type" "GAP-CLOSE-PWR-3"
			(at -0.0254 -8.255 180)
			(unlocked yes)
			(layer "B.Fab")
			(hide yes)
			(effects
				(font
					(size 1.016 1.016)
					(thickness 0.1524)
				)
				(justify mirror)
			)
		)
		(duplicate_pad_numbers_are_jumpers no)
		(fp_rect
			(start 0.7112 0.4572)
			(end -0.7112 -0.4572)
			(stroke
				(width 0)
				(type default)
			)
			(fill no)
			(layer "B.CrtYd")
		)
		(fp_poly
			(pts
				(xy 0.7112 -0.4572) (xy -0.7112 -0.4572) (xy -0.7112 0.4572) (xy 0.7112 0.4572)
			)
			(stroke
				(width 0)
				(type default)
			)
			(fill no)
			(layer "B.Fab")
		)
		(pad "1" smd rect
			(at 0.3048 0)
			(size 0.6604 0.762)
			(layers "B.Cu" "B.Mask" "B.Paste")
			(net "DUT_VDD")
		)
		(pad "2" smd rect
			(at -0.3048 0)
			(size 0.6604 0.762)
			(layers "B.Cu" "B.Mask" "B.Paste")
			(net "P0V9_E")
		)
	)
	(footprint ""
		(layer "B.Cu")
		(at 273.2532 -1.9304 90)
		(property "Reference" "R2908"
			(at 0 0 90)
			(layer "B.SilkS")
			(hide yes)
			(effects
				(font
					(size 1.27 1.27)
				)
				(justify mirror)
			)
		)
		(property "Value" "0R2J-2-GP"
			(at -0.064008 -3.993896 90)
			(unlocked yes)
			(layer "B.Fab")
			(hide yes)
			(effects
				(font
					(size 1.016 1.016)
					(thickness 0.1524)
				)
				(justify mirror)
			)
		)
		(property "Device Type" "R402H16"
			(at -0.064008 -5.517896 90)
			(unlocked yes)
			(layer "B.Fab")
			(hide yes)
			(effects
				(font
					(size 1.016 1.016)
					(thickness 0.1524)
				)
				(justify mirror)
			)
		)
		(duplicate_pad_numbers_are_jumpers no)
		(fp_line
			(start 0.508 -0.9398)
			(end 0.508 0.9398)
			(stroke
				(width 0.1524)
				(type default)
			)
			(layer "B.SilkS")
		)
		(fp_line
			(start -0.508 -0.9398)
			(end 0.508 -0.9398)
			(stroke
				(width 0.1524)
				(type default)
			)
			(layer "B.SilkS")
		)
		(fp_rect
			(start 0.508 0.9398)
			(end -0.508 -0.9398)
			(stroke
				(width 0)
				(type default)
			)
			(fill no)
			(layer "B.CrtYd")
		)
		(fp_rect
			(start 0.508 0.9398)
			(end -0.508 -0.9398)
			(stroke
				(width 0)
				(type default)
			)
			(fill no)
			(layer "B.Fab")
		)
		(pad "1" smd custom
			(at 0 -0.4445 270)
			(size 0.1397 0.1397)
			(layers "B.Cu" "B.Mask" "B.Paste")
			(net "CBL_PRSNT_N_8")
			(options
				(clearance outline)
				(anchor circle)
			)
			(primitives
				(gr_poly
					(pts
						(arc
							(start -0.1778 0.2794)
							(mid -0.249642 0.249642)
							(end -0.2794 0.1778)
						)
						(arc
							(start -0.2794 -0.1778)
							(mid -0.249642 -0.249642)
							(end -0.1778 -0.2794)
						)
						(arc
							(start 0.1778 -0.2794)
							(mid 0.249642 -0.249642)
							(end 0.2794 -0.1778)
						)
						(arc
							(start 0.2794 0.1778)
							(mid 0.249642 0.249642)
							(end 0.1778 0.2794)
						)
					)
					(width 0)
					(fill yes)
				)
			)
		)
		(pad "2" smd custom
			(at 0 0.4445 270)
			(size 0.1397 0.1397)
			(layers "B.Cu" "B.Mask" "B.Paste")
			(net "8644_CBL_PRSNT_R_8")
			(options
				(clearance outline)
				(anchor circle)
			)
			(primitives
				(gr_poly
					(pts
						(arc
							(start -0.1778 0.2794)
							(mid -0.249642 0.249642)
							(end -0.2794 0.1778)
						)
						(arc
							(start -0.2794 -0.1778)
							(mid -0.249642 -0.249642)
							(end -0.1778 -0.2794)
						)
						(arc
							(start 0.1778 -0.2794)
							(mid 0.249642 -0.249642)
							(end 0.2794 -0.1778)
						)
						(arc
							(start 0.2794 0.1778)
							(mid 0.249642 0.249642)
							(end 0.1778 0.2794)
						)
					)
					(width 0)
					(fill yes)
				)
			)
		)
	)
	(footprint ""
		(layer "B.Cu")
		(at 242.062 -26.543 90)
		(property "Reference" "TP196"
			(at 0 0 90)
			(layer "B.SilkS")
			(hide yes)
			(effects
				(font
					(size 1.27 1.27)
				)
				(justify mirror)
			)
		)
		(property "Value" "TPAD28-2-GP"
			(at 0.0127 -1.6637 90)
			(unlocked yes)
			(layer "B.Fab")
			(hide yes)
			(effects
				(font
					(size 1.016 1.016)
					(thickness 0.1524)
				)
				(justify mirror)
			)
		)
		(property "Device Type" "TPAD28"
			(at 0.0127 -3.1877 90)
			(unlocked yes)
			(layer "B.Fab")
			(hide yes)
			(effects
				(font
					(size 1.016 1.016)
					(thickness 0.1524)
				)
				(justify mirror)
			)
		)
		(duplicate_pad_numbers_are_jumpers no)
		(fp_poly
			(pts
				(arc
					(start 0 0.3556)
					(mid 0 -0.3556)
					(end 0 0.3556)
				)
			)
			(stroke
				(width 0)
				(type default)
			)
			(fill no)
			(layer "B.CrtYd")
		)
		(fp_poly
			(pts
				(arc
					(start 0 0.6096)
					(mid 0 -0.6096)
					(end 0 0.6096)
				)
			)
			(stroke
				(width 0)
				(type default)
			)
			(fill no)
			(layer "B.Fab")
		)
		(pad "1" smd circle
			(at 0 0 270)
			(size 0.7112 0.7112)
			(layers "B.Cu" "B.Mask" "B.Paste")
			(net "LBI_CE#2")
		)
	)
	(footprint ""
		(layer "B.Cu")
		(at 231.5972 -54.991 -90)
		(property "Reference" "C515"
			(at 0 0 90)
			(layer "B.SilkS")
			(hide yes)
			(effects
				(font
					(size 1.27 1.27)
				)
				(justify mirror)
			)
		)
		(property "Value" "SCD1U16V1KX-1-GP"
			(at 2.8321 -1.7399 270)
			(unlocked yes)
			(layer "B.Fab")
			(hide yes)
			(effects
				(font
					(size 1.016 1.016)
					(thickness 0.1524)
				)
				(justify mirror)
			)
		)
		(property "Device Type" "C0201H13"
			(at 2.8321 -3.2639 270)
			(unlocked yes)
			(layer "B.Fab")
			(hide yes)
			(effects
				(font
					(size 1.016 1.016)
					(thickness 0.1524)
				)
				(justify mirror)
			)
		)
		(duplicate_pad_numbers_are_jumpers no)
		(fp_rect
			(start 0.2794 0.6477)
			(end -0.2794 -0.6477)
			(stroke
				(width 0)
				(type default)
			)
			(fill no)
			(layer "B.CrtYd")
		)
		(fp_rect
			(start 0.2794 0.6477)
			(end -0.2794 -0.6477)
			(stroke
				(width 0)
				(type default)
			)
			(fill no)
			(layer "B.Fab")
		)
		(pad "1" smd custom
			(at 0 -0.2794 90)
			(size 0.0762 0.0762)
			(layers "B.Cu" "B.Mask" "B.Paste")
			(net "DUT_AVD_PCIE_Q")
			(options
				(clearance outline)
				(anchor circle)
			)
			(primitives
				(gr_poly
					(pts
						(arc
							(start 0.1524 0.127)
							(mid 0.137521 0.162921)
							(end 0.1016 0.1778)
						)
						(arc
							(start -0.1016 0.1778)
							(mid -0.137521 0.162921)
							(end -0.1524 0.127)
						)
						(arc
							(start -0.1524 -0.127)
							(mid -0.137521 -0.162921)
							(end -0.1016 -0.1778)
						)
						(arc
							(start 0.1016 -0.1778)
							(mid 0.137521 -0.162921)
							(end 0.1524 -0.127)
						)
					)
					(width 0)
					(fill yes)
				)
			)
		)
		(pad "2" smd custom
			(at 0 0.2794 90)
			(size 0.0762 0.0762)
			(layers "B.Cu" "B.Mask" "B.Paste")
			(net "GND")
			(options
				(clearance outline)
				(anchor circle)
			)
			(primitives
				(gr_poly
					(pts
						(arc
							(start 0.1524 0.127)
							(mid 0.137521 0.162921)
							(end 0.1016 0.1778)
						)
						(arc
							(start -0.1016 0.1778)
							(mid -0.137521 0.162921)
							(end -0.1524 0.127)
						)
						(arc
							(start -0.1524 -0.127)
							(mid -0.137521 -0.162921)
							(end -0.1016 -0.1778)
						)
						(arc
							(start 0.1016 -0.1778)
							(mid 0.137521 -0.162921)
							(end 0.1524 -0.127)
						)
					)
					(width 0)
					(fill yes)
				)
			)
		)
	)
	(footprint ""
		(layer "B.Cu")
		(at 237.109 -20.447)
		(property "Reference" "R815"
			(at 0 0 0)
			(layer "B.SilkS")
			(hide yes)
			(effects
				(font
					(size 1.27 1.27)
				)
				(justify mirror)
			)
		)
		(property "Value" "4K7R2F-GP"
			(at -0.064008 -3.993896 0)
			(unlocked yes)
			(layer "B.Fab")
			(hide yes)
			(effects
				(font
					(size 1.016 1.016)
					(thickness 0.1524)
				)
				(justify mirror)
			)
		)
		(property "Device Type" "R402H16"
			(at -0.064008 -5.517896 0)
			(unlocked yes)
			(layer "B.Fab")
			(hide yes)
			(effects
				(font
					(size 1.016 1.016)
					(thickness 0.1524)
				)
				(justify mirror)
			)
		)
		(duplicate_pad_numbers_are_jumpers no)
		(fp_line
			(start -0.508 -0.9398)
			(end 0.508 -0.9398)
			(stroke
				(width 0.1524)
				(type default)
			)
			(layer "B.SilkS")
		)
		(fp_line
			(start 0.508 -0.9398)
			(end 0.508 0.9398)
			(stroke
				(width 0.1524)
				(type default)
			)
			(layer "B.SilkS")
		)
		(fp_rect
			(start 0.508 0.9398)
			(end -0.508 -0.9398)
			(stroke
				(width 0)
				(type default)
			)
			(fill no)
			(layer "B.CrtYd")
		)
		(fp_rect
			(start 0.508 0.9398)
			(end -0.508 -0.9398)
			(stroke
				(width 0)
				(type default)
			)
			(fill no)
			(layer "B.Fab")
		)
		(pad "1" smd custom
			(at 0 -0.4445 180)
			(size 0.1397 0.1397)
			(layers "B.Cu" "B.Mask" "B.Paste")
			(net "BOOTSTRAP7")
			(options
				(clearance outline)
				(anchor circle)
			)
			(primitives
				(gr_poly
					(pts
						(arc
							(start -0.1778 0.2794)
							(mid -0.249642 0.249642)
							(end -0.2794 0.1778)
						)
						(arc
							(start -0.2794 -0.1778)
							(mid -0.249642 -0.249642)
							(end -0.1778 -0.2794)
						)
						(arc
							(start 0.1778 -0.2794)
							(mid 0.249642 -0.249642)
							(end 0.2794 -0.1778)
						)
						(arc
							(start 0.2794 0.1778)
							(mid 0.249642 0.249642)
							(end 0.1778 0.2794)
						)
					)
					(width 0)
					(fill yes)
				)
			)
		)
		(pad "2" smd custom
			(at 0 0.4445 180)
			(size 0.1397 0.1397)
			(layers "B.Cu" "B.Mask" "B.Paste")
			(net "DUT_VDDO")
			(options
				(clearance outline)
				(anchor circle)
			)
			(primitives
				(gr_poly
					(pts
						(arc
							(start -0.1778 0.2794)
							(mid -0.249642 0.249642)
							(end -0.2794 0.1778)
						)
						(arc
							(start -0.2794 -0.1778)
							(mid -0.249642 -0.249642)
							(end -0.1778 -0.2794)
						)
						(arc
							(start 0.1778 -0.2794)
							(mid 0.249642 -0.249642)
							(end 0.2794 -0.1778)
						)
						(arc
							(start 0.2794 0.1778)
							(mid 0.249642 0.249642)
							(end 0.1778 0.2794)
						)
					)
					(width 0)
					(fill yes)
				)
			)
		)
	)
	(footprint ""
		(layer "B.Cu")
		(at 242.599972 -37.999924)
		(property "Reference" "TP265"
			(at 0 0 0)
			(layer "B.SilkS")
			(hide yes)
			(effects
				(font
					(size 1.27 1.27)
				)
				(justify mirror)
			)
		)
		(property "Value" "TPAD28-2-GP"
			(at 0.0127 -1.6637 0)
			(unlocked yes)
			(layer "B.Fab")
			(hide yes)
			(effects
				(font
					(size 1.016 1.016)
					(thickness 0.1524)
				)
				(justify mirror)
			)
		)
		(property "Device Type" "TPAD28"
			(at 0.0127 -3.1877 0)
			(unlocked yes)
			(layer "B.Fab")
			(hide yes)
			(effects
				(font
					(size 1.016 1.016)
					(thickness 0.1524)
				)
				(justify mirror)
			)
		)
		(duplicate_pad_numbers_are_jumpers no)
		(fp_poly
			(pts
				(arc
					(start 0.3556 0)
					(mid -0.3556 0)
					(end 0.3556 0)
				)
			)
			(stroke
				(width 0)
				(type default)
			)
			(fill no)
			(layer "B.CrtYd")
		)
		(fp_poly
			(pts
				(arc
					(start 0.6096 0)
					(mid -0.6096 0)
					(end 0.6096 0)
				)
			)
			(stroke
				(width 0)
				(type default)
			)
			(fill no)
			(layer "B.Fab")
		)
		(pad "1" smd circle
			(at 0 0 180)
			(size 0.7112 0.7112)
			(layers "B.Cu" "B.Mask" "B.Paste")
			(net "LBI_DATA_6")
		)
	)
	(footprint ""
		(layer "B.Cu")
		(at 43.942 -139.065)
		(property "Reference" "TP321"
			(at 0 0 0)
			(layer "B.SilkS")
			(hide yes)
			(effects
				(font
					(size 1.27 1.27)
				)
				(justify mirror)
			)
		)
		(property "Value" "TPAD28-2-GP"
			(at 0.0127 -1.6637 0)
			(unlocked yes)
			(layer "B.Fab")
			(hide yes)
			(effects
				(font
					(size 1.016 1.016)
					(thickness 0.1524)
				)
				(justify mirror)
			)
		)
		(property "Device Type" "TPAD28"
			(at 0.0127 -3.1877 0)
			(unlocked yes)
			(layer "B.Fab")
			(hide yes)
			(effects
				(font
					(size 1.016 1.016)
					(thickness 0.1524)
				)
				(justify mirror)
			)
		)
		(duplicate_pad_numbers_are_jumpers no)
		(fp_poly
			(pts
				(arc
					(start 0.3556 0)
					(mid -0.3556 0)
					(end 0.3556 0)
				)
			)
			(stroke
				(width 0)
				(type default)
			)
			(fill no)
			(layer "B.CrtYd")
		)
		(fp_poly
			(pts
				(arc
					(start 0.6096 0)
					(mid -0.6096 0)
					(end 0.6096 0)
				)
			)
			(stroke
				(width 0)
				(type default)
			)
			(fill no)
			(layer "B.Fab")
		)
		(pad "1" smd circle
			(at 0 0 180)
			(size 0.7112 0.7112)
			(layers "B.Cu" "B.Mask" "B.Paste")
			(net "TP_GPIOO4")
		)
	)
	(footprint ""
		(layer "B.Cu")
		(at 82.722212 -192.641474)
		(property "Reference" "R3231"
			(at 0 0 0)
			(layer "B.SilkS")
			(hide yes)
			(effects
				(font
					(size 1.27 1.27)
				)
				(justify mirror)
			)
		)
		(property "Value" "0R2J-2-GP"
			(at -0.064008 -3.993896 0)
			(unlocked yes)
			(layer "B.Fab")
			(hide yes)
			(effects
				(font
					(size 1.016 1.016)
					(thickness 0.1524)
				)
				(justify mirror)
			)
		)
		(property "Device Type" "R402H16"
			(at -0.064008 -5.517896 0)
			(unlocked yes)
			(layer "B.Fab")
			(hide yes)
			(effects
				(font
					(size 1.016 1.016)
					(thickness 0.1524)
				)
				(justify mirror)
			)
		)
		(duplicate_pad_numbers_are_jumpers no)
		(fp_line
			(start -0.508 -0.9398)
			(end 0.508 -0.9398)
			(stroke
				(width 0.1524)
				(type default)
			)
			(layer "B.SilkS")
		)
		(fp_line
			(start 0.508 -0.9398)
			(end 0.508 0.9398)
			(stroke
				(width 0.1524)
				(type default)
			)
			(layer "B.SilkS")
		)
		(fp_rect
			(start 0.508 0.9398)
			(end -0.508 -0.9398)
			(stroke
				(width 0)
				(type default)
			)
			(fill no)
			(layer "B.CrtYd")
		)
		(fp_rect
			(start 0.508 0.9398)
			(end -0.508 -0.9398)
			(stroke
				(width 0)
				(type default)
			)
			(fill no)
			(layer "B.Fab")
		)
		(pad "1" smd custom
			(at 0 -0.4445 180)
			(size 0.1397 0.1397)
			(layers "B.Cu" "B.Mask" "B.Paste")
			(net "SSD_PERST#10")
			(options
				(clearance outline)
				(anchor circle)
			)
			(primitives
				(gr_poly
					(pts
						(arc
							(start -0.1778 0.2794)
							(mid -0.249642 0.249642)
							(end -0.2794 0.1778)
						)
						(arc
							(start -0.2794 -0.1778)
							(mid -0.249642 -0.249642)
							(end -0.1778 -0.2794)
						)
						(arc
							(start 0.1778 -0.2794)
							(mid 0.249642 -0.249642)
							(end 0.2794 -0.1778)
						)
						(arc
							(start 0.2794 0.1778)
							(mid 0.249642 0.249642)
							(end 0.1778 0.2794)
						)
					)
					(width 0)
					(fill yes)
				)
			)
		)
		(pad "2" smd custom
			(at 0 0.4445 180)
			(size 0.1397 0.1397)
			(layers "B.Cu" "B.Mask" "B.Paste")
			(net "SSD_PERST#0_B10")
			(options
				(clearance outline)
				(anchor circle)
			)
			(primitives
				(gr_poly
					(pts
						(arc
							(start -0.1778 0.2794)
							(mid -0.249642 0.249642)
							(end -0.2794 0.1778)
						)
						(arc
							(start -0.2794 -0.1778)
							(mid -0.249642 -0.249642)
							(end -0.1778 -0.2794)
						)
						(arc
							(start 0.1778 -0.2794)
							(mid 0.249642 -0.249642)
							(end 0.2794 -0.1778)
						)
						(arc
							(start 0.2794 0.1778)
							(mid 0.249642 0.249642)
							(end 0.1778 0.2794)
						)
					)
					(width 0)
					(fill yes)
				)
			)
		)
	)
	(footprint ""
		(layer "B.Cu")
		(at 177.292 -207.5942 90)
		(property "Reference" "C4148"
			(at 0 0 90)
			(layer "B.SilkS")
			(hide yes)
			(effects
				(font
					(size 1.27 1.27)
				)
				(justify mirror)
			)
		)
		(property "Value" "SCD1U25V3KX-GP"
			(at 0 -2.8194 90)
			(unlocked yes)
			(layer "B.Fab")
			(hide yes)
			(effects
				(font
					(size 1.016 1.016)
					(thickness 0.1524)
				)
				(justify mirror)
			)
		)
		(property "Device Type" "C603H36"
			(at 0 -4.3434 90)
			(unlocked yes)
			(layer "B.Fab")
			(hide yes)
			(effects
				(font
					(size 1.016 1.016)
					(thickness 0.1524)
				)
				(justify mirror)
			)
		)
		(duplicate_pad_numbers_are_jumpers no)
		(fp_line
			(start -0.508 0)
			(end 0.508 0)
			(stroke
				(width 0.2032)
				(type default)
			)
			(layer "B.SilkS")
		)
		(fp_rect
			(start 0.5842 1.3335)
			(end -0.5842 -1.3335)
			(stroke
				(width 0)
				(type default)
			)
			(fill no)
			(layer "B.CrtYd")
		)
		(fp_rect
			(start 0.5842 1.3335)
			(end -0.5842 -1.3335)
			(stroke
				(width 0)
				(type default)
			)
			(fill no)
			(layer "B.Fab")
		)
		(pad "1" smd custom
			(at 0 -0.762 270)
			(size 0.2159 0.2159)
			(layers "B.Cu" "B.Mask" "B.Paste")
			(net "GND")
			(options
				(clearance outline)
				(anchor circle)
			)
			(primitives
				(gr_poly
					(pts
						(arc
							(start -0.3302 0.4318)
							(mid -0.402042 0.402042)
							(end -0.4318 0.3302)
						)
						(arc
							(start -0.4318 -0.3302)
							(mid -0.402042 -0.402042)
							(end -0.3302 -0.4318)
						)
						(arc
							(start 0.3302 -0.4318)
							(mid 0.402042 -0.402042)
							(end 0.4318 -0.3302)
						)
						(arc
							(start 0.4318 0.3302)
							(mid 0.402042 0.402042)
							(end 0.3302 0.4318)
						)
					)
					(width 0)
					(fill yes)
				)
			)
		)
		(pad "2" smd custom
			(at 0 0.762 270)
			(size 0.2159 0.2159)
			(layers "B.Cu" "B.Mask" "B.Paste")
			(net "SSD_PWREN7_R")
			(options
				(clearance outline)
				(anchor circle)
			)
			(primitives
				(gr_poly
					(pts
						(arc
							(start -0.3302 0.4318)
							(mid -0.402042 0.402042)
							(end -0.4318 0.3302)
						)
						(arc
							(start -0.4318 -0.3302)
							(mid -0.402042 -0.402042)
							(end -0.3302 -0.4318)
						)
						(arc
							(start 0.3302 -0.4318)
							(mid 0.402042 -0.402042)
							(end 0.4318 -0.3302)
						)
						(arc
							(start 0.4318 0.3302)
							(mid 0.402042 0.402042)
							(end 0.3302 0.4318)
						)
					)
					(width 0)
					(fill yes)
				)
			)
		)
	)
	(footprint ""
		(layer "B.Cu")
		(at 10.922 -107.188 90)
		(property "Reference" "PC85"
			(at 0 0 90)
			(layer "B.SilkS")
			(hide yes)
			(effects
				(font
					(size 1.27 1.27)
				)
				(justify mirror)
			)
		)
		(property "Value" "SCD01U25V2KX-3GP"
			(at -1.1811 -2.7051 90)
			(unlocked yes)
			(layer "B.Fab")
			(hide yes)
			(effects
				(font
					(size 1.016 1.016)
					(thickness 0.1524)
				)
				(justify mirror)
			)
		)
		(property "Device Type" "C402H22"
			(at -1.1811 -4.2291 90)
			(unlocked yes)
			(layer "B.Fab")
			(hide yes)
			(effects
				(font
					(size 1.016 1.016)
					(thickness 0.1524)
				)
				(justify mirror)
			)
		)
		(duplicate_pad_numbers_are_jumpers no)
		(fp_rect
			(start 0.4318 0.9525)
			(end -0.4318 -0.9525)
			(stroke
				(width 0)
				(type default)
			)
			(fill no)
			(layer "B.CrtYd")
		)
		(fp_rect
			(start 0.4318 0.9525)
			(end -0.4318 -0.9525)
			(stroke
				(width 0)
				(type default)
			)
			(fill no)
			(layer "B.Fab")
		)
		(pad "1" smd custom
			(at 0 -0.4445 270)
			(size 0.1524 0.1524)
			(layers "B.Cu" "B.Mask" "B.Paste")
			(net "VR_P1V26_STBY_EN_R")
			(options
				(clearance outline)
				(anchor circle)
			)
			(primitives
				(gr_poly
					(pts
						(arc
							(start 0.3048 0.2032)
							(mid 0.275042 0.275042)
							(end 0.2032 0.3048)
						)
						(arc
							(start -0.2032 0.3048)
							(mid -0.275042 0.275042)
							(end -0.3048 0.2032)
						)
						(arc
							(start -0.3048 -0.2032)
							(mid -0.275042 -0.275042)
							(end -0.2032 -0.3048)
						)
						(arc
							(start 0.2032 -0.3048)
							(mid 0.275042 -0.275042)
							(end 0.3048 -0.2032)
						)
					)
					(width 0)
					(fill yes)
				)
			)
		)
		(pad "2" smd custom
			(at 0 0.4445 270)
			(size 0.1524 0.1524)
			(layers "B.Cu" "B.Mask" "B.Paste")
			(net "GND")
			(options
				(clearance outline)
				(anchor circle)
			)
			(primitives
				(gr_poly
					(pts
						(arc
							(start 0.3048 0.2032)
							(mid 0.275042 0.275042)
							(end 0.2032 0.3048)
						)
						(arc
							(start -0.2032 0.3048)
							(mid -0.275042 0.275042)
							(end -0.3048 0.2032)
						)
						(arc
							(start -0.3048 -0.2032)
							(mid -0.275042 -0.275042)
							(end -0.2032 -0.3048)
						)
						(arc
							(start 0.2032 -0.3048)
							(mid 0.275042 -0.275042)
							(end 0.3048 -0.2032)
						)
					)
					(width 0)
					(fill yes)
				)
			)
		)
	)
	(footprint ""
		(layer "B.Cu")
		(at 136.652 -202.819)
		(property "Reference" "U70"
			(at 0 0 0)
			(layer "B.SilkS")
			(hide yes)
			(effects
				(font
					(size 1.27 1.27)
				)
				(justify mirror)
			)
		)
		(property "Value" "SN74LVC1G08DCKR-GP"
			(at 2.3368 -8.6868 0)
			(unlocked yes)
			(layer "B.Fab")
			(hide yes)
			(effects
				(font
					(size 1.016 1.016)
					(thickness 0.1524)
				)
				(justify mirror)
			)
		)
		(property "Device Type" "SC70-5H44"
			(at 2.3114 -10.414 0)
			(unlocked yes)
			(layer "B.Fab")
			(hide yes)
			(effects
				(font
					(size 1.016 1.016)
					(thickness 0.1524)
				)
				(justify mirror)
			)
		)
		(duplicate_pad_numbers_are_jumpers no)
		(fp_line
			(start -1.3843 -1.8034)
			(end -1.3843 -1.1176)
			(stroke
				(width 0.3302)
				(type default)
			)
			(layer "B.SilkS")
		)
		(fp_line
			(start -1.27 -1.7018)
			(end -1.27 1.7018)
			(stroke
				(width 0.1524)
				(type default)
			)
			(layer "B.SilkS")
		)
		(fp_line
			(start -1.27 1.7018)
			(end 1.27 1.7018)
			(stroke
				(width 0.1524)
				(type default)
			)
			(layer "B.SilkS")
		)
		(fp_line
			(start -0.6604 -1.8034)
			(end -1.3843 -1.8034)
			(stroke
				(width 0.3302)
				(type default)
			)
			(layer "B.SilkS")
		)
		(fp_line
			(start 1.27 -1.7018)
			(end -1.27 -1.7018)
			(stroke
				(width 0.1524)
				(type default)
			)
			(layer "B.SilkS")
		)
		(fp_line
			(start 1.27 1.7018)
			(end 1.27 -1.7018)
			(stroke
				(width 0.1524)
				(type default)
			)
			(layer "B.SilkS")
		)
		(fp_rect
			(start 1.524 1.9558)
			(end -1.524 -1.9558)
			(stroke
				(width 0)
				(type default)
			)
			(fill no)
			(layer "B.CrtYd")
		)
		(fp_poly
			(pts
				(xy 1.524 -1.9558) (xy -1.524 -1.9558) (xy -1.524 1.9558) (xy 1.524 1.9558)
			)
			(stroke
				(width 0)
				(type default)
			)
			(fill no)
			(layer "B.Fab")
		)
		(pad "1" smd rect
			(at -0.65024 -0.8255 180)
			(size 0.4064 1.2192)
			(layers "B.Cu" "B.Mask" "B.Paste")
			(net "BMC_SSD_RST#0_A6")
		)
		(pad "2" smd rect
			(at 0 -0.8255 180)
			(size 0.4064 1.2192)
			(layers "B.Cu" "B.Mask" "B.Paste")
			(net "SSD_PERST#0_B6")
		)
		(pad "3" smd rect
			(at 0.65024 -0.8255 180)
			(size 0.4064 1.2192)
			(layers "B.Cu" "B.Mask" "B.Paste")
			(net "GND")
		)
		(pad "4" smd rect
			(at 0.65024 0.8255 180)
			(size 0.4064 1.2192)
			(layers "B.Cu" "B.Mask" "B.Paste")
			(net "SSD_PERST_Y6")
		)
		(pad "5" smd rect
			(at -0.65024 0.8255 180)
			(size 0.4064 1.2192)
			(layers "B.Cu" "B.Mask" "B.Paste")
			(net "P3V3_STBY")
		)
	)
	(footprint ""
		(layer "B.Cu")
		(at 336.5246 -175.7426)
		(property "Reference" "C3206"
			(at 0 0 0)
			(layer "B.SilkS")
			(hide yes)
			(effects
				(font
					(size 1.27 1.27)
				)
				(justify mirror)
			)
		)
		(property "Value" "SCD1U25V2KX-2-GP"
			(at -1.1811 -2.7051 0)
			(unlocked yes)
			(layer "B.Fab")
			(hide yes)
			(effects
				(font
					(size 1.016 1.016)
					(thickness 0.1524)
				)
				(justify mirror)
			)
		)
		(property "Device Type" "C402H22"
			(at -1.1811 -4.2291 0)
			(unlocked yes)
			(layer "B.Fab")
			(hide yes)
			(effects
				(font
					(size 1.016 1.016)
					(thickness 0.1524)
				)
				(justify mirror)
			)
		)
		(duplicate_pad_numbers_are_jumpers no)
		(fp_rect
			(start 0.4318 0.9525)
			(end -0.4318 -0.9525)
			(stroke
				(width 0)
				(type default)
			)
			(fill no)
			(layer "B.CrtYd")
		)
		(fp_rect
			(start 0.4318 0.9525)
			(end -0.4318 -0.9525)
			(stroke
				(width 0)
				(type default)
			)
			(fill no)
			(layer "B.Fab")
		)
		(pad "1" smd custom
			(at 0 -0.4445 180)
			(size 0.1524 0.1524)
			(layers "B.Cu" "B.Mask" "B.Paste")
			(net "P3V3_STBY")
			(options
				(clearance outline)
				(anchor circle)
			)
			(primitives
				(gr_poly
					(pts
						(arc
							(start 0.3048 0.2032)
							(mid 0.275042 0.275042)
							(end 0.2032 0.3048)
						)
						(arc
							(start -0.2032 0.3048)
							(mid -0.275042 0.275042)
							(end -0.3048 0.2032)
						)
						(arc
							(start -0.3048 -0.2032)
							(mid -0.275042 -0.275042)
							(end -0.2032 -0.3048)
						)
						(arc
							(start 0.2032 -0.3048)
							(mid 0.275042 -0.275042)
							(end 0.3048 -0.2032)
						)
					)
					(width 0)
					(fill yes)
				)
			)
		)
		(pad "2" smd custom
			(at 0 0.4445 180)
			(size 0.1524 0.1524)
			(layers "B.Cu" "B.Mask" "B.Paste")
			(net "GND")
			(options
				(clearance outline)
				(anchor circle)
			)
			(primitives
				(gr_poly
					(pts
						(arc
							(start 0.3048 0.2032)
							(mid 0.275042 0.275042)
							(end 0.2032 0.3048)
						)
						(arc
							(start -0.2032 0.3048)
							(mid -0.275042 0.275042)
							(end -0.3048 0.2032)
						)
						(arc
							(start -0.3048 -0.2032)
							(mid -0.275042 -0.275042)
							(end -0.2032 -0.3048)
						)
						(arc
							(start 0.2032 -0.3048)
							(mid 0.275042 -0.275042)
							(end 0.3048 -0.2032)
						)
					)
					(width 0)
					(fill yes)
				)
			)
		)
	)
	(footprint ""
		(layer "B.Cu")
		(at 13.506958 -75.786234 90)
		(property "Reference" "C622"
			(at 0 0 90)
			(layer "B.SilkS")
			(hide yes)
			(effects
				(font
					(size 1.27 1.27)
				)
				(justify mirror)
			)
		)
		(property "Value" "SCD1U16V2KX-3GP"
			(at -1.1811 -2.7051 90)
			(unlocked yes)
			(layer "B.Fab")
			(hide yes)
			(effects
				(font
					(size 1.016 1.016)
					(thickness 0.1524)
				)
				(justify mirror)
			)
		)
		(property "Device Type" "C402H22"
			(at -1.1811 -4.2291 90)
			(unlocked yes)
			(layer "B.Fab")
			(hide yes)
			(effects
				(font
					(size 1.016 1.016)
					(thickness 0.1524)
				)
				(justify mirror)
			)
		)
		(duplicate_pad_numbers_are_jumpers no)
		(fp_rect
			(start 0.4318 0.9525)
			(end -0.4318 -0.9525)
			(stroke
				(width 0)
				(type default)
			)
			(fill no)
			(layer "B.CrtYd")
		)
		(fp_rect
			(start 0.4318 0.9525)
			(end -0.4318 -0.9525)
			(stroke
				(width 0)
				(type default)
			)
			(fill no)
			(layer "B.Fab")
		)
		(pad "1" smd custom
			(at 0 -0.4445 270)
			(size 0.1524 0.1524)
			(layers "B.Cu" "B.Mask" "B.Paste")
			(net "P1V5_I210")
			(options
				(clearance outline)
				(anchor circle)
			)
			(primitives
				(gr_poly
					(pts
						(arc
							(start 0.3048 0.2032)
							(mid 0.275042 0.275042)
							(end 0.2032 0.3048)
						)
						(arc
							(start -0.2032 0.3048)
							(mid -0.275042 0.275042)
							(end -0.3048 0.2032)
						)
						(arc
							(start -0.3048 -0.2032)
							(mid -0.275042 -0.275042)
							(end -0.2032 -0.3048)
						)
						(arc
							(start 0.2032 -0.3048)
							(mid 0.275042 -0.275042)
							(end 0.3048 -0.2032)
						)
					)
					(width 0)
					(fill yes)
				)
			)
		)
		(pad "2" smd custom
			(at 0 0.4445 270)
			(size 0.1524 0.1524)
			(layers "B.Cu" "B.Mask" "B.Paste")
			(net "GND")
			(options
				(clearance outline)
				(anchor circle)
			)
			(primitives
				(gr_poly
					(pts
						(arc
							(start 0.3048 0.2032)
							(mid 0.275042 0.275042)
							(end 0.2032 0.3048)
						)
						(arc
							(start -0.2032 0.3048)
							(mid -0.275042 0.275042)
							(end -0.3048 0.2032)
						)
						(arc
							(start -0.3048 -0.2032)
							(mid -0.275042 -0.275042)
							(end -0.2032 -0.3048)
						)
						(arc
							(start 0.2032 -0.3048)
							(mid 0.275042 -0.275042)
							(end 0.3048 -0.2032)
						)
					)
					(width 0)
					(fill yes)
				)
			)
		)
	)
	(footprint ""
		(layer "B.Cu")
		(at 50.292 -125.349)
		(property "Reference" "TP180"
			(at 0 0 0)
			(layer "B.SilkS")
			(hide yes)
			(effects
				(font
					(size 1.27 1.27)
				)
				(justify mirror)
			)
		)
		(property "Value" "TPAD28-2-GP"
			(at 0.0127 -1.6637 0)
			(unlocked yes)
			(layer "B.Fab")
			(hide yes)
			(effects
				(font
					(size 1.016 1.016)
					(thickness 0.1524)
				)
				(justify mirror)
			)
		)
		(property "Device Type" "TPAD28"
			(at 0.0127 -3.1877 0)
			(unlocked yes)
			(layer "B.Fab")
			(hide yes)
			(effects
				(font
					(size 1.016 1.016)
					(thickness 0.1524)
				)
				(justify mirror)
			)
		)
		(duplicate_pad_numbers_are_jumpers no)
		(fp_poly
			(pts
				(arc
					(start 0.3556 0)
					(mid -0.3556 0)
					(end 0.3556 0)
				)
			)
			(stroke
				(width 0)
				(type default)
			)
			(fill no)
			(layer "B.CrtYd")
		)
		(fp_poly
			(pts
				(arc
					(start 0.6096 0)
					(mid -0.6096 0)
					(end 0.6096 0)
				)
			)
			(stroke
				(width 0)
				(type default)
			)
			(fill no)
			(layer "B.Fab")
		)
		(pad "1" smd circle
			(at 0 0 180)
			(size 0.7112 0.7112)
			(layers "B.Cu" "B.Mask" "B.Paste")
			(net "JTAG_BMC_TDO")
		)
	)
	(footprint ""
		(layer "B.Cu")
		(at 18.3134 -69.1134 180)
		(property "Reference" "R425"
			(at 0 0 0)
			(layer "B.SilkS")
			(hide yes)
			(effects
				(font
					(size 1.27 1.27)
				)
				(justify mirror)
			)
		)
		(property "Value" "0R3J-0-U-GP"
			(at 0.0254 -2.5146 180)
			(unlocked yes)
			(layer "B.Fab")
			(hide yes)
			(effects
				(font
					(size 1.016 1.016)
					(thickness 0.1524)
				)
				(justify mirror)
			)
		)
		(property "Device Type" "R603H22"
			(at 0.0254 -4.0386 180)
			(unlocked yes)
			(layer "B.Fab")
			(hide yes)
			(effects
				(font
					(size 1.016 1.016)
					(thickness 0.1524)
				)
				(justify mirror)
			)
		)
		(duplicate_pad_numbers_are_jumpers no)
		(fp_line
			(start 0.4826 0)
			(end 0.2032 0)
			(stroke
				(width 0.2032)
				(type default)
			)
			(layer "B.SilkS")
		)
		(fp_line
			(start -0.2032 0)
			(end -0.4826 0)
			(stroke
				(width 0.2032)
				(type default)
			)
			(layer "B.SilkS")
		)
		(fp_rect
			(start 0.5842 1.3335)
			(end -0.5842 -1.3335)
			(stroke
				(width 0)
				(type default)
			)
			(fill no)
			(layer "B.CrtYd")
		)
		(fp_rect
			(start 0.5842 1.3335)
			(end -0.5842 -1.3335)
			(stroke
				(width 0)
				(type default)
			)
			(fill no)
			(layer "B.Fab")
		)
		(pad "1" smd custom
			(at 0 -0.762)
			(size 0.2159 0.2159)
			(layers "B.Cu" "B.Mask" "B.Paste")
			(net "P3V3_STBY")
			(options
				(clearance outline)
				(anchor circle)
			)
			(primitives
				(gr_poly
					(pts
						(arc
							(start -0.3302 0.4318)
							(mid -0.402042 0.402042)
							(end -0.4318 0.3302)
						)
						(arc
							(start -0.4318 -0.3302)
							(mid -0.402042 -0.402042)
							(end -0.3302 -0.4318)
						)
						(arc
							(start 0.3302 -0.4318)
							(mid 0.402042 -0.402042)
							(end 0.4318 -0.3302)
						)
						(arc
							(start 0.4318 0.3302)
							(mid 0.402042 0.402042)
							(end 0.3302 0.4318)
						)
					)
					(width 0)
					(fill yes)
				)
			)
		)
		(pad "2" smd custom
			(at 0 0.762)
			(size 0.2159 0.2159)
			(layers "B.Cu" "B.Mask" "B.Paste")
			(net "LAN1_51")
			(options
				(clearance outline)
				(anchor circle)
			)
			(primitives
				(gr_poly
					(pts
						(arc
							(start -0.3302 0.4318)
							(mid -0.402042 0.402042)
							(end -0.4318 0.3302)
						)
						(arc
							(start -0.4318 -0.3302)
							(mid -0.402042 -0.402042)
							(end -0.3302 -0.4318)
						)
						(arc
							(start 0.3302 -0.4318)
							(mid 0.402042 -0.402042)
							(end 0.4318 -0.3302)
						)
						(arc
							(start 0.4318 0.3302)
							(mid 0.402042 0.402042)
							(end 0.3302 0.4318)
						)
					)
					(width 0)
					(fill yes)
				)
			)
		)
	)
	(footprint ""
		(layer "B.Cu")
		(at 264.19556 -2.352802 180)
		(property "Reference" "R202"
			(at 0 0 0)
			(layer "B.SilkS")
			(hide yes)
			(effects
				(font
					(size 1.27 1.27)
				)
				(justify mirror)
			)
		)
		(property "Value" "49D9R2D-GP"
			(at -0.064008 -3.993896 180)
			(unlocked yes)
			(layer "B.Fab")
			(hide yes)
			(effects
				(font
					(size 1.016 1.016)
					(thickness 0.1524)
				)
				(justify mirror)
			)
		)
		(property "Device Type" "R402H16"
			(at -0.064008 -5.517896 180)
			(unlocked yes)
			(layer "B.Fab")
			(hide yes)
			(effects
				(font
					(size 1.016 1.016)
					(thickness 0.1524)
				)
				(justify mirror)
			)
		)
		(duplicate_pad_numbers_are_jumpers no)
		(fp_line
			(start 0.508 -0.9398)
			(end 0.508 0.9398)
			(stroke
				(width 0.1524)
				(type default)
			)
			(layer "B.SilkS")
		)
		(fp_line
			(start -0.508 -0.9398)
			(end 0.508 -0.9398)
			(stroke
				(width 0.1524)
				(type default)
			)
			(layer "B.SilkS")
		)
		(fp_rect
			(start 0.508 0.9398)
			(end -0.508 -0.9398)
			(stroke
				(width 0)
				(type default)
			)
			(fill no)
			(layer "B.CrtYd")
		)
		(fp_rect
			(start 0.508 0.9398)
			(end -0.508 -0.9398)
			(stroke
				(width 0)
				(type default)
			)
			(fill no)
			(layer "B.Fab")
		)
		(pad "1" smd custom
			(at 0 -0.4445)
			(size 0.1397 0.1397)
			(layers "B.Cu" "B.Mask" "B.Paste")
			(net "TEMP_SENSOR_DXN_BJT")
			(options
				(clearance outline)
				(anchor circle)
			)
			(primitives
				(gr_poly
					(pts
						(arc
							(start -0.1778 0.2794)
							(mid -0.249642 0.249642)
							(end -0.2794 0.1778)
						)
						(arc
							(start -0.2794 -0.1778)
							(mid -0.249642 -0.249642)
							(end -0.1778 -0.2794)
						)
						(arc
							(start 0.1778 -0.2794)
							(mid 0.249642 -0.249642)
							(end 0.2794 -0.1778)
						)
						(arc
							(start 0.2794 0.1778)
							(mid 0.249642 0.249642)
							(end 0.1778 0.2794)
						)
					)
					(width 0)
					(fill yes)
				)
			)
		)
		(pad "2" smd custom
			(at 0 0.4445)
			(size 0.1397 0.1397)
			(layers "B.Cu" "B.Mask" "B.Paste")
			(net "TEMP_SENSOR_DXN")
			(options
				(clearance outline)
				(anchor circle)
			)
			(primitives
				(gr_poly
					(pts
						(arc
							(start -0.1778 0.2794)
							(mid -0.249642 0.249642)
							(end -0.2794 0.1778)
						)
						(arc
							(start -0.2794 -0.1778)
							(mid -0.249642 -0.249642)
							(end -0.1778 -0.2794)
						)
						(arc
							(start 0.1778 -0.2794)
							(mid 0.249642 -0.249642)
							(end 0.2794 -0.1778)
						)
						(arc
							(start 0.2794 0.1778)
							(mid 0.249642 0.249642)
							(end 0.1778 0.2794)
						)
					)
					(width 0)
					(fill yes)
				)
			)
		)
	)
	(footprint ""
		(layer "B.Cu")
		(at 56.092852 -110.14583)
		(property "Reference" "R327"
			(at 0 0 0)
			(layer "B.SilkS")
			(hide yes)
			(effects
				(font
					(size 1.27 1.27)
				)
				(justify mirror)
			)
		)
		(property "Value" "4K7R2F-GP"
			(at -0.064008 -3.993896 0)
			(unlocked yes)
			(layer "B.Fab")
			(hide yes)
			(effects
				(font
					(size 1.016 1.016)
					(thickness 0.1524)
				)
				(justify mirror)
			)
		)
		(property "Device Type" "R402H16"
			(at -0.064008 -5.517896 0)
			(unlocked yes)
			(layer "B.Fab")
			(hide yes)
			(effects
				(font
					(size 1.016 1.016)
					(thickness 0.1524)
				)
				(justify mirror)
			)
		)
		(duplicate_pad_numbers_are_jumpers no)
		(fp_line
			(start -0.508 -0.9398)
			(end 0.508 -0.9398)
			(stroke
				(width 0.1524)
				(type default)
			)
			(layer "B.SilkS")
		)
		(fp_line
			(start 0.508 -0.9398)
			(end 0.508 0.9398)
			(stroke
				(width 0.1524)
				(type default)
			)
			(layer "B.SilkS")
		)
		(fp_rect
			(start 0.508 0.9398)
			(end -0.508 -0.9398)
			(stroke
				(width 0)
				(type default)
			)
			(fill no)
			(layer "B.CrtYd")
		)
		(fp_rect
			(start 0.508 0.9398)
			(end -0.508 -0.9398)
			(stroke
				(width 0)
				(type default)
			)
			(fill no)
			(layer "B.Fab")
		)
		(pad "1" smd custom
			(at 0 -0.4445 180)
			(size 0.1397 0.1397)
			(layers "B.Cu" "B.Mask" "B.Paste")
			(net "P3V3_STBY")
			(options
				(clearance outline)
				(anchor circle)
			)
			(primitives
				(gr_poly
					(pts
						(arc
							(start -0.1778 0.2794)
							(mid -0.249642 0.249642)
							(end -0.2794 0.1778)
						)
						(arc
							(start -0.2794 -0.1778)
							(mid -0.249642 -0.249642)
							(end -0.1778 -0.2794)
						)
						(arc
							(start 0.1778 -0.2794)
							(mid 0.249642 -0.249642)
							(end 0.2794 -0.1778)
						)
						(arc
							(start 0.2794 0.1778)
							(mid 0.249642 0.249642)
							(end 0.1778 0.2794)
						)
					)
					(width 0)
					(fill yes)
				)
			)
		)
		(pad "2" smd custom
			(at 0 0.4445 180)
			(size 0.1397 0.1397)
			(layers "B.Cu" "B.Mask" "B.Paste")
			(net "I2C6_LS_G1")
			(options
				(clearance outline)
				(anchor circle)
			)
			(primitives
				(gr_poly
					(pts
						(arc
							(start -0.1778 0.2794)
							(mid -0.249642 0.249642)
							(end -0.2794 0.1778)
						)
						(arc
							(start -0.2794 -0.1778)
							(mid -0.249642 -0.249642)
							(end -0.1778 -0.2794)
						)
						(arc
							(start 0.1778 -0.2794)
							(mid 0.249642 -0.249642)
							(end 0.2794 -0.1778)
						)
						(arc
							(start 0.2794 0.1778)
							(mid 0.249642 0.249642)
							(end 0.1778 0.2794)
						)
					)
					(width 0)
					(fill yes)
				)
			)
		)
	)
	(footprint ""
		(layer "B.Cu")
		(at 240.538 -20.447)
		(property "Reference" "R807"
			(at 0 0 0)
			(layer "B.SilkS")
			(hide yes)
			(effects
				(font
					(size 1.27 1.27)
				)
				(justify mirror)
			)
		)
		(property "Value" "4K7R2F-GP"
			(at -0.064008 -3.993896 0)
			(unlocked yes)
			(layer "B.Fab")
			(hide yes)
			(effects
				(font
					(size 1.016 1.016)
					(thickness 0.1524)
				)
				(justify mirror)
			)
		)
		(property "Device Type" "R402H16"
			(at -0.064008 -5.517896 0)
			(unlocked yes)
			(layer "B.Fab")
			(hide yes)
			(effects
				(font
					(size 1.016 1.016)
					(thickness 0.1524)
				)
				(justify mirror)
			)
		)
		(duplicate_pad_numbers_are_jumpers no)
		(fp_line
			(start -0.508 -0.9398)
			(end 0.508 -0.9398)
			(stroke
				(width 0.1524)
				(type default)
			)
			(layer "B.SilkS")
		)
		(fp_line
			(start 0.508 -0.9398)
			(end 0.508 0.9398)
			(stroke
				(width 0.1524)
				(type default)
			)
			(layer "B.SilkS")
		)
		(fp_rect
			(start 0.508 0.9398)
			(end -0.508 -0.9398)
			(stroke
				(width 0)
				(type default)
			)
			(fill no)
			(layer "B.CrtYd")
		)
		(fp_rect
			(start 0.508 0.9398)
			(end -0.508 -0.9398)
			(stroke
				(width 0)
				(type default)
			)
			(fill no)
			(layer "B.Fab")
		)
		(pad "1" smd custom
			(at 0 -0.4445 180)
			(size 0.1397 0.1397)
			(layers "B.Cu" "B.Mask" "B.Paste")
			(net "BOOTSTRAP3")
			(options
				(clearance outline)
				(anchor circle)
			)
			(primitives
				(gr_poly
					(pts
						(arc
							(start -0.1778 0.2794)
							(mid -0.249642 0.249642)
							(end -0.2794 0.1778)
						)
						(arc
							(start -0.2794 -0.1778)
							(mid -0.249642 -0.249642)
							(end -0.1778 -0.2794)
						)
						(arc
							(start 0.1778 -0.2794)
							(mid 0.249642 -0.249642)
							(end 0.2794 -0.1778)
						)
						(arc
							(start 0.2794 0.1778)
							(mid 0.249642 0.249642)
							(end 0.1778 0.2794)
						)
					)
					(width 0)
					(fill yes)
				)
			)
		)
		(pad "2" smd custom
			(at 0 0.4445 180)
			(size 0.1397 0.1397)
			(layers "B.Cu" "B.Mask" "B.Paste")
			(net "DUT_VDDO")
			(options
				(clearance outline)
				(anchor circle)
			)
			(primitives
				(gr_poly
					(pts
						(arc
							(start -0.1778 0.2794)
							(mid -0.249642 0.249642)
							(end -0.2794 0.1778)
						)
						(arc
							(start -0.2794 -0.1778)
							(mid -0.249642 -0.249642)
							(end -0.1778 -0.2794)
						)
						(arc
							(start 0.1778 -0.2794)
							(mid 0.249642 -0.249642)
							(end 0.2794 -0.1778)
						)
						(arc
							(start 0.2794 0.1778)
							(mid 0.249642 0.249642)
							(end 0.1778 0.2794)
						)
					)
					(width 0)
					(fill yes)
				)
			)
		)
	)
	(footprint ""
		(layer "B.Cu")
		(at 62.357 -34.036 180)
		(property "Reference" "PR35"
			(at 0 0 0)
			(layer "B.SilkS")
			(hide yes)
			(effects
				(font
					(size 1.27 1.27)
				)
				(justify mirror)
			)
		)
		(property "Value" "619KR2F-GP"
			(at -0.064008 -3.993896 180)
			(unlocked yes)
			(layer "B.Fab")
			(hide yes)
			(effects
				(font
					(size 1.016 1.016)
					(thickness 0.1524)
				)
				(justify mirror)
			)
		)
		(property "Device Type" "R402H16"
			(at -0.064008 -5.517896 180)
			(unlocked yes)
			(layer "B.Fab")
			(hide yes)
			(effects
				(font
					(size 1.016 1.016)
					(thickness 0.1524)
				)
				(justify mirror)
			)
		)
		(duplicate_pad_numbers_are_jumpers no)
		(fp_line
			(start 0.508 -0.9398)
			(end 0.508 0.9398)
			(stroke
				(width 0.1524)
				(type default)
			)
			(layer "B.SilkS")
		)
		(fp_line
			(start -0.508 -0.9398)
			(end 0.508 -0.9398)
			(stroke
				(width 0.1524)
				(type default)
			)
			(layer "B.SilkS")
		)
		(fp_rect
			(start 0.508 0.9398)
			(end -0.508 -0.9398)
			(stroke
				(width 0)
				(type default)
			)
			(fill no)
			(layer "B.CrtYd")
		)
		(fp_rect
			(start 0.508 0.9398)
			(end -0.508 -0.9398)
			(stroke
				(width 0)
				(type default)
			)
			(fill no)
			(layer "B.Fab")
		)
		(pad "1" smd custom
			(at 0 -0.4445)
			(size 0.1397 0.1397)
			(layers "B.Cu" "B.Mask" "B.Paste")
			(net "AGND_P3V3_STBY")
			(options
				(clearance outline)
				(anchor circle)
			)
			(primitives
				(gr_poly
					(pts
						(arc
							(start -0.1778 0.2794)
							(mid -0.249642 0.249642)
							(end -0.2794 0.1778)
						)
						(arc
							(start -0.2794 -0.1778)
							(mid -0.249642 -0.249642)
							(end -0.1778 -0.2794)
						)
						(arc
							(start 0.1778 -0.2794)
							(mid 0.249642 -0.249642)
							(end 0.2794 -0.1778)
						)
						(arc
							(start 0.2794 0.1778)
							(mid 0.249642 0.249642)
							(end 0.1778 0.2794)
						)
					)
					(width 0)
					(fill yes)
				)
			)
		)
		(pad "2" smd custom
			(at 0 0.4445)
			(size 0.1397 0.1397)
			(layers "B.Cu" "B.Mask" "B.Paste")
			(net "P3V3_STBY_RF")
			(options
				(clearance outline)
				(anchor circle)
			)
			(primitives
				(gr_poly
					(pts
						(arc
							(start -0.1778 0.2794)
							(mid -0.249642 0.249642)
							(end -0.2794 0.1778)
						)
						(arc
							(start -0.2794 -0.1778)
							(mid -0.249642 -0.249642)
							(end -0.1778 -0.2794)
						)
						(arc
							(start 0.1778 -0.2794)
							(mid 0.249642 -0.249642)
							(end 0.2794 -0.1778)
						)
						(arc
							(start 0.2794 0.1778)
							(mid 0.249642 0.249642)
							(end 0.1778 0.2794)
						)
					)
					(width 0)
					(fill yes)
				)
			)
		)
	)
	(footprint ""
		(layer "B.Cu")
		(at 53.361844 -51.5874)
		(property "Reference" "R686"
			(at 0 0 0)
			(layer "B.SilkS")
			(hide yes)
			(effects
				(font
					(size 1.27 1.27)
				)
				(justify mirror)
			)
		)
		(property "Value" "0R2J-2-GP"
			(at -0.064008 -3.993896 0)
			(unlocked yes)
			(layer "B.Fab")
			(hide yes)
			(effects
				(font
					(size 1.016 1.016)
					(thickness 0.1524)
				)
				(justify mirror)
			)
		)
		(property "Device Type" "R402H16"
			(at -0.064008 -5.517896 0)
			(unlocked yes)
			(layer "B.Fab")
			(hide yes)
			(effects
				(font
					(size 1.016 1.016)
					(thickness 0.1524)
				)
				(justify mirror)
			)
		)
		(duplicate_pad_numbers_are_jumpers no)
		(fp_line
			(start -0.508 -0.9398)
			(end 0.508 -0.9398)
			(stroke
				(width 0.1524)
				(type default)
			)
			(layer "B.SilkS")
		)
		(fp_line
			(start 0.508 -0.9398)
			(end 0.508 0.9398)
			(stroke
				(width 0.1524)
				(type default)
			)
			(layer "B.SilkS")
		)
		(fp_rect
			(start 0.508 0.9398)
			(end -0.508 -0.9398)
			(stroke
				(width 0)
				(type default)
			)
			(fill no)
			(layer "B.CrtYd")
		)
		(fp_rect
			(start 0.508 0.9398)
			(end -0.508 -0.9398)
			(stroke
				(width 0)
				(type default)
			)
			(fill no)
			(layer "B.Fab")
		)
		(pad "1" smd custom
			(at 0 -0.4445 180)
			(size 0.1397 0.1397)
			(layers "B.Cu" "B.Mask" "B.Paste")
			(net "USB_P2_DP")
			(options
				(clearance outline)
				(anchor circle)
			)
			(primitives
				(gr_poly
					(pts
						(arc
							(start -0.1778 0.2794)
							(mid -0.249642 0.249642)
							(end -0.2794 0.1778)
						)
						(arc
							(start -0.2794 -0.1778)
							(mid -0.249642 -0.249642)
							(end -0.1778 -0.2794)
						)
						(arc
							(start 0.1778 -0.2794)
							(mid 0.249642 -0.249642)
							(end 0.2794 -0.1778)
						)
						(arc
							(start 0.2794 0.1778)
							(mid 0.249642 0.249642)
							(end 0.1778 0.2794)
						)
					)
					(width 0)
					(fill yes)
				)
			)
		)
		(pad "2" smd custom
			(at 0 0.4445 180)
			(size 0.1397 0.1397)
			(layers "B.Cu" "B.Mask" "B.Paste")
			(net "USB_DP_R")
			(options
				(clearance outline)
				(anchor circle)
			)
			(primitives
				(gr_poly
					(pts
						(arc
							(start -0.1778 0.2794)
							(mid -0.249642 0.249642)
							(end -0.2794 0.1778)
						)
						(arc
							(start -0.2794 -0.1778)
							(mid -0.249642 -0.249642)
							(end -0.1778 -0.2794)
						)
						(arc
							(start 0.1778 -0.2794)
							(mid 0.249642 -0.249642)
							(end 0.2794 -0.1778)
						)
						(arc
							(start 0.2794 0.1778)
							(mid 0.249642 0.249642)
							(end 0.1778 0.2794)
						)
					)
					(width 0)
					(fill yes)
				)
			)
		)
	)
	(footprint ""
		(layer "B.Cu")
		(at 20.945348 -141.89456 90)
		(property "Reference" "R743"
			(at 0 0 90)
			(layer "B.SilkS")
			(hide yes)
			(effects
				(font
					(size 1.27 1.27)
				)
				(justify mirror)
			)
		)
		(property "Value" "0R2J-2-GP"
			(at -0.064008 -3.993896 90)
			(unlocked yes)
			(layer "B.Fab")
			(hide yes)
			(effects
				(font
					(size 1.016 1.016)
					(thickness 0.1524)
				)
				(justify mirror)
			)
		)
		(property "Device Type" "R402H16"
			(at -0.064008 -5.517896 90)
			(unlocked yes)
			(layer "B.Fab")
			(hide yes)
			(effects
				(font
					(size 1.016 1.016)
					(thickness 0.1524)
				)
				(justify mirror)
			)
		)
		(duplicate_pad_numbers_are_jumpers no)
		(fp_line
			(start 0.508 -0.9398)
			(end 0.508 0.9398)
			(stroke
				(width 0.1524)
				(type default)
			)
			(layer "B.SilkS")
		)
		(fp_line
			(start -0.508 -0.9398)
			(end 0.508 -0.9398)
			(stroke
				(width 0.1524)
				(type default)
			)
			(layer "B.SilkS")
		)
		(fp_rect
			(start 0.508 0.9398)
			(end -0.508 -0.9398)
			(stroke
				(width 0)
				(type default)
			)
			(fill no)
			(layer "B.CrtYd")
		)
		(fp_rect
			(start 0.508 0.9398)
			(end -0.508 -0.9398)
			(stroke
				(width 0)
				(type default)
			)
			(fill no)
			(layer "B.Fab")
		)
		(pad "1" smd custom
			(at 0 -0.4445 270)
			(size 0.1397 0.1397)
			(layers "B.Cu" "B.Mask" "B.Paste")
			(net "RST_BMC_EXTRST_N")
			(options
				(clearance outline)
				(anchor circle)
			)
			(primitives
				(gr_poly
					(pts
						(arc
							(start -0.1778 0.2794)
							(mid -0.249642 0.249642)
							(end -0.2794 0.1778)
						)
						(arc
							(start -0.2794 -0.1778)
							(mid -0.249642 -0.249642)
							(end -0.1778 -0.2794)
						)
						(arc
							(start 0.1778 -0.2794)
							(mid 0.249642 -0.249642)
							(end 0.2794 -0.1778)
						)
						(arc
							(start 0.2794 0.1778)
							(mid 0.249642 0.249642)
							(end 0.1778 0.2794)
						)
					)
					(width 0)
					(fill yes)
				)
			)
		)
		(pad "2" smd custom
			(at 0 0.4445 270)
			(size 0.1397 0.1397)
			(layers "B.Cu" "B.Mask" "B.Paste")
			(net "BMC0_SRST_N")
			(options
				(clearance outline)
				(anchor circle)
			)
			(primitives
				(gr_poly
					(pts
						(arc
							(start -0.1778 0.2794)
							(mid -0.249642 0.249642)
							(end -0.2794 0.1778)
						)
						(arc
							(start -0.2794 -0.1778)
							(mid -0.249642 -0.249642)
							(end -0.1778 -0.2794)
						)
						(arc
							(start 0.1778 -0.2794)
							(mid 0.249642 -0.249642)
							(end 0.2794 -0.1778)
						)
						(arc
							(start 0.2794 0.1778)
							(mid 0.249642 0.249642)
							(end 0.1778 0.2794)
						)
					)
					(width 0)
					(fill yes)
				)
			)
		)
	)
	(footprint ""
		(layer "B.Cu")
		(at 347.0402 -64.643 -90)
		(property "Reference" "PR150"
			(at 0 0 90)
			(layer "B.SilkS")
			(hide yes)
			(effects
				(font
					(size 1.27 1.27)
				)
				(justify mirror)
			)
		)
		(property "Value" "0R3J-0-U-GP"
			(at 0.0254 -2.5146 270)
			(unlocked yes)
			(layer "B.Fab")
			(hide yes)
			(effects
				(font
					(size 1.016 1.016)
					(thickness 0.1524)
				)
				(justify mirror)
			)
		)
		(property "Device Type" "R603H22"
			(at 0.0254 -4.0386 270)
			(unlocked yes)
			(layer "B.Fab")
			(hide yes)
			(effects
				(font
					(size 1.016 1.016)
					(thickness 0.1524)
				)
				(justify mirror)
			)
		)
		(duplicate_pad_numbers_are_jumpers no)
		(fp_line
			(start -0.2032 0)
			(end -0.4826 0)
			(stroke
				(width 0.2032)
				(type default)
			)
			(layer "B.SilkS")
		)
		(fp_line
			(start 0.4826 0)
			(end 0.2032 0)
			(stroke
				(width 0.2032)
				(type default)
			)
			(layer "B.SilkS")
		)
		(fp_rect
			(start 0.5842 1.3335)
			(end -0.5842 -1.3335)
			(stroke
				(width 0)
				(type default)
			)
			(fill no)
			(layer "B.CrtYd")
		)
		(fp_rect
			(start 0.5842 1.3335)
			(end -0.5842 -1.3335)
			(stroke
				(width 0)
				(type default)
			)
			(fill no)
			(layer "B.Fab")
		)
		(pad "1" smd custom
			(at 0 -0.762 90)
			(size 0.2159 0.2159)
			(layers "B.Cu" "B.Mask" "B.Paste")
			(net "P12V")
			(options
				(clearance outline)
				(anchor circle)
			)
			(primitives
				(gr_poly
					(pts
						(arc
							(start -0.3302 0.4318)
							(mid -0.402042 0.402042)
							(end -0.4318 0.3302)
						)
						(arc
							(start -0.4318 -0.3302)
							(mid -0.402042 -0.402042)
							(end -0.3302 -0.4318)
						)
						(arc
							(start 0.3302 -0.4318)
							(mid 0.402042 -0.402042)
							(end 0.4318 -0.3302)
						)
						(arc
							(start 0.4318 0.3302)
							(mid 0.402042 0.402042)
							(end 0.3302 0.4318)
						)
					)
					(width 0)
					(fill yes)
				)
			)
		)
		(pad "2" smd custom
			(at 0 0.762 90)
			(size 0.2159 0.2159)
			(layers "B.Cu" "B.Mask" "B.Paste")
			(net "P0V9_E_VDD")
			(options
				(clearance outline)
				(anchor circle)
			)
			(primitives
				(gr_poly
					(pts
						(arc
							(start -0.3302 0.4318)
							(mid -0.402042 0.402042)
							(end -0.4318 0.3302)
						)
						(arc
							(start -0.4318 -0.3302)
							(mid -0.402042 -0.402042)
							(end -0.3302 -0.4318)
						)
						(arc
							(start 0.3302 -0.4318)
							(mid 0.402042 -0.402042)
							(end 0.4318 -0.3302)
						)
						(arc
							(start 0.4318 0.3302)
							(mid 0.402042 0.402042)
							(end 0.3302 0.4318)
						)
					)
					(width 0)
					(fill yes)
				)
			)
		)
	)
	(footprint ""
		(layer "B.Cu")
		(at 241.6048 -56.007 90)
		(property "Reference" "C502"
			(at 0 0 90)
			(layer "B.SilkS")
			(hide yes)
			(effects
				(font
					(size 1.27 1.27)
				)
				(justify mirror)
			)
		)
		(property "Value" "SCD1U16V1KX-1-GP"
			(at 2.8321 -1.7399 90)
			(unlocked yes)
			(layer "B.Fab")
			(hide yes)
			(effects
				(font
					(size 1.016 1.016)
					(thickness 0.1524)
				)
				(justify mirror)
			)
		)
		(property "Device Type" "C0201H13"
			(at 2.8321 -3.2639 90)
			(unlocked yes)
			(layer "B.Fab")
			(hide yes)
			(effects
				(font
					(size 1.016 1.016)
					(thickness 0.1524)
				)
				(justify mirror)
			)
		)
		(duplicate_pad_numbers_are_jumpers no)
		(fp_rect
			(start 0.2794 0.6477)
			(end -0.2794 -0.6477)
			(stroke
				(width 0)
				(type default)
			)
			(fill no)
			(layer "B.CrtYd")
		)
		(fp_rect
			(start 0.2794 0.6477)
			(end -0.2794 -0.6477)
			(stroke
				(width 0)
				(type default)
			)
			(fill no)
			(layer "B.Fab")
		)
		(pad "1" smd custom
			(at 0 -0.2794 270)
			(size 0.0762 0.0762)
			(layers "B.Cu" "B.Mask" "B.Paste")
			(net "DUT_AVD_TX")
			(options
				(clearance outline)
				(anchor circle)
			)
			(primitives
				(gr_poly
					(pts
						(arc
							(start 0.1524 0.127)
							(mid 0.137521 0.162921)
							(end 0.1016 0.1778)
						)
						(arc
							(start -0.1016 0.1778)
							(mid -0.137521 0.162921)
							(end -0.1524 0.127)
						)
						(arc
							(start -0.1524 -0.127)
							(mid -0.137521 -0.162921)
							(end -0.1016 -0.1778)
						)
						(arc
							(start 0.1016 -0.1778)
							(mid 0.137521 -0.162921)
							(end 0.1524 -0.127)
						)
					)
					(width 0)
					(fill yes)
				)
			)
		)
		(pad "2" smd custom
			(at 0 0.2794 270)
			(size 0.0762 0.0762)
			(layers "B.Cu" "B.Mask" "B.Paste")
			(net "GND")
			(options
				(clearance outline)
				(anchor circle)
			)
			(primitives
				(gr_poly
					(pts
						(arc
							(start 0.1524 0.127)
							(mid 0.137521 0.162921)
							(end 0.1016 0.1778)
						)
						(arc
							(start -0.1016 0.1778)
							(mid -0.137521 0.162921)
							(end -0.1524 0.127)
						)
						(arc
							(start -0.1524 -0.127)
							(mid -0.137521 -0.162921)
							(end -0.1016 -0.1778)
						)
						(arc
							(start 0.1016 -0.1778)
							(mid 0.137521 -0.162921)
							(end 0.1524 -0.127)
						)
					)
					(width 0)
					(fill yes)
				)
			)
		)
	)
	(footprint ""
		(layer "B.Cu")
		(at 59.2074 -127.508 90)
		(property "Reference" "R457"
			(at 0 0 90)
			(layer "B.SilkS")
			(hide yes)
			(effects
				(font
					(size 1.27 1.27)
				)
				(justify mirror)
			)
		)
		(property "Value" "4K7R2F-GP"
			(at -0.064008 -3.993896 90)
			(unlocked yes)
			(layer "B.Fab")
			(hide yes)
			(effects
				(font
					(size 1.016 1.016)
					(thickness 0.1524)
				)
				(justify mirror)
			)
		)
		(property "Device Type" "R402H16"
			(at -0.064008 -5.517896 90)
			(unlocked yes)
			(layer "B.Fab")
			(hide yes)
			(effects
				(font
					(size 1.016 1.016)
					(thickness 0.1524)
				)
				(justify mirror)
			)
		)
		(duplicate_pad_numbers_are_jumpers no)
		(fp_line
			(start 0.508 -0.9398)
			(end 0.508 0.9398)
			(stroke
				(width 0.1524)
				(type default)
			)
			(layer "B.SilkS")
		)
		(fp_line
			(start -0.508 -0.9398)
			(end 0.508 -0.9398)
			(stroke
				(width 0.1524)
				(type default)
			)
			(layer "B.SilkS")
		)
		(fp_rect
			(start 0.508 0.9398)
			(end -0.508 -0.9398)
			(stroke
				(width 0)
				(type default)
			)
			(fill no)
			(layer "B.CrtYd")
		)
		(fp_rect
			(start 0.508 0.9398)
			(end -0.508 -0.9398)
			(stroke
				(width 0)
				(type default)
			)
			(fill no)
			(layer "B.Fab")
		)
		(pad "1" smd custom
			(at 0 -0.4445 270)
			(size 0.1397 0.1397)
			(layers "B.Cu" "B.Mask" "B.Paste")
			(net "BMC_I2C14_MINI8_SDA_S")
			(options
				(clearance outline)
				(anchor circle)
			)
			(primitives
				(gr_poly
					(pts
						(arc
							(start -0.1778 0.2794)
							(mid -0.249642 0.249642)
							(end -0.2794 0.1778)
						)
						(arc
							(start -0.2794 -0.1778)
							(mid -0.249642 -0.249642)
							(end -0.1778 -0.2794)
						)
						(arc
							(start 0.1778 -0.2794)
							(mid 0.249642 -0.249642)
							(end 0.2794 -0.1778)
						)
						(arc
							(start 0.2794 0.1778)
							(mid 0.249642 0.249642)
							(end 0.1778 0.2794)
						)
					)
					(width 0)
					(fill yes)
				)
			)
		)
		(pad "2" smd custom
			(at 0 0.4445 270)
			(size 0.1397 0.1397)
			(layers "B.Cu" "B.Mask" "B.Paste")
			(net "P3V3_STBY")
			(options
				(clearance outline)
				(anchor circle)
			)
			(primitives
				(gr_poly
					(pts
						(arc
							(start -0.1778 0.2794)
							(mid -0.249642 0.249642)
							(end -0.2794 0.1778)
						)
						(arc
							(start -0.2794 -0.1778)
							(mid -0.249642 -0.249642)
							(end -0.1778 -0.2794)
						)
						(arc
							(start 0.1778 -0.2794)
							(mid 0.249642 -0.249642)
							(end 0.2794 -0.1778)
						)
						(arc
							(start 0.2794 0.1778)
							(mid 0.249642 0.249642)
							(end 0.1778 0.2794)
						)
					)
					(width 0)
					(fill yes)
				)
			)
		)
	)
	(footprint ""
		(layer "B.Cu")
		(at 53.721 -134.747 -90)
		(property "Reference" "R373"
			(at 0 0 90)
			(layer "B.SilkS")
			(hide yes)
			(effects
				(font
					(size 1.27 1.27)
				)
				(justify mirror)
			)
		)
		(property "Value" "0R2J-2-GP"
			(at -0.064008 -3.993896 270)
			(unlocked yes)
			(layer "B.Fab")
			(hide yes)
			(effects
				(font
					(size 1.016 1.016)
					(thickness 0.1524)
				)
				(justify mirror)
			)
		)
		(property "Device Type" "R402H16"
			(at -0.064008 -5.517896 270)
			(unlocked yes)
			(layer "B.Fab")
			(hide yes)
			(effects
				(font
					(size 1.016 1.016)
					(thickness 0.1524)
				)
				(justify mirror)
			)
		)
		(duplicate_pad_numbers_are_jumpers no)
		(fp_line
			(start -0.508 -0.9398)
			(end 0.508 -0.9398)
			(stroke
				(width 0.1524)
				(type default)
			)
			(layer "B.SilkS")
		)
		(fp_line
			(start 0.508 -0.9398)
			(end 0.508 0.9398)
			(stroke
				(width 0.1524)
				(type default)
			)
			(layer "B.SilkS")
		)
		(fp_rect
			(start 0.508 0.9398)
			(end -0.508 -0.9398)
			(stroke
				(width 0)
				(type default)
			)
			(fill no)
			(layer "B.CrtYd")
		)
		(fp_rect
			(start 0.508 0.9398)
			(end -0.508 -0.9398)
			(stroke
				(width 0)
				(type default)
			)
			(fill no)
			(layer "B.Fab")
		)
		(pad "1" smd custom
			(at 0 -0.4445 90)
			(size 0.1397 0.1397)
			(layers "B.Cu" "B.Mask" "B.Paste")
			(net "ADC_P1V26")
			(options
				(clearance outline)
				(anchor circle)
			)
			(primitives
				(gr_poly
					(pts
						(arc
							(start -0.1778 0.2794)
							(mid -0.249642 0.249642)
							(end -0.2794 0.1778)
						)
						(arc
							(start -0.2794 -0.1778)
							(mid -0.249642 -0.249642)
							(end -0.1778 -0.2794)
						)
						(arc
							(start 0.1778 -0.2794)
							(mid 0.249642 -0.249642)
							(end 0.2794 -0.1778)
						)
						(arc
							(start 0.2794 0.1778)
							(mid 0.249642 0.249642)
							(end 0.1778 0.2794)
						)
					)
					(width 0)
					(fill yes)
				)
			)
		)
		(pad "2" smd custom
			(at 0 0.4445 90)
			(size 0.1397 0.1397)
			(layers "B.Cu" "B.Mask" "B.Paste")
			(net "ADC_P1V26_BMC")
			(options
				(clearance outline)
				(anchor circle)
			)
			(primitives
				(gr_poly
					(pts
						(arc
							(start -0.1778 0.2794)
							(mid -0.249642 0.249642)
							(end -0.2794 0.1778)
						)
						(arc
							(start -0.2794 -0.1778)
							(mid -0.249642 -0.249642)
							(end -0.1778 -0.2794)
						)
						(arc
							(start 0.1778 -0.2794)
							(mid 0.249642 -0.249642)
							(end 0.2794 -0.1778)
						)
						(arc
							(start 0.2794 0.1778)
							(mid 0.249642 0.249642)
							(end 0.1778 0.2794)
						)
					)
					(width 0)
					(fill yes)
				)
			)
		)
	)
	(footprint ""
		(layer "B.Cu")
		(at 125.28423 -33.48355 180)
		(property "Reference" "C130"
			(at 0 0 0)
			(layer "B.SilkS")
			(hide yes)
			(effects
				(font
					(size 1.27 1.27)
				)
				(justify mirror)
			)
		)
		(property "Value" "SCD1U10V2KX-5GP"
			(at -1.1811 -2.7051 180)
			(unlocked yes)
			(layer "B.Fab")
			(hide yes)
			(effects
				(font
					(size 1.016 1.016)
					(thickness 0.1524)
				)
				(justify mirror)
			)
		)
		(property "Device Type" "C402H22"
			(at -1.1811 -4.2291 180)
			(unlocked yes)
			(layer "B.Fab")
			(hide yes)
			(effects
				(font
					(size 1.016 1.016)
					(thickness 0.1524)
				)
				(justify mirror)
			)
		)
		(duplicate_pad_numbers_are_jumpers no)
		(fp_rect
			(start 0.4318 0.9525)
			(end -0.4318 -0.9525)
			(stroke
				(width 0)
				(type default)
			)
			(fill no)
			(layer "B.CrtYd")
		)
		(fp_rect
			(start 0.4318 0.9525)
			(end -0.4318 -0.9525)
			(stroke
				(width 0)
				(type default)
			)
			(fill no)
			(layer "B.Fab")
		)
		(pad "1" smd custom
			(at 0 -0.4445)
			(size 0.1524 0.1524)
			(layers "B.Cu" "B.Mask" "B.Paste")
			(net "GND")
			(options
				(clearance outline)
				(anchor circle)
			)
			(primitives
				(gr_poly
					(pts
						(arc
							(start 0.3048 0.2032)
							(mid 0.275042 0.275042)
							(end 0.2032 0.3048)
						)
						(arc
							(start -0.2032 0.3048)
							(mid -0.275042 0.275042)
							(end -0.3048 0.2032)
						)
						(arc
							(start -0.3048 -0.2032)
							(mid -0.275042 -0.275042)
							(end -0.2032 -0.3048)
						)
						(arc
							(start 0.2032 -0.3048)
							(mid 0.275042 -0.275042)
							(end 0.3048 -0.2032)
						)
					)
					(width 0)
					(fill yes)
				)
			)
		)
		(pad "2" smd custom
			(at 0 0.4445)
			(size 0.1524 0.1524)
			(layers "B.Cu" "B.Mask" "B.Paste")
			(net "P3V3_STBY")
			(options
				(clearance outline)
				(anchor circle)
			)
			(primitives
				(gr_poly
					(pts
						(arc
							(start 0.3048 0.2032)
							(mid 0.275042 0.275042)
							(end 0.2032 0.3048)
						)
						(arc
							(start -0.2032 0.3048)
							(mid -0.275042 0.275042)
							(end -0.3048 0.2032)
						)
						(arc
							(start -0.3048 -0.2032)
							(mid -0.275042 -0.275042)
							(end -0.2032 -0.3048)
						)
						(arc
							(start 0.2032 -0.3048)
							(mid 0.275042 -0.275042)
							(end 0.3048 -0.2032)
						)
					)
					(width 0)
					(fill yes)
				)
			)
		)
	)
	(footprint ""
		(layer "B.Cu")
		(at 57.15 -132.08)
		(property "Reference" "R5770"
			(at 0 0 0)
			(layer "B.SilkS")
			(hide yes)
			(effects
				(font
					(size 1.27 1.27)
				)
				(justify mirror)
			)
		)
		(property "Value" "1KR2F-3-GP"
			(at -0.064008 -3.993896 0)
			(unlocked yes)
			(layer "B.Fab")
			(hide yes)
			(effects
				(font
					(size 1.016 1.016)
					(thickness 0.1524)
				)
				(justify mirror)
			)
		)
		(property "Device Type" "R402H16"
			(at -0.064008 -5.517896 0)
			(unlocked yes)
			(layer "B.Fab")
			(hide yes)
			(effects
				(font
					(size 1.016 1.016)
					(thickness 0.1524)
				)
				(justify mirror)
			)
		)
		(duplicate_pad_numbers_are_jumpers no)
		(fp_line
			(start -0.508 -0.9398)
			(end 0.508 -0.9398)
			(stroke
				(width 0.1524)
				(type default)
			)
			(layer "B.SilkS")
		)
		(fp_line
			(start 0.508 -0.9398)
			(end 0.508 0.9398)
			(stroke
				(width 0.1524)
				(type default)
			)
			(layer "B.SilkS")
		)
		(fp_rect
			(start 0.508 0.9398)
			(end -0.508 -0.9398)
			(stroke
				(width 0)
				(type default)
			)
			(fill no)
			(layer "B.CrtYd")
		)
		(fp_rect
			(start 0.508 0.9398)
			(end -0.508 -0.9398)
			(stroke
				(width 0)
				(type default)
			)
			(fill no)
			(layer "B.Fab")
		)
		(pad "1" smd custom
			(at 0 -0.4445 180)
			(size 0.1397 0.1397)
			(layers "B.Cu" "B.Mask" "B.Paste")
			(net "ADC_P3V3_STBY")
			(options
				(clearance outline)
				(anchor circle)
			)
			(primitives
				(gr_poly
					(pts
						(arc
							(start -0.1778 0.2794)
							(mid -0.249642 0.249642)
							(end -0.2794 0.1778)
						)
						(arc
							(start -0.2794 -0.1778)
							(mid -0.249642 -0.249642)
							(end -0.1778 -0.2794)
						)
						(arc
							(start 0.1778 -0.2794)
							(mid 0.249642 -0.249642)
							(end 0.2794 -0.1778)
						)
						(arc
							(start 0.2794 0.1778)
							(mid 0.249642 0.249642)
							(end 0.1778 0.2794)
						)
					)
					(width 0)
					(fill yes)
				)
			)
		)
		(pad "2" smd custom
			(at 0 0.4445 180)
			(size 0.1397 0.1397)
			(layers "B.Cu" "B.Mask" "B.Paste")
			(net "GND")
			(options
				(clearance outline)
				(anchor circle)
			)
			(primitives
				(gr_poly
					(pts
						(arc
							(start -0.1778 0.2794)
							(mid -0.249642 0.249642)
							(end -0.2794 0.1778)
						)
						(arc
							(start -0.2794 -0.1778)
							(mid -0.249642 -0.249642)
							(end -0.1778 -0.2794)
						)
						(arc
							(start 0.1778 -0.2794)
							(mid 0.249642 -0.249642)
							(end 0.2794 -0.1778)
						)
						(arc
							(start 0.2794 0.1778)
							(mid 0.249642 0.249642)
							(end 0.1778 0.2794)
						)
					)
					(width 0)
					(fill yes)
				)
			)
		)
	)
	(footprint ""
		(layer "B.Cu")
		(at 339.344 -178.689)
		(property "Reference" "R276"
			(at 0 0 0)
			(layer "B.SilkS")
			(hide yes)
			(effects
				(font
					(size 1.27 1.27)
				)
				(justify mirror)
			)
		)
		(property "Value" "4K7R2F-GP"
			(at -0.064008 -3.993896 0)
			(unlocked yes)
			(layer "B.Fab")
			(hide yes)
			(effects
				(font
					(size 1.016 1.016)
					(thickness 0.1524)
				)
				(justify mirror)
			)
		)
		(property "Device Type" "R402H16"
			(at -0.064008 -5.517896 0)
			(unlocked yes)
			(layer "B.Fab")
			(hide yes)
			(effects
				(font
					(size 1.016 1.016)
					(thickness 0.1524)
				)
				(justify mirror)
			)
		)
		(duplicate_pad_numbers_are_jumpers no)
		(fp_line
			(start -0.508 -0.9398)
			(end 0.508 -0.9398)
			(stroke
				(width 0.1524)
				(type default)
			)
			(layer "B.SilkS")
		)
		(fp_line
			(start 0.508 -0.9398)
			(end 0.508 0.9398)
			(stroke
				(width 0.1524)
				(type default)
			)
			(layer "B.SilkS")
		)
		(fp_rect
			(start 0.508 0.9398)
			(end -0.508 -0.9398)
			(stroke
				(width 0)
				(type default)
			)
			(fill no)
			(layer "B.CrtYd")
		)
		(fp_rect
			(start 0.508 0.9398)
			(end -0.508 -0.9398)
			(stroke
				(width 0)
				(type default)
			)
			(fill no)
			(layer "B.Fab")
		)
		(pad "1" smd custom
			(at 0 -0.4445 180)
			(size 0.1397 0.1397)
			(layers "B.Cu" "B.Mask" "B.Paste")
			(net "BMC_SSD_RST#0_A14")
			(options
				(clearance outline)
				(anchor circle)
			)
			(primitives
				(gr_poly
					(pts
						(arc
							(start -0.1778 0.2794)
							(mid -0.249642 0.249642)
							(end -0.2794 0.1778)
						)
						(arc
							(start -0.2794 -0.1778)
							(mid -0.249642 -0.249642)
							(end -0.1778 -0.2794)
						)
						(arc
							(start 0.1778 -0.2794)
							(mid 0.249642 -0.249642)
							(end 0.2794 -0.1778)
						)
						(arc
							(start 0.2794 0.1778)
							(mid 0.249642 0.249642)
							(end 0.1778 0.2794)
						)
					)
					(width 0)
					(fill yes)
				)
			)
		)
		(pad "2" smd custom
			(at 0 0.4445 180)
			(size 0.1397 0.1397)
			(layers "B.Cu" "B.Mask" "B.Paste")
			(net "P3V3_STBY")
			(options
				(clearance outline)
				(anchor circle)
			)
			(primitives
				(gr_poly
					(pts
						(arc
							(start -0.1778 0.2794)
							(mid -0.249642 0.249642)
							(end -0.2794 0.1778)
						)
						(arc
							(start -0.2794 -0.1778)
							(mid -0.249642 -0.249642)
							(end -0.1778 -0.2794)
						)
						(arc
							(start 0.1778 -0.2794)
							(mid 0.249642 -0.249642)
							(end 0.2794 -0.1778)
						)
						(arc
							(start 0.2794 0.1778)
							(mid 0.249642 0.249642)
							(end 0.1778 0.2794)
						)
					)
					(width 0)
					(fill yes)
				)
			)
		)
	)
	(footprint ""
		(layer "B.Cu")
		(at 228.6254 -58.996072 90)
		(property "Reference" "C533"
			(at 0 0 90)
			(layer "B.SilkS")
			(hide yes)
			(effects
				(font
					(size 1.27 1.27)
				)
				(justify mirror)
			)
		)
		(property "Value" "SCD1U16V1KX-1-GP"
			(at 2.8321 -1.7399 90)
			(unlocked yes)
			(layer "B.Fab")
			(hide yes)
			(effects
				(font
					(size 1.016 1.016)
					(thickness 0.1524)
				)
				(justify mirror)
			)
		)
		(property "Device Type" "C0201H13"
			(at 2.8321 -3.2639 90)
			(unlocked yes)
			(layer "B.Fab")
			(hide yes)
			(effects
				(font
					(size 1.016 1.016)
					(thickness 0.1524)
				)
				(justify mirror)
			)
		)
		(duplicate_pad_numbers_are_jumpers no)
		(fp_rect
			(start 0.2794 0.6477)
			(end -0.2794 -0.6477)
			(stroke
				(width 0)
				(type default)
			)
			(fill no)
			(layer "B.CrtYd")
		)
		(fp_rect
			(start 0.2794 0.6477)
			(end -0.2794 -0.6477)
			(stroke
				(width 0)
				(type default)
			)
			(fill no)
			(layer "B.Fab")
		)
		(pad "1" smd custom
			(at 0 -0.2794 270)
			(size 0.0762 0.0762)
			(layers "B.Cu" "B.Mask" "B.Paste")
			(net "DUT_AVD_PCIE")
			(options
				(clearance outline)
				(anchor circle)
			)
			(primitives
				(gr_poly
					(pts
						(arc
							(start 0.1524 0.127)
							(mid 0.137521 0.162921)
							(end 0.1016 0.1778)
						)
						(arc
							(start -0.1016 0.1778)
							(mid -0.137521 0.162921)
							(end -0.1524 0.127)
						)
						(arc
							(start -0.1524 -0.127)
							(mid -0.137521 -0.162921)
							(end -0.1016 -0.1778)
						)
						(arc
							(start 0.1016 -0.1778)
							(mid 0.137521 -0.162921)
							(end 0.1524 -0.127)
						)
					)
					(width 0)
					(fill yes)
				)
			)
		)
		(pad "2" smd custom
			(at 0 0.2794 270)
			(size 0.0762 0.0762)
			(layers "B.Cu" "B.Mask" "B.Paste")
			(net "GND")
			(options
				(clearance outline)
				(anchor circle)
			)
			(primitives
				(gr_poly
					(pts
						(arc
							(start 0.1524 0.127)
							(mid 0.137521 0.162921)
							(end 0.1016 0.1778)
						)
						(arc
							(start -0.1016 0.1778)
							(mid -0.137521 0.162921)
							(end -0.1524 0.127)
						)
						(arc
							(start -0.1524 -0.127)
							(mid -0.137521 -0.162921)
							(end -0.1016 -0.1778)
						)
						(arc
							(start 0.1016 -0.1778)
							(mid 0.137521 -0.162921)
							(end 0.1524 -0.127)
						)
					)
					(width 0)
					(fill yes)
				)
			)
		)
	)
	(footprint ""
		(layer "B.Cu")
		(at 225.679 -23.241 180)
		(property "Reference" "R829"
			(at 0 0 0)
			(layer "B.SilkS")
			(hide yes)
			(effects
				(font
					(size 1.27 1.27)
				)
				(justify mirror)
			)
		)
		(property "Value" "0R2J-2-GP"
			(at -0.064008 -3.993896 180)
			(unlocked yes)
			(layer "B.Fab")
			(hide yes)
			(effects
				(font
					(size 1.016 1.016)
					(thickness 0.1524)
				)
				(justify mirror)
			)
		)
		(property "Device Type" "R402H16"
			(at -0.064008 -5.517896 180)
			(unlocked yes)
			(layer "B.Fab")
			(hide yes)
			(effects
				(font
					(size 1.016 1.016)
					(thickness 0.1524)
				)
				(justify mirror)
			)
		)
		(duplicate_pad_numbers_are_jumpers no)
		(fp_line
			(start 0.508 -0.9398)
			(end 0.508 0.9398)
			(stroke
				(width 0.1524)
				(type default)
			)
			(layer "B.SilkS")
		)
		(fp_line
			(start -0.508 -0.9398)
			(end 0.508 -0.9398)
			(stroke
				(width 0.1524)
				(type default)
			)
			(layer "B.SilkS")
		)
		(fp_rect
			(start 0.508 0.9398)
			(end -0.508 -0.9398)
			(stroke
				(width 0)
				(type default)
			)
			(fill no)
			(layer "B.CrtYd")
		)
		(fp_rect
			(start 0.508 0.9398)
			(end -0.508 -0.9398)
			(stroke
				(width 0)
				(type default)
			)
			(fill no)
			(layer "B.Fab")
		)
		(pad "1" smd custom
			(at 0 -0.4445)
			(size 0.1397 0.1397)
			(layers "B.Cu" "B.Mask" "B.Paste")
			(net "HOST5_RST_N_LS")
			(options
				(clearance outline)
				(anchor circle)
			)
			(primitives
				(gr_poly
					(pts
						(arc
							(start -0.1778 0.2794)
							(mid -0.249642 0.249642)
							(end -0.2794 0.1778)
						)
						(arc
							(start -0.2794 -0.1778)
							(mid -0.249642 -0.249642)
							(end -0.1778 -0.2794)
						)
						(arc
							(start 0.1778 -0.2794)
							(mid 0.249642 -0.249642)
							(end 0.2794 -0.1778)
						)
						(arc
							(start 0.2794 0.1778)
							(mid 0.249642 0.249642)
							(end 0.1778 0.2794)
						)
					)
					(width 0)
					(fill yes)
				)
			)
		)
		(pad "2" smd custom
			(at 0 0.4445)
			(size 0.1397 0.1397)
			(layers "B.Cu" "B.Mask" "B.Paste")
			(net "LBI_ADDR_4_R")
			(options
				(clearance outline)
				(anchor circle)
			)
			(primitives
				(gr_poly
					(pts
						(arc
							(start -0.1778 0.2794)
							(mid -0.249642 0.249642)
							(end -0.2794 0.1778)
						)
						(arc
							(start -0.2794 -0.1778)
							(mid -0.249642 -0.249642)
							(end -0.1778 -0.2794)
						)
						(arc
							(start 0.1778 -0.2794)
							(mid 0.249642 -0.249642)
							(end 0.2794 -0.1778)
						)
						(arc
							(start 0.2794 0.1778)
							(mid 0.249642 0.249642)
							(end 0.1778 0.2794)
						)
					)
					(width 0)
					(fill yes)
				)
			)
		)
	)
	(footprint ""
		(layer "B.Cu")
		(at 20.955 -131.699 90)
		(property "Reference" "R359"
			(at 0 0 90)
			(layer "B.SilkS")
			(hide yes)
			(effects
				(font
					(size 1.27 1.27)
				)
				(justify mirror)
			)
		)
		(property "Value" "3K3R2F-2-GP"
			(at -0.064008 -3.993896 90)
			(unlocked yes)
			(layer "B.Fab")
			(hide yes)
			(effects
				(font
					(size 1.016 1.016)
					(thickness 0.1524)
				)
				(justify mirror)
			)
		)
		(property "Device Type" "R402H16"
			(at -0.064008 -5.517896 90)
			(unlocked yes)
			(layer "B.Fab")
			(hide yes)
			(effects
				(font
					(size 1.016 1.016)
					(thickness 0.1524)
				)
				(justify mirror)
			)
		)
		(duplicate_pad_numbers_are_jumpers no)
		(fp_line
			(start 0.508 -0.9398)
			(end 0.508 0.9398)
			(stroke
				(width 0.1524)
				(type default)
			)
			(layer "B.SilkS")
		)
		(fp_line
			(start -0.508 -0.9398)
			(end 0.508 -0.9398)
			(stroke
				(width 0.1524)
				(type default)
			)
			(layer "B.SilkS")
		)
		(fp_rect
			(start 0.508 0.9398)
			(end -0.508 -0.9398)
			(stroke
				(width 0)
				(type default)
			)
			(fill no)
			(layer "B.CrtYd")
		)
		(fp_rect
			(start 0.508 0.9398)
			(end -0.508 -0.9398)
			(stroke
				(width 0)
				(type default)
			)
			(fill no)
			(layer "B.Fab")
		)
		(pad "1" smd custom
			(at 0 -0.4445 270)
			(size 0.1397 0.1397)
			(layers "B.Cu" "B.Mask" "B.Paste")
			(net "P3V3_STBY")
			(options
				(clearance outline)
				(anchor circle)
			)
			(primitives
				(gr_poly
					(pts
						(arc
							(start -0.1778 0.2794)
							(mid -0.249642 0.249642)
							(end -0.2794 0.1778)
						)
						(arc
							(start -0.2794 -0.1778)
							(mid -0.249642 -0.249642)
							(end -0.1778 -0.2794)
						)
						(arc
							(start 0.1778 -0.2794)
							(mid 0.249642 -0.249642)
							(end 0.2794 -0.1778)
						)
						(arc
							(start 0.2794 0.1778)
							(mid 0.249642 0.249642)
							(end 0.1778 0.2794)
						)
					)
					(width 0)
					(fill yes)
				)
			)
		)
		(pad "2" smd custom
			(at 0 0.4445 270)
			(size 0.1397 0.1397)
			(layers "B.Cu" "B.Mask" "B.Paste")
			(net "ROMA5")
			(options
				(clearance outline)
				(anchor circle)
			)
			(primitives
				(gr_poly
					(pts
						(arc
							(start -0.1778 0.2794)
							(mid -0.249642 0.249642)
							(end -0.2794 0.1778)
						)
						(arc
							(start -0.2794 -0.1778)
							(mid -0.249642 -0.249642)
							(end -0.1778 -0.2794)
						)
						(arc
							(start 0.1778 -0.2794)
							(mid 0.249642 -0.249642)
							(end 0.2794 -0.1778)
						)
						(arc
							(start 0.2794 0.1778)
							(mid 0.249642 0.249642)
							(end 0.1778 0.2794)
						)
					)
					(width 0)
					(fill yes)
				)
			)
		)
	)
	(footprint ""
		(layer "B.Cu")
		(at 155.972002 -64.289432 -90)
		(property "Reference" "PC207"
			(at 0 0 90)
			(layer "B.SilkS")
			(hide yes)
			(effects
				(font
					(size 1.27 1.27)
				)
				(justify mirror)
			)
		)
		(property "Value" "SC470P50V2KX-3GP"
			(at -1.1811 -2.7051 270)
			(unlocked yes)
			(layer "B.Fab")
			(hide yes)
			(effects
				(font
					(size 1.016 1.016)
					(thickness 0.1524)
				)
				(justify mirror)
			)
		)
		(property "Device Type" "C402H22"
			(at -1.1811 -4.2291 270)
			(unlocked yes)
			(layer "B.Fab")
			(hide yes)
			(effects
				(font
					(size 1.016 1.016)
					(thickness 0.1524)
				)
				(justify mirror)
			)
		)
		(duplicate_pad_numbers_are_jumpers no)
		(fp_rect
			(start 0.4318 0.9525)
			(end -0.4318 -0.9525)
			(stroke
				(width 0)
				(type default)
			)
			(fill no)
			(layer "B.CrtYd")
		)
		(fp_rect
			(start 0.4318 0.9525)
			(end -0.4318 -0.9525)
			(stroke
				(width 0)
				(type default)
			)
			(fill no)
			(layer "B.Fab")
		)
		(pad "1" smd custom
			(at 0 -0.4445 90)
			(size 0.1524 0.1524)
			(layers "B.Cu" "B.Mask" "B.Paste")
			(net "P0V9_SNB")
			(options
				(clearance outline)
				(anchor circle)
			)
			(primitives
				(gr_poly
					(pts
						(arc
							(start 0.3048 0.2032)
							(mid 0.275042 0.275042)
							(end 0.2032 0.3048)
						)
						(arc
							(start -0.2032 0.3048)
							(mid -0.275042 0.275042)
							(end -0.3048 0.2032)
						)
						(arc
							(start -0.3048 -0.2032)
							(mid -0.275042 -0.275042)
							(end -0.2032 -0.3048)
						)
						(arc
							(start 0.2032 -0.3048)
							(mid 0.275042 -0.275042)
							(end 0.3048 -0.2032)
						)
					)
					(width 0)
					(fill yes)
				)
			)
		)
		(pad "2" smd custom
			(at 0 0.4445 90)
			(size 0.1524 0.1524)
			(layers "B.Cu" "B.Mask" "B.Paste")
			(net "GND")
			(options
				(clearance outline)
				(anchor circle)
			)
			(primitives
				(gr_poly
					(pts
						(arc
							(start 0.3048 0.2032)
							(mid 0.275042 0.275042)
							(end 0.2032 0.3048)
						)
						(arc
							(start -0.2032 0.3048)
							(mid -0.275042 0.275042)
							(end -0.3048 0.2032)
						)
						(arc
							(start -0.3048 -0.2032)
							(mid -0.275042 -0.275042)
							(end -0.2032 -0.3048)
						)
						(arc
							(start 0.2032 -0.3048)
							(mid 0.275042 -0.275042)
							(end 0.3048 -0.2032)
						)
					)
					(width 0)
					(fill yes)
				)
			)
		)
	)
	(footprint ""
		(layer "B.Cu")
		(at 53.721 -137.795 90)
		(property "Reference" "R148"
			(at 0 0 90)
			(layer "B.SilkS")
			(hide yes)
			(effects
				(font
					(size 1.27 1.27)
				)
				(justify mirror)
			)
		)
		(property "Value" "4K7R2F-GP"
			(at -0.064008 -3.993896 90)
			(unlocked yes)
			(layer "B.Fab")
			(hide yes)
			(effects
				(font
					(size 1.016 1.016)
					(thickness 0.1524)
				)
				(justify mirror)
			)
		)
		(property "Device Type" "R402H16"
			(at -0.064008 -5.517896 90)
			(unlocked yes)
			(layer "B.Fab")
			(hide yes)
			(effects
				(font
					(size 1.016 1.016)
					(thickness 0.1524)
				)
				(justify mirror)
			)
		)
		(duplicate_pad_numbers_are_jumpers no)
		(fp_line
			(start 0.508 -0.9398)
			(end 0.508 0.9398)
			(stroke
				(width 0.1524)
				(type default)
			)
			(layer "B.SilkS")
		)
		(fp_line
			(start -0.508 -0.9398)
			(end 0.508 -0.9398)
			(stroke
				(width 0.1524)
				(type default)
			)
			(layer "B.SilkS")
		)
		(fp_rect
			(start 0.508 0.9398)
			(end -0.508 -0.9398)
			(stroke
				(width 0)
				(type default)
			)
			(fill no)
			(layer "B.CrtYd")
		)
		(fp_rect
			(start 0.508 0.9398)
			(end -0.508 -0.9398)
			(stroke
				(width 0)
				(type default)
			)
			(fill no)
			(layer "B.Fab")
		)
		(pad "1" smd custom
			(at 0 -0.4445 270)
			(size 0.1397 0.1397)
			(layers "B.Cu" "B.Mask" "B.Paste")
			(net "CBL_PRSNT_N_3")
			(options
				(clearance outline)
				(anchor circle)
			)
			(primitives
				(gr_poly
					(pts
						(arc
							(start -0.1778 0.2794)
							(mid -0.249642 0.249642)
							(end -0.2794 0.1778)
						)
						(arc
							(start -0.2794 -0.1778)
							(mid -0.249642 -0.249642)
							(end -0.1778 -0.2794)
						)
						(arc
							(start 0.1778 -0.2794)
							(mid 0.249642 -0.249642)
							(end 0.2794 -0.1778)
						)
						(arc
							(start 0.2794 0.1778)
							(mid 0.249642 0.249642)
							(end 0.1778 0.2794)
						)
					)
					(width 0)
					(fill yes)
				)
			)
		)
		(pad "2" smd custom
			(at 0 0.4445 270)
			(size 0.1397 0.1397)
			(layers "B.Cu" "B.Mask" "B.Paste")
			(net "P3V3_STBY")
			(options
				(clearance outline)
				(anchor circle)
			)
			(primitives
				(gr_poly
					(pts
						(arc
							(start -0.1778 0.2794)
							(mid -0.249642 0.249642)
							(end -0.2794 0.1778)
						)
						(arc
							(start -0.2794 -0.1778)
							(mid -0.249642 -0.249642)
							(end -0.1778 -0.2794)
						)
						(arc
							(start 0.1778 -0.2794)
							(mid 0.249642 -0.249642)
							(end 0.2794 -0.1778)
						)
						(arc
							(start 0.2794 0.1778)
							(mid 0.249642 0.249642)
							(end 0.1778 0.2794)
						)
					)
					(width 0)
					(fill yes)
				)
			)
		)
	)
	(footprint ""
		(layer "B.Cu")
		(at 230.251 -20.447)
		(property "Reference" "R3701"
			(at 0 0 0)
			(layer "B.SilkS")
			(hide yes)
			(effects
				(font
					(size 1.27 1.27)
				)
				(justify mirror)
			)
		)
		(property "Value" "4K7R2F-GP"
			(at -0.064008 -3.993896 0)
			(unlocked yes)
			(layer "B.Fab")
			(hide yes)
			(effects
				(font
					(size 1.016 1.016)
					(thickness 0.1524)
				)
				(justify mirror)
			)
		)
		(property "Device Type" "R402H16"
			(at -0.064008 -5.517896 0)
			(unlocked yes)
			(layer "B.Fab")
			(hide yes)
			(effects
				(font
					(size 1.016 1.016)
					(thickness 0.1524)
				)
				(justify mirror)
			)
		)
		(duplicate_pad_numbers_are_jumpers no)
		(fp_line
			(start -0.508 -0.9398)
			(end 0.508 -0.9398)
			(stroke
				(width 0.1524)
				(type default)
			)
			(layer "B.SilkS")
		)
		(fp_line
			(start 0.508 -0.9398)
			(end 0.508 0.9398)
			(stroke
				(width 0.1524)
				(type default)
			)
			(layer "B.SilkS")
		)
		(fp_rect
			(start 0.508 0.9398)
			(end -0.508 -0.9398)
			(stroke
				(width 0)
				(type default)
			)
			(fill no)
			(layer "B.CrtYd")
		)
		(fp_rect
			(start 0.508 0.9398)
			(end -0.508 -0.9398)
			(stroke
				(width 0)
				(type default)
			)
			(fill no)
			(layer "B.Fab")
		)
		(pad "1" smd custom
			(at 0 -0.4445 180)
			(size 0.1397 0.1397)
			(layers "B.Cu" "B.Mask" "B.Paste")
			(net "HOST1_RST_N_LS")
			(options
				(clearance outline)
				(anchor circle)
			)
			(primitives
				(gr_poly
					(pts
						(arc
							(start -0.1778 0.2794)
							(mid -0.249642 0.249642)
							(end -0.2794 0.1778)
						)
						(arc
							(start -0.2794 -0.1778)
							(mid -0.249642 -0.249642)
							(end -0.1778 -0.2794)
						)
						(arc
							(start 0.1778 -0.2794)
							(mid 0.249642 -0.249642)
							(end 0.2794 -0.1778)
						)
						(arc
							(start 0.2794 0.1778)
							(mid 0.249642 0.249642)
							(end 0.1778 0.2794)
						)
					)
					(width 0)
					(fill yes)
				)
			)
		)
		(pad "2" smd custom
			(at 0 0.4445 180)
			(size 0.1397 0.1397)
			(layers "B.Cu" "B.Mask" "B.Paste")
			(net "DUT_VDDO")
			(options
				(clearance outline)
				(anchor circle)
			)
			(primitives
				(gr_poly
					(pts
						(arc
							(start -0.1778 0.2794)
							(mid -0.249642 0.249642)
							(end -0.2794 0.1778)
						)
						(arc
							(start -0.2794 -0.1778)
							(mid -0.249642 -0.249642)
							(end -0.1778 -0.2794)
						)
						(arc
							(start 0.1778 -0.2794)
							(mid 0.249642 -0.249642)
							(end 0.2794 -0.1778)
						)
						(arc
							(start 0.2794 0.1778)
							(mid 0.249642 0.249642)
							(end 0.1778 0.2794)
						)
					)
					(width 0)
					(fill yes)
				)
			)
		)
	)
	(footprint ""
		(layer "B.Cu")
		(at 239.1664 -41.995852 90)
		(property "Reference" "C434"
			(at 0 0 90)
			(layer "B.SilkS")
			(hide yes)
			(effects
				(font
					(size 1.27 1.27)
				)
				(justify mirror)
			)
		)
		(property "Value" "SCD1U16V1KX-1-GP"
			(at 2.8321 -1.7399 90)
			(unlocked yes)
			(layer "B.Fab")
			(hide yes)
			(effects
				(font
					(size 1.016 1.016)
					(thickness 0.1524)
				)
				(justify mirror)
			)
		)
		(property "Device Type" "C0201H13"
			(at 2.8321 -3.2639 90)
			(unlocked yes)
			(layer "B.Fab")
			(hide yes)
			(effects
				(font
					(size 1.016 1.016)
					(thickness 0.1524)
				)
				(justify mirror)
			)
		)
		(duplicate_pad_numbers_are_jumpers no)
		(fp_rect
			(start 0.2794 0.6477)
			(end -0.2794 -0.6477)
			(stroke
				(width 0)
				(type default)
			)
			(fill no)
			(layer "B.CrtYd")
		)
		(fp_rect
			(start 0.2794 0.6477)
			(end -0.2794 -0.6477)
			(stroke
				(width 0)
				(type default)
			)
			(fill no)
			(layer "B.Fab")
		)
		(pad "1" smd custom
			(at 0 -0.2794 270)
			(size 0.0762 0.0762)
			(layers "B.Cu" "B.Mask" "B.Paste")
			(net "DUT_VDD")
			(options
				(clearance outline)
				(anchor circle)
			)
			(primitives
				(gr_poly
					(pts
						(arc
							(start 0.1524 0.127)
							(mid 0.137521 0.162921)
							(end 0.1016 0.1778)
						)
						(arc
							(start -0.1016 0.1778)
							(mid -0.137521 0.162921)
							(end -0.1524 0.127)
						)
						(arc
							(start -0.1524 -0.127)
							(mid -0.137521 -0.162921)
							(end -0.1016 -0.1778)
						)
						(arc
							(start 0.1016 -0.1778)
							(mid 0.137521 -0.162921)
							(end 0.1524 -0.127)
						)
					)
					(width 0)
					(fill yes)
				)
			)
		)
		(pad "2" smd custom
			(at 0 0.2794 270)
			(size 0.0762 0.0762)
			(layers "B.Cu" "B.Mask" "B.Paste")
			(net "GND")
			(options
				(clearance outline)
				(anchor circle)
			)
			(primitives
				(gr_poly
					(pts
						(arc
							(start 0.1524 0.127)
							(mid 0.137521 0.162921)
							(end 0.1016 0.1778)
						)
						(arc
							(start -0.1016 0.1778)
							(mid -0.137521 0.162921)
							(end -0.1524 0.127)
						)
						(arc
							(start -0.1524 -0.127)
							(mid -0.137521 -0.162921)
							(end -0.1016 -0.1778)
						)
						(arc
							(start 0.1016 -0.1778)
							(mid 0.137521 -0.162921)
							(end 0.1524 -0.127)
						)
					)
					(width 0)
					(fill yes)
				)
			)
		)
	)
	(footprint ""
		(layer "B.Cu")
		(at 252.603 -50.995072 -90)
		(property "Reference" "C551"
			(at 0 0 90)
			(layer "B.SilkS")
			(hide yes)
			(effects
				(font
					(size 1.27 1.27)
				)
				(justify mirror)
			)
		)
		(property "Value" "SCD1U16V1KX-1-GP"
			(at 2.8321 -1.7399 270)
			(unlocked yes)
			(layer "B.Fab")
			(hide yes)
			(effects
				(font
					(size 1.016 1.016)
					(thickness 0.1524)
				)
				(justify mirror)
			)
		)
		(property "Device Type" "C0201H13"
			(at 2.8321 -3.2639 270)
			(unlocked yes)
			(layer "B.Fab")
			(hide yes)
			(effects
				(font
					(size 1.016 1.016)
					(thickness 0.1524)
				)
				(justify mirror)
			)
		)
		(duplicate_pad_numbers_are_jumpers no)
		(fp_rect
			(start 0.2794 0.6477)
			(end -0.2794 -0.6477)
			(stroke
				(width 0)
				(type default)
			)
			(fill no)
			(layer "B.CrtYd")
		)
		(fp_rect
			(start 0.2794 0.6477)
			(end -0.2794 -0.6477)
			(stroke
				(width 0)
				(type default)
			)
			(fill no)
			(layer "B.Fab")
		)
		(pad "1" smd custom
			(at 0 -0.2794 90)
			(size 0.0762 0.0762)
			(layers "B.Cu" "B.Mask" "B.Paste")
			(net "DUT_AVD_PCIE")
			(options
				(clearance outline)
				(anchor circle)
			)
			(primitives
				(gr_poly
					(pts
						(arc
							(start 0.1524 0.127)
							(mid 0.137521 0.162921)
							(end 0.1016 0.1778)
						)
						(arc
							(start -0.1016 0.1778)
							(mid -0.137521 0.162921)
							(end -0.1524 0.127)
						)
						(arc
							(start -0.1524 -0.127)
							(mid -0.137521 -0.162921)
							(end -0.1016 -0.1778)
						)
						(arc
							(start 0.1016 -0.1778)
							(mid 0.137521 -0.162921)
							(end 0.1524 -0.127)
						)
					)
					(width 0)
					(fill yes)
				)
			)
		)
		(pad "2" smd custom
			(at 0 0.2794 90)
			(size 0.0762 0.0762)
			(layers "B.Cu" "B.Mask" "B.Paste")
			(net "GND")
			(options
				(clearance outline)
				(anchor circle)
			)
			(primitives
				(gr_poly
					(pts
						(arc
							(start 0.1524 0.127)
							(mid 0.137521 0.162921)
							(end 0.1016 0.1778)
						)
						(arc
							(start -0.1016 0.1778)
							(mid -0.137521 0.162921)
							(end -0.1524 0.127)
						)
						(arc
							(start -0.1524 -0.127)
							(mid -0.137521 -0.162921)
							(end -0.1016 -0.1778)
						)
						(arc
							(start 0.1016 -0.1778)
							(mid 0.137521 -0.162921)
							(end 0.1524 -0.127)
						)
					)
					(width 0)
					(fill yes)
				)
			)
		)
	)
	(footprint ""
		(layer "B.Cu")
		(at 23.45944 -143.51254 180)
		(property "Reference" "R317"
			(at 0 0 0)
			(layer "B.SilkS")
			(hide yes)
			(effects
				(font
					(size 1.27 1.27)
				)
				(justify mirror)
			)
		)
		(property "Value" "8K2R2J-3-GP"
			(at -0.064008 -3.993896 180)
			(unlocked yes)
			(layer "B.Fab")
			(hide yes)
			(effects
				(font
					(size 1.016 1.016)
					(thickness 0.1524)
				)
				(justify mirror)
			)
		)
		(property "Device Type" "R402H16"
			(at -0.064008 -5.517896 180)
			(unlocked yes)
			(layer "B.Fab")
			(hide yes)
			(effects
				(font
					(size 1.016 1.016)
					(thickness 0.1524)
				)
				(justify mirror)
			)
		)
		(duplicate_pad_numbers_are_jumpers no)
		(fp_line
			(start 0.508 -0.9398)
			(end 0.508 0.9398)
			(stroke
				(width 0.1524)
				(type default)
			)
			(layer "B.SilkS")
		)
		(fp_line
			(start -0.508 -0.9398)
			(end 0.508 -0.9398)
			(stroke
				(width 0.1524)
				(type default)
			)
			(layer "B.SilkS")
		)
		(fp_rect
			(start 0.508 0.9398)
			(end -0.508 -0.9398)
			(stroke
				(width 0)
				(type default)
			)
			(fill no)
			(layer "B.CrtYd")
		)
		(fp_rect
			(start 0.508 0.9398)
			(end -0.508 -0.9398)
			(stroke
				(width 0)
				(type default)
			)
			(fill no)
			(layer "B.Fab")
		)
		(pad "1" smd custom
			(at 0 -0.4445)
			(size 0.1397 0.1397)
			(layers "B.Cu" "B.Mask" "B.Paste")
			(net "PD_USB2VRES")
			(options
				(clearance outline)
				(anchor circle)
			)
			(primitives
				(gr_poly
					(pts
						(arc
							(start -0.1778 0.2794)
							(mid -0.249642 0.249642)
							(end -0.2794 0.1778)
						)
						(arc
							(start -0.2794 -0.1778)
							(mid -0.249642 -0.249642)
							(end -0.1778 -0.2794)
						)
						(arc
							(start 0.1778 -0.2794)
							(mid 0.249642 -0.249642)
							(end 0.2794 -0.1778)
						)
						(arc
							(start 0.2794 0.1778)
							(mid 0.249642 0.249642)
							(end 0.1778 0.2794)
						)
					)
					(width 0)
					(fill yes)
				)
			)
		)
		(pad "2" smd custom
			(at 0 0.4445)
			(size 0.1397 0.1397)
			(layers "B.Cu" "B.Mask" "B.Paste")
			(net "GND")
			(options
				(clearance outline)
				(anchor circle)
			)
			(primitives
				(gr_poly
					(pts
						(arc
							(start -0.1778 0.2794)
							(mid -0.249642 0.249642)
							(end -0.2794 0.1778)
						)
						(arc
							(start -0.2794 -0.1778)
							(mid -0.249642 -0.249642)
							(end -0.1778 -0.2794)
						)
						(arc
							(start 0.1778 -0.2794)
							(mid 0.249642 -0.249642)
							(end 0.2794 -0.1778)
						)
						(arc
							(start 0.2794 0.1778)
							(mid 0.249642 0.249642)
							(end 0.1778 0.2794)
						)
					)
					(width 0)
					(fill yes)
				)
			)
		)
	)
	(footprint ""
		(layer "B.Cu")
		(at 127.084328 -33.518856 180)
		(property "Reference" "C221"
			(at 0 0 0)
			(layer "B.SilkS")
			(hide yes)
			(effects
				(font
					(size 1.27 1.27)
				)
				(justify mirror)
			)
		)
		(property "Value" "SCD1U10V2KX-5GP"
			(at -1.1811 -2.7051 180)
			(unlocked yes)
			(layer "B.Fab")
			(hide yes)
			(effects
				(font
					(size 1.016 1.016)
					(thickness 0.1524)
				)
				(justify mirror)
			)
		)
		(property "Device Type" "C402H22"
			(at -1.1811 -4.2291 180)
			(unlocked yes)
			(layer "B.Fab")
			(hide yes)
			(effects
				(font
					(size 1.016 1.016)
					(thickness 0.1524)
				)
				(justify mirror)
			)
		)
		(duplicate_pad_numbers_are_jumpers no)
		(fp_rect
			(start 0.4318 0.9525)
			(end -0.4318 -0.9525)
			(stroke
				(width 0)
				(type default)
			)
			(fill no)
			(layer "B.CrtYd")
		)
		(fp_rect
			(start 0.4318 0.9525)
			(end -0.4318 -0.9525)
			(stroke
				(width 0)
				(type default)
			)
			(fill no)
			(layer "B.Fab")
		)
		(pad "1" smd custom
			(at 0 -0.4445)
			(size 0.1524 0.1524)
			(layers "B.Cu" "B.Mask" "B.Paste")
			(net "GND")
			(options
				(clearance outline)
				(anchor circle)
			)
			(primitives
				(gr_poly
					(pts
						(arc
							(start 0.3048 0.2032)
							(mid 0.275042 0.275042)
							(end 0.2032 0.3048)
						)
						(arc
							(start -0.2032 0.3048)
							(mid -0.275042 0.275042)
							(end -0.3048 0.2032)
						)
						(arc
							(start -0.3048 -0.2032)
							(mid -0.275042 -0.275042)
							(end -0.2032 -0.3048)
						)
						(arc
							(start 0.2032 -0.3048)
							(mid 0.275042 -0.275042)
							(end 0.3048 -0.2032)
						)
					)
					(width 0)
					(fill yes)
				)
			)
		)
		(pad "2" smd custom
			(at 0 0.4445)
			(size 0.1524 0.1524)
			(layers "B.Cu" "B.Mask" "B.Paste")
			(net "P3V3_STBY")
			(options
				(clearance outline)
				(anchor circle)
			)
			(primitives
				(gr_poly
					(pts
						(arc
							(start 0.3048 0.2032)
							(mid 0.275042 0.275042)
							(end 0.2032 0.3048)
						)
						(arc
							(start -0.2032 0.3048)
							(mid -0.275042 0.275042)
							(end -0.3048 0.2032)
						)
						(arc
							(start -0.3048 -0.2032)
							(mid -0.275042 -0.275042)
							(end -0.2032 -0.3048)
						)
						(arc
							(start 0.2032 -0.3048)
							(mid 0.275042 -0.275042)
							(end 0.3048 -0.2032)
						)
					)
					(width 0)
					(fill yes)
				)
			)
		)
	)
	(footprint ""
		(layer "B.Cu")
		(at 344.17 -71.501 180)
		(property "Reference" "PR2"
			(at 0 0 0)
			(layer "B.SilkS")
			(hide yes)
			(effects
				(font
					(size 1.27 1.27)
				)
				(justify mirror)
			)
		)
		(property "Value" "121KR2F-L-GP"
			(at -0.064008 -3.993896 180)
			(unlocked yes)
			(layer "B.Fab")
			(hide yes)
			(effects
				(font
					(size 1.016 1.016)
					(thickness 0.1524)
				)
				(justify mirror)
			)
		)
		(property "Device Type" "R402H16"
			(at -0.064008 -5.517896 180)
			(unlocked yes)
			(layer "B.Fab")
			(hide yes)
			(effects
				(font
					(size 1.016 1.016)
					(thickness 0.1524)
				)
				(justify mirror)
			)
		)
		(duplicate_pad_numbers_are_jumpers no)
		(fp_line
			(start 0.508 -0.9398)
			(end 0.508 0.9398)
			(stroke
				(width 0.1524)
				(type default)
			)
			(layer "B.SilkS")
		)
		(fp_line
			(start -0.508 -0.9398)
			(end 0.508 -0.9398)
			(stroke
				(width 0.1524)
				(type default)
			)
			(layer "B.SilkS")
		)
		(fp_rect
			(start 0.508 0.9398)
			(end -0.508 -0.9398)
			(stroke
				(width 0)
				(type default)
			)
			(fill no)
			(layer "B.CrtYd")
		)
		(fp_rect
			(start 0.508 0.9398)
			(end -0.508 -0.9398)
			(stroke
				(width 0)
				(type default)
			)
			(fill no)
			(layer "B.Fab")
		)
		(pad "1" smd custom
			(at 0 -0.4445)
			(size 0.1397 0.1397)
			(layers "B.Cu" "B.Mask" "B.Paste")
			(net "P0V9_E_TRIP")
			(options
				(clearance outline)
				(anchor circle)
			)
			(primitives
				(gr_poly
					(pts
						(arc
							(start -0.1778 0.2794)
							(mid -0.249642 0.249642)
							(end -0.2794 0.1778)
						)
						(arc
							(start -0.2794 -0.1778)
							(mid -0.249642 -0.249642)
							(end -0.1778 -0.2794)
						)
						(arc
							(start 0.1778 -0.2794)
							(mid 0.249642 -0.249642)
							(end 0.2794 -0.1778)
						)
						(arc
							(start 0.2794 0.1778)
							(mid 0.249642 0.249642)
							(end 0.1778 0.2794)
						)
					)
					(width 0)
					(fill yes)
				)
			)
		)
		(pad "2" smd custom
			(at 0 0.4445)
			(size 0.1397 0.1397)
			(layers "B.Cu" "B.Mask" "B.Paste")
			(net "AGND_P0V9_E")
			(options
				(clearance outline)
				(anchor circle)
			)
			(primitives
				(gr_poly
					(pts
						(arc
							(start -0.1778 0.2794)
							(mid -0.249642 0.249642)
							(end -0.2794 0.1778)
						)
						(arc
							(start -0.2794 -0.1778)
							(mid -0.249642 -0.249642)
							(end -0.1778 -0.2794)
						)
						(arc
							(start 0.1778 -0.2794)
							(mid 0.249642 -0.249642)
							(end 0.2794 -0.1778)
						)
						(arc
							(start 0.2794 0.1778)
							(mid 0.249642 0.249642)
							(end 0.1778 0.2794)
						)
					)
					(width 0)
					(fill yes)
				)
			)
		)
	)
	(footprint ""
		(layer "B.Cu")
		(at 267.0683 -8.85571 180)
		(property "Reference" "R2967"
			(at 0 0 0)
			(layer "B.SilkS")
			(hide yes)
			(effects
				(font
					(size 1.27 1.27)
				)
				(justify mirror)
			)
		)
		(property "Value" "0R2J-2-GP"
			(at -0.064008 -3.993896 180)
			(unlocked yes)
			(layer "B.Fab")
			(hide yes)
			(effects
				(font
					(size 1.016 1.016)
					(thickness 0.1524)
				)
				(justify mirror)
			)
		)
		(property "Device Type" "R402H16"
			(at -0.064008 -5.517896 180)
			(unlocked yes)
			(layer "B.Fab")
			(hide yes)
			(effects
				(font
					(size 1.016 1.016)
					(thickness 0.1524)
				)
				(justify mirror)
			)
		)
		(duplicate_pad_numbers_are_jumpers no)
		(fp_line
			(start 0.508 -0.9398)
			(end 0.508 0.9398)
			(stroke
				(width 0.1524)
				(type default)
			)
			(layer "B.SilkS")
		)
		(fp_line
			(start -0.508 -0.9398)
			(end 0.508 -0.9398)
			(stroke
				(width 0.1524)
				(type default)
			)
			(layer "B.SilkS")
		)
		(fp_rect
			(start 0.508 0.9398)
			(end -0.508 -0.9398)
			(stroke
				(width 0)
				(type default)
			)
			(fill no)
			(layer "B.CrtYd")
		)
		(fp_rect
			(start 0.508 0.9398)
			(end -0.508 -0.9398)
			(stroke
				(width 0)
				(type default)
			)
			(fill no)
			(layer "B.Fab")
		)
		(pad "1" smd custom
			(at 0 -0.4445)
			(size 0.1397 0.1397)
			(layers "B.Cu" "B.Mask" "B.Paste")
			(net "HOST8_RST_N")
			(options
				(clearance outline)
				(anchor circle)
			)
			(primitives
				(gr_poly
					(pts
						(arc
							(start -0.1778 0.2794)
							(mid -0.249642 0.249642)
							(end -0.2794 0.1778)
						)
						(arc
							(start -0.2794 -0.1778)
							(mid -0.249642 -0.249642)
							(end -0.1778 -0.2794)
						)
						(arc
							(start 0.1778 -0.2794)
							(mid 0.249642 -0.249642)
							(end 0.2794 -0.1778)
						)
						(arc
							(start 0.2794 0.1778)
							(mid 0.249642 0.249642)
							(end 0.1778 0.2794)
						)
					)
					(width 0)
					(fill yes)
				)
			)
		)
		(pad "2" smd custom
			(at 0 0.4445)
			(size 0.1397 0.1397)
			(layers "B.Cu" "B.Mask" "B.Paste")
			(net "HOST8_RST_N_C")
			(options
				(clearance outline)
				(anchor circle)
			)
			(primitives
				(gr_poly
					(pts
						(arc
							(start -0.1778 0.2794)
							(mid -0.249642 0.249642)
							(end -0.2794 0.1778)
						)
						(arc
							(start -0.2794 -0.1778)
							(mid -0.249642 -0.249642)
							(end -0.1778 -0.2794)
						)
						(arc
							(start 0.1778 -0.2794)
							(mid 0.249642 -0.249642)
							(end 0.2794 -0.1778)
						)
						(arc
							(start 0.2794 0.1778)
							(mid 0.249642 0.249642)
							(end 0.1778 0.2794)
						)
					)
					(width 0)
					(fill yes)
				)
			)
		)
	)
	(footprint ""
		(layer "B.Cu")
		(at 39.842948 -127.002794 180)
		(property "Reference" "C216"
			(at 0 0 0)
			(layer "B.SilkS")
			(hide yes)
			(effects
				(font
					(size 1.27 1.27)
				)
				(justify mirror)
			)
		)
		(property "Value" "SC1U10V2KX-4-GP"
			(at -1.1811 -2.7051 180)
			(unlocked yes)
			(layer "B.Fab")
			(hide yes)
			(effects
				(font
					(size 1.016 1.016)
					(thickness 0.1524)
				)
				(justify mirror)
			)
		)
		(property "Device Type" "C402H22"
			(at -1.1811 -4.2291 180)
			(unlocked yes)
			(layer "B.Fab")
			(hide yes)
			(effects
				(font
					(size 1.016 1.016)
					(thickness 0.1524)
				)
				(justify mirror)
			)
		)
		(duplicate_pad_numbers_are_jumpers no)
		(fp_rect
			(start 0.4318 0.9525)
			(end -0.4318 -0.9525)
			(stroke
				(width 0)
				(type default)
			)
			(fill no)
			(layer "B.CrtYd")
		)
		(fp_rect
			(start 0.4318 0.9525)
			(end -0.4318 -0.9525)
			(stroke
				(width 0)
				(type default)
			)
			(fill no)
			(layer "B.Fab")
		)
		(pad "1" smd custom
			(at 0 -0.4445)
			(size 0.1524 0.1524)
			(layers "B.Cu" "B.Mask" "B.Paste")
			(net "P3V3_STBY")
			(options
				(clearance outline)
				(anchor circle)
			)
			(primitives
				(gr_poly
					(pts
						(arc
							(start 0.3048 0.2032)
							(mid 0.275042 0.275042)
							(end 0.2032 0.3048)
						)
						(arc
							(start -0.2032 0.3048)
							(mid -0.275042 0.275042)
							(end -0.3048 0.2032)
						)
						(arc
							(start -0.3048 -0.2032)
							(mid -0.275042 -0.275042)
							(end -0.2032 -0.3048)
						)
						(arc
							(start 0.2032 -0.3048)
							(mid 0.275042 -0.275042)
							(end 0.3048 -0.2032)
						)
					)
					(width 0)
					(fill yes)
				)
			)
		)
		(pad "2" smd custom
			(at 0 0.4445)
			(size 0.1524 0.1524)
			(layers "B.Cu" "B.Mask" "B.Paste")
			(net "GND")
			(options
				(clearance outline)
				(anchor circle)
			)
			(primitives
				(gr_poly
					(pts
						(arc
							(start 0.3048 0.2032)
							(mid 0.275042 0.275042)
							(end 0.2032 0.3048)
						)
						(arc
							(start -0.2032 0.3048)
							(mid -0.275042 0.275042)
							(end -0.3048 0.2032)
						)
						(arc
							(start -0.3048 -0.2032)
							(mid -0.275042 -0.275042)
							(end -0.2032 -0.3048)
						)
						(arc
							(start 0.2032 -0.3048)
							(mid 0.275042 -0.275042)
							(end 0.3048 -0.2032)
						)
					)
					(width 0)
					(fill yes)
				)
			)
		)
	)
	(footprint ""
		(layer "B.Cu")
		(at 59.218322 -123.425966 90)
		(property "Reference" "R323"
			(at 0 0 90)
			(layer "B.SilkS")
			(hide yes)
			(effects
				(font
					(size 1.27 1.27)
				)
				(justify mirror)
			)
		)
		(property "Value" "4K7R2F-GP"
			(at -0.064008 -3.993896 90)
			(unlocked yes)
			(layer "B.Fab")
			(hide yes)
			(effects
				(font
					(size 1.016 1.016)
					(thickness 0.1524)
				)
				(justify mirror)
			)
		)
		(property "Device Type" "R402H16"
			(at -0.064008 -5.517896 90)
			(unlocked yes)
			(layer "B.Fab")
			(hide yes)
			(effects
				(font
					(size 1.016 1.016)
					(thickness 0.1524)
				)
				(justify mirror)
			)
		)
		(duplicate_pad_numbers_are_jumpers no)
		(fp_line
			(start 0.508 -0.9398)
			(end 0.508 0.9398)
			(stroke
				(width 0.1524)
				(type default)
			)
			(layer "B.SilkS")
		)
		(fp_line
			(start -0.508 -0.9398)
			(end 0.508 -0.9398)
			(stroke
				(width 0.1524)
				(type default)
			)
			(layer "B.SilkS")
		)
		(fp_rect
			(start 0.508 0.9398)
			(end -0.508 -0.9398)
			(stroke
				(width 0)
				(type default)
			)
			(fill no)
			(layer "B.CrtYd")
		)
		(fp_rect
			(start 0.508 0.9398)
			(end -0.508 -0.9398)
			(stroke
				(width 0)
				(type default)
			)
			(fill no)
			(layer "B.Fab")
		)
		(pad "1" smd custom
			(at 0 -0.4445 270)
			(size 0.1397 0.1397)
			(layers "B.Cu" "B.Mask" "B.Paste")
			(net "BMC_I2C8_CLKBUF1_SDA")
			(options
				(clearance outline)
				(anchor circle)
			)
			(primitives
				(gr_poly
					(pts
						(arc
							(start -0.1778 0.2794)
							(mid -0.249642 0.249642)
							(end -0.2794 0.1778)
						)
						(arc
							(start -0.2794 -0.1778)
							(mid -0.249642 -0.249642)
							(end -0.1778 -0.2794)
						)
						(arc
							(start 0.1778 -0.2794)
							(mid 0.249642 -0.249642)
							(end 0.2794 -0.1778)
						)
						(arc
							(start 0.2794 0.1778)
							(mid 0.249642 0.249642)
							(end 0.1778 0.2794)
						)
					)
					(width 0)
					(fill yes)
				)
			)
		)
		(pad "2" smd custom
			(at 0 0.4445 270)
			(size 0.1397 0.1397)
			(layers "B.Cu" "B.Mask" "B.Paste")
			(net "P3V3_STBY")
			(options
				(clearance outline)
				(anchor circle)
			)
			(primitives
				(gr_poly
					(pts
						(arc
							(start -0.1778 0.2794)
							(mid -0.249642 0.249642)
							(end -0.2794 0.1778)
						)
						(arc
							(start -0.2794 -0.1778)
							(mid -0.249642 -0.249642)
							(end -0.1778 -0.2794)
						)
						(arc
							(start 0.1778 -0.2794)
							(mid 0.249642 -0.249642)
							(end 0.2794 -0.1778)
						)
						(arc
							(start 0.2794 0.1778)
							(mid 0.249642 0.249642)
							(end 0.1778 0.2794)
						)
					)
					(width 0)
					(fill yes)
				)
			)
		)
	)
	(footprint ""
		(layer "B.Cu")
		(at 26.289 -116.713)
		(property "Reference" "R259"
			(at 0 0 0)
			(layer "B.SilkS")
			(hide yes)
			(effects
				(font
					(size 1.27 1.27)
				)
				(justify mirror)
			)
		)
		(property "Value" "100KR2F-L1-GP"
			(at -0.064008 -3.993896 0)
			(unlocked yes)
			(layer "B.Fab")
			(hide yes)
			(effects
				(font
					(size 1.016 1.016)
					(thickness 0.1524)
				)
				(justify mirror)
			)
		)
		(property "Device Type" "R402H16"
			(at -0.064008 -5.517896 0)
			(unlocked yes)
			(layer "B.Fab")
			(hide yes)
			(effects
				(font
					(size 1.016 1.016)
					(thickness 0.1524)
				)
				(justify mirror)
			)
		)
		(duplicate_pad_numbers_are_jumpers no)
		(fp_line
			(start -0.508 -0.9398)
			(end 0.508 -0.9398)
			(stroke
				(width 0.1524)
				(type default)
			)
			(layer "B.SilkS")
		)
		(fp_line
			(start 0.508 -0.9398)
			(end 0.508 0.9398)
			(stroke
				(width 0.1524)
				(type default)
			)
			(layer "B.SilkS")
		)
		(fp_rect
			(start 0.508 0.9398)
			(end -0.508 -0.9398)
			(stroke
				(width 0)
				(type default)
			)
			(fill no)
			(layer "B.CrtYd")
		)
		(fp_rect
			(start 0.508 0.9398)
			(end -0.508 -0.9398)
			(stroke
				(width 0)
				(type default)
			)
			(fill no)
			(layer "B.Fab")
		)
		(pad "1" smd custom
			(at 0 -0.4445 180)
			(size 0.1397 0.1397)
			(layers "B.Cu" "B.Mask" "B.Paste")
			(net "TP_IRQ_CPU_SERIAL")
			(options
				(clearance outline)
				(anchor circle)
			)
			(primitives
				(gr_poly
					(pts
						(arc
							(start -0.1778 0.2794)
							(mid -0.249642 0.249642)
							(end -0.2794 0.1778)
						)
						(arc
							(start -0.2794 -0.1778)
							(mid -0.249642 -0.249642)
							(end -0.1778 -0.2794)
						)
						(arc
							(start 0.1778 -0.2794)
							(mid 0.249642 -0.249642)
							(end 0.2794 -0.1778)
						)
						(arc
							(start 0.2794 0.1778)
							(mid 0.249642 0.249642)
							(end 0.1778 0.2794)
						)
					)
					(width 0)
					(fill yes)
				)
			)
		)
		(pad "2" smd custom
			(at 0 0.4445 180)
			(size 0.1397 0.1397)
			(layers "B.Cu" "B.Mask" "B.Paste")
			(net "GND")
			(options
				(clearance outline)
				(anchor circle)
			)
			(primitives
				(gr_poly
					(pts
						(arc
							(start -0.1778 0.2794)
							(mid -0.249642 0.249642)
							(end -0.2794 0.1778)
						)
						(arc
							(start -0.2794 -0.1778)
							(mid -0.249642 -0.249642)
							(end -0.1778 -0.2794)
						)
						(arc
							(start 0.1778 -0.2794)
							(mid 0.249642 -0.249642)
							(end 0.2794 -0.1778)
						)
						(arc
							(start 0.2794 0.1778)
							(mid 0.249642 0.249642)
							(end 0.1778 0.2794)
						)
					)
					(width 0)
					(fill yes)
				)
			)
		)
	)
	(footprint ""
		(layer "B.Cu")
		(at 241.6048 -59.0042 -90)
		(property "Reference" "C509"
			(at 0 0 90)
			(layer "B.SilkS")
			(hide yes)
			(effects
				(font
					(size 1.27 1.27)
				)
				(justify mirror)
			)
		)
		(property "Value" "SCD1U16V1KX-1-GP"
			(at 2.8321 -1.7399 270)
			(unlocked yes)
			(layer "B.Fab")
			(hide yes)
			(effects
				(font
					(size 1.016 1.016)
					(thickness 0.1524)
				)
				(justify mirror)
			)
		)
		(property "Device Type" "C0201H13"
			(at 2.8321 -3.2639 270)
			(unlocked yes)
			(layer "B.Fab")
			(hide yes)
			(effects
				(font
					(size 1.016 1.016)
					(thickness 0.1524)
				)
				(justify mirror)
			)
		)
		(duplicate_pad_numbers_are_jumpers no)
		(fp_rect
			(start 0.2794 0.6477)
			(end -0.2794 -0.6477)
			(stroke
				(width 0)
				(type default)
			)
			(fill no)
			(layer "B.CrtYd")
		)
		(fp_rect
			(start 0.2794 0.6477)
			(end -0.2794 -0.6477)
			(stroke
				(width 0)
				(type default)
			)
			(fill no)
			(layer "B.Fab")
		)
		(pad "1" smd custom
			(at 0 -0.2794 90)
			(size 0.0762 0.0762)
			(layers "B.Cu" "B.Mask" "B.Paste")
			(net "DUT_AVD_TX")
			(options
				(clearance outline)
				(anchor circle)
			)
			(primitives
				(gr_poly
					(pts
						(arc
							(start 0.1524 0.127)
							(mid 0.137521 0.162921)
							(end 0.1016 0.1778)
						)
						(arc
							(start -0.1016 0.1778)
							(mid -0.137521 0.162921)
							(end -0.1524 0.127)
						)
						(arc
							(start -0.1524 -0.127)
							(mid -0.137521 -0.162921)
							(end -0.1016 -0.1778)
						)
						(arc
							(start 0.1016 -0.1778)
							(mid 0.137521 -0.162921)
							(end 0.1524 -0.127)
						)
					)
					(width 0)
					(fill yes)
				)
			)
		)
		(pad "2" smd custom
			(at 0 0.2794 90)
			(size 0.0762 0.0762)
			(layers "B.Cu" "B.Mask" "B.Paste")
			(net "GND")
			(options
				(clearance outline)
				(anchor circle)
			)
			(primitives
				(gr_poly
					(pts
						(arc
							(start 0.1524 0.127)
							(mid 0.137521 0.162921)
							(end 0.1016 0.1778)
						)
						(arc
							(start -0.1016 0.1778)
							(mid -0.137521 0.162921)
							(end -0.1524 0.127)
						)
						(arc
							(start -0.1524 -0.127)
							(mid -0.137521 -0.162921)
							(end -0.1016 -0.1778)
						)
						(arc
							(start 0.1016 -0.1778)
							(mid 0.137521 -0.162921)
							(end 0.1524 -0.127)
						)
					)
					(width 0)
					(fill yes)
				)
			)
		)
	)
	(footprint ""
		(layer "B.Cu")
		(at 18.315432 -128.664208 -90)
		(property "Reference" "R565"
			(at 0 0 90)
			(layer "B.SilkS")
			(hide yes)
			(effects
				(font
					(size 1.27 1.27)
				)
				(justify mirror)
			)
		)
		(property "Value" "0R2J-2-GP"
			(at -0.064008 -3.993896 270)
			(unlocked yes)
			(layer "B.Fab")
			(hide yes)
			(effects
				(font
					(size 1.016 1.016)
					(thickness 0.1524)
				)
				(justify mirror)
			)
		)
		(property "Device Type" "R402H16"
			(at -0.064008 -5.517896 270)
			(unlocked yes)
			(layer "B.Fab")
			(hide yes)
			(effects
				(font
					(size 1.016 1.016)
					(thickness 0.1524)
				)
				(justify mirror)
			)
		)
		(duplicate_pad_numbers_are_jumpers no)
		(fp_line
			(start -0.508 -0.9398)
			(end 0.508 -0.9398)
			(stroke
				(width 0.1524)
				(type default)
			)
			(layer "B.SilkS")
		)
		(fp_line
			(start 0.508 -0.9398)
			(end 0.508 0.9398)
			(stroke
				(width 0.1524)
				(type default)
			)
			(layer "B.SilkS")
		)
		(fp_rect
			(start 0.508 0.9398)
			(end -0.508 -0.9398)
			(stroke
				(width 0)
				(type default)
			)
			(fill no)
			(layer "B.CrtYd")
		)
		(fp_rect
			(start 0.508 0.9398)
			(end -0.508 -0.9398)
			(stroke
				(width 0)
				(type default)
			)
			(fill no)
			(layer "B.Fab")
		)
		(pad "1" smd custom
			(at 0 -0.4445 90)
			(size 0.1397 0.1397)
			(layers "B.Cu" "B.Mask" "B.Paste")
			(net "PE1_PERST#")
			(options
				(clearance outline)
				(anchor circle)
			)
			(primitives
				(gr_poly
					(pts
						(arc
							(start -0.1778 0.2794)
							(mid -0.249642 0.249642)
							(end -0.2794 0.1778)
						)
						(arc
							(start -0.2794 -0.1778)
							(mid -0.249642 -0.249642)
							(end -0.1778 -0.2794)
						)
						(arc
							(start 0.1778 -0.2794)
							(mid 0.249642 -0.249642)
							(end 0.2794 -0.1778)
						)
						(arc
							(start 0.2794 0.1778)
							(mid 0.249642 0.249642)
							(end 0.1778 0.2794)
						)
					)
					(width 0)
					(fill yes)
				)
			)
		)
		(pad "2" smd custom
			(at 0 0.4445 90)
			(size 0.1397 0.1397)
			(layers "B.Cu" "B.Mask" "B.Paste")
			(net "PE1_PERST#_BMC")
			(options
				(clearance outline)
				(anchor circle)
			)
			(primitives
				(gr_poly
					(pts
						(arc
							(start -0.1778 0.2794)
							(mid -0.249642 0.249642)
							(end -0.2794 0.1778)
						)
						(arc
							(start -0.2794 -0.1778)
							(mid -0.249642 -0.249642)
							(end -0.1778 -0.2794)
						)
						(arc
							(start 0.1778 -0.2794)
							(mid 0.249642 -0.249642)
							(end 0.2794 -0.1778)
						)
						(arc
							(start 0.2794 0.1778)
							(mid 0.249642 0.249642)
							(end 0.1778 0.2794)
						)
					)
					(width 0)
					(fill yes)
				)
			)
		)
	)
	(footprint ""
		(layer "B.Cu")
		(at 332.9686 -181.7116)
		(property "Reference" "R3213"
			(at 0 0 0)
			(layer "B.SilkS")
			(hide yes)
			(effects
				(font
					(size 1.27 1.27)
				)
				(justify mirror)
			)
		)
		(property "Value" "0R2J-2-GP"
			(at -0.064008 -3.993896 0)
			(unlocked yes)
			(layer "B.Fab")
			(hide yes)
			(effects
				(font
					(size 1.016 1.016)
					(thickness 0.1524)
				)
				(justify mirror)
			)
		)
		(property "Device Type" "R402H16"
			(at -0.064008 -5.517896 0)
			(unlocked yes)
			(layer "B.Fab")
			(hide yes)
			(effects
				(font
					(size 1.016 1.016)
					(thickness 0.1524)
				)
				(justify mirror)
			)
		)
		(duplicate_pad_numbers_are_jumpers no)
		(fp_line
			(start -0.508 -0.9398)
			(end 0.508 -0.9398)
			(stroke
				(width 0.1524)
				(type default)
			)
			(layer "B.SilkS")
		)
		(fp_line
			(start 0.508 -0.9398)
			(end 0.508 0.9398)
			(stroke
				(width 0.1524)
				(type default)
			)
			(layer "B.SilkS")
		)
		(fp_rect
			(start 0.508 0.9398)
			(end -0.508 -0.9398)
			(stroke
				(width 0)
				(type default)
			)
			(fill no)
			(layer "B.CrtYd")
		)
		(fp_rect
			(start 0.508 0.9398)
			(end -0.508 -0.9398)
			(stroke
				(width 0)
				(type default)
			)
			(fill no)
			(layer "B.Fab")
		)
		(pad "1" smd custom
			(at 0 -0.4445 180)
			(size 0.1397 0.1397)
			(layers "B.Cu" "B.Mask" "B.Paste")
			(net "SSD_PERST#4")
			(options
				(clearance outline)
				(anchor circle)
			)
			(primitives
				(gr_poly
					(pts
						(arc
							(start -0.1778 0.2794)
							(mid -0.249642 0.249642)
							(end -0.2794 0.1778)
						)
						(arc
							(start -0.2794 -0.1778)
							(mid -0.249642 -0.249642)
							(end -0.1778 -0.2794)
						)
						(arc
							(start 0.1778 -0.2794)
							(mid 0.249642 -0.249642)
							(end 0.2794 -0.1778)
						)
						(arc
							(start 0.2794 0.1778)
							(mid 0.249642 0.249642)
							(end 0.1778 0.2794)
						)
					)
					(width 0)
					(fill yes)
				)
			)
		)
		(pad "2" smd custom
			(at 0 0.4445 180)
			(size 0.1397 0.1397)
			(layers "B.Cu" "B.Mask" "B.Paste")
			(net "SSD_PERST#0_B4")
			(options
				(clearance outline)
				(anchor circle)
			)
			(primitives
				(gr_poly
					(pts
						(arc
							(start -0.1778 0.2794)
							(mid -0.249642 0.249642)
							(end -0.2794 0.1778)
						)
						(arc
							(start -0.2794 -0.1778)
							(mid -0.249642 -0.249642)
							(end -0.1778 -0.2794)
						)
						(arc
							(start 0.1778 -0.2794)
							(mid 0.249642 -0.249642)
							(end 0.2794 -0.1778)
						)
						(arc
							(start 0.2794 0.1778)
							(mid 0.249642 0.249642)
							(end 0.1778 0.2794)
						)
					)
					(width 0)
					(fill yes)
				)
			)
		)
	)
	(footprint ""
		(layer "B.Cu")
		(at 235.585 -59.0042 90)
		(property "Reference" "C528"
			(at 0 0 90)
			(layer "B.SilkS")
			(hide yes)
			(effects
				(font
					(size 1.27 1.27)
				)
				(justify mirror)
			)
		)
		(property "Value" "SCD1U16V1KX-1-GP"
			(at 2.8321 -1.7399 90)
			(unlocked yes)
			(layer "B.Fab")
			(hide yes)
			(effects
				(font
					(size 1.016 1.016)
					(thickness 0.1524)
				)
				(justify mirror)
			)
		)
		(property "Device Type" "C0201H13"
			(at 2.8321 -3.2639 90)
			(unlocked yes)
			(layer "B.Fab")
			(hide yes)
			(effects
				(font
					(size 1.016 1.016)
					(thickness 0.1524)
				)
				(justify mirror)
			)
		)
		(duplicate_pad_numbers_are_jumpers no)
		(fp_rect
			(start 0.2794 0.6477)
			(end -0.2794 -0.6477)
			(stroke
				(width 0)
				(type default)
			)
			(fill no)
			(layer "B.CrtYd")
		)
		(fp_rect
			(start 0.2794 0.6477)
			(end -0.2794 -0.6477)
			(stroke
				(width 0)
				(type default)
			)
			(fill no)
			(layer "B.Fab")
		)
		(pad "1" smd custom
			(at 0 -0.2794 270)
			(size 0.0762 0.0762)
			(layers "B.Cu" "B.Mask" "B.Paste")
			(net "DUT_AVD_TX")
			(options
				(clearance outline)
				(anchor circle)
			)
			(primitives
				(gr_poly
					(pts
						(arc
							(start 0.1524 0.127)
							(mid 0.137521 0.162921)
							(end 0.1016 0.1778)
						)
						(arc
							(start -0.1016 0.1778)
							(mid -0.137521 0.162921)
							(end -0.1524 0.127)
						)
						(arc
							(start -0.1524 -0.127)
							(mid -0.137521 -0.162921)
							(end -0.1016 -0.1778)
						)
						(arc
							(start 0.1016 -0.1778)
							(mid 0.137521 -0.162921)
							(end 0.1524 -0.127)
						)
					)
					(width 0)
					(fill yes)
				)
			)
		)
		(pad "2" smd custom
			(at 0 0.2794 270)
			(size 0.0762 0.0762)
			(layers "B.Cu" "B.Mask" "B.Paste")
			(net "GND")
			(options
				(clearance outline)
				(anchor circle)
			)
			(primitives
				(gr_poly
					(pts
						(arc
							(start 0.1524 0.127)
							(mid 0.137521 0.162921)
							(end 0.1016 0.1778)
						)
						(arc
							(start -0.1016 0.1778)
							(mid -0.137521 0.162921)
							(end -0.1524 0.127)
						)
						(arc
							(start -0.1524 -0.127)
							(mid -0.137521 -0.162921)
							(end -0.1016 -0.1778)
						)
						(arc
							(start 0.1016 -0.1778)
							(mid 0.137521 -0.162921)
							(end 0.1524 -0.127)
						)
					)
					(width 0)
					(fill yes)
				)
			)
		)
	)
	(footprint ""
		(layer "B.Cu")
		(at 246.599964 -38.999922 -90)
		(property "Reference" "TP300"
			(at 0 0 90)
			(layer "B.SilkS")
			(hide yes)
			(effects
				(font
					(size 1.27 1.27)
				)
				(justify mirror)
			)
		)
		(property "Value" "TPAD28-2-GP"
			(at 0.0127 -1.6637 270)
			(unlocked yes)
			(layer "B.Fab")
			(hide yes)
			(effects
				(font
					(size 1.016 1.016)
					(thickness 0.1524)
				)
				(justify mirror)
			)
		)
		(property "Device Type" "TPAD28"
			(at 0.0127 -3.1877 270)
			(unlocked yes)
			(layer "B.Fab")
			(hide yes)
			(effects
				(font
					(size 1.016 1.016)
					(thickness 0.1524)
				)
				(justify mirror)
			)
		)
		(duplicate_pad_numbers_are_jumpers no)
		(fp_poly
			(pts
				(arc
					(start 0 -0.3556)
					(mid 0 0.3556)
					(end 0 -0.3556)
				)
			)
			(stroke
				(width 0)
				(type default)
			)
			(fill no)
			(layer "B.CrtYd")
		)
		(fp_poly
			(pts
				(arc
					(start 0 -0.6096)
					(mid 0 0.6096)
					(end 0 -0.6096)
				)
			)
			(stroke
				(width 0)
				(type default)
			)
			(fill no)
			(layer "B.Fab")
		)
		(pad "1" smd circle
			(at 0 0 90)
			(size 0.7112 0.7112)
			(layers "B.Cu" "B.Mask" "B.Paste")
			(net "TWI_SRST#9")
		)
	)
	(footprint ""
		(layer "B.Cu")
		(at 49.1871 -116.032788 180)
		(property "Reference" "R462"
			(at 0 0 0)
			(layer "B.SilkS")
			(hide yes)
			(effects
				(font
					(size 1.27 1.27)
				)
				(justify mirror)
			)
		)
		(property "Value" "0R2J-2-GP"
			(at -0.064008 -3.993896 180)
			(unlocked yes)
			(layer "B.Fab")
			(hide yes)
			(effects
				(font
					(size 1.016 1.016)
					(thickness 0.1524)
				)
				(justify mirror)
			)
		)
		(property "Device Type" "R402H16"
			(at -0.064008 -5.517896 180)
			(unlocked yes)
			(layer "B.Fab")
			(hide yes)
			(effects
				(font
					(size 1.016 1.016)
					(thickness 0.1524)
				)
				(justify mirror)
			)
		)
		(duplicate_pad_numbers_are_jumpers no)
		(fp_line
			(start 0.508 -0.9398)
			(end 0.508 0.9398)
			(stroke
				(width 0.1524)
				(type default)
			)
			(layer "B.SilkS")
		)
		(fp_line
			(start -0.508 -0.9398)
			(end 0.508 -0.9398)
			(stroke
				(width 0.1524)
				(type default)
			)
			(layer "B.SilkS")
		)
		(fp_rect
			(start 0.508 0.9398)
			(end -0.508 -0.9398)
			(stroke
				(width 0)
				(type default)
			)
			(fill no)
			(layer "B.CrtYd")
		)
		(fp_rect
			(start 0.508 0.9398)
			(end -0.508 -0.9398)
			(stroke
				(width 0)
				(type default)
			)
			(fill no)
			(layer "B.Fab")
		)
		(pad "1" smd custom
			(at 0 -0.4445)
			(size 0.1397 0.1397)
			(layers "B.Cu" "B.Mask" "B.Paste")
			(net "BMC_I2C9_CLKBUF2_SDA")
			(options
				(clearance outline)
				(anchor circle)
			)
			(primitives
				(gr_poly
					(pts
						(arc
							(start -0.1778 0.2794)
							(mid -0.249642 0.249642)
							(end -0.2794 0.1778)
						)
						(arc
							(start -0.2794 -0.1778)
							(mid -0.249642 -0.249642)
							(end -0.1778 -0.2794)
						)
						(arc
							(start 0.1778 -0.2794)
							(mid 0.249642 -0.249642)
							(end 0.2794 -0.1778)
						)
						(arc
							(start 0.2794 0.1778)
							(mid 0.249642 0.249642)
							(end 0.1778 0.2794)
						)
					)
					(width 0)
					(fill yes)
				)
			)
		)
		(pad "2" smd custom
			(at 0 0.4445)
			(size 0.1397 0.1397)
			(layers "B.Cu" "B.Mask" "B.Paste")
			(net "BMC0_SMB9_DAT")
			(options
				(clearance outline)
				(anchor circle)
			)
			(primitives
				(gr_poly
					(pts
						(arc
							(start -0.1778 0.2794)
							(mid -0.249642 0.249642)
							(end -0.2794 0.1778)
						)
						(arc
							(start -0.2794 -0.1778)
							(mid -0.249642 -0.249642)
							(end -0.1778 -0.2794)
						)
						(arc
							(start 0.1778 -0.2794)
							(mid 0.249642 -0.249642)
							(end 0.2794 -0.1778)
						)
						(arc
							(start 0.2794 0.1778)
							(mid 0.249642 0.249642)
							(end 0.1778 0.2794)
						)
					)
					(width 0)
					(fill yes)
				)
			)
		)
	)
	(footprint ""
		(layer "B.Cu")
		(at 243.586 -56.9976 -90)
		(property "Reference" "C514"
			(at 0 0 90)
			(layer "B.SilkS")
			(hide yes)
			(effects
				(font
					(size 1.27 1.27)
				)
				(justify mirror)
			)
		)
		(property "Value" "SCD1U16V1KX-1-GP"
			(at 2.8321 -1.7399 270)
			(unlocked yes)
			(layer "B.Fab")
			(hide yes)
			(effects
				(font
					(size 1.016 1.016)
					(thickness 0.1524)
				)
				(justify mirror)
			)
		)
		(property "Device Type" "C0201H13"
			(at 2.8321 -3.2639 270)
			(unlocked yes)
			(layer "B.Fab")
			(hide yes)
			(effects
				(font
					(size 1.016 1.016)
					(thickness 0.1524)
				)
				(justify mirror)
			)
		)
		(duplicate_pad_numbers_are_jumpers no)
		(fp_rect
			(start 0.2794 0.6477)
			(end -0.2794 -0.6477)
			(stroke
				(width 0)
				(type default)
			)
			(fill no)
			(layer "B.CrtYd")
		)
		(fp_rect
			(start 0.2794 0.6477)
			(end -0.2794 -0.6477)
			(stroke
				(width 0)
				(type default)
			)
			(fill no)
			(layer "B.Fab")
		)
		(pad "1" smd custom
			(at 0 -0.2794 90)
			(size 0.0762 0.0762)
			(layers "B.Cu" "B.Mask" "B.Paste")
			(net "DUT_AVD_TX")
			(options
				(clearance outline)
				(anchor circle)
			)
			(primitives
				(gr_poly
					(pts
						(arc
							(start 0.1524 0.127)
							(mid 0.137521 0.162921)
							(end 0.1016 0.1778)
						)
						(arc
							(start -0.1016 0.1778)
							(mid -0.137521 0.162921)
							(end -0.1524 0.127)
						)
						(arc
							(start -0.1524 -0.127)
							(mid -0.137521 -0.162921)
							(end -0.1016 -0.1778)
						)
						(arc
							(start 0.1016 -0.1778)
							(mid 0.137521 -0.162921)
							(end 0.1524 -0.127)
						)
					)
					(width 0)
					(fill yes)
				)
			)
		)
		(pad "2" smd custom
			(at 0 0.2794 90)
			(size 0.0762 0.0762)
			(layers "B.Cu" "B.Mask" "B.Paste")
			(net "GND")
			(options
				(clearance outline)
				(anchor circle)
			)
			(primitives
				(gr_poly
					(pts
						(arc
							(start 0.1524 0.127)
							(mid 0.137521 0.162921)
							(end 0.1016 0.1778)
						)
						(arc
							(start -0.1016 0.1778)
							(mid -0.137521 0.162921)
							(end -0.1524 0.127)
						)
						(arc
							(start -0.1524 -0.127)
							(mid -0.137521 -0.162921)
							(end -0.1016 -0.1778)
						)
						(arc
							(start 0.1016 -0.1778)
							(mid 0.137521 -0.162921)
							(end 0.1524 -0.127)
						)
					)
					(width 0)
					(fill yes)
				)
			)
		)
	)
	(footprint ""
		(layer "B.Cu")
		(at 272.161 -9.271 90)
		(property "Reference" "R2964"
			(at 0 0 90)
			(layer "B.SilkS")
			(hide yes)
			(effects
				(font
					(size 1.27 1.27)
				)
				(justify mirror)
			)
		)
		(property "Value" "0R2J-2-GP"
			(at -0.064008 -3.993896 90)
			(unlocked yes)
			(layer "B.Fab")
			(hide yes)
			(effects
				(font
					(size 1.016 1.016)
					(thickness 0.1524)
				)
				(justify mirror)
			)
		)
		(property "Device Type" "R402H16"
			(at -0.064008 -5.517896 90)
			(unlocked yes)
			(layer "B.Fab")
			(hide yes)
			(effects
				(font
					(size 1.016 1.016)
					(thickness 0.1524)
				)
				(justify mirror)
			)
		)
		(duplicate_pad_numbers_are_jumpers no)
		(fp_line
			(start 0.508 -0.9398)
			(end 0.508 0.9398)
			(stroke
				(width 0.1524)
				(type default)
			)
			(layer "B.SilkS")
		)
		(fp_line
			(start -0.508 -0.9398)
			(end 0.508 -0.9398)
			(stroke
				(width 0.1524)
				(type default)
			)
			(layer "B.SilkS")
		)
		(fp_rect
			(start 0.508 0.9398)
			(end -0.508 -0.9398)
			(stroke
				(width 0)
				(type default)
			)
			(fill no)
			(layer "B.CrtYd")
		)
		(fp_rect
			(start 0.508 0.9398)
			(end -0.508 -0.9398)
			(stroke
				(width 0)
				(type default)
			)
			(fill no)
			(layer "B.Fab")
		)
		(pad "1" smd custom
			(at 0 -0.4445 270)
			(size 0.1397 0.1397)
			(layers "B.Cu" "B.Mask" "B.Paste")
			(net "PCIE_REFCLK_H0_P")
			(options
				(clearance outline)
				(anchor circle)
			)
			(primitives
				(gr_poly
					(pts
						(arc
							(start -0.1778 0.2794)
							(mid -0.249642 0.249642)
							(end -0.2794 0.1778)
						)
						(arc
							(start -0.2794 -0.1778)
							(mid -0.249642 -0.249642)
							(end -0.1778 -0.2794)
						)
						(arc
							(start 0.1778 -0.2794)
							(mid 0.249642 -0.249642)
							(end 0.2794 -0.1778)
						)
						(arc
							(start 0.2794 0.1778)
							(mid 0.249642 0.249642)
							(end 0.1778 0.2794)
						)
					)
					(width 0)
					(fill yes)
				)
			)
		)
		(pad "2" smd custom
			(at 0 0.4445 270)
			(size 0.1397 0.1397)
			(layers "B.Cu" "B.Mask" "B.Paste")
			(net "PCIE_REFCLK_H0_P_R")
			(options
				(clearance outline)
				(anchor circle)
			)
			(primitives
				(gr_poly
					(pts
						(arc
							(start -0.1778 0.2794)
							(mid -0.249642 0.249642)
							(end -0.2794 0.1778)
						)
						(arc
							(start -0.2794 -0.1778)
							(mid -0.249642 -0.249642)
							(end -0.1778 -0.2794)
						)
						(arc
							(start 0.1778 -0.2794)
							(mid 0.249642 -0.249642)
							(end 0.2794 -0.1778)
						)
						(arc
							(start 0.2794 0.1778)
							(mid 0.249642 0.249642)
							(end 0.1778 0.2794)
						)
					)
					(width 0)
					(fill yes)
				)
			)
		)
	)
	(footprint ""
		(layer "B.Cu")
		(at 58.565288 -116.995702)
		(property "Reference" "R475"
			(at 0 0 0)
			(layer "B.SilkS")
			(hide yes)
			(effects
				(font
					(size 1.27 1.27)
				)
				(justify mirror)
			)
		)
		(property "Value" "4K7R2F-GP"
			(at -0.064008 -3.993896 0)
			(unlocked yes)
			(layer "B.Fab")
			(hide yes)
			(effects
				(font
					(size 1.016 1.016)
					(thickness 0.1524)
				)
				(justify mirror)
			)
		)
		(property "Device Type" "R402H16"
			(at -0.064008 -5.517896 0)
			(unlocked yes)
			(layer "B.Fab")
			(hide yes)
			(effects
				(font
					(size 1.016 1.016)
					(thickness 0.1524)
				)
				(justify mirror)
			)
		)
		(duplicate_pad_numbers_are_jumpers no)
		(fp_line
			(start -0.508 -0.9398)
			(end 0.508 -0.9398)
			(stroke
				(width 0.1524)
				(type default)
			)
			(layer "B.SilkS")
		)
		(fp_line
			(start 0.508 -0.9398)
			(end 0.508 0.9398)
			(stroke
				(width 0.1524)
				(type default)
			)
			(layer "B.SilkS")
		)
		(fp_rect
			(start 0.508 0.9398)
			(end -0.508 -0.9398)
			(stroke
				(width 0)
				(type default)
			)
			(fill no)
			(layer "B.CrtYd")
		)
		(fp_rect
			(start 0.508 0.9398)
			(end -0.508 -0.9398)
			(stroke
				(width 0)
				(type default)
			)
			(fill no)
			(layer "B.Fab")
		)
		(pad "1" smd custom
			(at 0 -0.4445 180)
			(size 0.1397 0.1397)
			(layers "B.Cu" "B.Mask" "B.Paste")
			(net "BMC_I2C3_MINI3_SCL_S")
			(options
				(clearance outline)
				(anchor circle)
			)
			(primitives
				(gr_poly
					(pts
						(arc
							(start -0.1778 0.2794)
							(mid -0.249642 0.249642)
							(end -0.2794 0.1778)
						)
						(arc
							(start -0.2794 -0.1778)
							(mid -0.249642 -0.249642)
							(end -0.1778 -0.2794)
						)
						(arc
							(start 0.1778 -0.2794)
							(mid 0.249642 -0.249642)
							(end 0.2794 -0.1778)
						)
						(arc
							(start 0.2794 0.1778)
							(mid 0.249642 0.249642)
							(end 0.1778 0.2794)
						)
					)
					(width 0)
					(fill yes)
				)
			)
		)
		(pad "2" smd custom
			(at 0 0.4445 180)
			(size 0.1397 0.1397)
			(layers "B.Cu" "B.Mask" "B.Paste")
			(net "P3V3_STBY")
			(options
				(clearance outline)
				(anchor circle)
			)
			(primitives
				(gr_poly
					(pts
						(arc
							(start -0.1778 0.2794)
							(mid -0.249642 0.249642)
							(end -0.2794 0.1778)
						)
						(arc
							(start -0.2794 -0.1778)
							(mid -0.249642 -0.249642)
							(end -0.1778 -0.2794)
						)
						(arc
							(start 0.1778 -0.2794)
							(mid 0.249642 -0.249642)
							(end 0.2794 -0.1778)
						)
						(arc
							(start 0.2794 0.1778)
							(mid 0.249642 0.249642)
							(end 0.1778 0.2794)
						)
					)
					(width 0)
					(fill yes)
				)
			)
		)
	)
	(footprint ""
		(layer "B.Cu")
		(at 131.843526 -199.889618)
		(property "Reference" "C418"
			(at 0 0 0)
			(layer "B.SilkS")
			(hide yes)
			(effects
				(font
					(size 1.27 1.27)
				)
				(justify mirror)
			)
		)
		(property "Value" "SCD1U25V2KX-2-GP"
			(at -1.1811 -2.7051 0)
			(unlocked yes)
			(layer "B.Fab")
			(hide yes)
			(effects
				(font
					(size 1.016 1.016)
					(thickness 0.1524)
				)
				(justify mirror)
			)
		)
		(property "Device Type" "C402H22"
			(at -1.1811 -4.2291 0)
			(unlocked yes)
			(layer "B.Fab")
			(hide yes)
			(effects
				(font
					(size 1.016 1.016)
					(thickness 0.1524)
				)
				(justify mirror)
			)
		)
		(duplicate_pad_numbers_are_jumpers no)
		(fp_rect
			(start 0.4318 0.9525)
			(end -0.4318 -0.9525)
			(stroke
				(width 0)
				(type default)
			)
			(fill no)
			(layer "B.CrtYd")
		)
		(fp_rect
			(start 0.4318 0.9525)
			(end -0.4318 -0.9525)
			(stroke
				(width 0)
				(type default)
			)
			(fill no)
			(layer "B.Fab")
		)
		(pad "1" smd custom
			(at 0 -0.4445 180)
			(size 0.1524 0.1524)
			(layers "B.Cu" "B.Mask" "B.Paste")
			(net "P3V3_STBY")
			(options
				(clearance outline)
				(anchor circle)
			)
			(primitives
				(gr_poly
					(pts
						(arc
							(start 0.3048 0.2032)
							(mid 0.275042 0.275042)
							(end 0.2032 0.3048)
						)
						(arc
							(start -0.2032 0.3048)
							(mid -0.275042 0.275042)
							(end -0.3048 0.2032)
						)
						(arc
							(start -0.3048 -0.2032)
							(mid -0.275042 -0.275042)
							(end -0.2032 -0.3048)
						)
						(arc
							(start 0.2032 -0.3048)
							(mid 0.275042 -0.275042)
							(end 0.3048 -0.2032)
						)
					)
					(width 0)
					(fill yes)
				)
			)
		)
		(pad "2" smd custom
			(at 0 0.4445 180)
			(size 0.1524 0.1524)
			(layers "B.Cu" "B.Mask" "B.Paste")
			(net "GND")
			(options
				(clearance outline)
				(anchor circle)
			)
			(primitives
				(gr_poly
					(pts
						(arc
							(start 0.3048 0.2032)
							(mid 0.275042 0.275042)
							(end 0.2032 0.3048)
						)
						(arc
							(start -0.2032 0.3048)
							(mid -0.275042 0.275042)
							(end -0.3048 0.2032)
						)
						(arc
							(start -0.3048 -0.2032)
							(mid -0.275042 -0.275042)
							(end -0.2032 -0.3048)
						)
						(arc
							(start 0.2032 -0.3048)
							(mid 0.275042 -0.275042)
							(end 0.3048 -0.2032)
						)
					)
					(width 0)
					(fill yes)
				)
			)
		)
	)
	(footprint ""
		(layer "B.Cu")
		(at 49.1744 -113.1316)
		(property "Reference" "R433"
			(at 0 0 0)
			(layer "B.SilkS")
			(hide yes)
			(effects
				(font
					(size 1.27 1.27)
				)
				(justify mirror)
			)
		)
		(property "Value" "4K7R2F-GP"
			(at -0.064008 -3.993896 0)
			(unlocked yes)
			(layer "B.Fab")
			(hide yes)
			(effects
				(font
					(size 1.016 1.016)
					(thickness 0.1524)
				)
				(justify mirror)
			)
		)
		(property "Device Type" "R402H16"
			(at -0.064008 -5.517896 0)
			(unlocked yes)
			(layer "B.Fab")
			(hide yes)
			(effects
				(font
					(size 1.016 1.016)
					(thickness 0.1524)
				)
				(justify mirror)
			)
		)
		(duplicate_pad_numbers_are_jumpers no)
		(fp_line
			(start -0.508 -0.9398)
			(end 0.508 -0.9398)
			(stroke
				(width 0.1524)
				(type default)
			)
			(layer "B.SilkS")
		)
		(fp_line
			(start 0.508 -0.9398)
			(end 0.508 0.9398)
			(stroke
				(width 0.1524)
				(type default)
			)
			(layer "B.SilkS")
		)
		(fp_rect
			(start 0.508 0.9398)
			(end -0.508 -0.9398)
			(stroke
				(width 0)
				(type default)
			)
			(fill no)
			(layer "B.CrtYd")
		)
		(fp_rect
			(start 0.508 0.9398)
			(end -0.508 -0.9398)
			(stroke
				(width 0)
				(type default)
			)
			(fill no)
			(layer "B.Fab")
		)
		(pad "1" smd custom
			(at 0 -0.4445 180)
			(size 0.1397 0.1397)
			(layers "B.Cu" "B.Mask" "B.Paste")
			(net "BMC_I2C9_CLKBUF2_SDA")
			(options
				(clearance outline)
				(anchor circle)
			)
			(primitives
				(gr_poly
					(pts
						(arc
							(start -0.1778 0.2794)
							(mid -0.249642 0.249642)
							(end -0.2794 0.1778)
						)
						(arc
							(start -0.2794 -0.1778)
							(mid -0.249642 -0.249642)
							(end -0.1778 -0.2794)
						)
						(arc
							(start 0.1778 -0.2794)
							(mid 0.249642 -0.249642)
							(end 0.2794 -0.1778)
						)
						(arc
							(start 0.2794 0.1778)
							(mid 0.249642 0.249642)
							(end 0.1778 0.2794)
						)
					)
					(width 0)
					(fill yes)
				)
			)
		)
		(pad "2" smd custom
			(at 0 0.4445 180)
			(size 0.1397 0.1397)
			(layers "B.Cu" "B.Mask" "B.Paste")
			(net "P3V3_STBY")
			(options
				(clearance outline)
				(anchor circle)
			)
			(primitives
				(gr_poly
					(pts
						(arc
							(start -0.1778 0.2794)
							(mid -0.249642 0.249642)
							(end -0.2794 0.1778)
						)
						(arc
							(start -0.2794 -0.1778)
							(mid -0.249642 -0.249642)
							(end -0.1778 -0.2794)
						)
						(arc
							(start 0.1778 -0.2794)
							(mid 0.249642 -0.249642)
							(end 0.2794 -0.1778)
						)
						(arc
							(start 0.2794 0.1778)
							(mid 0.249642 0.249642)
							(end 0.1778 0.2794)
						)
					)
					(width 0)
					(fill yes)
				)
			)
		)
	)
	(footprint ""
		(layer "B.Cu")
		(at 337.7946 -181.8386)
		(property "Reference" "R3228"
			(at 0 0 0)
			(layer "B.SilkS")
			(hide yes)
			(effects
				(font
					(size 1.27 1.27)
				)
				(justify mirror)
			)
		)
		(property "Value" "0R2J-2-GP"
			(at -0.064008 -3.993896 0)
			(unlocked yes)
			(layer "B.Fab")
			(hide yes)
			(effects
				(font
					(size 1.016 1.016)
					(thickness 0.1524)
				)
				(justify mirror)
			)
		)
		(property "Device Type" "R402H16"
			(at -0.064008 -5.517896 0)
			(unlocked yes)
			(layer "B.Fab")
			(hide yes)
			(effects
				(font
					(size 1.016 1.016)
					(thickness 0.1524)
				)
				(justify mirror)
			)
		)
		(duplicate_pad_numbers_are_jumpers no)
		(fp_line
			(start -0.508 -0.9398)
			(end 0.508 -0.9398)
			(stroke
				(width 0.1524)
				(type default)
			)
			(layer "B.SilkS")
		)
		(fp_line
			(start 0.508 -0.9398)
			(end 0.508 0.9398)
			(stroke
				(width 0.1524)
				(type default)
			)
			(layer "B.SilkS")
		)
		(fp_rect
			(start 0.508 0.9398)
			(end -0.508 -0.9398)
			(stroke
				(width 0)
				(type default)
			)
			(fill no)
			(layer "B.CrtYd")
		)
		(fp_rect
			(start 0.508 0.9398)
			(end -0.508 -0.9398)
			(stroke
				(width 0)
				(type default)
			)
			(fill no)
			(layer "B.Fab")
		)
		(pad "1" smd custom
			(at 0 -0.4445 180)
			(size 0.1397 0.1397)
			(layers "B.Cu" "B.Mask" "B.Paste")
			(net "SSD_PERST#9")
			(options
				(clearance outline)
				(anchor circle)
			)
			(primitives
				(gr_poly
					(pts
						(arc
							(start -0.1778 0.2794)
							(mid -0.249642 0.249642)
							(end -0.2794 0.1778)
						)
						(arc
							(start -0.2794 -0.1778)
							(mid -0.249642 -0.249642)
							(end -0.1778 -0.2794)
						)
						(arc
							(start 0.1778 -0.2794)
							(mid 0.249642 -0.249642)
							(end 0.2794 -0.1778)
						)
						(arc
							(start 0.2794 0.1778)
							(mid 0.249642 0.249642)
							(end 0.1778 0.2794)
						)
					)
					(width 0)
					(fill yes)
				)
			)
		)
		(pad "2" smd custom
			(at 0 0.4445 180)
			(size 0.1397 0.1397)
			(layers "B.Cu" "B.Mask" "B.Paste")
			(net "SSD_PERST#0_B9")
			(options
				(clearance outline)
				(anchor circle)
			)
			(primitives
				(gr_poly
					(pts
						(arc
							(start -0.1778 0.2794)
							(mid -0.249642 0.249642)
							(end -0.2794 0.1778)
						)
						(arc
							(start -0.2794 -0.1778)
							(mid -0.249642 -0.249642)
							(end -0.1778 -0.2794)
						)
						(arc
							(start 0.1778 -0.2794)
							(mid 0.249642 -0.249642)
							(end 0.2794 -0.1778)
						)
						(arc
							(start 0.2794 0.1778)
							(mid 0.249642 0.249642)
							(end 0.1778 0.2794)
						)
					)
					(width 0)
					(fill yes)
				)
			)
		)
	)
	(footprint ""
		(layer "B.Cu")
		(at 232.59542 -60.1218)
		(property "Reference" "C604"
			(at 0 0 0)
			(layer "B.SilkS")
			(hide yes)
			(effects
				(font
					(size 1.27 1.27)
				)
				(justify mirror)
			)
		)
		(property "Value" "SCD1U16V1KX-1-GP"
			(at 2.8321 -1.7399 0)
			(unlocked yes)
			(layer "B.Fab")
			(hide yes)
			(effects
				(font
					(size 1.016 1.016)
					(thickness 0.1524)
				)
				(justify mirror)
			)
		)
		(property "Device Type" "C0201H13"
			(at 2.8321 -3.2639 0)
			(unlocked yes)
			(layer "B.Fab")
			(hide yes)
			(effects
				(font
					(size 1.016 1.016)
					(thickness 0.1524)
				)
				(justify mirror)
			)
		)
		(duplicate_pad_numbers_are_jumpers no)
		(fp_rect
			(start 0.2794 0.6477)
			(end -0.2794 -0.6477)
			(stroke
				(width 0)
				(type default)
			)
			(fill no)
			(layer "B.CrtYd")
		)
		(fp_rect
			(start 0.2794 0.6477)
			(end -0.2794 -0.6477)
			(stroke
				(width 0)
				(type default)
			)
			(fill no)
			(layer "B.Fab")
		)
		(pad "1" smd custom
			(at 0 -0.2794 180)
			(size 0.0762 0.0762)
			(layers "B.Cu" "B.Mask" "B.Paste")
			(net "DUT_AVD_PCIE")
			(options
				(clearance outline)
				(anchor circle)
			)
			(primitives
				(gr_poly
					(pts
						(arc
							(start 0.1524 0.127)
							(mid 0.137521 0.162921)
							(end 0.1016 0.1778)
						)
						(arc
							(start -0.1016 0.1778)
							(mid -0.137521 0.162921)
							(end -0.1524 0.127)
						)
						(arc
							(start -0.1524 -0.127)
							(mid -0.137521 -0.162921)
							(end -0.1016 -0.1778)
						)
						(arc
							(start 0.1016 -0.1778)
							(mid 0.137521 -0.162921)
							(end 0.1524 -0.127)
						)
					)
					(width 0)
					(fill yes)
				)
			)
		)
		(pad "2" smd custom
			(at 0 0.2794 180)
			(size 0.0762 0.0762)
			(layers "B.Cu" "B.Mask" "B.Paste")
			(net "GND")
			(options
				(clearance outline)
				(anchor circle)
			)
			(primitives
				(gr_poly
					(pts
						(arc
							(start 0.1524 0.127)
							(mid 0.137521 0.162921)
							(end 0.1016 0.1778)
						)
						(arc
							(start -0.1016 0.1778)
							(mid -0.137521 0.162921)
							(end -0.1524 0.127)
						)
						(arc
							(start -0.1524 -0.127)
							(mid -0.137521 -0.162921)
							(end -0.1016 -0.1778)
						)
						(arc
							(start 0.1016 -0.1778)
							(mid 0.137521 -0.162921)
							(end 0.1524 -0.127)
						)
					)
					(width 0)
					(fill yes)
				)
			)
		)
	)
	(footprint ""
		(layer "B.Cu")
		(at 82.55 -189.611)
		(property "Reference" "U74"
			(at 0 0 0)
			(layer "B.SilkS")
			(hide yes)
			(effects
				(font
					(size 1.27 1.27)
				)
				(justify mirror)
			)
		)
		(property "Value" "SN74LVC1G08DCKR-GP"
			(at 2.3368 -8.6868 0)
			(unlocked yes)
			(layer "B.Fab")
			(hide yes)
			(effects
				(font
					(size 1.016 1.016)
					(thickness 0.1524)
				)
				(justify mirror)
			)
		)
		(property "Device Type" "SC70-5H44"
			(at 2.3114 -10.414 0)
			(unlocked yes)
			(layer "B.Fab")
			(hide yes)
			(effects
				(font
					(size 1.016 1.016)
					(thickness 0.1524)
				)
				(justify mirror)
			)
		)
		(duplicate_pad_numbers_are_jumpers no)
		(fp_line
			(start -1.3843 -1.8034)
			(end -1.3843 -1.1176)
			(stroke
				(width 0.3302)
				(type default)
			)
			(layer "B.SilkS")
		)
		(fp_line
			(start -1.27 -1.7018)
			(end -1.27 1.7018)
			(stroke
				(width 0.1524)
				(type default)
			)
			(layer "B.SilkS")
		)
		(fp_line
			(start -1.27 1.7018)
			(end 1.27 1.7018)
			(stroke
				(width 0.1524)
				(type default)
			)
			(layer "B.SilkS")
		)
		(fp_line
			(start -0.6604 -1.8034)
			(end -1.3843 -1.8034)
			(stroke
				(width 0.3302)
				(type default)
			)
			(layer "B.SilkS")
		)
		(fp_line
			(start 1.27 -1.7018)
			(end -1.27 -1.7018)
			(stroke
				(width 0.1524)
				(type default)
			)
			(layer "B.SilkS")
		)
		(fp_line
			(start 1.27 1.7018)
			(end 1.27 -1.7018)
			(stroke
				(width 0.1524)
				(type default)
			)
			(layer "B.SilkS")
		)
		(fp_rect
			(start 1.524 1.9558)
			(end -1.524 -1.9558)
			(stroke
				(width 0)
				(type default)
			)
			(fill no)
			(layer "B.CrtYd")
		)
		(fp_poly
			(pts
				(xy 1.524 -1.9558) (xy -1.524 -1.9558) (xy -1.524 1.9558) (xy 1.524 1.9558)
			)
			(stroke
				(width 0)
				(type default)
			)
			(fill no)
			(layer "B.Fab")
		)
		(pad "1" smd rect
			(at -0.65024 -0.8255 180)
			(size 0.4064 1.2192)
			(layers "B.Cu" "B.Mask" "B.Paste")
			(net "BMC_SSD_RST#0_A10")
		)
		(pad "2" smd rect
			(at 0 -0.8255 180)
			(size 0.4064 1.2192)
			(layers "B.Cu" "B.Mask" "B.Paste")
			(net "SSD_PERST#0_B10")
		)
		(pad "3" smd rect
			(at 0.65024 -0.8255 180)
			(size 0.4064 1.2192)
			(layers "B.Cu" "B.Mask" "B.Paste")
			(net "GND")
		)
		(pad "4" smd rect
			(at 0.65024 0.8255 180)
			(size 0.4064 1.2192)
			(layers "B.Cu" "B.Mask" "B.Paste")
			(net "SSD_PERST_Y10")
		)
		(pad "5" smd rect
			(at -0.65024 0.8255 180)
			(size 0.4064 1.2192)
			(layers "B.Cu" "B.Mask" "B.Paste")
			(net "P3V3_STBY")
		)
	)
	(footprint ""
		(layer "B.Cu")
		(at 178.0794 -65.405)
		(property "Reference" "PG22"
			(at 0 0 0)
			(layer "B.SilkS")
			(hide yes)
			(effects
				(font
					(size 1.27 1.27)
				)
				(justify mirror)
			)
		)
		(property "Value" "GAP-CLOSE-PWR-3-GP"
			(at -0.0254 -6.5786 0)
			(unlocked yes)
			(layer "B.Fab")
			(hide yes)
			(effects
				(font
					(size 1.016 1.016)
					(thickness 0.1524)
				)
				(justify mirror)
			)
		)
		(property "Device Type" "GAP-CLOSE-PWR-3"
			(at -0.0254 -8.255 0)
			(unlocked yes)
			(layer "B.Fab")
			(hide yes)
			(effects
				(font
					(size 1.016 1.016)
					(thickness 0.1524)
				)
				(justify mirror)
			)
		)
		(duplicate_pad_numbers_are_jumpers no)
		(fp_rect
			(start 0.7112 0.4572)
			(end -0.7112 -0.4572)
			(stroke
				(width 0)
				(type default)
			)
			(fill no)
			(layer "B.CrtYd")
		)
		(fp_poly
			(pts
				(xy 0.7112 -0.4572) (xy -0.7112 -0.4572) (xy -0.7112 0.4572) (xy 0.7112 0.4572)
			)
			(stroke
				(width 0)
				(type default)
			)
			(fill no)
			(layer "B.Fab")
		)
		(pad "1" smd rect
			(at 0.3048 0 180)
			(size 0.6604 0.762)
			(layers "B.Cu" "B.Mask" "B.Paste")
			(net "DUT_AVD_PCIE")
		)
		(pad "2" smd rect
			(at -0.3048 0 180)
			(size 0.6604 0.762)
			(layers "B.Cu" "B.Mask" "B.Paste")
			(net "P0V9")
		)
	)
	(footprint ""
		(layer "B.Cu")
		(at 217.66276 -200.71588 90)
		(property "Reference" "R3211"
			(at 0 0 90)
			(layer "B.SilkS")
			(hide yes)
			(effects
				(font
					(size 1.27 1.27)
				)
				(justify mirror)
			)
		)
		(property "Value" "0R2J-2-GP"
			(at -0.064008 -3.993896 90)
			(unlocked yes)
			(layer "B.Fab")
			(hide yes)
			(effects
				(font
					(size 1.016 1.016)
					(thickness 0.1524)
				)
				(justify mirror)
			)
		)
		(property "Device Type" "R402H16"
			(at -0.064008 -5.517896 90)
			(unlocked yes)
			(layer "B.Fab")
			(hide yes)
			(effects
				(font
					(size 1.016 1.016)
					(thickness 0.1524)
				)
				(justify mirror)
			)
		)
		(duplicate_pad_numbers_are_jumpers no)
		(fp_line
			(start 0.508 -0.9398)
			(end 0.508 0.9398)
			(stroke
				(width 0.1524)
				(type default)
			)
			(layer "B.SilkS")
		)
		(fp_line
			(start -0.508 -0.9398)
			(end 0.508 -0.9398)
			(stroke
				(width 0.1524)
				(type default)
			)
			(layer "B.SilkS")
		)
		(fp_rect
			(start 0.508 0.9398)
			(end -0.508 -0.9398)
			(stroke
				(width 0)
				(type default)
			)
			(fill no)
			(layer "B.CrtYd")
		)
		(fp_rect
			(start 0.508 0.9398)
			(end -0.508 -0.9398)
			(stroke
				(width 0)
				(type default)
			)
			(fill no)
			(layer "B.Fab")
		)
		(pad "1" smd custom
			(at 0 -0.4445 270)
			(size 0.1397 0.1397)
			(layers "B.Cu" "B.Mask" "B.Paste")
			(net "BMC_SSD_RST#3")
			(options
				(clearance outline)
				(anchor circle)
			)
			(primitives
				(gr_poly
					(pts
						(arc
							(start -0.1778 0.2794)
							(mid -0.249642 0.249642)
							(end -0.2794 0.1778)
						)
						(arc
							(start -0.2794 -0.1778)
							(mid -0.249642 -0.249642)
							(end -0.1778 -0.2794)
						)
						(arc
							(start 0.1778 -0.2794)
							(mid 0.249642 -0.249642)
							(end 0.2794 -0.1778)
						)
						(arc
							(start 0.2794 0.1778)
							(mid 0.249642 0.249642)
							(end 0.1778 0.2794)
						)
					)
					(width 0)
					(fill yes)
				)
			)
		)
		(pad "2" smd custom
			(at 0 0.4445 270)
			(size 0.1397 0.1397)
			(layers "B.Cu" "B.Mask" "B.Paste")
			(net "BMC_SSD_RST#0_A3")
			(options
				(clearance outline)
				(anchor circle)
			)
			(primitives
				(gr_poly
					(pts
						(arc
							(start -0.1778 0.2794)
							(mid -0.249642 0.249642)
							(end -0.2794 0.1778)
						)
						(arc
							(start -0.2794 -0.1778)
							(mid -0.249642 -0.249642)
							(end -0.1778 -0.2794)
						)
						(arc
							(start 0.1778 -0.2794)
							(mid 0.249642 -0.249642)
							(end 0.2794 -0.1778)
						)
						(arc
							(start 0.2794 0.1778)
							(mid 0.249642 0.249642)
							(end 0.1778 0.2794)
						)
					)
					(width 0)
					(fill yes)
				)
			)
		)
	)
	(footprint ""
		(layer "B.Cu")
		(at 214.58174 -200.04786)
		(property "Reference" "R3240"
			(at 0 0 0)
			(layer "B.SilkS")
			(hide yes)
			(effects
				(font
					(size 1.27 1.27)
				)
				(justify mirror)
			)
		)
		(property "Value" "0R2J-2-GP"
			(at -0.064008 -3.993896 0)
			(unlocked yes)
			(layer "B.Fab")
			(hide yes)
			(effects
				(font
					(size 1.016 1.016)
					(thickness 0.1524)
				)
				(justify mirror)
			)
		)
		(property "Device Type" "R402H16"
			(at -0.064008 -5.517896 0)
			(unlocked yes)
			(layer "B.Fab")
			(hide yes)
			(effects
				(font
					(size 1.016 1.016)
					(thickness 0.1524)
				)
				(justify mirror)
			)
		)
		(duplicate_pad_numbers_are_jumpers no)
		(fp_line
			(start -0.508 -0.9398)
			(end 0.508 -0.9398)
			(stroke
				(width 0.1524)
				(type default)
			)
			(layer "B.SilkS")
		)
		(fp_line
			(start 0.508 -0.9398)
			(end 0.508 0.9398)
			(stroke
				(width 0.1524)
				(type default)
			)
			(layer "B.SilkS")
		)
		(fp_rect
			(start 0.508 0.9398)
			(end -0.508 -0.9398)
			(stroke
				(width 0)
				(type default)
			)
			(fill no)
			(layer "B.CrtYd")
		)
		(fp_rect
			(start 0.508 0.9398)
			(end -0.508 -0.9398)
			(stroke
				(width 0)
				(type default)
			)
			(fill no)
			(layer "B.Fab")
		)
		(pad "1" smd custom
			(at 0 -0.4445 180)
			(size 0.1397 0.1397)
			(layers "B.Cu" "B.Mask" "B.Paste")
			(net "SSD_PERST#13")
			(options
				(clearance outline)
				(anchor circle)
			)
			(primitives
				(gr_poly
					(pts
						(arc
							(start -0.1778 0.2794)
							(mid -0.249642 0.249642)
							(end -0.2794 0.1778)
						)
						(arc
							(start -0.2794 -0.1778)
							(mid -0.249642 -0.249642)
							(end -0.1778 -0.2794)
						)
						(arc
							(start 0.1778 -0.2794)
							(mid 0.249642 -0.249642)
							(end 0.2794 -0.1778)
						)
						(arc
							(start 0.2794 0.1778)
							(mid 0.249642 0.249642)
							(end 0.1778 0.2794)
						)
					)
					(width 0)
					(fill yes)
				)
			)
		)
		(pad "2" smd custom
			(at 0 0.4445 180)
			(size 0.1397 0.1397)
			(layers "B.Cu" "B.Mask" "B.Paste")
			(net "SSD_PERST#0_B13")
			(options
				(clearance outline)
				(anchor circle)
			)
			(primitives
				(gr_poly
					(pts
						(arc
							(start -0.1778 0.2794)
							(mid -0.249642 0.249642)
							(end -0.2794 0.1778)
						)
						(arc
							(start -0.2794 -0.1778)
							(mid -0.249642 -0.249642)
							(end -0.1778 -0.2794)
						)
						(arc
							(start 0.1778 -0.2794)
							(mid 0.249642 -0.249642)
							(end 0.2794 -0.1778)
						)
						(arc
							(start 0.2794 0.1778)
							(mid 0.249642 0.249642)
							(end 0.1778 0.2794)
						)
					)
					(width 0)
					(fill yes)
				)
			)
		)
	)
	(footprint ""
		(layer "B.Cu")
		(at 242.824 -23.241 180)
		(property "Reference" "R780"
			(at 0 0 0)
			(layer "B.SilkS")
			(hide yes)
			(effects
				(font
					(size 1.27 1.27)
				)
				(justify mirror)
			)
		)
		(property "Value" "4K7R2F-GP"
			(at -0.064008 -3.993896 180)
			(unlocked yes)
			(layer "B.Fab")
			(hide yes)
			(effects
				(font
					(size 1.016 1.016)
					(thickness 0.1524)
				)
				(justify mirror)
			)
		)
		(property "Device Type" "R402H16"
			(at -0.064008 -5.517896 180)
			(unlocked yes)
			(layer "B.Fab")
			(hide yes)
			(effects
				(font
					(size 1.016 1.016)
					(thickness 0.1524)
				)
				(justify mirror)
			)
		)
		(duplicate_pad_numbers_are_jumpers no)
		(fp_line
			(start 0.508 -0.9398)
			(end 0.508 0.9398)
			(stroke
				(width 0.1524)
				(type default)
			)
			(layer "B.SilkS")
		)
		(fp_line
			(start -0.508 -0.9398)
			(end 0.508 -0.9398)
			(stroke
				(width 0.1524)
				(type default)
			)
			(layer "B.SilkS")
		)
		(fp_rect
			(start 0.508 0.9398)
			(end -0.508 -0.9398)
			(stroke
				(width 0)
				(type default)
			)
			(fill no)
			(layer "B.CrtYd")
		)
		(fp_rect
			(start 0.508 0.9398)
			(end -0.508 -0.9398)
			(stroke
				(width 0)
				(type default)
			)
			(fill no)
			(layer "B.Fab")
		)
		(pad "1" smd custom
			(at 0 -0.4445)
			(size 0.1397 0.1397)
			(layers "B.Cu" "B.Mask" "B.Paste")
			(net "BOOTSTRAP0")
			(options
				(clearance outline)
				(anchor circle)
			)
			(primitives
				(gr_poly
					(pts
						(arc
							(start -0.1778 0.2794)
							(mid -0.249642 0.249642)
							(end -0.2794 0.1778)
						)
						(arc
							(start -0.2794 -0.1778)
							(mid -0.249642 -0.249642)
							(end -0.1778 -0.2794)
						)
						(arc
							(start 0.1778 -0.2794)
							(mid 0.249642 -0.249642)
							(end 0.2794 -0.1778)
						)
						(arc
							(start 0.2794 0.1778)
							(mid 0.249642 0.249642)
							(end 0.1778 0.2794)
						)
					)
					(width 0)
					(fill yes)
				)
			)
		)
		(pad "2" smd custom
			(at 0 0.4445)
			(size 0.1397 0.1397)
			(layers "B.Cu" "B.Mask" "B.Paste")
			(net "BOOTSTRAP_R_0")
			(options
				(clearance outline)
				(anchor circle)
			)
			(primitives
				(gr_poly
					(pts
						(arc
							(start -0.1778 0.2794)
							(mid -0.249642 0.249642)
							(end -0.2794 0.1778)
						)
						(arc
							(start -0.2794 -0.1778)
							(mid -0.249642 -0.249642)
							(end -0.1778 -0.2794)
						)
						(arc
							(start 0.1778 -0.2794)
							(mid 0.249642 -0.249642)
							(end 0.2794 -0.1778)
						)
						(arc
							(start 0.2794 0.1778)
							(mid 0.249642 0.249642)
							(end 0.1778 0.2794)
						)
					)
					(width 0)
					(fill yes)
				)
			)
		)
	)
	(footprint ""
		(layer "B.Cu")
		(at 310.007 -57.785 180)
		(property "Reference" "PG39"
			(at 0 0 0)
			(layer "B.SilkS")
			(hide yes)
			(effects
				(font
					(size 1.27 1.27)
				)
				(justify mirror)
			)
		)
		(property "Value" "GAP-CLOSE-PWR-3-GP"
			(at -0.0254 -6.5786 180)
			(unlocked yes)
			(layer "B.Fab")
			(hide yes)
			(effects
				(font
					(size 1.016 1.016)
					(thickness 0.1524)
				)
				(justify mirror)
			)
		)
		(property "Device Type" "GAP-CLOSE-PWR-3"
			(at -0.0254 -8.255 180)
			(unlocked yes)
			(layer "B.Fab")
			(hide yes)
			(effects
				(font
					(size 1.016 1.016)
					(thickness 0.1524)
				)
				(justify mirror)
			)
		)
		(duplicate_pad_numbers_are_jumpers no)
		(fp_rect
			(start 0.7112 0.4572)
			(end -0.7112 -0.4572)
			(stroke
				(width 0)
				(type default)
			)
			(fill no)
			(layer "B.CrtYd")
		)
		(fp_poly
			(pts
				(xy 0.7112 -0.4572) (xy -0.7112 -0.4572) (xy -0.7112 0.4572) (xy 0.7112 0.4572)
			)
			(stroke
				(width 0)
				(type default)
			)
			(fill no)
			(layer "B.Fab")
		)
		(pad "1" smd rect
			(at 0.3048 0)
			(size 0.6604 0.762)
			(layers "B.Cu" "B.Mask" "B.Paste")
			(net "DUT_VDD")
		)
		(pad "2" smd rect
			(at -0.3048 0)
			(size 0.6604 0.762)
			(layers "B.Cu" "B.Mask" "B.Paste")
			(net "P0V9_E")
		)
	)
	(footprint ""
		(layer "B.Cu")
		(at 245.5926 -32.004)
		(property "Reference" "C472"
			(at 0 0 0)
			(layer "B.SilkS")
			(hide yes)
			(effects
				(font
					(size 1.27 1.27)
				)
				(justify mirror)
			)
		)
		(property "Value" "SCD1U16V1KX-1-GP"
			(at 2.8321 -1.7399 0)
			(unlocked yes)
			(layer "B.Fab")
			(hide yes)
			(effects
				(font
					(size 1.016 1.016)
					(thickness 0.1524)
				)
				(justify mirror)
			)
		)
		(property "Device Type" "C0201H13"
			(at 2.8321 -3.2639 0)
			(unlocked yes)
			(layer "B.Fab")
			(hide yes)
			(effects
				(font
					(size 1.016 1.016)
					(thickness 0.1524)
				)
				(justify mirror)
			)
		)
		(duplicate_pad_numbers_are_jumpers no)
		(fp_rect
			(start 0.2794 0.6477)
			(end -0.2794 -0.6477)
			(stroke
				(width 0)
				(type default)
			)
			(fill no)
			(layer "B.CrtYd")
		)
		(fp_rect
			(start 0.2794 0.6477)
			(end -0.2794 -0.6477)
			(stroke
				(width 0)
				(type default)
			)
			(fill no)
			(layer "B.Fab")
		)
		(pad "1" smd custom
			(at 0 -0.2794 180)
			(size 0.0762 0.0762)
			(layers "B.Cu" "B.Mask" "B.Paste")
			(net "DUT_VDDO")
			(options
				(clearance outline)
				(anchor circle)
			)
			(primitives
				(gr_poly
					(pts
						(arc
							(start 0.1524 0.127)
							(mid 0.137521 0.162921)
							(end 0.1016 0.1778)
						)
						(arc
							(start -0.1016 0.1778)
							(mid -0.137521 0.162921)
							(end -0.1524 0.127)
						)
						(arc
							(start -0.1524 -0.127)
							(mid -0.137521 -0.162921)
							(end -0.1016 -0.1778)
						)
						(arc
							(start 0.1016 -0.1778)
							(mid 0.137521 -0.162921)
							(end 0.1524 -0.127)
						)
					)
					(width 0)
					(fill yes)
				)
			)
		)
		(pad "2" smd custom
			(at 0 0.2794 180)
			(size 0.0762 0.0762)
			(layers "B.Cu" "B.Mask" "B.Paste")
			(net "GND")
			(options
				(clearance outline)
				(anchor circle)
			)
			(primitives
				(gr_poly
					(pts
						(arc
							(start 0.1524 0.127)
							(mid 0.137521 0.162921)
							(end 0.1016 0.1778)
						)
						(arc
							(start -0.1016 0.1778)
							(mid -0.137521 0.162921)
							(end -0.1524 0.127)
						)
						(arc
							(start -0.1524 -0.127)
							(mid -0.137521 -0.162921)
							(end -0.1016 -0.1778)
						)
						(arc
							(start 0.1016 -0.1778)
							(mid 0.137521 -0.162921)
							(end 0.1524 -0.127)
						)
					)
					(width 0)
					(fill yes)
				)
			)
		)
	)
	(footprint ""
		(layer "B.Cu")
		(at 132.588 -202.819)
		(property "Reference" "U66"
			(at 0 0 0)
			(layer "B.SilkS")
			(hide yes)
			(effects
				(font
					(size 1.27 1.27)
				)
				(justify mirror)
			)
		)
		(property "Value" "SN74LVC1G08DCKR-GP"
			(at 2.3368 -8.6868 0)
			(unlocked yes)
			(layer "B.Fab")
			(hide yes)
			(effects
				(font
					(size 1.016 1.016)
					(thickness 0.1524)
				)
				(justify mirror)
			)
		)
		(property "Device Type" "SC70-5H44"
			(at 2.3114 -10.414 0)
			(unlocked yes)
			(layer "B.Fab")
			(hide yes)
			(effects
				(font
					(size 1.016 1.016)
					(thickness 0.1524)
				)
				(justify mirror)
			)
		)
		(duplicate_pad_numbers_are_jumpers no)
		(fp_line
			(start -1.3843 -1.8034)
			(end -1.3843 -1.1176)
			(stroke
				(width 0.3302)
				(type default)
			)
			(layer "B.SilkS")
		)
		(fp_line
			(start -1.27 -1.7018)
			(end -1.27 1.7018)
			(stroke
				(width 0.1524)
				(type default)
			)
			(layer "B.SilkS")
		)
		(fp_line
			(start -1.27 1.7018)
			(end 1.27 1.7018)
			(stroke
				(width 0.1524)
				(type default)
			)
			(layer "B.SilkS")
		)
		(fp_line
			(start -0.6604 -1.8034)
			(end -1.3843 -1.8034)
			(stroke
				(width 0.3302)
				(type default)
			)
			(layer "B.SilkS")
		)
		(fp_line
			(start 1.27 -1.7018)
			(end -1.27 -1.7018)
			(stroke
				(width 0.1524)
				(type default)
			)
			(layer "B.SilkS")
		)
		(fp_line
			(start 1.27 1.7018)
			(end 1.27 -1.7018)
			(stroke
				(width 0.1524)
				(type default)
			)
			(layer "B.SilkS")
		)
		(fp_rect
			(start 1.524 1.9558)
			(end -1.524 -1.9558)
			(stroke
				(width 0)
				(type default)
			)
			(fill no)
			(layer "B.CrtYd")
		)
		(fp_poly
			(pts
				(xy 1.524 -1.9558) (xy -1.524 -1.9558) (xy -1.524 1.9558) (xy 1.524 1.9558)
			)
			(stroke
				(width 0)
				(type default)
			)
			(fill no)
			(layer "B.Fab")
		)
		(pad "1" smd rect
			(at -0.65024 -0.8255 180)
			(size 0.4064 1.2192)
			(layers "B.Cu" "B.Mask" "B.Paste")
			(net "BMC_SSD_RST#0_A2")
		)
		(pad "2" smd rect
			(at 0 -0.8255 180)
			(size 0.4064 1.2192)
			(layers "B.Cu" "B.Mask" "B.Paste")
			(net "SSD_PERST#0_B2")
		)
		(pad "3" smd rect
			(at 0.65024 -0.8255 180)
			(size 0.4064 1.2192)
			(layers "B.Cu" "B.Mask" "B.Paste")
			(net "GND")
		)
		(pad "4" smd rect
			(at 0.65024 0.8255 180)
			(size 0.4064 1.2192)
			(layers "B.Cu" "B.Mask" "B.Paste")
			(net "SSD_PERST_Y2")
		)
		(pad "5" smd rect
			(at -0.65024 0.8255 180)
			(size 0.4064 1.2192)
			(layers "B.Cu" "B.Mask" "B.Paste")
			(net "P3V3_STBY")
		)
	)
	(footprint ""
		(layer "B.Cu")
		(at 245.5926 -57.9882 90)
		(property "Reference" "C501"
			(at 0 0 90)
			(layer "B.SilkS")
			(hide yes)
			(effects
				(font
					(size 1.27 1.27)
				)
				(justify mirror)
			)
		)
		(property "Value" "SCD1U16V1KX-1-GP"
			(at 2.8321 -1.7399 90)
			(unlocked yes)
			(layer "B.Fab")
			(hide yes)
			(effects
				(font
					(size 1.016 1.016)
					(thickness 0.1524)
				)
				(justify mirror)
			)
		)
		(property "Device Type" "C0201H13"
			(at 2.8321 -3.2639 90)
			(unlocked yes)
			(layer "B.Fab")
			(hide yes)
			(effects
				(font
					(size 1.016 1.016)
					(thickness 0.1524)
				)
				(justify mirror)
			)
		)
		(duplicate_pad_numbers_are_jumpers no)
		(fp_rect
			(start 0.2794 0.6477)
			(end -0.2794 -0.6477)
			(stroke
				(width 0)
				(type default)
			)
			(fill no)
			(layer "B.CrtYd")
		)
		(fp_rect
			(start 0.2794 0.6477)
			(end -0.2794 -0.6477)
			(stroke
				(width 0)
				(type default)
			)
			(fill no)
			(layer "B.Fab")
		)
		(pad "1" smd custom
			(at 0 -0.2794 270)
			(size 0.0762 0.0762)
			(layers "B.Cu" "B.Mask" "B.Paste")
			(net "DUT_AVD_TX")
			(options
				(clearance outline)
				(anchor circle)
			)
			(primitives
				(gr_poly
					(pts
						(arc
							(start 0.1524 0.127)
							(mid 0.137521 0.162921)
							(end 0.1016 0.1778)
						)
						(arc
							(start -0.1016 0.1778)
							(mid -0.137521 0.162921)
							(end -0.1524 0.127)
						)
						(arc
							(start -0.1524 -0.127)
							(mid -0.137521 -0.162921)
							(end -0.1016 -0.1778)
						)
						(arc
							(start 0.1016 -0.1778)
							(mid 0.137521 -0.162921)
							(end 0.1524 -0.127)
						)
					)
					(width 0)
					(fill yes)
				)
			)
		)
		(pad "2" smd custom
			(at 0 0.2794 270)
			(size 0.0762 0.0762)
			(layers "B.Cu" "B.Mask" "B.Paste")
			(net "GND")
			(options
				(clearance outline)
				(anchor circle)
			)
			(primitives
				(gr_poly
					(pts
						(arc
							(start 0.1524 0.127)
							(mid 0.137521 0.162921)
							(end 0.1016 0.1778)
						)
						(arc
							(start -0.1016 0.1778)
							(mid -0.137521 0.162921)
							(end -0.1524 0.127)
						)
						(arc
							(start -0.1524 -0.127)
							(mid -0.137521 -0.162921)
							(end -0.1016 -0.1778)
						)
						(arc
							(start 0.1016 -0.1778)
							(mid 0.137521 -0.162921)
							(end 0.1524 -0.127)
						)
					)
					(width 0)
					(fill yes)
				)
			)
		)
	)
	(footprint ""
		(layer "B.Cu")
		(at 235.585 -59.99734 -90)
		(property "Reference" "C525"
			(at 0 0 90)
			(layer "B.SilkS")
			(hide yes)
			(effects
				(font
					(size 1.27 1.27)
				)
				(justify mirror)
			)
		)
		(property "Value" "SCD1U16V1KX-1-GP"
			(at 2.8321 -1.7399 270)
			(unlocked yes)
			(layer "B.Fab")
			(hide yes)
			(effects
				(font
					(size 1.016 1.016)
					(thickness 0.1524)
				)
				(justify mirror)
			)
		)
		(property "Device Type" "C0201H13"
			(at 2.8321 -3.2639 270)
			(unlocked yes)
			(layer "B.Fab")
			(hide yes)
			(effects
				(font
					(size 1.016 1.016)
					(thickness 0.1524)
				)
				(justify mirror)
			)
		)
		(duplicate_pad_numbers_are_jumpers no)
		(fp_rect
			(start 0.2794 0.6477)
			(end -0.2794 -0.6477)
			(stroke
				(width 0)
				(type default)
			)
			(fill no)
			(layer "B.CrtYd")
		)
		(fp_rect
			(start 0.2794 0.6477)
			(end -0.2794 -0.6477)
			(stroke
				(width 0)
				(type default)
			)
			(fill no)
			(layer "B.Fab")
		)
		(pad "1" smd custom
			(at 0 -0.2794 90)
			(size 0.0762 0.0762)
			(layers "B.Cu" "B.Mask" "B.Paste")
			(net "DUT_AVD_TX")
			(options
				(clearance outline)
				(anchor circle)
			)
			(primitives
				(gr_poly
					(pts
						(arc
							(start 0.1524 0.127)
							(mid 0.137521 0.162921)
							(end 0.1016 0.1778)
						)
						(arc
							(start -0.1016 0.1778)
							(mid -0.137521 0.162921)
							(end -0.1524 0.127)
						)
						(arc
							(start -0.1524 -0.127)
							(mid -0.137521 -0.162921)
							(end -0.1016 -0.1778)
						)
						(arc
							(start 0.1016 -0.1778)
							(mid 0.137521 -0.162921)
							(end 0.1524 -0.127)
						)
					)
					(width 0)
					(fill yes)
				)
			)
		)
		(pad "2" smd custom
			(at 0 0.2794 90)
			(size 0.0762 0.0762)
			(layers "B.Cu" "B.Mask" "B.Paste")
			(net "GND")
			(options
				(clearance outline)
				(anchor circle)
			)
			(primitives
				(gr_poly
					(pts
						(arc
							(start 0.1524 0.127)
							(mid 0.137521 0.162921)
							(end 0.1016 0.1778)
						)
						(arc
							(start -0.1016 0.1778)
							(mid -0.137521 0.162921)
							(end -0.1524 0.127)
						)
						(arc
							(start -0.1524 -0.127)
							(mid -0.137521 -0.162921)
							(end -0.1016 -0.1778)
						)
						(arc
							(start 0.1016 -0.1778)
							(mid 0.137521 -0.162921)
							(end 0.1524 -0.127)
						)
					)
					(width 0)
					(fill yes)
				)
			)
		)
	)
	(footprint ""
		(layer "B.Cu")
		(at 242.130072 -39.996872 -90)
		(property "Reference" "C486"
			(at 0 0 90)
			(layer "B.SilkS")
			(hide yes)
			(effects
				(font
					(size 1.27 1.27)
				)
				(justify mirror)
			)
		)
		(property "Value" "SCD1U16V1KX-1-GP"
			(at 2.8321 -1.7399 270)
			(unlocked yes)
			(layer "B.Fab")
			(hide yes)
			(effects
				(font
					(size 1.016 1.016)
					(thickness 0.1524)
				)
				(justify mirror)
			)
		)
		(property "Device Type" "C0201H13"
			(at 2.8321 -3.2639 270)
			(unlocked yes)
			(layer "B.Fab")
			(hide yes)
			(effects
				(font
					(size 1.016 1.016)
					(thickness 0.1524)
				)
				(justify mirror)
			)
		)
		(duplicate_pad_numbers_are_jumpers no)
		(fp_rect
			(start 0.2794 0.6477)
			(end -0.2794 -0.6477)
			(stroke
				(width 0)
				(type default)
			)
			(fill no)
			(layer "B.CrtYd")
		)
		(fp_rect
			(start 0.2794 0.6477)
			(end -0.2794 -0.6477)
			(stroke
				(width 0)
				(type default)
			)
			(fill no)
			(layer "B.Fab")
		)
		(pad "1" smd custom
			(at 0 -0.2794 90)
			(size 0.0762 0.0762)
			(layers "B.Cu" "B.Mask" "B.Paste")
			(net "DUT_VDDO")
			(options
				(clearance outline)
				(anchor circle)
			)
			(primitives
				(gr_poly
					(pts
						(arc
							(start 0.1524 0.127)
							(mid 0.137521 0.162921)
							(end 0.1016 0.1778)
						)
						(arc
							(start -0.1016 0.1778)
							(mid -0.137521 0.162921)
							(end -0.1524 0.127)
						)
						(arc
							(start -0.1524 -0.127)
							(mid -0.137521 -0.162921)
							(end -0.1016 -0.1778)
						)
						(arc
							(start 0.1016 -0.1778)
							(mid 0.137521 -0.162921)
							(end 0.1524 -0.127)
						)
					)
					(width 0)
					(fill yes)
				)
			)
		)
		(pad "2" smd custom
			(at 0 0.2794 90)
			(size 0.0762 0.0762)
			(layers "B.Cu" "B.Mask" "B.Paste")
			(net "GND")
			(options
				(clearance outline)
				(anchor circle)
			)
			(primitives
				(gr_poly
					(pts
						(arc
							(start 0.1524 0.127)
							(mid 0.137521 0.162921)
							(end 0.1016 0.1778)
						)
						(arc
							(start -0.1016 0.1778)
							(mid -0.137521 0.162921)
							(end -0.1524 0.127)
						)
						(arc
							(start -0.1524 -0.127)
							(mid -0.137521 -0.162921)
							(end -0.1016 -0.1778)
						)
						(arc
							(start 0.1016 -0.1778)
							(mid 0.137521 -0.162921)
							(end 0.1524 -0.127)
						)
					)
					(width 0)
					(fill yes)
				)
			)
		)
	)
	(footprint ""
		(layer "B.Cu")
		(at 61.4426 -120.2944 90)
		(property "Reference" "R306"
			(at 0 0 90)
			(layer "B.SilkS")
			(hide yes)
			(effects
				(font
					(size 1.27 1.27)
				)
				(justify mirror)
			)
		)
		(property "Value" "4K7R2F-GP"
			(at -0.064008 -3.993896 90)
			(unlocked yes)
			(layer "B.Fab")
			(hide yes)
			(effects
				(font
					(size 1.016 1.016)
					(thickness 0.1524)
				)
				(justify mirror)
			)
		)
		(property "Device Type" "R402H16"
			(at -0.064008 -5.517896 90)
			(unlocked yes)
			(layer "B.Fab")
			(hide yes)
			(effects
				(font
					(size 1.016 1.016)
					(thickness 0.1524)
				)
				(justify mirror)
			)
		)
		(duplicate_pad_numbers_are_jumpers no)
		(fp_line
			(start 0.508 -0.9398)
			(end 0.508 0.9398)
			(stroke
				(width 0.1524)
				(type default)
			)
			(layer "B.SilkS")
		)
		(fp_line
			(start -0.508 -0.9398)
			(end 0.508 -0.9398)
			(stroke
				(width 0.1524)
				(type default)
			)
			(layer "B.SilkS")
		)
		(fp_rect
			(start 0.508 0.9398)
			(end -0.508 -0.9398)
			(stroke
				(width 0)
				(type default)
			)
			(fill no)
			(layer "B.CrtYd")
		)
		(fp_rect
			(start 0.508 0.9398)
			(end -0.508 -0.9398)
			(stroke
				(width 0)
				(type default)
			)
			(fill no)
			(layer "B.Fab")
		)
		(pad "1" smd custom
			(at 0 -0.4445 270)
			(size 0.1397 0.1397)
			(layers "B.Cu" "B.Mask" "B.Paste")
			(net "P3V3_STBY")
			(options
				(clearance outline)
				(anchor circle)
			)
			(primitives
				(gr_poly
					(pts
						(arc
							(start -0.1778 0.2794)
							(mid -0.249642 0.249642)
							(end -0.2794 0.1778)
						)
						(arc
							(start -0.2794 -0.1778)
							(mid -0.249642 -0.249642)
							(end -0.1778 -0.2794)
						)
						(arc
							(start 0.1778 -0.2794)
							(mid 0.249642 -0.249642)
							(end 0.2794 -0.1778)
						)
						(arc
							(start 0.2794 0.1778)
							(mid 0.249642 0.249642)
							(end 0.1778 0.2794)
						)
					)
					(width 0)
					(fill yes)
				)
			)
		)
		(pad "2" smd custom
			(at 0 0.4445 270)
			(size 0.1397 0.1397)
			(layers "B.Cu" "B.Mask" "B.Paste")
			(net "I2C3_LS_G1")
			(options
				(clearance outline)
				(anchor circle)
			)
			(primitives
				(gr_poly
					(pts
						(arc
							(start -0.1778 0.2794)
							(mid -0.249642 0.249642)
							(end -0.2794 0.1778)
						)
						(arc
							(start -0.2794 -0.1778)
							(mid -0.249642 -0.249642)
							(end -0.1778 -0.2794)
						)
						(arc
							(start 0.1778 -0.2794)
							(mid 0.249642 -0.249642)
							(end 0.2794 -0.1778)
						)
						(arc
							(start 0.2794 0.1778)
							(mid 0.249642 0.249642)
							(end 0.1778 0.2794)
						)
					)
					(width 0)
					(fill yes)
				)
			)
		)
	)
	(footprint ""
		(layer "B.Cu")
		(at 124.944124 -196.443092 180)
		(property "Reference" "R525"
			(at 0 0 0)
			(layer "B.SilkS")
			(hide yes)
			(effects
				(font
					(size 1.27 1.27)
				)
				(justify mirror)
			)
		)
		(property "Value" "10KR2F-2-GP"
			(at -0.064008 -3.993896 180)
			(unlocked yes)
			(layer "B.Fab")
			(hide yes)
			(effects
				(font
					(size 1.016 1.016)
					(thickness 0.1524)
				)
				(justify mirror)
			)
		)
		(property "Device Type" "R402H16"
			(at -0.064008 -5.517896 180)
			(unlocked yes)
			(layer "B.Fab")
			(hide yes)
			(effects
				(font
					(size 1.016 1.016)
					(thickness 0.1524)
				)
				(justify mirror)
			)
		)
		(duplicate_pad_numbers_are_jumpers no)
		(fp_line
			(start 0.508 -0.9398)
			(end 0.508 0.9398)
			(stroke
				(width 0.1524)
				(type default)
			)
			(layer "B.SilkS")
		)
		(fp_line
			(start -0.508 -0.9398)
			(end 0.508 -0.9398)
			(stroke
				(width 0.1524)
				(type default)
			)
			(layer "B.SilkS")
		)
		(fp_rect
			(start 0.508 0.9398)
			(end -0.508 -0.9398)
			(stroke
				(width 0)
				(type default)
			)
			(fill no)
			(layer "B.CrtYd")
		)
		(fp_rect
			(start 0.508 0.9398)
			(end -0.508 -0.9398)
			(stroke
				(width 0)
				(type default)
			)
			(fill no)
			(layer "B.Fab")
		)
		(pad "1" smd custom
			(at 0 -0.4445)
			(size 0.1397 0.1397)
			(layers "B.Cu" "B.Mask" "B.Paste")
			(net "P3V3_STBY")
			(options
				(clearance outline)
				(anchor circle)
			)
			(primitives
				(gr_poly
					(pts
						(arc
							(start -0.1778 0.2794)
							(mid -0.249642 0.249642)
							(end -0.2794 0.1778)
						)
						(arc
							(start -0.2794 -0.1778)
							(mid -0.249642 -0.249642)
							(end -0.1778 -0.2794)
						)
						(arc
							(start 0.1778 -0.2794)
							(mid 0.249642 -0.249642)
							(end 0.2794 -0.1778)
						)
						(arc
							(start 0.2794 0.1778)
							(mid 0.249642 0.249642)
							(end 0.1778 0.2794)
						)
					)
					(width 0)
					(fill yes)
				)
			)
		)
		(pad "2" smd custom
			(at 0 0.4445)
			(size 0.1397 0.1397)
			(layers "B.Cu" "B.Mask" "B.Paste")
			(net "IOEXP2_AD2")
			(options
				(clearance outline)
				(anchor circle)
			)
			(primitives
				(gr_poly
					(pts
						(arc
							(start -0.1778 0.2794)
							(mid -0.249642 0.249642)
							(end -0.2794 0.1778)
						)
						(arc
							(start -0.2794 -0.1778)
							(mid -0.249642 -0.249642)
							(end -0.1778 -0.2794)
						)
						(arc
							(start 0.1778 -0.2794)
							(mid 0.249642 -0.249642)
							(end 0.2794 -0.1778)
						)
						(arc
							(start 0.2794 0.1778)
							(mid 0.249642 0.249642)
							(end 0.1778 0.2794)
						)
					)
					(width 0)
					(fill yes)
				)
			)
		)
	)
	(footprint ""
		(layer "B.Cu")
		(at 239.395 -20.447)
		(property "Reference" "R795"
			(at 0 0 0)
			(layer "B.SilkS")
			(hide yes)
			(effects
				(font
					(size 1.27 1.27)
				)
				(justify mirror)
			)
		)
		(property "Value" "4K7R2F-GP"
			(at -0.064008 -3.993896 0)
			(unlocked yes)
			(layer "B.Fab")
			(hide yes)
			(effects
				(font
					(size 1.016 1.016)
					(thickness 0.1524)
				)
				(justify mirror)
			)
		)
		(property "Device Type" "R402H16"
			(at -0.064008 -5.517896 0)
			(unlocked yes)
			(layer "B.Fab")
			(hide yes)
			(effects
				(font
					(size 1.016 1.016)
					(thickness 0.1524)
				)
				(justify mirror)
			)
		)
		(duplicate_pad_numbers_are_jumpers no)
		(fp_line
			(start -0.508 -0.9398)
			(end 0.508 -0.9398)
			(stroke
				(width 0.1524)
				(type default)
			)
			(layer "B.SilkS")
		)
		(fp_line
			(start 0.508 -0.9398)
			(end 0.508 0.9398)
			(stroke
				(width 0.1524)
				(type default)
			)
			(layer "B.SilkS")
		)
		(fp_rect
			(start 0.508 0.9398)
			(end -0.508 -0.9398)
			(stroke
				(width 0)
				(type default)
			)
			(fill no)
			(layer "B.CrtYd")
		)
		(fp_rect
			(start 0.508 0.9398)
			(end -0.508 -0.9398)
			(stroke
				(width 0)
				(type default)
			)
			(fill no)
			(layer "B.Fab")
		)
		(pad "1" smd custom
			(at 0 -0.4445 180)
			(size 0.1397 0.1397)
			(layers "B.Cu" "B.Mask" "B.Paste")
			(net "BOOTSTRAP1")
			(options
				(clearance outline)
				(anchor circle)
			)
			(primitives
				(gr_poly
					(pts
						(arc
							(start -0.1778 0.2794)
							(mid -0.249642 0.249642)
							(end -0.2794 0.1778)
						)
						(arc
							(start -0.2794 -0.1778)
							(mid -0.249642 -0.249642)
							(end -0.1778 -0.2794)
						)
						(arc
							(start 0.1778 -0.2794)
							(mid 0.249642 -0.249642)
							(end 0.2794 -0.1778)
						)
						(arc
							(start 0.2794 0.1778)
							(mid 0.249642 0.249642)
							(end 0.1778 0.2794)
						)
					)
					(width 0)
					(fill yes)
				)
			)
		)
		(pad "2" smd custom
			(at 0 0.4445 180)
			(size 0.1397 0.1397)
			(layers "B.Cu" "B.Mask" "B.Paste")
			(net "DUT_VDDO")
			(options
				(clearance outline)
				(anchor circle)
			)
			(primitives
				(gr_poly
					(pts
						(arc
							(start -0.1778 0.2794)
							(mid -0.249642 0.249642)
							(end -0.2794 0.1778)
						)
						(arc
							(start -0.2794 -0.1778)
							(mid -0.249642 -0.249642)
							(end -0.1778 -0.2794)
						)
						(arc
							(start 0.1778 -0.2794)
							(mid 0.249642 -0.249642)
							(end 0.2794 -0.1778)
						)
						(arc
							(start 0.2794 0.1778)
							(mid 0.249642 0.249642)
							(end 0.1778 0.2794)
						)
					)
					(width 0)
					(fill yes)
				)
			)
		)
	)
	(footprint ""
		(layer "B.Cu")
		(at 57.023 -140.843 -90)
		(property "Reference" "R220"
			(at 0 0 90)
			(layer "B.SilkS")
			(hide yes)
			(effects
				(font
					(size 1.27 1.27)
				)
				(justify mirror)
			)
		)
		(property "Value" "4K7R2F-GP"
			(at -0.064008 -3.993896 270)
			(unlocked yes)
			(layer "B.Fab")
			(hide yes)
			(effects
				(font
					(size 1.016 1.016)
					(thickness 0.1524)
				)
				(justify mirror)
			)
		)
		(property "Device Type" "R402H16"
			(at -0.064008 -5.517896 270)
			(unlocked yes)
			(layer "B.Fab")
			(hide yes)
			(effects
				(font
					(size 1.016 1.016)
					(thickness 0.1524)
				)
				(justify mirror)
			)
		)
		(duplicate_pad_numbers_are_jumpers no)
		(fp_line
			(start -0.508 -0.9398)
			(end 0.508 -0.9398)
			(stroke
				(width 0.1524)
				(type default)
			)
			(layer "B.SilkS")
		)
		(fp_line
			(start 0.508 -0.9398)
			(end 0.508 0.9398)
			(stroke
				(width 0.1524)
				(type default)
			)
			(layer "B.SilkS")
		)
		(fp_rect
			(start 0.508 0.9398)
			(end -0.508 -0.9398)
			(stroke
				(width 0)
				(type default)
			)
			(fill no)
			(layer "B.CrtYd")
		)
		(fp_rect
			(start 0.508 0.9398)
			(end -0.508 -0.9398)
			(stroke
				(width 0)
				(type default)
			)
			(fill no)
			(layer "B.Fab")
		)
		(pad "1" smd custom
			(at 0 -0.4445 90)
			(size 0.1397 0.1397)
			(layers "B.Cu" "B.Mask" "B.Paste")
			(net "BMC_SELF_TRAY")
			(options
				(clearance outline)
				(anchor circle)
			)
			(primitives
				(gr_poly
					(pts
						(arc
							(start -0.1778 0.2794)
							(mid -0.249642 0.249642)
							(end -0.2794 0.1778)
						)
						(arc
							(start -0.2794 -0.1778)
							(mid -0.249642 -0.249642)
							(end -0.1778 -0.2794)
						)
						(arc
							(start 0.1778 -0.2794)
							(mid 0.249642 -0.249642)
							(end 0.2794 -0.1778)
						)
						(arc
							(start 0.2794 0.1778)
							(mid 0.249642 0.249642)
							(end 0.1778 0.2794)
						)
					)
					(width 0)
					(fill yes)
				)
			)
		)
		(pad "2" smd custom
			(at 0 0.4445 90)
			(size 0.1397 0.1397)
			(layers "B.Cu" "B.Mask" "B.Paste")
			(net "P3V3_STBY")
			(options
				(clearance outline)
				(anchor circle)
			)
			(primitives
				(gr_poly
					(pts
						(arc
							(start -0.1778 0.2794)
							(mid -0.249642 0.249642)
							(end -0.2794 0.1778)
						)
						(arc
							(start -0.2794 -0.1778)
							(mid -0.249642 -0.249642)
							(end -0.1778 -0.2794)
						)
						(arc
							(start 0.1778 -0.2794)
							(mid 0.249642 -0.249642)
							(end 0.2794 -0.1778)
						)
						(arc
							(start 0.2794 0.1778)
							(mid 0.249642 0.249642)
							(end 0.1778 0.2794)
						)
					)
					(width 0)
					(fill yes)
				)
			)
		)
	)
	(footprint ""
		(layer "B.Cu")
		(at 222.8342 -7.366)
		(property "Reference" "R674"
			(at 0 0 0)
			(layer "B.SilkS")
			(hide yes)
			(effects
				(font
					(size 1.27 1.27)
				)
				(justify mirror)
			)
		)
		(property "Value" "100KR2F-L1-GP"
			(at -0.064008 -3.993896 0)
			(unlocked yes)
			(layer "B.Fab")
			(hide yes)
			(effects
				(font
					(size 1.016 1.016)
					(thickness 0.1524)
				)
				(justify mirror)
			)
		)
		(property "Device Type" "R402H16"
			(at -0.064008 -5.517896 0)
			(unlocked yes)
			(layer "B.Fab")
			(hide yes)
			(effects
				(font
					(size 1.016 1.016)
					(thickness 0.1524)
				)
				(justify mirror)
			)
		)
		(duplicate_pad_numbers_are_jumpers no)
		(fp_line
			(start -0.508 -0.9398)
			(end 0.508 -0.9398)
			(stroke
				(width 0.1524)
				(type default)
			)
			(layer "B.SilkS")
		)
		(fp_line
			(start 0.508 -0.9398)
			(end 0.508 0.9398)
			(stroke
				(width 0.1524)
				(type default)
			)
			(layer "B.SilkS")
		)
		(fp_rect
			(start 0.508 0.9398)
			(end -0.508 -0.9398)
			(stroke
				(width 0)
				(type default)
			)
			(fill no)
			(layer "B.CrtYd")
		)
		(fp_rect
			(start 0.508 0.9398)
			(end -0.508 -0.9398)
			(stroke
				(width 0)
				(type default)
			)
			(fill no)
			(layer "B.Fab")
		)
		(pad "1" smd custom
			(at 0 -0.4445 180)
			(size 0.1397 0.1397)
			(layers "B.Cu" "B.Mask" "B.Paste")
			(net "HOST1_RST_N")
			(options
				(clearance outline)
				(anchor circle)
			)
			(primitives
				(gr_poly
					(pts
						(arc
							(start -0.1778 0.2794)
							(mid -0.249642 0.249642)
							(end -0.2794 0.1778)
						)
						(arc
							(start -0.2794 -0.1778)
							(mid -0.249642 -0.249642)
							(end -0.1778 -0.2794)
						)
						(arc
							(start 0.1778 -0.2794)
							(mid 0.249642 -0.249642)
							(end 0.2794 -0.1778)
						)
						(arc
							(start 0.2794 0.1778)
							(mid 0.249642 0.249642)
							(end 0.1778 0.2794)
						)
					)
					(width 0)
					(fill yes)
				)
			)
		)
		(pad "2" smd custom
			(at 0 0.4445 180)
			(size 0.1397 0.1397)
			(layers "B.Cu" "B.Mask" "B.Paste")
			(net "GND")
			(options
				(clearance outline)
				(anchor circle)
			)
			(primitives
				(gr_poly
					(pts
						(arc
							(start -0.1778 0.2794)
							(mid -0.249642 0.249642)
							(end -0.2794 0.1778)
						)
						(arc
							(start -0.2794 -0.1778)
							(mid -0.249642 -0.249642)
							(end -0.1778 -0.2794)
						)
						(arc
							(start 0.1778 -0.2794)
							(mid 0.249642 -0.249642)
							(end 0.2794 -0.1778)
						)
						(arc
							(start 0.2794 0.1778)
							(mid 0.249642 0.249642)
							(end 0.1778 0.2794)
						)
					)
					(width 0)
					(fill yes)
				)
			)
		)
	)
	(footprint ""
		(layer "B.Cu")
		(at 51.689 -181.483 180)
		(property "Reference" "R901"
			(at 0 0 0)
			(layer "B.SilkS")
			(hide yes)
			(effects
				(font
					(size 1.27 1.27)
				)
				(justify mirror)
			)
		)
		(property "Value" "0R2J-2-GP"
			(at -0.064008 -3.993896 180)
			(unlocked yes)
			(layer "B.Fab")
			(hide yes)
			(effects
				(font
					(size 1.016 1.016)
					(thickness 0.1524)
				)
				(justify mirror)
			)
		)
		(property "Device Type" "R402H16"
			(at -0.064008 -5.517896 180)
			(unlocked yes)
			(layer "B.Fab")
			(hide yes)
			(effects
				(font
					(size 1.016 1.016)
					(thickness 0.1524)
				)
				(justify mirror)
			)
		)
		(duplicate_pad_numbers_are_jumpers no)
		(fp_line
			(start 0.508 -0.9398)
			(end 0.508 0.9398)
			(stroke
				(width 0.1524)
				(type default)
			)
			(layer "B.SilkS")
		)
		(fp_line
			(start -0.508 -0.9398)
			(end 0.508 -0.9398)
			(stroke
				(width 0.1524)
				(type default)
			)
			(layer "B.SilkS")
		)
		(fp_rect
			(start 0.508 0.9398)
			(end -0.508 -0.9398)
			(stroke
				(width 0)
				(type default)
			)
			(fill no)
			(layer "B.CrtYd")
		)
		(fp_rect
			(start 0.508 0.9398)
			(end -0.508 -0.9398)
			(stroke
				(width 0)
				(type default)
			)
			(fill no)
			(layer "B.Fab")
		)
		(pad "1" smd custom
			(at 0 -0.4445)
			(size 0.1397 0.1397)
			(layers "B.Cu" "B.Mask" "B.Paste")
			(net "BMC_I2C8_CLKBUF1_SCL")
			(options
				(clearance outline)
				(anchor circle)
			)
			(primitives
				(gr_poly
					(pts
						(arc
							(start -0.1778 0.2794)
							(mid -0.249642 0.249642)
							(end -0.2794 0.1778)
						)
						(arc
							(start -0.2794 -0.1778)
							(mid -0.249642 -0.249642)
							(end -0.1778 -0.2794)
						)
						(arc
							(start 0.1778 -0.2794)
							(mid 0.249642 -0.249642)
							(end 0.2794 -0.1778)
						)
						(arc
							(start 0.2794 0.1778)
							(mid 0.249642 0.249642)
							(end 0.1778 0.2794)
						)
					)
					(width 0)
					(fill yes)
				)
			)
		)
		(pad "2" smd custom
			(at 0 0.4445)
			(size 0.1397 0.1397)
			(layers "B.Cu" "B.Mask" "B.Paste")
			(net "BUF_I2C8_CLKBUF1_SCL")
			(options
				(clearance outline)
				(anchor circle)
			)
			(primitives
				(gr_poly
					(pts
						(arc
							(start -0.1778 0.2794)
							(mid -0.249642 0.249642)
							(end -0.2794 0.1778)
						)
						(arc
							(start -0.2794 -0.1778)
							(mid -0.249642 -0.249642)
							(end -0.1778 -0.2794)
						)
						(arc
							(start 0.1778 -0.2794)
							(mid 0.249642 -0.249642)
							(end 0.2794 -0.1778)
						)
						(arc
							(start 0.2794 0.1778)
							(mid 0.249642 0.249642)
							(end 0.1778 0.2794)
						)
					)
					(width 0)
					(fill yes)
				)
			)
		)
	)
	(footprint ""
		(layer "B.Cu")
		(at 33.885886 -108.289598 90)
		(property "Reference" "R288"
			(at 0 0 90)
			(layer "B.SilkS")
			(hide yes)
			(effects
				(font
					(size 1.27 1.27)
				)
				(justify mirror)
			)
		)
		(property "Value" "47KR2F-GP"
			(at -0.064008 -3.993896 90)
			(unlocked yes)
			(layer "B.Fab")
			(hide yes)
			(effects
				(font
					(size 1.016 1.016)
					(thickness 0.1524)
				)
				(justify mirror)
			)
		)
		(property "Device Type" "R402H16"
			(at -0.064008 -5.517896 90)
			(unlocked yes)
			(layer "B.Fab")
			(hide yes)
			(effects
				(font
					(size 1.016 1.016)
					(thickness 0.1524)
				)
				(justify mirror)
			)
		)
		(duplicate_pad_numbers_are_jumpers no)
		(fp_line
			(start 0.508 -0.9398)
			(end 0.508 0.9398)
			(stroke
				(width 0.1524)
				(type default)
			)
			(layer "B.SilkS")
		)
		(fp_line
			(start -0.508 -0.9398)
			(end 0.508 -0.9398)
			(stroke
				(width 0.1524)
				(type default)
			)
			(layer "B.SilkS")
		)
		(fp_rect
			(start 0.508 0.9398)
			(end -0.508 -0.9398)
			(stroke
				(width 0)
				(type default)
			)
			(fill no)
			(layer "B.CrtYd")
		)
		(fp_rect
			(start 0.508 0.9398)
			(end -0.508 -0.9398)
			(stroke
				(width 0)
				(type default)
			)
			(fill no)
			(layer "B.Fab")
		)
		(pad "1" smd custom
			(at 0 -0.4445 270)
			(size 0.1397 0.1397)
			(layers "B.Cu" "B.Mask" "B.Paste")
			(net "GND")
			(options
				(clearance outline)
				(anchor circle)
			)
			(primitives
				(gr_poly
					(pts
						(arc
							(start -0.1778 0.2794)
							(mid -0.249642 0.249642)
							(end -0.2794 0.1778)
						)
						(arc
							(start -0.2794 -0.1778)
							(mid -0.249642 -0.249642)
							(end -0.1778 -0.2794)
						)
						(arc
							(start 0.1778 -0.2794)
							(mid 0.249642 -0.249642)
							(end 0.2794 -0.1778)
						)
						(arc
							(start 0.2794 0.1778)
							(mid 0.249642 0.249642)
							(end 0.1778 0.2794)
						)
					)
					(width 0)
					(fill yes)
				)
			)
		)
		(pad "2" smd custom
			(at 0 0.4445 270)
			(size 0.1397 0.1397)
			(layers "B.Cu" "B.Mask" "B.Paste")
			(net "RMII_BMC_RX_ER")
			(options
				(clearance outline)
				(anchor circle)
			)
			(primitives
				(gr_poly
					(pts
						(arc
							(start -0.1778 0.2794)
							(mid -0.249642 0.249642)
							(end -0.2794 0.1778)
						)
						(arc
							(start -0.2794 -0.1778)
							(mid -0.249642 -0.249642)
							(end -0.1778 -0.2794)
						)
						(arc
							(start 0.1778 -0.2794)
							(mid 0.249642 -0.249642)
							(end 0.2794 -0.1778)
						)
						(arc
							(start 0.2794 0.1778)
							(mid 0.249642 0.249642)
							(end 0.1778 0.2794)
						)
					)
					(width 0)
					(fill yes)
				)
			)
		)
	)
	(footprint ""
		(layer "B.Cu")
		(at 32.6263 -122.29338)
		(property "Reference" "TP306"
			(at 0 0 0)
			(layer "B.SilkS")
			(hide yes)
			(effects
				(font
					(size 1.27 1.27)
				)
				(justify mirror)
			)
		)
		(property "Value" "TPAD28-2-GP"
			(at 0.0127 -1.6637 0)
			(unlocked yes)
			(layer "B.Fab")
			(hide yes)
			(effects
				(font
					(size 1.016 1.016)
					(thickness 0.1524)
				)
				(justify mirror)
			)
		)
		(property "Device Type" "TPAD28"
			(at 0.0127 -3.1877 0)
			(unlocked yes)
			(layer "B.Fab")
			(hide yes)
			(effects
				(font
					(size 1.016 1.016)
					(thickness 0.1524)
				)
				(justify mirror)
			)
		)
		(duplicate_pad_numbers_are_jumpers no)
		(fp_poly
			(pts
				(arc
					(start 0.3556 0)
					(mid -0.3556 0)
					(end 0.3556 0)
				)
			)
			(stroke
				(width 0)
				(type default)
			)
			(fill no)
			(layer "B.CrtYd")
		)
		(fp_poly
			(pts
				(arc
					(start 0.6096 0)
					(mid -0.6096 0)
					(end 0.6096 0)
				)
			)
			(stroke
				(width 0)
				(type default)
			)
			(fill no)
			(layer "B.Fab")
		)
		(pad "1" smd circle
			(at 0 0 180)
			(size 0.7112 0.7112)
			(layers "B.Cu" "B.Mask" "B.Paste")
			(net "TP_GPIOD1")
		)
	)
	(footprint ""
		(layer "B.Cu")
		(at 158.6992 -91.9734 90)
		(property "Reference" "C731"
			(at 0 0 90)
			(layer "B.SilkS")
			(hide yes)
			(effects
				(font
					(size 1.27 1.27)
				)
				(justify mirror)
			)
		)
		(property "Value" "SC10U16V5KX-1-GP"
			(at 0.0762 -6.1214 90)
			(unlocked yes)
			(layer "B.Fab")
			(hide yes)
			(effects
				(font
					(size 1.016 1.016)
					(thickness 0.1524)
				)
				(justify mirror)
			)
		)
		(property "Device Type" "C805H54"
			(at 0.0762 -8.1534 90)
			(unlocked yes)
			(layer "B.Fab")
			(hide yes)
			(effects
				(font
					(size 1.016 1.016)
					(thickness 0.1524)
				)
				(justify mirror)
			)
		)
		(duplicate_pad_numbers_are_jumpers no)
		(fp_line
			(start -0.635 0)
			(end 0.635 0)
			(stroke
				(width 0.508)
				(type default)
			)
			(layer "B.SilkS")
		)
		(fp_rect
			(start 0.9652 1.778)
			(end -0.9652 -1.778)
			(stroke
				(width 0)
				(type default)
			)
			(fill no)
			(layer "B.CrtYd")
		)
		(fp_poly
			(pts
				(xy 0.9652 -1.778) (xy -0.9652 -1.778) (xy -0.9652 1.778) (xy 0.9652 1.778)
			)
			(stroke
				(width 0)
				(type default)
			)
			(fill no)
			(layer "B.Fab")
		)
		(pad "1" smd rect
			(at 0 -0.9652 270)
			(size 1.397 1.143)
			(layers "B.Cu" "B.Mask" "B.Paste")
			(net "P1V8_CLKGEN")
		)
		(pad "2" smd rect
			(at 0 0.9652 270)
			(size 1.397 1.143)
			(layers "B.Cu" "B.Mask" "B.Paste")
			(net "GND")
		)
	)
	(footprint ""
		(layer "B.Cu")
		(at 230.1494 -41.9862 90)
		(property "Reference" "C575"
			(at 0 0 90)
			(layer "B.SilkS")
			(hide yes)
			(effects
				(font
					(size 1.27 1.27)
				)
				(justify mirror)
			)
		)
		(property "Value" "SCD1U16V1KX-1-GP"
			(at 2.8321 -1.7399 90)
			(unlocked yes)
			(layer "B.Fab")
			(hide yes)
			(effects
				(font
					(size 1.016 1.016)
					(thickness 0.1524)
				)
				(justify mirror)
			)
		)
		(property "Device Type" "C0201H13"
			(at 2.8321 -3.2639 90)
			(unlocked yes)
			(layer "B.Fab")
			(hide yes)
			(effects
				(font
					(size 1.016 1.016)
					(thickness 0.1524)
				)
				(justify mirror)
			)
		)
		(duplicate_pad_numbers_are_jumpers no)
		(fp_rect
			(start 0.2794 0.6477)
			(end -0.2794 -0.6477)
			(stroke
				(width 0)
				(type default)
			)
			(fill no)
			(layer "B.CrtYd")
		)
		(fp_rect
			(start 0.2794 0.6477)
			(end -0.2794 -0.6477)
			(stroke
				(width 0)
				(type default)
			)
			(fill no)
			(layer "B.Fab")
		)
		(pad "1" smd custom
			(at 0 -0.2794 270)
			(size 0.0762 0.0762)
			(layers "B.Cu" "B.Mask" "B.Paste")
			(net "DUT_AVD_PCIE")
			(options
				(clearance outline)
				(anchor circle)
			)
			(primitives
				(gr_poly
					(pts
						(arc
							(start 0.1524 0.127)
							(mid 0.137521 0.162921)
							(end 0.1016 0.1778)
						)
						(arc
							(start -0.1016 0.1778)
							(mid -0.137521 0.162921)
							(end -0.1524 0.127)
						)
						(arc
							(start -0.1524 -0.127)
							(mid -0.137521 -0.162921)
							(end -0.1016 -0.1778)
						)
						(arc
							(start 0.1016 -0.1778)
							(mid 0.137521 -0.162921)
							(end 0.1524 -0.127)
						)
					)
					(width 0)
					(fill yes)
				)
			)
		)
		(pad "2" smd custom
			(at 0 0.2794 270)
			(size 0.0762 0.0762)
			(layers "B.Cu" "B.Mask" "B.Paste")
			(net "GND")
			(options
				(clearance outline)
				(anchor circle)
			)
			(primitives
				(gr_poly
					(pts
						(arc
							(start 0.1524 0.127)
							(mid 0.137521 0.162921)
							(end 0.1016 0.1778)
						)
						(arc
							(start -0.1016 0.1778)
							(mid -0.137521 0.162921)
							(end -0.1524 0.127)
						)
						(arc
							(start -0.1524 -0.127)
							(mid -0.137521 -0.162921)
							(end -0.1016 -0.1778)
						)
						(arc
							(start 0.1016 -0.1778)
							(mid 0.137521 -0.162921)
							(end 0.1524 -0.127)
						)
					)
					(width 0)
					(fill yes)
				)
			)
		)
	)
	(footprint ""
		(layer "B.Cu")
		(at 228.195124 -203.047092 180)
		(property "Reference" "R4134"
			(at 0 0 0)
			(layer "B.SilkS")
			(hide yes)
			(effects
				(font
					(size 1.27 1.27)
				)
				(justify mirror)
			)
		)
		(property "Value" "4K7R2F-GP"
			(at -0.064008 -3.993896 180)
			(unlocked yes)
			(layer "B.Fab")
			(hide yes)
			(effects
				(font
					(size 1.016 1.016)
					(thickness 0.1524)
				)
				(justify mirror)
			)
		)
		(property "Device Type" "R402H16"
			(at -0.064008 -5.517896 180)
			(unlocked yes)
			(layer "B.Fab")
			(hide yes)
			(effects
				(font
					(size 1.016 1.016)
					(thickness 0.1524)
				)
				(justify mirror)
			)
		)
		(duplicate_pad_numbers_are_jumpers no)
		(fp_line
			(start 0.508 -0.9398)
			(end 0.508 0.9398)
			(stroke
				(width 0.1524)
				(type default)
			)
			(layer "B.SilkS")
		)
		(fp_line
			(start -0.508 -0.9398)
			(end 0.508 -0.9398)
			(stroke
				(width 0.1524)
				(type default)
			)
			(layer "B.SilkS")
		)
		(fp_rect
			(start 0.508 0.9398)
			(end -0.508 -0.9398)
			(stroke
				(width 0)
				(type default)
			)
			(fill no)
			(layer "B.CrtYd")
		)
		(fp_rect
			(start 0.508 0.9398)
			(end -0.508 -0.9398)
			(stroke
				(width 0)
				(type default)
			)
			(fill no)
			(layer "B.Fab")
		)
		(pad "1" smd custom
			(at 0 -0.4445)
			(size 0.1397 0.1397)
			(layers "B.Cu" "B.Mask" "B.Paste")
			(net "SSD_PRSNT#12")
			(options
				(clearance outline)
				(anchor circle)
			)
			(primitives
				(gr_poly
					(pts
						(arc
							(start -0.1778 0.2794)
							(mid -0.249642 0.249642)
							(end -0.2794 0.1778)
						)
						(arc
							(start -0.2794 -0.1778)
							(mid -0.249642 -0.249642)
							(end -0.1778 -0.2794)
						)
						(arc
							(start 0.1778 -0.2794)
							(mid 0.249642 -0.249642)
							(end 0.2794 -0.1778)
						)
						(arc
							(start 0.2794 0.1778)
							(mid 0.249642 0.249642)
							(end 0.1778 0.2794)
						)
					)
					(width 0)
					(fill yes)
				)
			)
		)
		(pad "2" smd custom
			(at 0 0.4445)
			(size 0.1397 0.1397)
			(layers "B.Cu" "B.Mask" "B.Paste")
			(net "P3V3_STBY")
			(options
				(clearance outline)
				(anchor circle)
			)
			(primitives
				(gr_poly
					(pts
						(arc
							(start -0.1778 0.2794)
							(mid -0.249642 0.249642)
							(end -0.2794 0.1778)
						)
						(arc
							(start -0.2794 -0.1778)
							(mid -0.249642 -0.249642)
							(end -0.1778 -0.2794)
						)
						(arc
							(start 0.1778 -0.2794)
							(mid 0.249642 -0.249642)
							(end 0.2794 -0.1778)
						)
						(arc
							(start 0.2794 0.1778)
							(mid 0.249642 0.249642)
							(end 0.1778 0.2794)
						)
					)
					(width 0)
					(fill yes)
				)
			)
		)
	)
	(footprint ""
		(layer "B.Cu")
		(at 227.965 -20.447)
		(property "Reference" "R3703"
			(at 0 0 0)
			(layer "B.SilkS")
			(hide yes)
			(effects
				(font
					(size 1.27 1.27)
				)
				(justify mirror)
			)
		)
		(property "Value" "4K7R2F-GP"
			(at -0.064008 -3.993896 0)
			(unlocked yes)
			(layer "B.Fab")
			(hide yes)
			(effects
				(font
					(size 1.016 1.016)
					(thickness 0.1524)
				)
				(justify mirror)
			)
		)
		(property "Device Type" "R402H16"
			(at -0.064008 -5.517896 0)
			(unlocked yes)
			(layer "B.Fab")
			(hide yes)
			(effects
				(font
					(size 1.016 1.016)
					(thickness 0.1524)
				)
				(justify mirror)
			)
		)
		(duplicate_pad_numbers_are_jumpers no)
		(fp_line
			(start -0.508 -0.9398)
			(end 0.508 -0.9398)
			(stroke
				(width 0.1524)
				(type default)
			)
			(layer "B.SilkS")
		)
		(fp_line
			(start 0.508 -0.9398)
			(end 0.508 0.9398)
			(stroke
				(width 0.1524)
				(type default)
			)
			(layer "B.SilkS")
		)
		(fp_rect
			(start 0.508 0.9398)
			(end -0.508 -0.9398)
			(stroke
				(width 0)
				(type default)
			)
			(fill no)
			(layer "B.CrtYd")
		)
		(fp_rect
			(start 0.508 0.9398)
			(end -0.508 -0.9398)
			(stroke
				(width 0)
				(type default)
			)
			(fill no)
			(layer "B.Fab")
		)
		(pad "1" smd custom
			(at 0 -0.4445 180)
			(size 0.1397 0.1397)
			(layers "B.Cu" "B.Mask" "B.Paste")
			(net "HOST3_RST_N_LS")
			(options
				(clearance outline)
				(anchor circle)
			)
			(primitives
				(gr_poly
					(pts
						(arc
							(start -0.1778 0.2794)
							(mid -0.249642 0.249642)
							(end -0.2794 0.1778)
						)
						(arc
							(start -0.2794 -0.1778)
							(mid -0.249642 -0.249642)
							(end -0.1778 -0.2794)
						)
						(arc
							(start 0.1778 -0.2794)
							(mid 0.249642 -0.249642)
							(end 0.2794 -0.1778)
						)
						(arc
							(start 0.2794 0.1778)
							(mid 0.249642 0.249642)
							(end 0.1778 0.2794)
						)
					)
					(width 0)
					(fill yes)
				)
			)
		)
		(pad "2" smd custom
			(at 0 0.4445 180)
			(size 0.1397 0.1397)
			(layers "B.Cu" "B.Mask" "B.Paste")
			(net "DUT_VDDO")
			(options
				(clearance outline)
				(anchor circle)
			)
			(primitives
				(gr_poly
					(pts
						(arc
							(start -0.1778 0.2794)
							(mid -0.249642 0.249642)
							(end -0.2794 0.1778)
						)
						(arc
							(start -0.2794 -0.1778)
							(mid -0.249642 -0.249642)
							(end -0.1778 -0.2794)
						)
						(arc
							(start 0.1778 -0.2794)
							(mid 0.249642 -0.249642)
							(end 0.2794 -0.1778)
						)
						(arc
							(start 0.2794 0.1778)
							(mid 0.249642 0.249642)
							(end 0.1778 0.2794)
						)
					)
					(width 0)
					(fill yes)
				)
			)
		)
	)
	(footprint ""
		(layer "B.Cu")
		(at 215.55964 -200.02246 180)
		(property "Reference" "C8092"
			(at 0 0 0)
			(layer "B.SilkS")
			(hide yes)
			(effects
				(font
					(size 1.27 1.27)
				)
				(justify mirror)
			)
		)
		(property "Value" "SCD047U25V2KX-GP"
			(at -1.1811 -2.7051 180)
			(unlocked yes)
			(layer "B.Fab")
			(hide yes)
			(effects
				(font
					(size 1.016 1.016)
					(thickness 0.1524)
				)
				(justify mirror)
			)
		)
		(property "Device Type" "C402H22"
			(at -1.1811 -4.2291 180)
			(unlocked yes)
			(layer "B.Fab")
			(hide yes)
			(effects
				(font
					(size 1.016 1.016)
					(thickness 0.1524)
				)
				(justify mirror)
			)
		)
		(duplicate_pad_numbers_are_jumpers no)
		(fp_rect
			(start 0.4318 0.9525)
			(end -0.4318 -0.9525)
			(stroke
				(width 0)
				(type default)
			)
			(fill no)
			(layer "B.CrtYd")
		)
		(fp_rect
			(start 0.4318 0.9525)
			(end -0.4318 -0.9525)
			(stroke
				(width 0)
				(type default)
			)
			(fill no)
			(layer "B.Fab")
		)
		(pad "1" smd custom
			(at 0 -0.4445)
			(size 0.1524 0.1524)
			(layers "B.Cu" "B.Mask" "B.Paste")
			(net "P3V3_STBY")
			(options
				(clearance outline)
				(anchor circle)
			)
			(primitives
				(gr_poly
					(pts
						(arc
							(start 0.3048 0.2032)
							(mid 0.275042 0.275042)
							(end 0.2032 0.3048)
						)
						(arc
							(start -0.2032 0.3048)
							(mid -0.275042 0.275042)
							(end -0.3048 0.2032)
						)
						(arc
							(start -0.3048 -0.2032)
							(mid -0.275042 -0.275042)
							(end -0.2032 -0.3048)
						)
						(arc
							(start 0.2032 -0.3048)
							(mid 0.275042 -0.275042)
							(end 0.3048 -0.2032)
						)
					)
					(width 0)
					(fill yes)
				)
			)
		)
		(pad "2" smd custom
			(at 0 0.4445)
			(size 0.1524 0.1524)
			(layers "B.Cu" "B.Mask" "B.Paste")
			(net "GND")
			(options
				(clearance outline)
				(anchor circle)
			)
			(primitives
				(gr_poly
					(pts
						(arc
							(start 0.3048 0.2032)
							(mid 0.275042 0.275042)
							(end 0.2032 0.3048)
						)
						(arc
							(start -0.2032 0.3048)
							(mid -0.275042 0.275042)
							(end -0.3048 0.2032)
						)
						(arc
							(start -0.3048 -0.2032)
							(mid -0.275042 -0.275042)
							(end -0.2032 -0.3048)
						)
						(arc
							(start 0.2032 -0.3048)
							(mid 0.275042 -0.275042)
							(end 0.3048 -0.2032)
						)
					)
					(width 0)
					(fill yes)
				)
			)
		)
	)
	(footprint ""
		(layer "B.Cu")
		(at 234.823 -20.447)
		(property "Reference" "R809"
			(at 0 0 0)
			(layer "B.SilkS")
			(hide yes)
			(effects
				(font
					(size 1.27 1.27)
				)
				(justify mirror)
			)
		)
		(property "Value" "4K7R2F-GP"
			(at -0.064008 -3.993896 0)
			(unlocked yes)
			(layer "B.Fab")
			(hide yes)
			(effects
				(font
					(size 1.016 1.016)
					(thickness 0.1524)
				)
				(justify mirror)
			)
		)
		(property "Device Type" "R402H16"
			(at -0.064008 -5.517896 0)
			(unlocked yes)
			(layer "B.Fab")
			(hide yes)
			(effects
				(font
					(size 1.016 1.016)
					(thickness 0.1524)
				)
				(justify mirror)
			)
		)
		(duplicate_pad_numbers_are_jumpers no)
		(fp_line
			(start -0.508 -0.9398)
			(end 0.508 -0.9398)
			(stroke
				(width 0.1524)
				(type default)
			)
			(layer "B.SilkS")
		)
		(fp_line
			(start 0.508 -0.9398)
			(end 0.508 0.9398)
			(stroke
				(width 0.1524)
				(type default)
			)
			(layer "B.SilkS")
		)
		(fp_rect
			(start 0.508 0.9398)
			(end -0.508 -0.9398)
			(stroke
				(width 0)
				(type default)
			)
			(fill no)
			(layer "B.CrtYd")
		)
		(fp_rect
			(start 0.508 0.9398)
			(end -0.508 -0.9398)
			(stroke
				(width 0)
				(type default)
			)
			(fill no)
			(layer "B.Fab")
		)
		(pad "1" smd custom
			(at 0 -0.4445 180)
			(size 0.1397 0.1397)
			(layers "B.Cu" "B.Mask" "B.Paste")
			(net "BOOTSTRAP4")
			(options
				(clearance outline)
				(anchor circle)
			)
			(primitives
				(gr_poly
					(pts
						(arc
							(start -0.1778 0.2794)
							(mid -0.249642 0.249642)
							(end -0.2794 0.1778)
						)
						(arc
							(start -0.2794 -0.1778)
							(mid -0.249642 -0.249642)
							(end -0.1778 -0.2794)
						)
						(arc
							(start 0.1778 -0.2794)
							(mid 0.249642 -0.249642)
							(end 0.2794 -0.1778)
						)
						(arc
							(start 0.2794 0.1778)
							(mid 0.249642 0.249642)
							(end 0.1778 0.2794)
						)
					)
					(width 0)
					(fill yes)
				)
			)
		)
		(pad "2" smd custom
			(at 0 0.4445 180)
			(size 0.1397 0.1397)
			(layers "B.Cu" "B.Mask" "B.Paste")
			(net "DUT_VDDO")
			(options
				(clearance outline)
				(anchor circle)
			)
			(primitives
				(gr_poly
					(pts
						(arc
							(start -0.1778 0.2794)
							(mid -0.249642 0.249642)
							(end -0.2794 0.1778)
						)
						(arc
							(start -0.2794 -0.1778)
							(mid -0.249642 -0.249642)
							(end -0.1778 -0.2794)
						)
						(arc
							(start 0.1778 -0.2794)
							(mid 0.249642 -0.249642)
							(end 0.2794 -0.1778)
						)
						(arc
							(start 0.2794 0.1778)
							(mid 0.249642 0.249642)
							(end 0.1778 0.2794)
						)
					)
					(width 0)
					(fill yes)
				)
			)
		)
	)
	(footprint ""
		(layer "B.Cu")
		(at 61.8236 -118.0084)
		(property "Reference" "U13"
			(at 0 0 0)
			(layer "B.SilkS")
			(hide yes)
			(effects
				(font
					(size 1.27 1.27)
				)
				(justify mirror)
			)
		)
		(property "Value" "2N7002DW-7F-GP"
			(at 2.3622 -8.2042 0)
			(unlocked yes)
			(layer "B.Fab")
			(hide yes)
			(effects
				(font
					(size 1.016 1.016)
					(thickness 0.1524)
				)
				(justify mirror)
			)
		)
		(property "Device Type" "SOT-363H44"
			(at 2.3622 -10.1092 0)
			(unlocked yes)
			(layer "B.Fab")
			(hide yes)
			(effects
				(font
					(size 1.016 1.016)
					(thickness 0.1524)
				)
				(justify mirror)
			)
		)
		(duplicate_pad_numbers_are_jumpers no)
		(fp_line
			(start -1.4478 -1.7018)
			(end 1.4478 -1.7018)
			(stroke
				(width 0.1524)
				(type default)
			)
			(layer "B.SilkS")
		)
		(fp_line
			(start -1.4478 1.7018)
			(end -1.4478 -1.7018)
			(stroke
				(width 0.1524)
				(type default)
			)
			(layer "B.SilkS")
		)
		(fp_line
			(start 1.27 1.524)
			(end 1.27 0.6604)
			(stroke
				(width 0.4826)
				(type default)
			)
			(layer "B.SilkS")
		)
		(fp_line
			(start 1.4478 -1.7018)
			(end 1.4478 1.7018)
			(stroke
				(width 0.1524)
				(type default)
			)
			(layer "B.SilkS")
		)
		(fp_line
			(start 1.4478 1.7018)
			(end -1.4478 1.7018)
			(stroke
				(width 0.1524)
				(type default)
			)
			(layer "B.SilkS")
		)
		(fp_poly
			(pts
				(xy 1.524 -1.778) (xy -1.524 -1.778) (xy -1.524 1.778) (xy 1.524 1.778)
			)
			(stroke
				(width 0)
				(type default)
			)
			(fill no)
			(layer "B.CrtYd")
		)
		(fp_poly
			(pts
				(xy 1.524 -1.778) (xy -1.524 -1.778) (xy -1.524 1.778) (xy 1.524 1.778)
			)
			(stroke
				(width 0)
				(type default)
			)
			(fill no)
			(layer "B.Fab")
		)
		(pad "1" smd rect
			(at 0.65024 0.9398 180)
			(size 0.4064 1.016)
			(layers "B.Cu" "B.Mask" "B.Paste")
			(net "BMC_I2C3_MINI3_SCL_S")
		)
		(pad "2" smd rect
			(at 0 0.9398 180)
			(size 0.4064 1.016)
			(layers "B.Cu" "B.Mask" "B.Paste")
			(net "I2C3_LS_G2")
		)
		(pad "3" smd rect
			(at -0.65024 0.9398 180)
			(size 0.4064 1.016)
			(layers "B.Cu" "B.Mask" "B.Paste")
			(net "BMC_I2C3_MINI3_SDA")
		)
		(pad "4" smd rect
			(at -0.65024 -0.9398 180)
			(size 0.4064 1.016)
			(layers "B.Cu" "B.Mask" "B.Paste")
			(net "BMC_I2C3_MINI3_SDA_S")
		)
		(pad "5" smd rect
			(at 0 -0.9398 180)
			(size 0.4064 1.016)
			(layers "B.Cu" "B.Mask" "B.Paste")
			(net "I2C3_LS_G1")
		)
		(pad "6" smd rect
			(at 0.65024 -0.9398 180)
			(size 0.4064 1.016)
			(layers "B.Cu" "B.Mask" "B.Paste")
			(net "BMC_I2C3_MINI3_SCL")
		)
	)
	(footprint ""
		(layer "B.Cu")
		(at 159.909002 -60.479432 -90)
		(property "Reference" "PR159"
			(at 0 0 90)
			(layer "B.SilkS")
			(hide yes)
			(effects
				(font
					(size 1.27 1.27)
				)
				(justify mirror)
			)
		)
		(property "Value" "0R3J-0-U-GP"
			(at 0.0254 -2.5146 270)
			(unlocked yes)
			(layer "B.Fab")
			(hide yes)
			(effects
				(font
					(size 1.016 1.016)
					(thickness 0.1524)
				)
				(justify mirror)
			)
		)
		(property "Device Type" "R603H22"
			(at 0.0254 -4.0386 270)
			(unlocked yes)
			(layer "B.Fab")
			(hide yes)
			(effects
				(font
					(size 1.016 1.016)
					(thickness 0.1524)
				)
				(justify mirror)
			)
		)
		(duplicate_pad_numbers_are_jumpers no)
		(fp_line
			(start -0.2032 0)
			(end -0.4826 0)
			(stroke
				(width 0.2032)
				(type default)
			)
			(layer "B.SilkS")
		)
		(fp_line
			(start 0.4826 0)
			(end 0.2032 0)
			(stroke
				(width 0.2032)
				(type default)
			)
			(layer "B.SilkS")
		)
		(fp_rect
			(start 0.5842 1.3335)
			(end -0.5842 -1.3335)
			(stroke
				(width 0)
				(type default)
			)
			(fill no)
			(layer "B.CrtYd")
		)
		(fp_rect
			(start 0.5842 1.3335)
			(end -0.5842 -1.3335)
			(stroke
				(width 0)
				(type default)
			)
			(fill no)
			(layer "B.Fab")
		)
		(pad "1" smd custom
			(at 0 -0.762 90)
			(size 0.2159 0.2159)
			(layers "B.Cu" "B.Mask" "B.Paste")
			(net "P0V9_LX")
			(options
				(clearance outline)
				(anchor circle)
			)
			(primitives
				(gr_poly
					(pts
						(arc
							(start -0.3302 0.4318)
							(mid -0.402042 0.402042)
							(end -0.4318 0.3302)
						)
						(arc
							(start -0.4318 -0.3302)
							(mid -0.402042 -0.402042)
							(end -0.3302 -0.4318)
						)
						(arc
							(start 0.3302 -0.4318)
							(mid 0.402042 -0.402042)
							(end 0.4318 -0.3302)
						)
						(arc
							(start 0.4318 0.3302)
							(mid 0.402042 0.402042)
							(end 0.3302 0.4318)
						)
					)
					(width 0)
					(fill yes)
				)
			)
		)
		(pad "2" smd custom
			(at 0 0.762 90)
			(size 0.2159 0.2159)
			(layers "B.Cu" "B.Mask" "B.Paste")
			(net "P0V9_VBST_RC")
			(options
				(clearance outline)
				(anchor circle)
			)
			(primitives
				(gr_poly
					(pts
						(arc
							(start -0.3302 0.4318)
							(mid -0.402042 0.402042)
							(end -0.4318 0.3302)
						)
						(arc
							(start -0.4318 -0.3302)
							(mid -0.402042 -0.402042)
							(end -0.3302 -0.4318)
						)
						(arc
							(start 0.3302 -0.4318)
							(mid 0.402042 -0.402042)
							(end 0.4318 -0.3302)
						)
						(arc
							(start 0.4318 0.3302)
							(mid 0.402042 0.402042)
							(end 0.3302 0.4318)
						)
					)
					(width 0)
					(fill yes)
				)
			)
		)
	)
	(footprint ""
		(layer "B.Cu")
		(at 249.605038 -60.071)
		(property "Reference" "C600"
			(at 0 0 0)
			(layer "B.SilkS")
			(hide yes)
			(effects
				(font
					(size 1.27 1.27)
				)
				(justify mirror)
			)
		)
		(property "Value" "SCD1U16V1KX-1-GP"
			(at 2.8321 -1.7399 0)
			(unlocked yes)
			(layer "B.Fab")
			(hide yes)
			(effects
				(font
					(size 1.016 1.016)
					(thickness 0.1524)
				)
				(justify mirror)
			)
		)
		(property "Device Type" "C0201H13"
			(at 2.8321 -3.2639 0)
			(unlocked yes)
			(layer "B.Fab")
			(hide yes)
			(effects
				(font
					(size 1.016 1.016)
					(thickness 0.1524)
				)
				(justify mirror)
			)
		)
		(duplicate_pad_numbers_are_jumpers no)
		(fp_rect
			(start 0.2794 0.6477)
			(end -0.2794 -0.6477)
			(stroke
				(width 0)
				(type default)
			)
			(fill no)
			(layer "B.CrtYd")
		)
		(fp_rect
			(start 0.2794 0.6477)
			(end -0.2794 -0.6477)
			(stroke
				(width 0)
				(type default)
			)
			(fill no)
			(layer "B.Fab")
		)
		(pad "1" smd custom
			(at 0 -0.2794 180)
			(size 0.0762 0.0762)
			(layers "B.Cu" "B.Mask" "B.Paste")
			(net "DUT_AVD_PCIE")
			(options
				(clearance outline)
				(anchor circle)
			)
			(primitives
				(gr_poly
					(pts
						(arc
							(start 0.1524 0.127)
							(mid 0.137521 0.162921)
							(end 0.1016 0.1778)
						)
						(arc
							(start -0.1016 0.1778)
							(mid -0.137521 0.162921)
							(end -0.1524 0.127)
						)
						(arc
							(start -0.1524 -0.127)
							(mid -0.137521 -0.162921)
							(end -0.1016 -0.1778)
						)
						(arc
							(start 0.1016 -0.1778)
							(mid 0.137521 -0.162921)
							(end 0.1524 -0.127)
						)
					)
					(width 0)
					(fill yes)
				)
			)
		)
		(pad "2" smd custom
			(at 0 0.2794 180)
			(size 0.0762 0.0762)
			(layers "B.Cu" "B.Mask" "B.Paste")
			(net "GND")
			(options
				(clearance outline)
				(anchor circle)
			)
			(primitives
				(gr_poly
					(pts
						(arc
							(start 0.1524 0.127)
							(mid 0.137521 0.162921)
							(end 0.1016 0.1778)
						)
						(arc
							(start -0.1016 0.1778)
							(mid -0.137521 0.162921)
							(end -0.1524 0.127)
						)
						(arc
							(start -0.1524 -0.127)
							(mid -0.137521 -0.162921)
							(end -0.1016 -0.1778)
						)
						(arc
							(start 0.1016 -0.1778)
							(mid 0.137521 -0.162921)
							(end 0.1524 -0.127)
						)
					)
					(width 0)
					(fill yes)
				)
			)
		)
	)
	(footprint ""
		(layer "B.Cu")
		(at 246.599964 -34.99993)
		(property "Reference" "TP294"
			(at 0 0 0)
			(layer "B.SilkS")
			(hide yes)
			(effects
				(font
					(size 1.27 1.27)
				)
				(justify mirror)
			)
		)
		(property "Value" "TPAD28-2-GP"
			(at 0.0127 -1.6637 0)
			(unlocked yes)
			(layer "B.Fab")
			(hide yes)
			(effects
				(font
					(size 1.016 1.016)
					(thickness 0.1524)
				)
				(justify mirror)
			)
		)
		(property "Device Type" "TPAD28"
			(at 0.0127 -3.1877 0)
			(unlocked yes)
			(layer "B.Fab")
			(hide yes)
			(effects
				(font
					(size 1.016 1.016)
					(thickness 0.1524)
				)
				(justify mirror)
			)
		)
		(duplicate_pad_numbers_are_jumpers no)
		(fp_poly
			(pts
				(arc
					(start 0.3556 0)
					(mid -0.3556 0)
					(end 0.3556 0)
				)
			)
			(stroke
				(width 0)
				(type default)
			)
			(fill no)
			(layer "B.CrtYd")
		)
		(fp_poly
			(pts
				(arc
					(start 0.6096 0)
					(mid -0.6096 0)
					(end 0.6096 0)
				)
			)
			(stroke
				(width 0)
				(type default)
			)
			(fill no)
			(layer "B.Fab")
		)
		(pad "1" smd circle
			(at 0 0 180)
			(size 0.7112 0.7112)
			(layers "B.Cu" "B.Mask" "B.Paste")
			(net "TWI_SRST#7")
		)
	)
	(footprint ""
		(layer "B.Cu")
		(at 247.1166 -48.9966 -90)
		(property "Reference" "C445"
			(at 0 0 90)
			(layer "B.SilkS")
			(hide yes)
			(effects
				(font
					(size 1.27 1.27)
				)
				(justify mirror)
			)
		)
		(property "Value" "SCD1U16V1KX-1-GP"
			(at 2.8321 -1.7399 270)
			(unlocked yes)
			(layer "B.Fab")
			(hide yes)
			(effects
				(font
					(size 1.016 1.016)
					(thickness 0.1524)
				)
				(justify mirror)
			)
		)
		(property "Device Type" "C0201H13"
			(at 2.8321 -3.2639 270)
			(unlocked yes)
			(layer "B.Fab")
			(hide yes)
			(effects
				(font
					(size 1.016 1.016)
					(thickness 0.1524)
				)
				(justify mirror)
			)
		)
		(duplicate_pad_numbers_are_jumpers no)
		(fp_rect
			(start 0.2794 0.6477)
			(end -0.2794 -0.6477)
			(stroke
				(width 0)
				(type default)
			)
			(fill no)
			(layer "B.CrtYd")
		)
		(fp_rect
			(start 0.2794 0.6477)
			(end -0.2794 -0.6477)
			(stroke
				(width 0)
				(type default)
			)
			(fill no)
			(layer "B.Fab")
		)
		(pad "1" smd custom
			(at 0 -0.2794 90)
			(size 0.0762 0.0762)
			(layers "B.Cu" "B.Mask" "B.Paste")
			(net "DUT_VDD")
			(options
				(clearance outline)
				(anchor circle)
			)
			(primitives
				(gr_poly
					(pts
						(arc
							(start 0.1524 0.127)
							(mid 0.137521 0.162921)
							(end 0.1016 0.1778)
						)
						(arc
							(start -0.1016 0.1778)
							(mid -0.137521 0.162921)
							(end -0.1524 0.127)
						)
						(arc
							(start -0.1524 -0.127)
							(mid -0.137521 -0.162921)
							(end -0.1016 -0.1778)
						)
						(arc
							(start 0.1016 -0.1778)
							(mid 0.137521 -0.162921)
							(end 0.1524 -0.127)
						)
					)
					(width 0)
					(fill yes)
				)
			)
		)
		(pad "2" smd custom
			(at 0 0.2794 90)
			(size 0.0762 0.0762)
			(layers "B.Cu" "B.Mask" "B.Paste")
			(net "GND")
			(options
				(clearance outline)
				(anchor circle)
			)
			(primitives
				(gr_poly
					(pts
						(arc
							(start 0.1524 0.127)
							(mid 0.137521 0.162921)
							(end 0.1016 0.1778)
						)
						(arc
							(start -0.1016 0.1778)
							(mid -0.137521 0.162921)
							(end -0.1524 0.127)
						)
						(arc
							(start -0.1524 -0.127)
							(mid -0.137521 -0.162921)
							(end -0.1016 -0.1778)
						)
						(arc
							(start 0.1016 -0.1778)
							(mid 0.137521 -0.162921)
							(end 0.1524 -0.127)
						)
					)
					(width 0)
					(fill yes)
				)
			)
		)
	)
	(footprint ""
		(layer "B.Cu")
		(at 35.433 -118.491 -90)
		(property "Reference" "TP220"
			(at 0 0 90)
			(layer "B.SilkS")
			(hide yes)
			(effects
				(font
					(size 1.27 1.27)
				)
				(justify mirror)
			)
		)
		(property "Value" "TPAD28-2-GP"
			(at 0.0127 -1.6637 270)
			(unlocked yes)
			(layer "B.Fab")
			(hide yes)
			(effects
				(font
					(size 1.016 1.016)
					(thickness 0.1524)
				)
				(justify mirror)
			)
		)
		(property "Device Type" "TPAD28"
			(at 0.0127 -3.1877 270)
			(unlocked yes)
			(layer "B.Fab")
			(hide yes)
			(effects
				(font
					(size 1.016 1.016)
					(thickness 0.1524)
				)
				(justify mirror)
			)
		)
		(duplicate_pad_numbers_are_jumpers no)
		(fp_poly
			(pts
				(arc
					(start 0 -0.3556)
					(mid 0 0.3556)
					(end 0 -0.3556)
				)
			)
			(stroke
				(width 0)
				(type default)
			)
			(fill no)
			(layer "B.CrtYd")
		)
		(fp_poly
			(pts
				(arc
					(start 0 -0.6096)
					(mid 0 0.6096)
					(end 0 -0.6096)
				)
			)
			(stroke
				(width 0)
				(type default)
			)
			(fill no)
			(layer "B.Fab")
		)
		(pad "1" smd circle
			(at 0 0 90)
			(size 0.7112 0.7112)
			(layers "B.Cu" "B.Mask" "B.Paste")
			(net "TP_GPIOE6")
		)
	)
	(footprint ""
		(layer "B.Cu")
		(at 335.153 -179.705)
		(property "Reference" "R209"
			(at 0 0 0)
			(layer "B.SilkS")
			(hide yes)
			(effects
				(font
					(size 1.27 1.27)
				)
				(justify mirror)
			)
		)
		(property "Value" "4K7R2F-GP"
			(at -0.064008 -3.993896 0)
			(unlocked yes)
			(layer "B.Fab")
			(hide yes)
			(effects
				(font
					(size 1.016 1.016)
					(thickness 0.1524)
				)
				(justify mirror)
			)
		)
		(property "Device Type" "R402H16"
			(at -0.064008 -5.517896 0)
			(unlocked yes)
			(layer "B.Fab")
			(hide yes)
			(effects
				(font
					(size 1.016 1.016)
					(thickness 0.1524)
				)
				(justify mirror)
			)
		)
		(duplicate_pad_numbers_are_jumpers no)
		(fp_line
			(start -0.508 -0.9398)
			(end 0.508 -0.9398)
			(stroke
				(width 0.1524)
				(type default)
			)
			(layer "B.SilkS")
		)
		(fp_line
			(start 0.508 -0.9398)
			(end 0.508 0.9398)
			(stroke
				(width 0.1524)
				(type default)
			)
			(layer "B.SilkS")
		)
		(fp_rect
			(start 0.508 0.9398)
			(end -0.508 -0.9398)
			(stroke
				(width 0)
				(type default)
			)
			(fill no)
			(layer "B.CrtYd")
		)
		(fp_rect
			(start 0.508 0.9398)
			(end -0.508 -0.9398)
			(stroke
				(width 0)
				(type default)
			)
			(fill no)
			(layer "B.Fab")
		)
		(pad "1" smd custom
			(at 0 -0.4445 180)
			(size 0.1397 0.1397)
			(layers "B.Cu" "B.Mask" "B.Paste")
			(net "BMC_SSD_RST#0_A9")
			(options
				(clearance outline)
				(anchor circle)
			)
			(primitives
				(gr_poly
					(pts
						(arc
							(start -0.1778 0.2794)
							(mid -0.249642 0.249642)
							(end -0.2794 0.1778)
						)
						(arc
							(start -0.2794 -0.1778)
							(mid -0.249642 -0.249642)
							(end -0.1778 -0.2794)
						)
						(arc
							(start 0.1778 -0.2794)
							(mid 0.249642 -0.249642)
							(end 0.2794 -0.1778)
						)
						(arc
							(start 0.2794 0.1778)
							(mid 0.249642 0.249642)
							(end 0.1778 0.2794)
						)
					)
					(width 0)
					(fill yes)
				)
			)
		)
		(pad "2" smd custom
			(at 0 0.4445 180)
			(size 0.1397 0.1397)
			(layers "B.Cu" "B.Mask" "B.Paste")
			(net "P3V3_STBY")
			(options
				(clearance outline)
				(anchor circle)
			)
			(primitives
				(gr_poly
					(pts
						(arc
							(start -0.1778 0.2794)
							(mid -0.249642 0.249642)
							(end -0.2794 0.1778)
						)
						(arc
							(start -0.2794 -0.1778)
							(mid -0.249642 -0.249642)
							(end -0.1778 -0.2794)
						)
						(arc
							(start 0.1778 -0.2794)
							(mid 0.249642 -0.249642)
							(end 0.2794 -0.1778)
						)
						(arc
							(start 0.2794 0.1778)
							(mid 0.249642 0.249642)
							(end 0.1778 0.2794)
						)
					)
					(width 0)
					(fill yes)
				)
			)
		)
	)
	(footprint ""
		(layer "B.Cu")
		(at 239.1664 -48.9966 90)
		(property "Reference" "C35"
			(at 0 0 90)
			(layer "B.SilkS")
			(hide yes)
			(effects
				(font
					(size 1.27 1.27)
				)
				(justify mirror)
			)
		)
		(property "Value" "SCD1U16V1KX-1-GP"
			(at 2.8321 -1.7399 90)
			(unlocked yes)
			(layer "B.Fab")
			(hide yes)
			(effects
				(font
					(size 1.016 1.016)
					(thickness 0.1524)
				)
				(justify mirror)
			)
		)
		(property "Device Type" "C0201H13"
			(at 2.8321 -3.2639 90)
			(unlocked yes)
			(layer "B.Fab")
			(hide yes)
			(effects
				(font
					(size 1.016 1.016)
					(thickness 0.1524)
				)
				(justify mirror)
			)
		)
		(duplicate_pad_numbers_are_jumpers no)
		(fp_rect
			(start 0.2794 0.6477)
			(end -0.2794 -0.6477)
			(stroke
				(width 0)
				(type default)
			)
			(fill no)
			(layer "B.CrtYd")
		)
		(fp_rect
			(start 0.2794 0.6477)
			(end -0.2794 -0.6477)
			(stroke
				(width 0)
				(type default)
			)
			(fill no)
			(layer "B.Fab")
		)
		(pad "1" smd custom
			(at 0 -0.2794 270)
			(size 0.0762 0.0762)
			(layers "B.Cu" "B.Mask" "B.Paste")
			(net "DUT_VDD")
			(options
				(clearance outline)
				(anchor circle)
			)
			(primitives
				(gr_poly
					(pts
						(arc
							(start 0.1524 0.127)
							(mid 0.137521 0.162921)
							(end 0.1016 0.1778)
						)
						(arc
							(start -0.1016 0.1778)
							(mid -0.137521 0.162921)
							(end -0.1524 0.127)
						)
						(arc
							(start -0.1524 -0.127)
							(mid -0.137521 -0.162921)
							(end -0.1016 -0.1778)
						)
						(arc
							(start 0.1016 -0.1778)
							(mid 0.137521 -0.162921)
							(end 0.1524 -0.127)
						)
					)
					(width 0)
					(fill yes)
				)
			)
		)
		(pad "2" smd custom
			(at 0 0.2794 270)
			(size 0.0762 0.0762)
			(layers "B.Cu" "B.Mask" "B.Paste")
			(net "GND")
			(options
				(clearance outline)
				(anchor circle)
			)
			(primitives
				(gr_poly
					(pts
						(arc
							(start 0.1524 0.127)
							(mid 0.137521 0.162921)
							(end 0.1016 0.1778)
						)
						(arc
							(start -0.1016 0.1778)
							(mid -0.137521 0.162921)
							(end -0.1524 0.127)
						)
						(arc
							(start -0.1524 -0.127)
							(mid -0.137521 -0.162921)
							(end -0.1016 -0.1778)
						)
						(arc
							(start 0.1016 -0.1778)
							(mid 0.137521 -0.162921)
							(end 0.1524 -0.127)
						)
					)
					(width 0)
					(fill yes)
				)
			)
		)
	)
	(footprint ""
		(layer "B.Cu")
		(at 24.13 -119.9896 -90)
		(property "Reference" "R9024"
			(at 0 0 90)
			(layer "B.SilkS")
			(hide yes)
			(effects
				(font
					(size 1.27 1.27)
				)
				(justify mirror)
			)
		)
		(property "Value" "191R2F-GP"
			(at -0.064008 -3.993896 270)
			(unlocked yes)
			(layer "B.Fab")
			(hide yes)
			(effects
				(font
					(size 1.016 1.016)
					(thickness 0.1524)
				)
				(justify mirror)
			)
		)
		(property "Device Type" "R402H16"
			(at -0.064008 -5.517896 270)
			(unlocked yes)
			(layer "B.Fab")
			(hide yes)
			(effects
				(font
					(size 1.016 1.016)
					(thickness 0.1524)
				)
				(justify mirror)
			)
		)
		(duplicate_pad_numbers_are_jumpers no)
		(fp_line
			(start -0.508 -0.9398)
			(end 0.508 -0.9398)
			(stroke
				(width 0.1524)
				(type default)
			)
			(layer "B.SilkS")
		)
		(fp_line
			(start 0.508 -0.9398)
			(end 0.508 0.9398)
			(stroke
				(width 0.1524)
				(type default)
			)
			(layer "B.SilkS")
		)
		(fp_rect
			(start 0.508 0.9398)
			(end -0.508 -0.9398)
			(stroke
				(width 0)
				(type default)
			)
			(fill no)
			(layer "B.CrtYd")
		)
		(fp_rect
			(start 0.508 0.9398)
			(end -0.508 -0.9398)
			(stroke
				(width 0)
				(type default)
			)
			(fill no)
			(layer "B.Fab")
		)
		(pad "1" smd custom
			(at 0 -0.4445 90)
			(size 0.1397 0.1397)
			(layers "B.Cu" "B.Mask" "B.Paste")
			(net "BMC_PEREXT")
			(options
				(clearance outline)
				(anchor circle)
			)
			(primitives
				(gr_poly
					(pts
						(arc
							(start -0.1778 0.2794)
							(mid -0.249642 0.249642)
							(end -0.2794 0.1778)
						)
						(arc
							(start -0.2794 -0.1778)
							(mid -0.249642 -0.249642)
							(end -0.1778 -0.2794)
						)
						(arc
							(start 0.1778 -0.2794)
							(mid 0.249642 -0.249642)
							(end 0.2794 -0.1778)
						)
						(arc
							(start 0.2794 0.1778)
							(mid 0.249642 0.249642)
							(end 0.1778 0.2794)
						)
					)
					(width 0)
					(fill yes)
				)
			)
		)
		(pad "2" smd custom
			(at 0 0.4445 90)
			(size 0.1397 0.1397)
			(layers "B.Cu" "B.Mask" "B.Paste")
			(net "GND")
			(options
				(clearance outline)
				(anchor circle)
			)
			(primitives
				(gr_poly
					(pts
						(arc
							(start -0.1778 0.2794)
							(mid -0.249642 0.249642)
							(end -0.2794 0.1778)
						)
						(arc
							(start -0.2794 -0.1778)
							(mid -0.249642 -0.249642)
							(end -0.1778 -0.2794)
						)
						(arc
							(start 0.1778 -0.2794)
							(mid 0.249642 -0.249642)
							(end 0.2794 -0.1778)
						)
						(arc
							(start 0.2794 0.1778)
							(mid 0.249642 0.249642)
							(end 0.1778 0.2794)
						)
					)
					(width 0)
					(fill yes)
				)
			)
		)
	)
	(footprint ""
		(layer "B.Cu")
		(at 140.589 -34.059876 90)
		(property "Reference" "C224"
			(at 0 0 90)
			(layer "B.SilkS")
			(hide yes)
			(effects
				(font
					(size 1.27 1.27)
				)
				(justify mirror)
			)
		)
		(property "Value" "SCD1U10V2KX-5GP"
			(at -1.1811 -2.7051 90)
			(unlocked yes)
			(layer "B.Fab")
			(hide yes)
			(effects
				(font
					(size 1.016 1.016)
					(thickness 0.1524)
				)
				(justify mirror)
			)
		)
		(property "Device Type" "C402H22"
			(at -1.1811 -4.2291 90)
			(unlocked yes)
			(layer "B.Fab")
			(hide yes)
			(effects
				(font
					(size 1.016 1.016)
					(thickness 0.1524)
				)
				(justify mirror)
			)
		)
		(duplicate_pad_numbers_are_jumpers no)
		(fp_rect
			(start 0.4318 0.9525)
			(end -0.4318 -0.9525)
			(stroke
				(width 0)
				(type default)
			)
			(fill no)
			(layer "B.CrtYd")
		)
		(fp_rect
			(start 0.4318 0.9525)
			(end -0.4318 -0.9525)
			(stroke
				(width 0)
				(type default)
			)
			(fill no)
			(layer "B.Fab")
		)
		(pad "1" smd custom
			(at 0 -0.4445 270)
			(size 0.1524 0.1524)
			(layers "B.Cu" "B.Mask" "B.Paste")
			(net "GND")
			(options
				(clearance outline)
				(anchor circle)
			)
			(primitives
				(gr_poly
					(pts
						(arc
							(start 0.3048 0.2032)
							(mid 0.275042 0.275042)
							(end 0.2032 0.3048)
						)
						(arc
							(start -0.2032 0.3048)
							(mid -0.275042 0.275042)
							(end -0.3048 0.2032)
						)
						(arc
							(start -0.3048 -0.2032)
							(mid -0.275042 -0.275042)
							(end -0.2032 -0.3048)
						)
						(arc
							(start 0.2032 -0.3048)
							(mid 0.275042 -0.275042)
							(end 0.3048 -0.2032)
						)
					)
					(width 0)
					(fill yes)
				)
			)
		)
		(pad "2" smd custom
			(at 0 0.4445 270)
			(size 0.1524 0.1524)
			(layers "B.Cu" "B.Mask" "B.Paste")
			(net "P3V3_STBY")
			(options
				(clearance outline)
				(anchor circle)
			)
			(primitives
				(gr_poly
					(pts
						(arc
							(start 0.3048 0.2032)
							(mid 0.275042 0.275042)
							(end 0.2032 0.3048)
						)
						(arc
							(start -0.2032 0.3048)
							(mid -0.275042 0.275042)
							(end -0.3048 0.2032)
						)
						(arc
							(start -0.3048 -0.2032)
							(mid -0.275042 -0.275042)
							(end -0.2032 -0.3048)
						)
						(arc
							(start 0.2032 -0.3048)
							(mid 0.275042 -0.275042)
							(end 0.3048 -0.2032)
						)
					)
					(width 0)
					(fill yes)
				)
			)
		)
	)
	(footprint ""
		(layer "B.Cu")
		(at 61.341 -121.412 -90)
		(property "Reference" "R598"
			(at 0 0 90)
			(layer "B.SilkS")
			(hide yes)
			(effects
				(font
					(size 1.27 1.27)
				)
				(justify mirror)
			)
		)
		(property "Value" "4K7R2F-GP"
			(at -0.064008 -3.993896 270)
			(unlocked yes)
			(layer "B.Fab")
			(hide yes)
			(effects
				(font
					(size 1.016 1.016)
					(thickness 0.1524)
				)
				(justify mirror)
			)
		)
		(property "Device Type" "R402H16"
			(at -0.064008 -5.517896 270)
			(unlocked yes)
			(layer "B.Fab")
			(hide yes)
			(effects
				(font
					(size 1.016 1.016)
					(thickness 0.1524)
				)
				(justify mirror)
			)
		)
		(duplicate_pad_numbers_are_jumpers no)
		(fp_line
			(start -0.508 -0.9398)
			(end 0.508 -0.9398)
			(stroke
				(width 0.1524)
				(type default)
			)
			(layer "B.SilkS")
		)
		(fp_line
			(start 0.508 -0.9398)
			(end 0.508 0.9398)
			(stroke
				(width 0.1524)
				(type default)
			)
			(layer "B.SilkS")
		)
		(fp_rect
			(start 0.508 0.9398)
			(end -0.508 -0.9398)
			(stroke
				(width 0)
				(type default)
			)
			(fill no)
			(layer "B.CrtYd")
		)
		(fp_rect
			(start 0.508 0.9398)
			(end -0.508 -0.9398)
			(stroke
				(width 0)
				(type default)
			)
			(fill no)
			(layer "B.Fab")
		)
		(pad "1" smd custom
			(at 0 -0.4445 90)
			(size 0.1397 0.1397)
			(layers "B.Cu" "B.Mask" "B.Paste")
			(net "BMC_I2C4_MINI4_SCL_S")
			(options
				(clearance outline)
				(anchor circle)
			)
			(primitives
				(gr_poly
					(pts
						(arc
							(start -0.1778 0.2794)
							(mid -0.249642 0.249642)
							(end -0.2794 0.1778)
						)
						(arc
							(start -0.2794 -0.1778)
							(mid -0.249642 -0.249642)
							(end -0.1778 -0.2794)
						)
						(arc
							(start 0.1778 -0.2794)
							(mid 0.249642 -0.249642)
							(end 0.2794 -0.1778)
						)
						(arc
							(start 0.2794 0.1778)
							(mid 0.249642 0.249642)
							(end 0.1778 0.2794)
						)
					)
					(width 0)
					(fill yes)
				)
			)
		)
		(pad "2" smd custom
			(at 0 0.4445 90)
			(size 0.1397 0.1397)
			(layers "B.Cu" "B.Mask" "B.Paste")
			(net "P3V3_STBY")
			(options
				(clearance outline)
				(anchor circle)
			)
			(primitives
				(gr_poly
					(pts
						(arc
							(start -0.1778 0.2794)
							(mid -0.249642 0.249642)
							(end -0.2794 0.1778)
						)
						(arc
							(start -0.2794 -0.1778)
							(mid -0.249642 -0.249642)
							(end -0.1778 -0.2794)
						)
						(arc
							(start 0.1778 -0.2794)
							(mid 0.249642 -0.249642)
							(end 0.2794 -0.1778)
						)
						(arc
							(start 0.2794 0.1778)
							(mid 0.249642 0.249642)
							(end 0.1778 0.2794)
						)
					)
					(width 0)
					(fill yes)
				)
			)
		)
	)
	(footprint ""
		(layer "B.Cu")
		(at 63.881 -125.5014 -90)
		(property "Reference" "R280"
			(at 0 0 90)
			(layer "B.SilkS")
			(hide yes)
			(effects
				(font
					(size 1.27 1.27)
				)
				(justify mirror)
			)
		)
		(property "Value" "0R2J-2-GP"
			(at -0.064008 -3.993896 270)
			(unlocked yes)
			(layer "B.Fab")
			(hide yes)
			(effects
				(font
					(size 1.016 1.016)
					(thickness 0.1524)
				)
				(justify mirror)
			)
		)
		(property "Device Type" "R402H16"
			(at -0.064008 -5.517896 270)
			(unlocked yes)
			(layer "B.Fab")
			(hide yes)
			(effects
				(font
					(size 1.016 1.016)
					(thickness 0.1524)
				)
				(justify mirror)
			)
		)
		(duplicate_pad_numbers_are_jumpers no)
		(fp_line
			(start -0.508 -0.9398)
			(end 0.508 -0.9398)
			(stroke
				(width 0.1524)
				(type default)
			)
			(layer "B.SilkS")
		)
		(fp_line
			(start 0.508 -0.9398)
			(end 0.508 0.9398)
			(stroke
				(width 0.1524)
				(type default)
			)
			(layer "B.SilkS")
		)
		(fp_rect
			(start 0.508 0.9398)
			(end -0.508 -0.9398)
			(stroke
				(width 0)
				(type default)
			)
			(fill no)
			(layer "B.CrtYd")
		)
		(fp_rect
			(start 0.508 0.9398)
			(end -0.508 -0.9398)
			(stroke
				(width 0)
				(type default)
			)
			(fill no)
			(layer "B.Fab")
		)
		(pad "1" smd custom
			(at 0 -0.4445 90)
			(size 0.1397 0.1397)
			(layers "B.Cu" "B.Mask" "B.Paste")
			(net "BMC_TXD5")
			(options
				(clearance outline)
				(anchor circle)
			)
			(primitives
				(gr_poly
					(pts
						(arc
							(start -0.1778 0.2794)
							(mid -0.249642 0.249642)
							(end -0.2794 0.1778)
						)
						(arc
							(start -0.2794 -0.1778)
							(mid -0.249642 -0.249642)
							(end -0.1778 -0.2794)
						)
						(arc
							(start 0.1778 -0.2794)
							(mid 0.249642 -0.249642)
							(end 0.2794 -0.1778)
						)
						(arc
							(start 0.2794 0.1778)
							(mid 0.249642 0.249642)
							(end 0.1778 0.2794)
						)
					)
					(width 0)
					(fill yes)
				)
			)
		)
		(pad "2" smd custom
			(at 0 0.4445 90)
			(size 0.1397 0.1397)
			(layers "B.Cu" "B.Mask" "B.Paste")
			(net "BMC_TXD5_R")
			(options
				(clearance outline)
				(anchor circle)
			)
			(primitives
				(gr_poly
					(pts
						(arc
							(start -0.1778 0.2794)
							(mid -0.249642 0.249642)
							(end -0.2794 0.1778)
						)
						(arc
							(start -0.2794 -0.1778)
							(mid -0.249642 -0.249642)
							(end -0.1778 -0.2794)
						)
						(arc
							(start 0.1778 -0.2794)
							(mid 0.249642 -0.249642)
							(end 0.2794 -0.1778)
						)
						(arc
							(start 0.2794 0.1778)
							(mid 0.249642 0.249642)
							(end 0.1778 0.2794)
						)
					)
					(width 0)
					(fill yes)
				)
			)
		)
	)
	(footprint ""
		(layer "B.Cu")
		(at 245.1354 -41.995852 -90)
		(property "Reference" "C457"
			(at 0 0 90)
			(layer "B.SilkS")
			(hide yes)
			(effects
				(font
					(size 1.27 1.27)
				)
				(justify mirror)
			)
		)
		(property "Value" "SCD1U16V1KX-1-GP"
			(at 2.8321 -1.7399 270)
			(unlocked yes)
			(layer "B.Fab")
			(hide yes)
			(effects
				(font
					(size 1.016 1.016)
					(thickness 0.1524)
				)
				(justify mirror)
			)
		)
		(property "Device Type" "C0201H13"
			(at 2.8321 -3.2639 270)
			(unlocked yes)
			(layer "B.Fab")
			(hide yes)
			(effects
				(font
					(size 1.016 1.016)
					(thickness 0.1524)
				)
				(justify mirror)
			)
		)
		(duplicate_pad_numbers_are_jumpers no)
		(fp_rect
			(start 0.2794 0.6477)
			(end -0.2794 -0.6477)
			(stroke
				(width 0)
				(type default)
			)
			(fill no)
			(layer "B.CrtYd")
		)
		(fp_rect
			(start 0.2794 0.6477)
			(end -0.2794 -0.6477)
			(stroke
				(width 0)
				(type default)
			)
			(fill no)
			(layer "B.Fab")
		)
		(pad "1" smd custom
			(at 0 -0.2794 90)
			(size 0.0762 0.0762)
			(layers "B.Cu" "B.Mask" "B.Paste")
			(net "DUT_VDD")
			(options
				(clearance outline)
				(anchor circle)
			)
			(primitives
				(gr_poly
					(pts
						(arc
							(start 0.1524 0.127)
							(mid 0.137521 0.162921)
							(end 0.1016 0.1778)
						)
						(arc
							(start -0.1016 0.1778)
							(mid -0.137521 0.162921)
							(end -0.1524 0.127)
						)
						(arc
							(start -0.1524 -0.127)
							(mid -0.137521 -0.162921)
							(end -0.1016 -0.1778)
						)
						(arc
							(start 0.1016 -0.1778)
							(mid 0.137521 -0.162921)
							(end 0.1524 -0.127)
						)
					)
					(width 0)
					(fill yes)
				)
			)
		)
		(pad "2" smd custom
			(at 0 0.2794 90)
			(size 0.0762 0.0762)
			(layers "B.Cu" "B.Mask" "B.Paste")
			(net "GND")
			(options
				(clearance outline)
				(anchor circle)
			)
			(primitives
				(gr_poly
					(pts
						(arc
							(start 0.1524 0.127)
							(mid 0.137521 0.162921)
							(end 0.1016 0.1778)
						)
						(arc
							(start -0.1016 0.1778)
							(mid -0.137521 0.162921)
							(end -0.1524 0.127)
						)
						(arc
							(start -0.1524 -0.127)
							(mid -0.137521 -0.162921)
							(end -0.1016 -0.1778)
						)
						(arc
							(start 0.1016 -0.1778)
							(mid 0.137521 -0.162921)
							(end 0.1524 -0.127)
						)
					)
					(width 0)
					(fill yes)
				)
			)
		)
	)
	(footprint ""
		(layer "B.Cu")
		(at 149.444202 -56.542432)
		(property "Reference" "PR3"
			(at 0 0 0)
			(layer "B.SilkS")
			(hide yes)
			(effects
				(font
					(size 1.27 1.27)
				)
				(justify mirror)
			)
		)
		(property "Value" "82KR2J-GP"
			(at -0.064008 -3.993896 0)
			(unlocked yes)
			(layer "B.Fab")
			(hide yes)
			(effects
				(font
					(size 1.016 1.016)
					(thickness 0.1524)
				)
				(justify mirror)
			)
		)
		(property "Device Type" "R402H16"
			(at -0.064008 -5.517896 0)
			(unlocked yes)
			(layer "B.Fab")
			(hide yes)
			(effects
				(font
					(size 1.016 1.016)
					(thickness 0.1524)
				)
				(justify mirror)
			)
		)
		(duplicate_pad_numbers_are_jumpers no)
		(fp_line
			(start -0.508 -0.9398)
			(end 0.508 -0.9398)
			(stroke
				(width 0.1524)
				(type default)
			)
			(layer "B.SilkS")
		)
		(fp_line
			(start 0.508 -0.9398)
			(end 0.508 0.9398)
			(stroke
				(width 0.1524)
				(type default)
			)
			(layer "B.SilkS")
		)
		(fp_rect
			(start 0.508 0.9398)
			(end -0.508 -0.9398)
			(stroke
				(width 0)
				(type default)
			)
			(fill no)
			(layer "B.CrtYd")
		)
		(fp_rect
			(start 0.508 0.9398)
			(end -0.508 -0.9398)
			(stroke
				(width 0)
				(type default)
			)
			(fill no)
			(layer "B.Fab")
		)
		(pad "1" smd custom
			(at 0 -0.4445 180)
			(size 0.1397 0.1397)
			(layers "B.Cu" "B.Mask" "B.Paste")
			(net "P0V9_TRIP")
			(options
				(clearance outline)
				(anchor circle)
			)
			(primitives
				(gr_poly
					(pts
						(arc
							(start -0.1778 0.2794)
							(mid -0.249642 0.249642)
							(end -0.2794 0.1778)
						)
						(arc
							(start -0.2794 -0.1778)
							(mid -0.249642 -0.249642)
							(end -0.1778 -0.2794)
						)
						(arc
							(start 0.1778 -0.2794)
							(mid 0.249642 -0.249642)
							(end 0.2794 -0.1778)
						)
						(arc
							(start 0.2794 0.1778)
							(mid 0.249642 0.249642)
							(end 0.1778 0.2794)
						)
					)
					(width 0)
					(fill yes)
				)
			)
		)
		(pad "2" smd custom
			(at 0 0.4445 180)
			(size 0.1397 0.1397)
			(layers "B.Cu" "B.Mask" "B.Paste")
			(net "AGND_P0V9")
			(options
				(clearance outline)
				(anchor circle)
			)
			(primitives
				(gr_poly
					(pts
						(arc
							(start -0.1778 0.2794)
							(mid -0.249642 0.249642)
							(end -0.2794 0.1778)
						)
						(arc
							(start -0.2794 -0.1778)
							(mid -0.249642 -0.249642)
							(end -0.1778 -0.2794)
						)
						(arc
							(start 0.1778 -0.2794)
							(mid 0.249642 -0.249642)
							(end 0.2794 -0.1778)
						)
						(arc
							(start 0.2794 0.1778)
							(mid 0.249642 0.249642)
							(end 0.1778 0.2794)
						)
					)
					(width 0)
					(fill yes)
				)
			)
		)
	)
	(footprint ""
		(layer "B.Cu")
		(at 163.998402 -60.073032)
		(property "Reference" "PC208"
			(at 0 0 0)
			(layer "B.SilkS")
			(hide yes)
			(effects
				(font
					(size 1.27 1.27)
				)
				(justify mirror)
			)
		)
		(property "Value" "SCD1U16V2KX-3GP"
			(at -1.1811 -2.7051 0)
			(unlocked yes)
			(layer "B.Fab")
			(hide yes)
			(effects
				(font
					(size 1.016 1.016)
					(thickness 0.1524)
				)
				(justify mirror)
			)
		)
		(property "Device Type" "C402H22"
			(at -1.1811 -4.2291 0)
			(unlocked yes)
			(layer "B.Fab")
			(hide yes)
			(effects
				(font
					(size 1.016 1.016)
					(thickness 0.1524)
				)
				(justify mirror)
			)
		)
		(duplicate_pad_numbers_are_jumpers no)
		(fp_rect
			(start 0.4318 0.9525)
			(end -0.4318 -0.9525)
			(stroke
				(width 0)
				(type default)
			)
			(fill no)
			(layer "B.CrtYd")
		)
		(fp_rect
			(start 0.4318 0.9525)
			(end -0.4318 -0.9525)
			(stroke
				(width 0)
				(type default)
			)
			(fill no)
			(layer "B.Fab")
		)
		(pad "1" smd custom
			(at 0 -0.4445 180)
			(size 0.1524 0.1524)
			(layers "B.Cu" "B.Mask" "B.Paste")
			(net "P0V9")
			(options
				(clearance outline)
				(anchor circle)
			)
			(primitives
				(gr_poly
					(pts
						(arc
							(start 0.3048 0.2032)
							(mid 0.275042 0.275042)
							(end 0.2032 0.3048)
						)
						(arc
							(start -0.2032 0.3048)
							(mid -0.275042 0.275042)
							(end -0.3048 0.2032)
						)
						(arc
							(start -0.3048 -0.2032)
							(mid -0.275042 -0.275042)
							(end -0.2032 -0.3048)
						)
						(arc
							(start 0.2032 -0.3048)
							(mid 0.275042 -0.275042)
							(end 0.3048 -0.2032)
						)
					)
					(width 0)
					(fill yes)
				)
			)
		)
		(pad "2" smd custom
			(at 0 0.4445 180)
			(size 0.1524 0.1524)
			(layers "B.Cu" "B.Mask" "B.Paste")
			(net "P0V9_SW_R")
			(options
				(clearance outline)
				(anchor circle)
			)
			(primitives
				(gr_poly
					(pts
						(arc
							(start 0.3048 0.2032)
							(mid 0.275042 0.275042)
							(end 0.2032 0.3048)
						)
						(arc
							(start -0.2032 0.3048)
							(mid -0.275042 0.275042)
							(end -0.3048 0.2032)
						)
						(arc
							(start -0.3048 -0.2032)
							(mid -0.275042 -0.275042)
							(end -0.2032 -0.3048)
						)
						(arc
							(start 0.2032 -0.3048)
							(mid 0.275042 -0.275042)
							(end 0.3048 -0.2032)
						)
					)
					(width 0)
					(fill yes)
				)
			)
		)
	)
	(footprint ""
		(layer "B.Cu")
		(at 142.374874 -92.22232)
		(property "Reference" "PC89"
			(at 0 0 0)
			(layer "B.SilkS")
			(hide yes)
			(effects
				(font
					(size 1.27 1.27)
				)
				(justify mirror)
			)
		)
		(property "Value" "SC1KP50V2KX-1GP"
			(at -1.1811 -2.7051 0)
			(unlocked yes)
			(layer "B.Fab")
			(hide yes)
			(effects
				(font
					(size 1.016 1.016)
					(thickness 0.1524)
				)
				(justify mirror)
			)
		)
		(property "Device Type" "C402H22"
			(at -1.1811 -4.2291 0)
			(unlocked yes)
			(layer "B.Fab")
			(hide yes)
			(effects
				(font
					(size 1.016 1.016)
					(thickness 0.1524)
				)
				(justify mirror)
			)
		)
		(duplicate_pad_numbers_are_jumpers no)
		(fp_rect
			(start 0.4318 0.9525)
			(end -0.4318 -0.9525)
			(stroke
				(width 0)
				(type default)
			)
			(fill no)
			(layer "B.CrtYd")
		)
		(fp_rect
			(start 0.4318 0.9525)
			(end -0.4318 -0.9525)
			(stroke
				(width 0)
				(type default)
			)
			(fill no)
			(layer "B.Fab")
		)
		(pad "1" smd custom
			(at 0 -0.4445 180)
			(size 0.1524 0.1524)
			(layers "B.Cu" "B.Mask" "B.Paste")
			(net "PWRGD_P1V8_STBY")
			(options
				(clearance outline)
				(anchor circle)
			)
			(primitives
				(gr_poly
					(pts
						(arc
							(start 0.3048 0.2032)
							(mid 0.275042 0.275042)
							(end 0.2032 0.3048)
						)
						(arc
							(start -0.2032 0.3048)
							(mid -0.275042 0.275042)
							(end -0.3048 0.2032)
						)
						(arc
							(start -0.3048 -0.2032)
							(mid -0.275042 -0.275042)
							(end -0.2032 -0.3048)
						)
						(arc
							(start 0.2032 -0.3048)
							(mid 0.275042 -0.275042)
							(end 0.3048 -0.2032)
						)
					)
					(width 0)
					(fill yes)
				)
			)
		)
		(pad "2" smd custom
			(at 0 0.4445 180)
			(size 0.1524 0.1524)
			(layers "B.Cu" "B.Mask" "B.Paste")
			(net "GND")
			(options
				(clearance outline)
				(anchor circle)
			)
			(primitives
				(gr_poly
					(pts
						(arc
							(start 0.3048 0.2032)
							(mid 0.275042 0.275042)
							(end 0.2032 0.3048)
						)
						(arc
							(start -0.2032 0.3048)
							(mid -0.275042 0.275042)
							(end -0.3048 0.2032)
						)
						(arc
							(start -0.3048 -0.2032)
							(mid -0.275042 -0.275042)
							(end -0.2032 -0.3048)
						)
						(arc
							(start 0.2032 -0.3048)
							(mid 0.275042 -0.275042)
							(end 0.3048 -0.2032)
						)
					)
					(width 0)
					(fill yes)
				)
			)
		)
	)
	(footprint ""
		(layer "B.Cu")
		(at 229.108 -23.241 180)
		(property "Reference" "R826"
			(at 0 0 0)
			(layer "B.SilkS")
			(hide yes)
			(effects
				(font
					(size 1.27 1.27)
				)
				(justify mirror)
			)
		)
		(property "Value" "0R2J-2-GP"
			(at -0.064008 -3.993896 180)
			(unlocked yes)
			(layer "B.Fab")
			(hide yes)
			(effects
				(font
					(size 1.016 1.016)
					(thickness 0.1524)
				)
				(justify mirror)
			)
		)
		(property "Device Type" "R402H16"
			(at -0.064008 -5.517896 180)
			(unlocked yes)
			(layer "B.Fab")
			(hide yes)
			(effects
				(font
					(size 1.016 1.016)
					(thickness 0.1524)
				)
				(justify mirror)
			)
		)
		(duplicate_pad_numbers_are_jumpers no)
		(fp_line
			(start 0.508 -0.9398)
			(end 0.508 0.9398)
			(stroke
				(width 0.1524)
				(type default)
			)
			(layer "B.SilkS")
		)
		(fp_line
			(start -0.508 -0.9398)
			(end 0.508 -0.9398)
			(stroke
				(width 0.1524)
				(type default)
			)
			(layer "B.SilkS")
		)
		(fp_rect
			(start 0.508 0.9398)
			(end -0.508 -0.9398)
			(stroke
				(width 0)
				(type default)
			)
			(fill no)
			(layer "B.CrtYd")
		)
		(fp_rect
			(start 0.508 0.9398)
			(end -0.508 -0.9398)
			(stroke
				(width 0)
				(type default)
			)
			(fill no)
			(layer "B.Fab")
		)
		(pad "1" smd custom
			(at 0 -0.4445)
			(size 0.1397 0.1397)
			(layers "B.Cu" "B.Mask" "B.Paste")
			(net "HOST2_RST_N_LS")
			(options
				(clearance outline)
				(anchor circle)
			)
			(primitives
				(gr_poly
					(pts
						(arc
							(start -0.1778 0.2794)
							(mid -0.249642 0.249642)
							(end -0.2794 0.1778)
						)
						(arc
							(start -0.2794 -0.1778)
							(mid -0.249642 -0.249642)
							(end -0.1778 -0.2794)
						)
						(arc
							(start 0.1778 -0.2794)
							(mid 0.249642 -0.249642)
							(end 0.2794 -0.1778)
						)
						(arc
							(start 0.2794 0.1778)
							(mid 0.249642 0.249642)
							(end 0.1778 0.2794)
						)
					)
					(width 0)
					(fill yes)
				)
			)
		)
		(pad "2" smd custom
			(at 0 0.4445)
			(size 0.1397 0.1397)
			(layers "B.Cu" "B.Mask" "B.Paste")
			(net "LBI_ADDR_1_R")
			(options
				(clearance outline)
				(anchor circle)
			)
			(primitives
				(gr_poly
					(pts
						(arc
							(start -0.1778 0.2794)
							(mid -0.249642 0.249642)
							(end -0.2794 0.1778)
						)
						(arc
							(start -0.2794 -0.1778)
							(mid -0.249642 -0.249642)
							(end -0.1778 -0.2794)
						)
						(arc
							(start 0.1778 -0.2794)
							(mid 0.249642 -0.249642)
							(end 0.2794 -0.1778)
						)
						(arc
							(start 0.2794 0.1778)
							(mid 0.249642 0.249642)
							(end 0.1778 0.2794)
						)
					)
					(width 0)
					(fill yes)
				)
			)
		)
	)
	(footprint ""
		(layer "B.Cu")
		(at 232.537 -23.241 180)
		(property "Reference" "R789"
			(at 0 0 0)
			(layer "B.SilkS")
			(hide yes)
			(effects
				(font
					(size 1.27 1.27)
				)
				(justify mirror)
			)
		)
		(property "Value" "4K7R2F-GP"
			(at -0.064008 -3.993896 180)
			(unlocked yes)
			(layer "B.Fab")
			(hide yes)
			(effects
				(font
					(size 1.016 1.016)
					(thickness 0.1524)
				)
				(justify mirror)
			)
		)
		(property "Device Type" "R402H16"
			(at -0.064008 -5.517896 180)
			(unlocked yes)
			(layer "B.Fab")
			(hide yes)
			(effects
				(font
					(size 1.016 1.016)
					(thickness 0.1524)
				)
				(justify mirror)
			)
		)
		(duplicate_pad_numbers_are_jumpers no)
		(fp_line
			(start 0.508 -0.9398)
			(end 0.508 0.9398)
			(stroke
				(width 0.1524)
				(type default)
			)
			(layer "B.SilkS")
		)
		(fp_line
			(start -0.508 -0.9398)
			(end 0.508 -0.9398)
			(stroke
				(width 0.1524)
				(type default)
			)
			(layer "B.SilkS")
		)
		(fp_rect
			(start 0.508 0.9398)
			(end -0.508 -0.9398)
			(stroke
				(width 0)
				(type default)
			)
			(fill no)
			(layer "B.CrtYd")
		)
		(fp_rect
			(start 0.508 0.9398)
			(end -0.508 -0.9398)
			(stroke
				(width 0)
				(type default)
			)
			(fill no)
			(layer "B.Fab")
		)
		(pad "1" smd custom
			(at 0 -0.4445)
			(size 0.1397 0.1397)
			(layers "B.Cu" "B.Mask" "B.Paste")
			(net "BOOTSTRAP9")
			(options
				(clearance outline)
				(anchor circle)
			)
			(primitives
				(gr_poly
					(pts
						(arc
							(start -0.1778 0.2794)
							(mid -0.249642 0.249642)
							(end -0.2794 0.1778)
						)
						(arc
							(start -0.2794 -0.1778)
							(mid -0.249642 -0.249642)
							(end -0.1778 -0.2794)
						)
						(arc
							(start 0.1778 -0.2794)
							(mid 0.249642 -0.249642)
							(end 0.2794 -0.1778)
						)
						(arc
							(start 0.2794 0.1778)
							(mid 0.249642 0.249642)
							(end 0.1778 0.2794)
						)
					)
					(width 0)
					(fill yes)
				)
			)
		)
		(pad "2" smd custom
			(at 0 0.4445)
			(size 0.1397 0.1397)
			(layers "B.Cu" "B.Mask" "B.Paste")
			(net "BOOTSTRAP_R_9")
			(options
				(clearance outline)
				(anchor circle)
			)
			(primitives
				(gr_poly
					(pts
						(arc
							(start -0.1778 0.2794)
							(mid -0.249642 0.249642)
							(end -0.2794 0.1778)
						)
						(arc
							(start -0.2794 -0.1778)
							(mid -0.249642 -0.249642)
							(end -0.1778 -0.2794)
						)
						(arc
							(start 0.1778 -0.2794)
							(mid 0.249642 -0.249642)
							(end 0.2794 -0.1778)
						)
						(arc
							(start 0.2794 0.1778)
							(mid 0.249642 0.249642)
							(end 0.1778 0.2794)
						)
					)
					(width 0)
					(fill yes)
				)
			)
		)
	)
	(footprint ""
		(layer "B.Cu")
		(at 178.0794 -63.881)
		(property "Reference" "PG18"
			(at 0 0 0)
			(layer "B.SilkS")
			(hide yes)
			(effects
				(font
					(size 1.27 1.27)
				)
				(justify mirror)
			)
		)
		(property "Value" "GAP-CLOSE-PWR-3-GP"
			(at -0.0254 -6.5786 0)
			(unlocked yes)
			(layer "B.Fab")
			(hide yes)
			(effects
				(font
					(size 1.016 1.016)
					(thickness 0.1524)
				)
				(justify mirror)
			)
		)
		(property "Device Type" "GAP-CLOSE-PWR-3"
			(at -0.0254 -8.255 0)
			(unlocked yes)
			(layer "B.Fab")
			(hide yes)
			(effects
				(font
					(size 1.016 1.016)
					(thickness 0.1524)
				)
				(justify mirror)
			)
		)
		(duplicate_pad_numbers_are_jumpers no)
		(fp_rect
			(start 0.7112 0.4572)
			(end -0.7112 -0.4572)
			(stroke
				(width 0)
				(type default)
			)
			(fill no)
			(layer "B.CrtYd")
		)
		(fp_poly
			(pts
				(xy 0.7112 -0.4572) (xy -0.7112 -0.4572) (xy -0.7112 0.4572) (xy 0.7112 0.4572)
			)
			(stroke
				(width 0)
				(type default)
			)
			(fill no)
			(layer "B.Fab")
		)
		(pad "1" smd rect
			(at 0.3048 0 180)
			(size 0.6604 0.762)
			(layers "B.Cu" "B.Mask" "B.Paste")
			(net "DUT_AVD_PCIE")
		)
		(pad "2" smd rect
			(at -0.3048 0 180)
			(size 0.6604 0.762)
			(layers "B.Cu" "B.Mask" "B.Paste")
			(net "P0V9")
		)
	)
	(footprint ""
		(layer "B.Cu")
		(at 32.220154 -159.622744 180)
		(property "Reference" "C198"
			(at 0 0 0)
			(layer "B.SilkS")
			(hide yes)
			(effects
				(font
					(size 1.27 1.27)
				)
				(justify mirror)
			)
		)
		(property "Value" "SC1U10V2KX-4-GP"
			(at -1.1811 -2.7051 180)
			(unlocked yes)
			(layer "B.Fab")
			(hide yes)
			(effects
				(font
					(size 1.016 1.016)
					(thickness 0.1524)
				)
				(justify mirror)
			)
		)
		(property "Device Type" "C402H22"
			(at -1.1811 -4.2291 180)
			(unlocked yes)
			(layer "B.Fab")
			(hide yes)
			(effects
				(font
					(size 1.016 1.016)
					(thickness 0.1524)
				)
				(justify mirror)
			)
		)
		(duplicate_pad_numbers_are_jumpers no)
		(fp_rect
			(start 0.4318 0.9525)
			(end -0.4318 -0.9525)
			(stroke
				(width 0)
				(type default)
			)
			(fill no)
			(layer "B.CrtYd")
		)
		(fp_rect
			(start 0.4318 0.9525)
			(end -0.4318 -0.9525)
			(stroke
				(width 0)
				(type default)
			)
			(fill no)
			(layer "B.Fab")
		)
		(pad "1" smd custom
			(at 0 -0.4445)
			(size 0.1524 0.1524)
			(layers "B.Cu" "B.Mask" "B.Paste")
			(net "P1V53_STBY")
			(options
				(clearance outline)
				(anchor circle)
			)
			(primitives
				(gr_poly
					(pts
						(arc
							(start 0.3048 0.2032)
							(mid 0.275042 0.275042)
							(end 0.2032 0.3048)
						)
						(arc
							(start -0.2032 0.3048)
							(mid -0.275042 0.275042)
							(end -0.3048 0.2032)
						)
						(arc
							(start -0.3048 -0.2032)
							(mid -0.275042 -0.275042)
							(end -0.2032 -0.3048)
						)
						(arc
							(start 0.2032 -0.3048)
							(mid 0.275042 -0.275042)
							(end 0.3048 -0.2032)
						)
					)
					(width 0)
					(fill yes)
				)
			)
		)
		(pad "2" smd custom
			(at 0 0.4445)
			(size 0.1524 0.1524)
			(layers "B.Cu" "B.Mask" "B.Paste")
			(net "GND")
			(options
				(clearance outline)
				(anchor circle)
			)
			(primitives
				(gr_poly
					(pts
						(arc
							(start 0.3048 0.2032)
							(mid 0.275042 0.275042)
							(end 0.2032 0.3048)
						)
						(arc
							(start -0.2032 0.3048)
							(mid -0.275042 0.275042)
							(end -0.3048 0.2032)
						)
						(arc
							(start -0.3048 -0.2032)
							(mid -0.275042 -0.275042)
							(end -0.2032 -0.3048)
						)
						(arc
							(start 0.2032 -0.3048)
							(mid 0.275042 -0.275042)
							(end 0.3048 -0.2032)
						)
					)
					(width 0)
					(fill yes)
				)
			)
		)
	)
	(footprint ""
		(layer "B.Cu")
		(at 26.854912 -119.793512 -90)
		(property "Reference" "TP273"
			(at 0 0 90)
			(layer "B.SilkS")
			(hide yes)
			(effects
				(font
					(size 1.27 1.27)
				)
				(justify mirror)
			)
		)
		(property "Value" "TPAD28-2-GP"
			(at 0.0127 -1.6637 270)
			(unlocked yes)
			(layer "B.Fab")
			(hide yes)
			(effects
				(font
					(size 1.016 1.016)
					(thickness 0.1524)
				)
				(justify mirror)
			)
		)
		(property "Device Type" "TPAD28"
			(at 0.0127 -3.1877 270)
			(unlocked yes)
			(layer "B.Fab")
			(hide yes)
			(effects
				(font
					(size 1.016 1.016)
					(thickness 0.1524)
				)
				(justify mirror)
			)
		)
		(duplicate_pad_numbers_are_jumpers no)
		(fp_poly
			(pts
				(arc
					(start 0 -0.3556)
					(mid 0 0.3556)
					(end 0 -0.3556)
				)
			)
			(stroke
				(width 0)
				(type default)
			)
			(fill no)
			(layer "B.CrtYd")
		)
		(fp_poly
			(pts
				(arc
					(start 0 -0.6096)
					(mid 0 0.6096)
					(end 0 -0.6096)
				)
			)
			(stroke
				(width 0)
				(type default)
			)
			(fill no)
			(layer "B.Fab")
		)
		(pad "1" smd circle
			(at 0 0 90)
			(size 0.7112 0.7112)
			(layers "B.Cu" "B.Mask" "B.Paste")
			(net "TP_GPIOI2")
		)
	)
	(footprint ""
		(layer "B.Cu")
		(at 246.599964 -36.999926)
		(property "Reference" "TP282"
			(at 0 0 0)
			(layer "B.SilkS")
			(hide yes)
			(effects
				(font
					(size 1.27 1.27)
				)
				(justify mirror)
			)
		)
		(property "Value" "TPAD28-2-GP"
			(at 0.0127 -1.6637 0)
			(unlocked yes)
			(layer "B.Fab")
			(hide yes)
			(effects
				(font
					(size 1.016 1.016)
					(thickness 0.1524)
				)
				(justify mirror)
			)
		)
		(property "Device Type" "TPAD28"
			(at 0.0127 -3.1877 0)
			(unlocked yes)
			(layer "B.Fab")
			(hide yes)
			(effects
				(font
					(size 1.016 1.016)
					(thickness 0.1524)
				)
				(justify mirror)
			)
		)
		(duplicate_pad_numbers_are_jumpers no)
		(fp_poly
			(pts
				(arc
					(start 0.3556 0)
					(mid -0.3556 0)
					(end 0.3556 0)
				)
			)
			(stroke
				(width 0)
				(type default)
			)
			(fill no)
			(layer "B.CrtYd")
		)
		(fp_poly
			(pts
				(arc
					(start 0.6096 0)
					(mid -0.6096 0)
					(end 0.6096 0)
				)
			)
			(stroke
				(width 0)
				(type default)
			)
			(fill no)
			(layer "B.Fab")
		)
		(pad "1" smd circle
			(at 0 0 180)
			(size 0.7112 0.7112)
			(layers "B.Cu" "B.Mask" "B.Paste")
			(net "TWI_SRST#3")
		)
	)
	(footprint ""
		(layer "B.Cu")
		(at 228.6254 -50.995072 90)
		(property "Reference" "C562"
			(at 0 0 90)
			(layer "B.SilkS")
			(hide yes)
			(effects
				(font
					(size 1.27 1.27)
				)
				(justify mirror)
			)
		)
		(property "Value" "SCD1U16V1KX-1-GP"
			(at 2.8321 -1.7399 90)
			(unlocked yes)
			(layer "B.Fab")
			(hide yes)
			(effects
				(font
					(size 1.016 1.016)
					(thickness 0.1524)
				)
				(justify mirror)
			)
		)
		(property "Device Type" "C0201H13"
			(at 2.8321 -3.2639 90)
			(unlocked yes)
			(layer "B.Fab")
			(hide yes)
			(effects
				(font
					(size 1.016 1.016)
					(thickness 0.1524)
				)
				(justify mirror)
			)
		)
		(duplicate_pad_numbers_are_jumpers no)
		(fp_rect
			(start 0.2794 0.6477)
			(end -0.2794 -0.6477)
			(stroke
				(width 0)
				(type default)
			)
			(fill no)
			(layer "B.CrtYd")
		)
		(fp_rect
			(start 0.2794 0.6477)
			(end -0.2794 -0.6477)
			(stroke
				(width 0)
				(type default)
			)
			(fill no)
			(layer "B.Fab")
		)
		(pad "1" smd custom
			(at 0 -0.2794 270)
			(size 0.0762 0.0762)
			(layers "B.Cu" "B.Mask" "B.Paste")
			(net "DUT_AVD_PCIE")
			(options
				(clearance outline)
				(anchor circle)
			)
			(primitives
				(gr_poly
					(pts
						(arc
							(start 0.1524 0.127)
							(mid 0.137521 0.162921)
							(end 0.1016 0.1778)
						)
						(arc
							(start -0.1016 0.1778)
							(mid -0.137521 0.162921)
							(end -0.1524 0.127)
						)
						(arc
							(start -0.1524 -0.127)
							(mid -0.137521 -0.162921)
							(end -0.1016 -0.1778)
						)
						(arc
							(start 0.1016 -0.1778)
							(mid 0.137521 -0.162921)
							(end 0.1524 -0.127)
						)
					)
					(width 0)
					(fill yes)
				)
			)
		)
		(pad "2" smd custom
			(at 0 0.2794 270)
			(size 0.0762 0.0762)
			(layers "B.Cu" "B.Mask" "B.Paste")
			(net "GND")
			(options
				(clearance outline)
				(anchor circle)
			)
			(primitives
				(gr_poly
					(pts
						(arc
							(start 0.1524 0.127)
							(mid 0.137521 0.162921)
							(end 0.1016 0.1778)
						)
						(arc
							(start -0.1016 0.1778)
							(mid -0.137521 0.162921)
							(end -0.1524 0.127)
						)
						(arc
							(start -0.1524 -0.127)
							(mid -0.137521 -0.162921)
							(end -0.1016 -0.1778)
						)
						(arc
							(start 0.1016 -0.1778)
							(mid 0.137521 -0.162921)
							(end 0.1524 -0.127)
						)
					)
					(width 0)
					(fill yes)
				)
			)
		)
	)
	(footprint ""
		(layer "B.Cu")
		(at 58.039 -40.386 180)
		(property "Reference" "PR19"
			(at 0 0 0)
			(layer "B.SilkS")
			(hide yes)
			(effects
				(font
					(size 1.27 1.27)
				)
				(justify mirror)
			)
		)
		(property "Value" "2D2R3J-2-GP"
			(at 0.0254 -2.5146 180)
			(unlocked yes)
			(layer "B.Fab")
			(hide yes)
			(effects
				(font
					(size 1.016 1.016)
					(thickness 0.1524)
				)
				(justify mirror)
			)
		)
		(property "Device Type" "R603H22"
			(at 0.0254 -4.0386 180)
			(unlocked yes)
			(layer "B.Fab")
			(hide yes)
			(effects
				(font
					(size 1.016 1.016)
					(thickness 0.1524)
				)
				(justify mirror)
			)
		)
		(duplicate_pad_numbers_are_jumpers no)
		(fp_line
			(start 0.4826 0)
			(end 0.2032 0)
			(stroke
				(width 0.2032)
				(type default)
			)
			(layer "B.SilkS")
		)
		(fp_line
			(start -0.2032 0)
			(end -0.4826 0)
			(stroke
				(width 0.2032)
				(type default)
			)
			(layer "B.SilkS")
		)
		(fp_rect
			(start 0.5842 1.3335)
			(end -0.5842 -1.3335)
			(stroke
				(width 0)
				(type default)
			)
			(fill no)
			(layer "B.CrtYd")
		)
		(fp_rect
			(start 0.5842 1.3335)
			(end -0.5842 -1.3335)
			(stroke
				(width 0)
				(type default)
			)
			(fill no)
			(layer "B.Fab")
		)
		(pad "1" smd custom
			(at 0 -0.762)
			(size 0.2159 0.2159)
			(layers "B.Cu" "B.Mask" "B.Paste")
			(net "P3V3_STBY_VDD")
			(options
				(clearance outline)
				(anchor circle)
			)
			(primitives
				(gr_poly
					(pts
						(arc
							(start -0.3302 0.4318)
							(mid -0.402042 0.402042)
							(end -0.4318 0.3302)
						)
						(arc
							(start -0.4318 -0.3302)
							(mid -0.402042 -0.402042)
							(end -0.3302 -0.4318)
						)
						(arc
							(start 0.3302 -0.4318)
							(mid 0.402042 -0.402042)
							(end 0.4318 -0.3302)
						)
						(arc
							(start 0.4318 0.3302)
							(mid 0.402042 0.402042)
							(end 0.3302 0.4318)
						)
					)
					(width 0)
					(fill yes)
				)
			)
		)
		(pad "2" smd custom
			(at 0 0.762)
			(size 0.2159 0.2159)
			(layers "B.Cu" "B.Mask" "B.Paste")
			(net "P12V")
			(options
				(clearance outline)
				(anchor circle)
			)
			(primitives
				(gr_poly
					(pts
						(arc
							(start -0.3302 0.4318)
							(mid -0.402042 0.402042)
							(end -0.4318 0.3302)
						)
						(arc
							(start -0.4318 -0.3302)
							(mid -0.402042 -0.402042)
							(end -0.3302 -0.4318)
						)
						(arc
							(start 0.3302 -0.4318)
							(mid 0.402042 -0.402042)
							(end 0.4318 -0.3302)
						)
						(arc
							(start 0.4318 0.3302)
							(mid 0.402042 0.402042)
							(end 0.3302 0.4318)
						)
					)
					(width 0)
					(fill yes)
				)
			)
		)
	)
	(footprint ""
		(layer "B.Cu")
		(at 33.885632 -109.31271 90)
		(property "Reference" "R291"
			(at 0 0 90)
			(layer "B.SilkS")
			(hide yes)
			(effects
				(font
					(size 1.27 1.27)
				)
				(justify mirror)
			)
		)
		(property "Value" "0R2J-2-GP"
			(at -0.064008 -3.993896 90)
			(unlocked yes)
			(layer "B.Fab")
			(hide yes)
			(effects
				(font
					(size 1.016 1.016)
					(thickness 0.1524)
				)
				(justify mirror)
			)
		)
		(property "Device Type" "R402H16"
			(at -0.064008 -5.517896 90)
			(unlocked yes)
			(layer "B.Fab")
			(hide yes)
			(effects
				(font
					(size 1.016 1.016)
					(thickness 0.1524)
				)
				(justify mirror)
			)
		)
		(duplicate_pad_numbers_are_jumpers no)
		(fp_line
			(start 0.508 -0.9398)
			(end 0.508 0.9398)
			(stroke
				(width 0.1524)
				(type default)
			)
			(layer "B.SilkS")
		)
		(fp_line
			(start -0.508 -0.9398)
			(end 0.508 -0.9398)
			(stroke
				(width 0.1524)
				(type default)
			)
			(layer "B.SilkS")
		)
		(fp_rect
			(start 0.508 0.9398)
			(end -0.508 -0.9398)
			(stroke
				(width 0)
				(type default)
			)
			(fill no)
			(layer "B.CrtYd")
		)
		(fp_rect
			(start 0.508 0.9398)
			(end -0.508 -0.9398)
			(stroke
				(width 0)
				(type default)
			)
			(fill no)
			(layer "B.Fab")
		)
		(pad "1" smd custom
			(at 0 -0.4445 270)
			(size 0.1397 0.1397)
			(layers "B.Cu" "B.Mask" "B.Paste")
			(net "GND")
			(options
				(clearance outline)
				(anchor circle)
			)
			(primitives
				(gr_poly
					(pts
						(arc
							(start -0.1778 0.2794)
							(mid -0.249642 0.249642)
							(end -0.2794 0.1778)
						)
						(arc
							(start -0.2794 -0.1778)
							(mid -0.249642 -0.249642)
							(end -0.1778 -0.2794)
						)
						(arc
							(start 0.1778 -0.2794)
							(mid 0.249642 -0.249642)
							(end 0.2794 -0.1778)
						)
						(arc
							(start 0.2794 0.1778)
							(mid 0.249642 0.249642)
							(end 0.1778 0.2794)
						)
					)
					(width 0)
					(fill yes)
				)
			)
		)
		(pad "2" smd custom
			(at 0 0.4445 270)
			(size 0.1397 0.1397)
			(layers "B.Cu" "B.Mask" "B.Paste")
			(net "CLK_50M_BMC0")
			(options
				(clearance outline)
				(anchor circle)
			)
			(primitives
				(gr_poly
					(pts
						(arc
							(start -0.1778 0.2794)
							(mid -0.249642 0.249642)
							(end -0.2794 0.1778)
						)
						(arc
							(start -0.2794 -0.1778)
							(mid -0.249642 -0.249642)
							(end -0.1778 -0.2794)
						)
						(arc
							(start 0.1778 -0.2794)
							(mid 0.249642 -0.249642)
							(end 0.2794 -0.1778)
						)
						(arc
							(start 0.2794 0.1778)
							(mid 0.249642 0.249642)
							(end 0.1778 0.2794)
						)
					)
					(width 0)
					(fill yes)
				)
			)
		)
	)
	(footprint ""
		(layer "B.Cu")
		(at 231.6988 -28.5242)
		(property "Reference" "TP121"
			(at 0 0 0)
			(layer "B.SilkS")
			(hide yes)
			(effects
				(font
					(size 1.27 1.27)
				)
				(justify mirror)
			)
		)
		(property "Value" "TPAD28-2-GP"
			(at 0.0127 -1.6637 0)
			(unlocked yes)
			(layer "B.Fab")
			(hide yes)
			(effects
				(font
					(size 1.016 1.016)
					(thickness 0.1524)
				)
				(justify mirror)
			)
		)
		(property "Device Type" "TPAD28"
			(at 0.0127 -3.1877 0)
			(unlocked yes)
			(layer "B.Fab")
			(hide yes)
			(effects
				(font
					(size 1.016 1.016)
					(thickness 0.1524)
				)
				(justify mirror)
			)
		)
		(duplicate_pad_numbers_are_jumpers no)
		(fp_poly
			(pts
				(arc
					(start 0.3556 0)
					(mid -0.3556 0)
					(end 0.3556 0)
				)
			)
			(stroke
				(width 0)
				(type default)
			)
			(fill no)
			(layer "B.CrtYd")
		)
		(fp_poly
			(pts
				(arc
					(start 0.6096 0)
					(mid -0.6096 0)
					(end 0.6096 0)
				)
			)
			(stroke
				(width 0)
				(type default)
			)
			(fill no)
			(layer "B.Fab")
		)
		(pad "1" smd circle
			(at 0 0 180)
			(size 0.7112 0.7112)
			(layers "B.Cu" "B.Mask" "B.Paste")
			(net "LBI_ADDR_9")
		)
	)
	(footprint ""
		(layer "B.Cu")
		(at 232.6005 -36.9951 90)
		(property "Reference" "TP202"
			(at 0 0 90)
			(layer "B.SilkS")
			(hide yes)
			(effects
				(font
					(size 1.27 1.27)
				)
				(justify mirror)
			)
		)
		(property "Value" "TPAD28-2-GP"
			(at 0.0127 -1.6637 90)
			(unlocked yes)
			(layer "B.Fab")
			(hide yes)
			(effects
				(font
					(size 1.016 1.016)
					(thickness 0.1524)
				)
				(justify mirror)
			)
		)
		(property "Device Type" "TPAD28"
			(at 0.0127 -3.1877 90)
			(unlocked yes)
			(layer "B.Fab")
			(hide yes)
			(effects
				(font
					(size 1.016 1.016)
					(thickness 0.1524)
				)
				(justify mirror)
			)
		)
		(duplicate_pad_numbers_are_jumpers no)
		(fp_poly
			(pts
				(arc
					(start 0 0.3556)
					(mid 0 -0.3556)
					(end 0 0.3556)
				)
			)
			(stroke
				(width 0)
				(type default)
			)
			(fill no)
			(layer "B.CrtYd")
		)
		(fp_poly
			(pts
				(arc
					(start 0 0.6096)
					(mid 0 -0.6096)
					(end 0 0.6096)
				)
			)
			(stroke
				(width 0)
				(type default)
			)
			(fill no)
			(layer "B.Fab")
		)
		(pad "1" smd circle
			(at 0 0 270)
			(size 0.7112 0.7112)
			(layers "B.Cu" "B.Mask" "B.Paste")
			(net "RMII_RXD_0")
		)
	)
	(footprint ""
		(layer "B.Cu")
		(at 231.60228 -40.005 90)
		(property "Reference" "TP214"
			(at 0 0 90)
			(layer "B.SilkS")
			(hide yes)
			(effects
				(font
					(size 1.27 1.27)
				)
				(justify mirror)
			)
		)
		(property "Value" "TPAD28-2-GP"
			(at 0.0127 -1.6637 90)
			(unlocked yes)
			(layer "B.Fab")
			(hide yes)
			(effects
				(font
					(size 1.016 1.016)
					(thickness 0.1524)
				)
				(justify mirror)
			)
		)
		(property "Device Type" "TPAD28"
			(at 0.0127 -3.1877 90)
			(unlocked yes)
			(layer "B.Fab")
			(hide yes)
			(effects
				(font
					(size 1.016 1.016)
					(thickness 0.1524)
				)
				(justify mirror)
			)
		)
		(duplicate_pad_numbers_are_jumpers no)
		(fp_poly
			(pts
				(arc
					(start 0 0.3556)
					(mid 0 -0.3556)
					(end 0 0.3556)
				)
			)
			(stroke
				(width 0)
				(type default)
			)
			(fill no)
			(layer "B.CrtYd")
		)
		(fp_poly
			(pts
				(arc
					(start 0 0.6096)
					(mid 0 -0.6096)
					(end 0 0.6096)
				)
			)
			(stroke
				(width 0)
				(type default)
			)
			(fill no)
			(layer "B.Fab")
		)
		(pad "1" smd circle
			(at 0 0 270)
			(size 0.7112 0.7112)
			(layers "B.Cu" "B.Mask" "B.Paste")
			(net "LINK")
		)
	)
	(footprint ""
		(layer "B.Cu")
		(at 50.673 -181.483 180)
		(property "Reference" "R902"
			(at 0 0 0)
			(layer "B.SilkS")
			(hide yes)
			(effects
				(font
					(size 1.27 1.27)
				)
				(justify mirror)
			)
		)
		(property "Value" "0R2J-2-GP"
			(at -0.064008 -3.993896 180)
			(unlocked yes)
			(layer "B.Fab")
			(hide yes)
			(effects
				(font
					(size 1.016 1.016)
					(thickness 0.1524)
				)
				(justify mirror)
			)
		)
		(property "Device Type" "R402H16"
			(at -0.064008 -5.517896 180)
			(unlocked yes)
			(layer "B.Fab")
			(hide yes)
			(effects
				(font
					(size 1.016 1.016)
					(thickness 0.1524)
				)
				(justify mirror)
			)
		)
		(duplicate_pad_numbers_are_jumpers no)
		(fp_line
			(start 0.508 -0.9398)
			(end 0.508 0.9398)
			(stroke
				(width 0.1524)
				(type default)
			)
			(layer "B.SilkS")
		)
		(fp_line
			(start -0.508 -0.9398)
			(end 0.508 -0.9398)
			(stroke
				(width 0.1524)
				(type default)
			)
			(layer "B.SilkS")
		)
		(fp_rect
			(start 0.508 0.9398)
			(end -0.508 -0.9398)
			(stroke
				(width 0)
				(type default)
			)
			(fill no)
			(layer "B.CrtYd")
		)
		(fp_rect
			(start 0.508 0.9398)
			(end -0.508 -0.9398)
			(stroke
				(width 0)
				(type default)
			)
			(fill no)
			(layer "B.Fab")
		)
		(pad "1" smd custom
			(at 0 -0.4445)
			(size 0.1397 0.1397)
			(layers "B.Cu" "B.Mask" "B.Paste")
			(net "BMC_I2C8_CLKBUF1_SDA")
			(options
				(clearance outline)
				(anchor circle)
			)
			(primitives
				(gr_poly
					(pts
						(arc
							(start -0.1778 0.2794)
							(mid -0.249642 0.249642)
							(end -0.2794 0.1778)
						)
						(arc
							(start -0.2794 -0.1778)
							(mid -0.249642 -0.249642)
							(end -0.1778 -0.2794)
						)
						(arc
							(start 0.1778 -0.2794)
							(mid 0.249642 -0.249642)
							(end 0.2794 -0.1778)
						)
						(arc
							(start 0.2794 0.1778)
							(mid 0.249642 0.249642)
							(end 0.1778 0.2794)
						)
					)
					(width 0)
					(fill yes)
				)
			)
		)
		(pad "2" smd custom
			(at 0 0.4445)
			(size 0.1397 0.1397)
			(layers "B.Cu" "B.Mask" "B.Paste")
			(net "BUF_I2C8_CLKBUF1_SDA")
			(options
				(clearance outline)
				(anchor circle)
			)
			(primitives
				(gr_poly
					(pts
						(arc
							(start -0.1778 0.2794)
							(mid -0.249642 0.249642)
							(end -0.2794 0.1778)
						)
						(arc
							(start -0.2794 -0.1778)
							(mid -0.249642 -0.249642)
							(end -0.1778 -0.2794)
						)
						(arc
							(start 0.1778 -0.2794)
							(mid 0.249642 -0.249642)
							(end 0.2794 -0.1778)
						)
						(arc
							(start 0.2794 0.1778)
							(mid 0.249642 0.249642)
							(end 0.1778 0.2794)
						)
					)
					(width 0)
					(fill yes)
				)
			)
		)
	)
	(footprint ""
		(layer "B.Cu")
		(at 219.59824 -200.37552 -90)
		(property "Reference" "R3210"
			(at 0 0 90)
			(layer "B.SilkS")
			(hide yes)
			(effects
				(font
					(size 1.27 1.27)
				)
				(justify mirror)
			)
		)
		(property "Value" "0R2J-2-GP"
			(at -0.064008 -3.993896 270)
			(unlocked yes)
			(layer "B.Fab")
			(hide yes)
			(effects
				(font
					(size 1.016 1.016)
					(thickness 0.1524)
				)
				(justify mirror)
			)
		)
		(property "Device Type" "R402H16"
			(at -0.064008 -5.517896 270)
			(unlocked yes)
			(layer "B.Fab")
			(hide yes)
			(effects
				(font
					(size 1.016 1.016)
					(thickness 0.1524)
				)
				(justify mirror)
			)
		)
		(duplicate_pad_numbers_are_jumpers no)
		(fp_line
			(start -0.508 -0.9398)
			(end 0.508 -0.9398)
			(stroke
				(width 0.1524)
				(type default)
			)
			(layer "B.SilkS")
		)
		(fp_line
			(start 0.508 -0.9398)
			(end 0.508 0.9398)
			(stroke
				(width 0.1524)
				(type default)
			)
			(layer "B.SilkS")
		)
		(fp_rect
			(start 0.508 0.9398)
			(end -0.508 -0.9398)
			(stroke
				(width 0)
				(type default)
			)
			(fill no)
			(layer "B.CrtYd")
		)
		(fp_rect
			(start 0.508 0.9398)
			(end -0.508 -0.9398)
			(stroke
				(width 0)
				(type default)
			)
			(fill no)
			(layer "B.Fab")
		)
		(pad "1" smd custom
			(at 0 -0.4445 90)
			(size 0.1397 0.1397)
			(layers "B.Cu" "B.Mask" "B.Paste")
			(net "SSD_PERST#3")
			(options
				(clearance outline)
				(anchor circle)
			)
			(primitives
				(gr_poly
					(pts
						(arc
							(start -0.1778 0.2794)
							(mid -0.249642 0.249642)
							(end -0.2794 0.1778)
						)
						(arc
							(start -0.2794 -0.1778)
							(mid -0.249642 -0.249642)
							(end -0.1778 -0.2794)
						)
						(arc
							(start 0.1778 -0.2794)
							(mid 0.249642 -0.249642)
							(end 0.2794 -0.1778)
						)
						(arc
							(start 0.2794 0.1778)
							(mid 0.249642 0.249642)
							(end 0.1778 0.2794)
						)
					)
					(width 0)
					(fill yes)
				)
			)
		)
		(pad "2" smd custom
			(at 0 0.4445 90)
			(size 0.1397 0.1397)
			(layers "B.Cu" "B.Mask" "B.Paste")
			(net "SSD_PERST#0_B3")
			(options
				(clearance outline)
				(anchor circle)
			)
			(primitives
				(gr_poly
					(pts
						(arc
							(start -0.1778 0.2794)
							(mid -0.249642 0.249642)
							(end -0.2794 0.1778)
						)
						(arc
							(start -0.2794 -0.1778)
							(mid -0.249642 -0.249642)
							(end -0.1778 -0.2794)
						)
						(arc
							(start 0.1778 -0.2794)
							(mid 0.249642 -0.249642)
							(end 0.2794 -0.1778)
						)
						(arc
							(start 0.2794 0.1778)
							(mid 0.249642 0.249642)
							(end 0.1778 0.2794)
						)
					)
					(width 0)
					(fill yes)
				)
			)
		)
	)
	(footprint ""
		(layer "B.Cu")
		(at 57.15 -133.985 180)
		(property "Reference" "R5771"
			(at 0 0 0)
			(layer "B.SilkS")
			(hide yes)
			(effects
				(font
					(size 1.27 1.27)
				)
				(justify mirror)
			)
		)
		(property "Value" "1KR2F-3-GP"
			(at -0.064008 -3.993896 180)
			(unlocked yes)
			(layer "B.Fab")
			(hide yes)
			(effects
				(font
					(size 1.016 1.016)
					(thickness 0.1524)
				)
				(justify mirror)
			)
		)
		(property "Device Type" "R402H16"
			(at -0.064008 -5.517896 180)
			(unlocked yes)
			(layer "B.Fab")
			(hide yes)
			(effects
				(font
					(size 1.016 1.016)
					(thickness 0.1524)
				)
				(justify mirror)
			)
		)
		(duplicate_pad_numbers_are_jumpers no)
		(fp_line
			(start 0.508 -0.9398)
			(end 0.508 0.9398)
			(stroke
				(width 0.1524)
				(type default)
			)
			(layer "B.SilkS")
		)
		(fp_line
			(start -0.508 -0.9398)
			(end 0.508 -0.9398)
			(stroke
				(width 0.1524)
				(type default)
			)
			(layer "B.SilkS")
		)
		(fp_rect
			(start 0.508 0.9398)
			(end -0.508 -0.9398)
			(stroke
				(width 0)
				(type default)
			)
			(fill no)
			(layer "B.CrtYd")
		)
		(fp_rect
			(start 0.508 0.9398)
			(end -0.508 -0.9398)
			(stroke
				(width 0)
				(type default)
			)
			(fill no)
			(layer "B.Fab")
		)
		(pad "1" smd custom
			(at 0 -0.4445)
			(size 0.1397 0.1397)
			(layers "B.Cu" "B.Mask" "B.Paste")
			(net "ADC_P5V_STBY")
			(options
				(clearance outline)
				(anchor circle)
			)
			(primitives
				(gr_poly
					(pts
						(arc
							(start -0.1778 0.2794)
							(mid -0.249642 0.249642)
							(end -0.2794 0.1778)
						)
						(arc
							(start -0.2794 -0.1778)
							(mid -0.249642 -0.249642)
							(end -0.1778 -0.2794)
						)
						(arc
							(start 0.1778 -0.2794)
							(mid 0.249642 -0.249642)
							(end 0.2794 -0.1778)
						)
						(arc
							(start 0.2794 0.1778)
							(mid 0.249642 0.249642)
							(end 0.1778 0.2794)
						)
					)
					(width 0)
					(fill yes)
				)
			)
		)
		(pad "2" smd custom
			(at 0 0.4445)
			(size 0.1397 0.1397)
			(layers "B.Cu" "B.Mask" "B.Paste")
			(net "GND")
			(options
				(clearance outline)
				(anchor circle)
			)
			(primitives
				(gr_poly
					(pts
						(arc
							(start -0.1778 0.2794)
							(mid -0.249642 0.249642)
							(end -0.2794 0.1778)
						)
						(arc
							(start -0.2794 -0.1778)
							(mid -0.249642 -0.249642)
							(end -0.1778 -0.2794)
						)
						(arc
							(start 0.1778 -0.2794)
							(mid 0.249642 -0.249642)
							(end 0.2794 -0.1778)
						)
						(arc
							(start 0.2794 0.1778)
							(mid 0.249642 0.249642)
							(end 0.1778 0.2794)
						)
					)
					(width 0)
					(fill yes)
				)
			)
		)
	)
	(footprint ""
		(layer "B.Cu")
		(at 176.723802 -71.071232 90)
		(property "Reference" "PG35"
			(at 0 0 90)
			(layer "B.SilkS")
			(hide yes)
			(effects
				(font
					(size 1.27 1.27)
				)
				(justify mirror)
			)
		)
		(property "Value" "GAP-CLOSE-PWR-3-GP"
			(at -0.0254 -6.5786 90)
			(unlocked yes)
			(layer "B.Fab")
			(hide yes)
			(effects
				(font
					(size 1.016 1.016)
					(thickness 0.1524)
				)
				(justify mirror)
			)
		)
		(property "Device Type" "GAP-CLOSE-PWR-3"
			(at -0.0254 -8.255 90)
			(unlocked yes)
			(layer "B.Fab")
			(hide yes)
			(effects
				(font
					(size 1.016 1.016)
					(thickness 0.1524)
				)
				(justify mirror)
			)
		)
		(duplicate_pad_numbers_are_jumpers no)
		(fp_rect
			(start 0.7112 0.4572)
			(end -0.7112 -0.4572)
			(stroke
				(width 0)
				(type default)
			)
			(fill no)
			(layer "B.CrtYd")
		)
		(fp_poly
			(pts
				(xy 0.7112 -0.4572) (xy -0.7112 -0.4572) (xy -0.7112 0.4572) (xy 0.7112 0.4572)
			)
			(stroke
				(width 0)
				(type default)
			)
			(fill no)
			(layer "B.Fab")
		)
		(pad "1" smd rect
			(at 0.3048 0 270)
			(size 0.6604 0.762)
			(layers "B.Cu" "B.Mask" "B.Paste")
			(net "DUT_AVD_TX")
		)
		(pad "2" smd rect
			(at -0.3048 0 270)
			(size 0.6604 0.762)
			(layers "B.Cu" "B.Mask" "B.Paste")
			(net "P0V9")
		)
	)
	(footprint ""
		(layer "B.Cu")
		(at 245.599966 -37.999924)
		(property "Reference" "TP310"
			(at 0 0 0)
			(layer "B.SilkS")
			(hide yes)
			(effects
				(font
					(size 1.27 1.27)
				)
				(justify mirror)
			)
		)
		(property "Value" "TPAD28-2-GP"
			(at 0.0127 -1.6637 0)
			(unlocked yes)
			(layer "B.Fab")
			(hide yes)
			(effects
				(font
					(size 1.016 1.016)
					(thickness 0.1524)
				)
				(justify mirror)
			)
		)
		(property "Device Type" "TPAD28"
			(at 0.0127 -3.1877 0)
			(unlocked yes)
			(layer "B.Fab")
			(hide yes)
			(effects
				(font
					(size 1.016 1.016)
					(thickness 0.1524)
				)
				(justify mirror)
			)
		)
		(duplicate_pad_numbers_are_jumpers no)
		(fp_poly
			(pts
				(arc
					(start 0.3556 0)
					(mid -0.3556 0)
					(end 0.3556 0)
				)
			)
			(stroke
				(width 0)
				(type default)
			)
			(fill no)
			(layer "B.CrtYd")
		)
		(fp_poly
			(pts
				(arc
					(start 0.6096 0)
					(mid -0.6096 0)
					(end 0.6096 0)
				)
			)
			(stroke
				(width 0)
				(type default)
			)
			(fill no)
			(layer "B.Fab")
		)
		(pad "1" smd circle
			(at 0 0 180)
			(size 0.7112 0.7112)
			(layers "B.Cu" "B.Mask" "B.Paste")
			(net "TPIN")
		)
	)
	(footprint ""
		(layer "B.Cu")
		(at 241.0968 -51.9938 90)
		(property "Reference" "C460"
			(at 0 0 90)
			(layer "B.SilkS")
			(hide yes)
			(effects
				(font
					(size 1.27 1.27)
				)
				(justify mirror)
			)
		)
		(property "Value" "SCD1U16V1KX-1-GP"
			(at 2.8321 -1.7399 90)
			(unlocked yes)
			(layer "B.Fab")
			(hide yes)
			(effects
				(font
					(size 1.016 1.016)
					(thickness 0.1524)
				)
				(justify mirror)
			)
		)
		(property "Device Type" "C0201H13"
			(at 2.8321 -3.2639 90)
			(unlocked yes)
			(layer "B.Fab")
			(hide yes)
			(effects
				(font
					(size 1.016 1.016)
					(thickness 0.1524)
				)
				(justify mirror)
			)
		)
		(duplicate_pad_numbers_are_jumpers no)
		(fp_rect
			(start 0.2794 0.6477)
			(end -0.2794 -0.6477)
			(stroke
				(width 0)
				(type default)
			)
			(fill no)
			(layer "B.CrtYd")
		)
		(fp_rect
			(start 0.2794 0.6477)
			(end -0.2794 -0.6477)
			(stroke
				(width 0)
				(type default)
			)
			(fill no)
			(layer "B.Fab")
		)
		(pad "1" smd custom
			(at 0 -0.2794 270)
			(size 0.0762 0.0762)
			(layers "B.Cu" "B.Mask" "B.Paste")
			(net "DUT_VDD")
			(options
				(clearance outline)
				(anchor circle)
			)
			(primitives
				(gr_poly
					(pts
						(arc
							(start 0.1524 0.127)
							(mid 0.137521 0.162921)
							(end 0.1016 0.1778)
						)
						(arc
							(start -0.1016 0.1778)
							(mid -0.137521 0.162921)
							(end -0.1524 0.127)
						)
						(arc
							(start -0.1524 -0.127)
							(mid -0.137521 -0.162921)
							(end -0.1016 -0.1778)
						)
						(arc
							(start 0.1016 -0.1778)
							(mid 0.137521 -0.162921)
							(end 0.1524 -0.127)
						)
					)
					(width 0)
					(fill yes)
				)
			)
		)
		(pad "2" smd custom
			(at 0 0.2794 270)
			(size 0.0762 0.0762)
			(layers "B.Cu" "B.Mask" "B.Paste")
			(net "GND")
			(options
				(clearance outline)
				(anchor circle)
			)
			(primitives
				(gr_poly
					(pts
						(arc
							(start 0.1524 0.127)
							(mid 0.137521 0.162921)
							(end 0.1016 0.1778)
						)
						(arc
							(start -0.1016 0.1778)
							(mid -0.137521 0.162921)
							(end -0.1524 0.127)
						)
						(arc
							(start -0.1524 -0.127)
							(mid -0.137521 -0.162921)
							(end -0.1016 -0.1778)
						)
						(arc
							(start 0.1016 -0.1778)
							(mid 0.137521 -0.162921)
							(end 0.1524 -0.127)
						)
					)
					(width 0)
					(fill yes)
				)
			)
		)
	)
	(footprint ""
		(layer "B.Cu")
		(at 241.0968 -54.0004 90)
		(property "Reference" "C441"
			(at 0 0 90)
			(layer "B.SilkS")
			(hide yes)
			(effects
				(font
					(size 1.27 1.27)
				)
				(justify mirror)
			)
		)
		(property "Value" "SCD1U16V1KX-1-GP"
			(at 2.8321 -1.7399 90)
			(unlocked yes)
			(layer "B.Fab")
			(hide yes)
			(effects
				(font
					(size 1.016 1.016)
					(thickness 0.1524)
				)
				(justify mirror)
			)
		)
		(property "Device Type" "C0201H13"
			(at 2.8321 -3.2639 90)
			(unlocked yes)
			(layer "B.Fab")
			(hide yes)
			(effects
				(font
					(size 1.016 1.016)
					(thickness 0.1524)
				)
				(justify mirror)
			)
		)
		(duplicate_pad_numbers_are_jumpers no)
		(fp_rect
			(start 0.2794 0.6477)
			(end -0.2794 -0.6477)
			(stroke
				(width 0)
				(type default)
			)
			(fill no)
			(layer "B.CrtYd")
		)
		(fp_rect
			(start 0.2794 0.6477)
			(end -0.2794 -0.6477)
			(stroke
				(width 0)
				(type default)
			)
			(fill no)
			(layer "B.Fab")
		)
		(pad "1" smd custom
			(at 0 -0.2794 270)
			(size 0.0762 0.0762)
			(layers "B.Cu" "B.Mask" "B.Paste")
			(net "DUT_VDD")
			(options
				(clearance outline)
				(anchor circle)
			)
			(primitives
				(gr_poly
					(pts
						(arc
							(start 0.1524 0.127)
							(mid 0.137521 0.162921)
							(end 0.1016 0.1778)
						)
						(arc
							(start -0.1016 0.1778)
							(mid -0.137521 0.162921)
							(end -0.1524 0.127)
						)
						(arc
							(start -0.1524 -0.127)
							(mid -0.137521 -0.162921)
							(end -0.1016 -0.1778)
						)
						(arc
							(start 0.1016 -0.1778)
							(mid 0.137521 -0.162921)
							(end 0.1524 -0.127)
						)
					)
					(width 0)
					(fill yes)
				)
			)
		)
		(pad "2" smd custom
			(at 0 0.2794 270)
			(size 0.0762 0.0762)
			(layers "B.Cu" "B.Mask" "B.Paste")
			(net "GND")
			(options
				(clearance outline)
				(anchor circle)
			)
			(primitives
				(gr_poly
					(pts
						(arc
							(start 0.1524 0.127)
							(mid 0.137521 0.162921)
							(end 0.1016 0.1778)
						)
						(arc
							(start -0.1016 0.1778)
							(mid -0.137521 0.162921)
							(end -0.1524 0.127)
						)
						(arc
							(start -0.1524 -0.127)
							(mid -0.137521 -0.162921)
							(end -0.1016 -0.1778)
						)
						(arc
							(start 0.1016 -0.1778)
							(mid 0.137521 -0.162921)
							(end 0.1524 -0.127)
						)
					)
					(width 0)
					(fill yes)
				)
			)
		)
	)
	(footprint ""
		(layer "B.Cu")
		(at 222.25 -20.447)
		(property "Reference" "R3706"
			(at 0 0 0)
			(layer "B.SilkS")
			(hide yes)
			(effects
				(font
					(size 1.27 1.27)
				)
				(justify mirror)
			)
		)
		(property "Value" "4K7R2F-GP"
			(at -0.064008 -3.993896 0)
			(unlocked yes)
			(layer "B.Fab")
			(hide yes)
			(effects
				(font
					(size 1.016 1.016)
					(thickness 0.1524)
				)
				(justify mirror)
			)
		)
		(property "Device Type" "R402H16"
			(at -0.064008 -5.517896 0)
			(unlocked yes)
			(layer "B.Fab")
			(hide yes)
			(effects
				(font
					(size 1.016 1.016)
					(thickness 0.1524)
				)
				(justify mirror)
			)
		)
		(duplicate_pad_numbers_are_jumpers no)
		(fp_line
			(start -0.508 -0.9398)
			(end 0.508 -0.9398)
			(stroke
				(width 0.1524)
				(type default)
			)
			(layer "B.SilkS")
		)
		(fp_line
			(start 0.508 -0.9398)
			(end 0.508 0.9398)
			(stroke
				(width 0.1524)
				(type default)
			)
			(layer "B.SilkS")
		)
		(fp_rect
			(start 0.508 0.9398)
			(end -0.508 -0.9398)
			(stroke
				(width 0)
				(type default)
			)
			(fill no)
			(layer "B.CrtYd")
		)
		(fp_rect
			(start 0.508 0.9398)
			(end -0.508 -0.9398)
			(stroke
				(width 0)
				(type default)
			)
			(fill no)
			(layer "B.Fab")
		)
		(pad "1" smd custom
			(at 0 -0.4445 180)
			(size 0.1397 0.1397)
			(layers "B.Cu" "B.Mask" "B.Paste")
			(net "HOST8_RST_N_LS")
			(options
				(clearance outline)
				(anchor circle)
			)
			(primitives
				(gr_poly
					(pts
						(arc
							(start -0.1778 0.2794)
							(mid -0.249642 0.249642)
							(end -0.2794 0.1778)
						)
						(arc
							(start -0.2794 -0.1778)
							(mid -0.249642 -0.249642)
							(end -0.1778 -0.2794)
						)
						(arc
							(start 0.1778 -0.2794)
							(mid 0.249642 -0.249642)
							(end 0.2794 -0.1778)
						)
						(arc
							(start 0.2794 0.1778)
							(mid 0.249642 0.249642)
							(end 0.1778 0.2794)
						)
					)
					(width 0)
					(fill yes)
				)
			)
		)
		(pad "2" smd custom
			(at 0 0.4445 180)
			(size 0.1397 0.1397)
			(layers "B.Cu" "B.Mask" "B.Paste")
			(net "DUT_VDDO")
			(options
				(clearance outline)
				(anchor circle)
			)
			(primitives
				(gr_poly
					(pts
						(arc
							(start -0.1778 0.2794)
							(mid -0.249642 0.249642)
							(end -0.2794 0.1778)
						)
						(arc
							(start -0.2794 -0.1778)
							(mid -0.249642 -0.249642)
							(end -0.1778 -0.2794)
						)
						(arc
							(start 0.1778 -0.2794)
							(mid 0.249642 -0.249642)
							(end 0.2794 -0.1778)
						)
						(arc
							(start 0.2794 0.1778)
							(mid 0.249642 0.249642)
							(end 0.1778 0.2794)
						)
					)
					(width 0)
					(fill yes)
				)
			)
		)
	)
	(footprint ""
		(layer "B.Cu")
		(at 21.6916 -67.2084)
		(property "Reference" "C626"
			(at 0 0 0)
			(layer "B.SilkS")
			(hide yes)
			(effects
				(font
					(size 1.27 1.27)
				)
				(justify mirror)
			)
		)
		(property "Value" "SC10U6D3V5KX-4GP"
			(at 0.0762 -6.1214 0)
			(unlocked yes)
			(layer "B.Fab")
			(hide yes)
			(effects
				(font
					(size 1.016 1.016)
					(thickness 0.1524)
				)
				(justify mirror)
			)
		)
		(property "Device Type" "C805H58"
			(at 0.0762 -8.1534 0)
			(unlocked yes)
			(layer "B.Fab")
			(hide yes)
			(effects
				(font
					(size 1.016 1.016)
					(thickness 0.1524)
				)
				(justify mirror)
			)
		)
		(duplicate_pad_numbers_are_jumpers no)
		(fp_line
			(start -0.635 0)
			(end 0.635 0)
			(stroke
				(width 0.508)
				(type default)
			)
			(layer "B.SilkS")
		)
		(fp_rect
			(start 0.9652 1.778)
			(end -0.9652 -1.778)
			(stroke
				(width 0)
				(type default)
			)
			(fill no)
			(layer "B.CrtYd")
		)
		(fp_poly
			(pts
				(xy 0.9652 -1.778) (xy -0.9652 -1.778) (xy -0.9652 1.778) (xy 0.9652 1.778)
			)
			(stroke
				(width 0)
				(type default)
			)
			(fill no)
			(layer "B.Fab")
		)
		(pad "1" smd rect
			(at 0 -0.9652 180)
			(size 1.397 1.143)
			(layers "B.Cu" "B.Mask" "B.Paste")
			(net "P3V3_STBY")
		)
		(pad "2" smd rect
			(at 0 0.9652 180)
			(size 1.397 1.143)
			(layers "B.Cu" "B.Mask" "B.Paste")
			(net "GND")
		)
	)
	(footprint ""
		(layer "B.Cu")
		(at 36.83 -116.84 180)
		(property "Reference" "R283"
			(at 0 0 0)
			(layer "B.SilkS")
			(hide yes)
			(effects
				(font
					(size 1.27 1.27)
				)
				(justify mirror)
			)
		)
		(property "Value" "22R2J-2-GP"
			(at -0.064008 -3.993896 180)
			(unlocked yes)
			(layer "B.Fab")
			(hide yes)
			(effects
				(font
					(size 1.016 1.016)
					(thickness 0.1524)
				)
				(justify mirror)
			)
		)
		(property "Device Type" "R402H16"
			(at -0.064008 -5.517896 180)
			(unlocked yes)
			(layer "B.Fab")
			(hide yes)
			(effects
				(font
					(size 1.016 1.016)
					(thickness 0.1524)
				)
				(justify mirror)
			)
		)
		(duplicate_pad_numbers_are_jumpers no)
		(fp_line
			(start 0.508 -0.9398)
			(end 0.508 0.9398)
			(stroke
				(width 0.1524)
				(type default)
			)
			(layer "B.SilkS")
		)
		(fp_line
			(start -0.508 -0.9398)
			(end 0.508 -0.9398)
			(stroke
				(width 0.1524)
				(type default)
			)
			(layer "B.SilkS")
		)
		(fp_rect
			(start 0.508 0.9398)
			(end -0.508 -0.9398)
			(stroke
				(width 0)
				(type default)
			)
			(fill no)
			(layer "B.CrtYd")
		)
		(fp_rect
			(start 0.508 0.9398)
			(end -0.508 -0.9398)
			(stroke
				(width 0)
				(type default)
			)
			(fill no)
			(layer "B.Fab")
		)
		(pad "1" smd custom
			(at 0 -0.4445)
			(size 0.1397 0.1397)
			(layers "B.Cu" "B.Mask" "B.Paste")
			(net "RMII_BMC_PHY_TXD0")
			(options
				(clearance outline)
				(anchor circle)
			)
			(primitives
				(gr_poly
					(pts
						(arc
							(start -0.1778 0.2794)
							(mid -0.249642 0.249642)
							(end -0.2794 0.1778)
						)
						(arc
							(start -0.2794 -0.1778)
							(mid -0.249642 -0.249642)
							(end -0.1778 -0.2794)
						)
						(arc
							(start 0.1778 -0.2794)
							(mid 0.249642 -0.249642)
							(end 0.2794 -0.1778)
						)
						(arc
							(start 0.2794 0.1778)
							(mid 0.249642 0.249642)
							(end 0.1778 0.2794)
						)
					)
					(width 0)
					(fill yes)
				)
			)
		)
		(pad "2" smd custom
			(at 0 0.4445)
			(size 0.1397 0.1397)
			(layers "B.Cu" "B.Mask" "B.Paste")
			(net "RMII0_BMC_C_PHY_TXD0")
			(options
				(clearance outline)
				(anchor circle)
			)
			(primitives
				(gr_poly
					(pts
						(arc
							(start -0.1778 0.2794)
							(mid -0.249642 0.249642)
							(end -0.2794 0.1778)
						)
						(arc
							(start -0.2794 -0.1778)
							(mid -0.249642 -0.249642)
							(end -0.1778 -0.2794)
						)
						(arc
							(start 0.1778 -0.2794)
							(mid 0.249642 -0.249642)
							(end 0.2794 -0.1778)
						)
						(arc
							(start 0.2794 0.1778)
							(mid 0.249642 0.249642)
							(end 0.1778 0.2794)
						)
					)
					(width 0)
					(fill yes)
				)
			)
		)
	)
	(footprint ""
		(layer "B.Cu")
		(at 237.617 -56.00192 -90)
		(property "Reference" "C522"
			(at 0 0 90)
			(layer "B.SilkS")
			(hide yes)
			(effects
				(font
					(size 1.27 1.27)
				)
				(justify mirror)
			)
		)
		(property "Value" "SCD1U16V1KX-1-GP"
			(at 2.8321 -1.7399 270)
			(unlocked yes)
			(layer "B.Fab")
			(hide yes)
			(effects
				(font
					(size 1.016 1.016)
					(thickness 0.1524)
				)
				(justify mirror)
			)
		)
		(property "Device Type" "C0201H13"
			(at 2.8321 -3.2639 270)
			(unlocked yes)
			(layer "B.Fab")
			(hide yes)
			(effects
				(font
					(size 1.016 1.016)
					(thickness 0.1524)
				)
				(justify mirror)
			)
		)
		(duplicate_pad_numbers_are_jumpers no)
		(fp_rect
			(start 0.2794 0.6477)
			(end -0.2794 -0.6477)
			(stroke
				(width 0)
				(type default)
			)
			(fill no)
			(layer "B.CrtYd")
		)
		(fp_rect
			(start 0.2794 0.6477)
			(end -0.2794 -0.6477)
			(stroke
				(width 0)
				(type default)
			)
			(fill no)
			(layer "B.Fab")
		)
		(pad "1" smd custom
			(at 0 -0.2794 90)
			(size 0.0762 0.0762)
			(layers "B.Cu" "B.Mask" "B.Paste")
			(net "DUT_AVD_TX")
			(options
				(clearance outline)
				(anchor circle)
			)
			(primitives
				(gr_poly
					(pts
						(arc
							(start 0.1524 0.127)
							(mid 0.137521 0.162921)
							(end 0.1016 0.1778)
						)
						(arc
							(start -0.1016 0.1778)
							(mid -0.137521 0.162921)
							(end -0.1524 0.127)
						)
						(arc
							(start -0.1524 -0.127)
							(mid -0.137521 -0.162921)
							(end -0.1016 -0.1778)
						)
						(arc
							(start 0.1016 -0.1778)
							(mid 0.137521 -0.162921)
							(end 0.1524 -0.127)
						)
					)
					(width 0)
					(fill yes)
				)
			)
		)
		(pad "2" smd custom
			(at 0 0.2794 90)
			(size 0.0762 0.0762)
			(layers "B.Cu" "B.Mask" "B.Paste")
			(net "GND")
			(options
				(clearance outline)
				(anchor circle)
			)
			(primitives
				(gr_poly
					(pts
						(arc
							(start 0.1524 0.127)
							(mid 0.137521 0.162921)
							(end 0.1016 0.1778)
						)
						(arc
							(start -0.1016 0.1778)
							(mid -0.137521 0.162921)
							(end -0.1524 0.127)
						)
						(arc
							(start -0.1524 -0.127)
							(mid -0.137521 -0.162921)
							(end -0.1016 -0.1778)
						)
						(arc
							(start 0.1016 -0.1778)
							(mid 0.137521 -0.162921)
							(end 0.1524 -0.127)
						)
					)
					(width 0)
					(fill yes)
				)
			)
		)
	)
	(footprint ""
		(layer "B.Cu")
		(at 29.4894 -73.1774 -90)
		(property "Reference" "PR64"
			(at 0 0 90)
			(layer "B.SilkS")
			(hide yes)
			(effects
				(font
					(size 1.27 1.27)
				)
				(justify mirror)
			)
		)
		(property "Value" "47KR2F-GP"
			(at -0.064008 -3.993896 270)
			(unlocked yes)
			(layer "B.Fab")
			(hide yes)
			(effects
				(font
					(size 1.016 1.016)
					(thickness 0.1524)
				)
				(justify mirror)
			)
		)
		(property "Device Type" "R402H16"
			(at -0.064008 -5.517896 270)
			(unlocked yes)
			(layer "B.Fab")
			(hide yes)
			(effects
				(font
					(size 1.016 1.016)
					(thickness 0.1524)
				)
				(justify mirror)
			)
		)
		(duplicate_pad_numbers_are_jumpers no)
		(fp_line
			(start -0.508 -0.9398)
			(end 0.508 -0.9398)
			(stroke
				(width 0.1524)
				(type default)
			)
			(layer "B.SilkS")
		)
		(fp_line
			(start 0.508 -0.9398)
			(end 0.508 0.9398)
			(stroke
				(width 0.1524)
				(type default)
			)
			(layer "B.SilkS")
		)
		(fp_rect
			(start 0.508 0.9398)
			(end -0.508 -0.9398)
			(stroke
				(width 0)
				(type default)
			)
			(fill no)
			(layer "B.CrtYd")
		)
		(fp_rect
			(start 0.508 0.9398)
			(end -0.508 -0.9398)
			(stroke
				(width 0)
				(type default)
			)
			(fill no)
			(layer "B.Fab")
		)
		(pad "1" smd custom
			(at 0 -0.4445 90)
			(size 0.1397 0.1397)
			(layers "B.Cu" "B.Mask" "B.Paste")
			(net "P12V")
			(options
				(clearance outline)
				(anchor circle)
			)
			(primitives
				(gr_poly
					(pts
						(arc
							(start -0.1778 0.2794)
							(mid -0.249642 0.249642)
							(end -0.2794 0.1778)
						)
						(arc
							(start -0.2794 -0.1778)
							(mid -0.249642 -0.249642)
							(end -0.1778 -0.2794)
						)
						(arc
							(start 0.1778 -0.2794)
							(mid 0.249642 -0.249642)
							(end 0.2794 -0.1778)
						)
						(arc
							(start 0.2794 0.1778)
							(mid 0.249642 0.249642)
							(end 0.1778 0.2794)
						)
					)
					(width 0)
					(fill yes)
				)
			)
		)
		(pad "2" smd custom
			(at 0 0.4445 90)
			(size 0.1397 0.1397)
			(layers "B.Cu" "B.Mask" "B.Paste")
			(net "P5V_STBY_EN")
			(options
				(clearance outline)
				(anchor circle)
			)
			(primitives
				(gr_poly
					(pts
						(arc
							(start -0.1778 0.2794)
							(mid -0.249642 0.249642)
							(end -0.2794 0.1778)
						)
						(arc
							(start -0.2794 -0.1778)
							(mid -0.249642 -0.249642)
							(end -0.1778 -0.2794)
						)
						(arc
							(start 0.1778 -0.2794)
							(mid 0.249642 -0.249642)
							(end 0.2794 -0.1778)
						)
						(arc
							(start 0.2794 0.1778)
							(mid 0.249642 0.249642)
							(end 0.1778 0.2794)
						)
					)
					(width 0)
					(fill yes)
				)
			)
		)
	)
	(footprint ""
		(layer "B.Cu")
		(at 81.706212 -192.641474)
		(property "Reference" "R3232"
			(at 0 0 0)
			(layer "B.SilkS")
			(hide yes)
			(effects
				(font
					(size 1.27 1.27)
				)
				(justify mirror)
			)
		)
		(property "Value" "0R2J-2-GP"
			(at -0.064008 -3.993896 0)
			(unlocked yes)
			(layer "B.Fab")
			(hide yes)
			(effects
				(font
					(size 1.016 1.016)
					(thickness 0.1524)
				)
				(justify mirror)
			)
		)
		(property "Device Type" "R402H16"
			(at -0.064008 -5.517896 0)
			(unlocked yes)
			(layer "B.Fab")
			(hide yes)
			(effects
				(font
					(size 1.016 1.016)
					(thickness 0.1524)
				)
				(justify mirror)
			)
		)
		(duplicate_pad_numbers_are_jumpers no)
		(fp_line
			(start -0.508 -0.9398)
			(end 0.508 -0.9398)
			(stroke
				(width 0.1524)
				(type default)
			)
			(layer "B.SilkS")
		)
		(fp_line
			(start 0.508 -0.9398)
			(end 0.508 0.9398)
			(stroke
				(width 0.1524)
				(type default)
			)
			(layer "B.SilkS")
		)
		(fp_rect
			(start 0.508 0.9398)
			(end -0.508 -0.9398)
			(stroke
				(width 0)
				(type default)
			)
			(fill no)
			(layer "B.CrtYd")
		)
		(fp_rect
			(start 0.508 0.9398)
			(end -0.508 -0.9398)
			(stroke
				(width 0)
				(type default)
			)
			(fill no)
			(layer "B.Fab")
		)
		(pad "1" smd custom
			(at 0 -0.4445 180)
			(size 0.1397 0.1397)
			(layers "B.Cu" "B.Mask" "B.Paste")
			(net "BMC_SSD_RST#10")
			(options
				(clearance outline)
				(anchor circle)
			)
			(primitives
				(gr_poly
					(pts
						(arc
							(start -0.1778 0.2794)
							(mid -0.249642 0.249642)
							(end -0.2794 0.1778)
						)
						(arc
							(start -0.2794 -0.1778)
							(mid -0.249642 -0.249642)
							(end -0.1778 -0.2794)
						)
						(arc
							(start 0.1778 -0.2794)
							(mid 0.249642 -0.249642)
							(end 0.2794 -0.1778)
						)
						(arc
							(start 0.2794 0.1778)
							(mid 0.249642 0.249642)
							(end 0.1778 0.2794)
						)
					)
					(width 0)
					(fill yes)
				)
			)
		)
		(pad "2" smd custom
			(at 0 0.4445 180)
			(size 0.1397 0.1397)
			(layers "B.Cu" "B.Mask" "B.Paste")
			(net "BMC_SSD_RST#0_A10")
			(options
				(clearance outline)
				(anchor circle)
			)
			(primitives
				(gr_poly
					(pts
						(arc
							(start -0.1778 0.2794)
							(mid -0.249642 0.249642)
							(end -0.2794 0.1778)
						)
						(arc
							(start -0.2794 -0.1778)
							(mid -0.249642 -0.249642)
							(end -0.1778 -0.2794)
						)
						(arc
							(start 0.1778 -0.2794)
							(mid 0.249642 -0.249642)
							(end 0.2794 -0.1778)
						)
						(arc
							(start 0.2794 0.1778)
							(mid 0.249642 0.249642)
							(end 0.1778 0.2794)
						)
					)
					(width 0)
					(fill yes)
				)
			)
		)
	)
	(footprint ""
		(layer "B.Cu")
		(at 165.227 -33.528)
		(property "Reference" "R2929"
			(at 0 0 0)
			(layer "B.SilkS")
			(hide yes)
			(effects
				(font
					(size 1.27 1.27)
				)
				(justify mirror)
			)
		)
		(property "Value" "0R2J-2-GP"
			(at -0.064008 -3.993896 0)
			(unlocked yes)
			(layer "B.Fab")
			(hide yes)
			(effects
				(font
					(size 1.016 1.016)
					(thickness 0.1524)
				)
				(justify mirror)
			)
		)
		(property "Device Type" "R402H16"
			(at -0.064008 -5.517896 0)
			(unlocked yes)
			(layer "B.Fab")
			(hide yes)
			(effects
				(font
					(size 1.016 1.016)
					(thickness 0.1524)
				)
				(justify mirror)
			)
		)
		(duplicate_pad_numbers_are_jumpers no)
		(fp_line
			(start -0.508 -0.9398)
			(end 0.508 -0.9398)
			(stroke
				(width 0.1524)
				(type default)
			)
			(layer "B.SilkS")
		)
		(fp_line
			(start 0.508 -0.9398)
			(end 0.508 0.9398)
			(stroke
				(width 0.1524)
				(type default)
			)
			(layer "B.SilkS")
		)
		(fp_rect
			(start 0.508 0.9398)
			(end -0.508 -0.9398)
			(stroke
				(width 0)
				(type default)
			)
			(fill no)
			(layer "B.CrtYd")
		)
		(fp_rect
			(start 0.508 0.9398)
			(end -0.508 -0.9398)
			(stroke
				(width 0)
				(type default)
			)
			(fill no)
			(layer "B.Fab")
		)
		(pad "1" smd custom
			(at 0 -0.4445 180)
			(size 0.1397 0.1397)
			(layers "B.Cu" "B.Mask" "B.Paste")
			(net "CBL_PRSNT_N_4")
			(options
				(clearance outline)
				(anchor circle)
			)
			(primitives
				(gr_poly
					(pts
						(arc
							(start -0.1778 0.2794)
							(mid -0.249642 0.249642)
							(end -0.2794 0.1778)
						)
						(arc
							(start -0.2794 -0.1778)
							(mid -0.249642 -0.249642)
							(end -0.1778 -0.2794)
						)
						(arc
							(start 0.1778 -0.2794)
							(mid 0.249642 -0.249642)
							(end 0.2794 -0.1778)
						)
						(arc
							(start 0.2794 0.1778)
							(mid 0.249642 0.249642)
							(end 0.1778 0.2794)
						)
					)
					(width 0)
					(fill yes)
				)
			)
		)
		(pad "2" smd custom
			(at 0 0.4445 180)
			(size 0.1397 0.1397)
			(layers "B.Cu" "B.Mask" "B.Paste")
			(net "8644_SDA_R_4")
			(options
				(clearance outline)
				(anchor circle)
			)
			(primitives
				(gr_poly
					(pts
						(arc
							(start -0.1778 0.2794)
							(mid -0.249642 0.249642)
							(end -0.2794 0.1778)
						)
						(arc
							(start -0.2794 -0.1778)
							(mid -0.249642 -0.249642)
							(end -0.1778 -0.2794)
						)
						(arc
							(start 0.1778 -0.2794)
							(mid 0.249642 -0.249642)
							(end 0.2794 -0.1778)
						)
						(arc
							(start 0.2794 0.1778)
							(mid 0.249642 0.249642)
							(end 0.1778 0.2794)
						)
					)
					(width 0)
					(fill yes)
				)
			)
		)
	)
	(footprint ""
		(layer "B.Cu")
		(at 263.656318 -3.73634 90)
		(property "Reference" "C153"
			(at 0 0 90)
			(layer "B.SilkS")
			(hide yes)
			(effects
				(font
					(size 1.27 1.27)
				)
				(justify mirror)
			)
		)
		(property "Value" "SC100P50V2JN-3GP"
			(at -1.1811 -2.7051 90)
			(unlocked yes)
			(layer "B.Fab")
			(hide yes)
			(effects
				(font
					(size 1.016 1.016)
					(thickness 0.1524)
				)
				(justify mirror)
			)
		)
		(property "Device Type" "C402H22"
			(at -1.1811 -4.2291 90)
			(unlocked yes)
			(layer "B.Fab")
			(hide yes)
			(effects
				(font
					(size 1.016 1.016)
					(thickness 0.1524)
				)
				(justify mirror)
			)
		)
		(duplicate_pad_numbers_are_jumpers no)
		(fp_rect
			(start 0.4318 0.9525)
			(end -0.4318 -0.9525)
			(stroke
				(width 0)
				(type default)
			)
			(fill no)
			(layer "B.CrtYd")
		)
		(fp_rect
			(start 0.4318 0.9525)
			(end -0.4318 -0.9525)
			(stroke
				(width 0)
				(type default)
			)
			(fill no)
			(layer "B.Fab")
		)
		(pad "1" smd custom
			(at 0 -0.4445 270)
			(size 0.1524 0.1524)
			(layers "B.Cu" "B.Mask" "B.Paste")
			(net "TEMP_SENSOR_DXP")
			(options
				(clearance outline)
				(anchor circle)
			)
			(primitives
				(gr_poly
					(pts
						(arc
							(start 0.3048 0.2032)
							(mid 0.275042 0.275042)
							(end 0.2032 0.3048)
						)
						(arc
							(start -0.2032 0.3048)
							(mid -0.275042 0.275042)
							(end -0.3048 0.2032)
						)
						(arc
							(start -0.3048 -0.2032)
							(mid -0.275042 -0.275042)
							(end -0.2032 -0.3048)
						)
						(arc
							(start 0.2032 -0.3048)
							(mid 0.275042 -0.275042)
							(end 0.3048 -0.2032)
						)
					)
					(width 0)
					(fill yes)
				)
			)
		)
		(pad "2" smd custom
			(at 0 0.4445 270)
			(size 0.1524 0.1524)
			(layers "B.Cu" "B.Mask" "B.Paste")
			(net "TEMP_SENSOR_DXN")
			(options
				(clearance outline)
				(anchor circle)
			)
			(primitives
				(gr_poly
					(pts
						(arc
							(start 0.3048 0.2032)
							(mid 0.275042 0.275042)
							(end 0.2032 0.3048)
						)
						(arc
							(start -0.2032 0.3048)
							(mid -0.275042 0.275042)
							(end -0.3048 0.2032)
						)
						(arc
							(start -0.3048 -0.2032)
							(mid -0.275042 -0.275042)
							(end -0.2032 -0.3048)
						)
						(arc
							(start 0.2032 -0.3048)
							(mid 0.275042 -0.275042)
							(end 0.3048 -0.2032)
						)
					)
					(width 0)
					(fill yes)
				)
			)
		)
	)
	(footprint ""
		(layer "B.Cu")
		(at 54.8894 -113.8428 90)
		(property "Reference" "R436"
			(at 0 0 90)
			(layer "B.SilkS")
			(hide yes)
			(effects
				(font
					(size 1.27 1.27)
				)
				(justify mirror)
			)
		)
		(property "Value" "4K7R2F-GP"
			(at -0.064008 -3.993896 90)
			(unlocked yes)
			(layer "B.Fab")
			(hide yes)
			(effects
				(font
					(size 1.016 1.016)
					(thickness 0.1524)
				)
				(justify mirror)
			)
		)
		(property "Device Type" "R402H16"
			(at -0.064008 -5.517896 90)
			(unlocked yes)
			(layer "B.Fab")
			(hide yes)
			(effects
				(font
					(size 1.016 1.016)
					(thickness 0.1524)
				)
				(justify mirror)
			)
		)
		(duplicate_pad_numbers_are_jumpers no)
		(fp_line
			(start 0.508 -0.9398)
			(end 0.508 0.9398)
			(stroke
				(width 0.1524)
				(type default)
			)
			(layer "B.SilkS")
		)
		(fp_line
			(start -0.508 -0.9398)
			(end 0.508 -0.9398)
			(stroke
				(width 0.1524)
				(type default)
			)
			(layer "B.SilkS")
		)
		(fp_rect
			(start 0.508 0.9398)
			(end -0.508 -0.9398)
			(stroke
				(width 0)
				(type default)
			)
			(fill no)
			(layer "B.CrtYd")
		)
		(fp_rect
			(start 0.508 0.9398)
			(end -0.508 -0.9398)
			(stroke
				(width 0)
				(type default)
			)
			(fill no)
			(layer "B.Fab")
		)
		(pad "1" smd custom
			(at 0 -0.4445 270)
			(size 0.1397 0.1397)
			(layers "B.Cu" "B.Mask" "B.Paste")
			(net "BMC_I2C12_MINI6_SDA_S")
			(options
				(clearance outline)
				(anchor circle)
			)
			(primitives
				(gr_poly
					(pts
						(arc
							(start -0.1778 0.2794)
							(mid -0.249642 0.249642)
							(end -0.2794 0.1778)
						)
						(arc
							(start -0.2794 -0.1778)
							(mid -0.249642 -0.249642)
							(end -0.1778 -0.2794)
						)
						(arc
							(start 0.1778 -0.2794)
							(mid 0.249642 -0.249642)
							(end 0.2794 -0.1778)
						)
						(arc
							(start 0.2794 0.1778)
							(mid 0.249642 0.249642)
							(end 0.1778 0.2794)
						)
					)
					(width 0)
					(fill yes)
				)
			)
		)
		(pad "2" smd custom
			(at 0 0.4445 270)
			(size 0.1397 0.1397)
			(layers "B.Cu" "B.Mask" "B.Paste")
			(net "P3V3_STBY")
			(options
				(clearance outline)
				(anchor circle)
			)
			(primitives
				(gr_poly
					(pts
						(arc
							(start -0.1778 0.2794)
							(mid -0.249642 0.249642)
							(end -0.2794 0.1778)
						)
						(arc
							(start -0.2794 -0.1778)
							(mid -0.249642 -0.249642)
							(end -0.1778 -0.2794)
						)
						(arc
							(start 0.1778 -0.2794)
							(mid 0.249642 -0.249642)
							(end 0.2794 -0.1778)
						)
						(arc
							(start 0.2794 0.1778)
							(mid 0.249642 0.249642)
							(end 0.1778 0.2794)
						)
					)
					(width 0)
					(fill yes)
				)
			)
		)
	)
	(footprint ""
		(layer "B.Cu")
		(at 133.326124 -208.889092 180)
		(property "Reference" "R4119"
			(at 0 0 0)
			(layer "B.SilkS")
			(hide yes)
			(effects
				(font
					(size 1.27 1.27)
				)
				(justify mirror)
			)
		)
		(property "Value" "4K7R2F-GP"
			(at -0.064008 -3.993896 180)
			(unlocked yes)
			(layer "B.Fab")
			(hide yes)
			(effects
				(font
					(size 1.016 1.016)
					(thickness 0.1524)
				)
				(justify mirror)
			)
		)
		(property "Device Type" "R402H16"
			(at -0.064008 -5.517896 180)
			(unlocked yes)
			(layer "B.Fab")
			(hide yes)
			(effects
				(font
					(size 1.016 1.016)
					(thickness 0.1524)
				)
				(justify mirror)
			)
		)
		(duplicate_pad_numbers_are_jumpers no)
		(fp_line
			(start 0.508 -0.9398)
			(end 0.508 0.9398)
			(stroke
				(width 0.1524)
				(type default)
			)
			(layer "B.SilkS")
		)
		(fp_line
			(start -0.508 -0.9398)
			(end 0.508 -0.9398)
			(stroke
				(width 0.1524)
				(type default)
			)
			(layer "B.SilkS")
		)
		(fp_rect
			(start 0.508 0.9398)
			(end -0.508 -0.9398)
			(stroke
				(width 0)
				(type default)
			)
			(fill no)
			(layer "B.CrtYd")
		)
		(fp_rect
			(start 0.508 0.9398)
			(end -0.508 -0.9398)
			(stroke
				(width 0)
				(type default)
			)
			(fill no)
			(layer "B.Fab")
		)
		(pad "1" smd custom
			(at 0 -0.4445)
			(size 0.1397 0.1397)
			(layers "B.Cu" "B.Mask" "B.Paste")
			(net "SSD_ATNLED#6")
			(options
				(clearance outline)
				(anchor circle)
			)
			(primitives
				(gr_poly
					(pts
						(arc
							(start -0.1778 0.2794)
							(mid -0.249642 0.249642)
							(end -0.2794 0.1778)
						)
						(arc
							(start -0.2794 -0.1778)
							(mid -0.249642 -0.249642)
							(end -0.1778 -0.2794)
						)
						(arc
							(start 0.1778 -0.2794)
							(mid 0.249642 -0.249642)
							(end 0.2794 -0.1778)
						)
						(arc
							(start 0.2794 0.1778)
							(mid 0.249642 0.249642)
							(end 0.1778 0.2794)
						)
					)
					(width 0)
					(fill yes)
				)
			)
		)
		(pad "2" smd custom
			(at 0 0.4445)
			(size 0.1397 0.1397)
			(layers "B.Cu" "B.Mask" "B.Paste")
			(net "P3V3_STBY")
			(options
				(clearance outline)
				(anchor circle)
			)
			(primitives
				(gr_poly
					(pts
						(arc
							(start -0.1778 0.2794)
							(mid -0.249642 0.249642)
							(end -0.2794 0.1778)
						)
						(arc
							(start -0.2794 -0.1778)
							(mid -0.249642 -0.249642)
							(end -0.1778 -0.2794)
						)
						(arc
							(start 0.1778 -0.2794)
							(mid 0.249642 -0.249642)
							(end 0.2794 -0.1778)
						)
						(arc
							(start 0.2794 0.1778)
							(mid 0.249642 0.249642)
							(end 0.1778 0.2794)
						)
					)
					(width 0)
					(fill yes)
				)
			)
		)
	)
	(footprint ""
		(layer "B.Cu")
		(at 269.580868 -16.940276)
		(property "Reference" "R719"
			(at 0 0 0)
			(layer "B.SilkS")
			(hide yes)
			(effects
				(font
					(size 1.27 1.27)
				)
				(justify mirror)
			)
		)
		(property "Value" "0R2J-2-GP"
			(at -0.064008 -3.993896 0)
			(unlocked yes)
			(layer "B.Fab")
			(hide yes)
			(effects
				(font
					(size 1.016 1.016)
					(thickness 0.1524)
				)
				(justify mirror)
			)
		)
		(property "Device Type" "R402H16"
			(at -0.064008 -5.517896 0)
			(unlocked yes)
			(layer "B.Fab")
			(hide yes)
			(effects
				(font
					(size 1.016 1.016)
					(thickness 0.1524)
				)
				(justify mirror)
			)
		)
		(duplicate_pad_numbers_are_jumpers no)
		(fp_line
			(start -0.508 -0.9398)
			(end 0.508 -0.9398)
			(stroke
				(width 0.1524)
				(type default)
			)
			(layer "B.SilkS")
		)
		(fp_line
			(start 0.508 -0.9398)
			(end 0.508 0.9398)
			(stroke
				(width 0.1524)
				(type default)
			)
			(layer "B.SilkS")
		)
		(fp_rect
			(start 0.508 0.9398)
			(end -0.508 -0.9398)
			(stroke
				(width 0)
				(type default)
			)
			(fill no)
			(layer "B.CrtYd")
		)
		(fp_rect
			(start 0.508 0.9398)
			(end -0.508 -0.9398)
			(stroke
				(width 0)
				(type default)
			)
			(fill no)
			(layer "B.Fab")
		)
		(pad "1" smd custom
			(at 0 -0.4445 180)
			(size 0.1397 0.1397)
			(layers "B.Cu" "B.Mask" "B.Paste")
			(net "8644_USB_DP5")
			(options
				(clearance outline)
				(anchor circle)
			)
			(primitives
				(gr_poly
					(pts
						(arc
							(start -0.1778 0.2794)
							(mid -0.249642 0.249642)
							(end -0.2794 0.1778)
						)
						(arc
							(start -0.2794 -0.1778)
							(mid -0.249642 -0.249642)
							(end -0.1778 -0.2794)
						)
						(arc
							(start 0.1778 -0.2794)
							(mid 0.249642 -0.249642)
							(end 0.2794 -0.1778)
						)
						(arc
							(start 0.2794 0.1778)
							(mid 0.249642 0.249642)
							(end 0.1778 0.2794)
						)
					)
					(width 0)
					(fill yes)
				)
			)
		)
		(pad "2" smd custom
			(at 0 0.4445 180)
			(size 0.1397 0.1397)
			(layers "B.Cu" "B.Mask" "B.Paste")
			(net "P3V3_STBY")
			(options
				(clearance outline)
				(anchor circle)
			)
			(primitives
				(gr_poly
					(pts
						(arc
							(start -0.1778 0.2794)
							(mid -0.249642 0.249642)
							(end -0.2794 0.1778)
						)
						(arc
							(start -0.2794 -0.1778)
							(mid -0.249642 -0.249642)
							(end -0.1778 -0.2794)
						)
						(arc
							(start 0.1778 -0.2794)
							(mid 0.249642 -0.249642)
							(end 0.2794 -0.1778)
						)
						(arc
							(start 0.2794 0.1778)
							(mid 0.249642 0.249642)
							(end 0.1778 0.2794)
						)
					)
					(width 0)
					(fill yes)
				)
			)
		)
	)
	(footprint ""
		(layer "B.Cu")
		(at 349.040196 -45.46473 180)
		(property "Reference" "U47"
			(at 0 0 0)
			(layer "B.SilkS")
			(hide yes)
			(effects
				(font
					(size 1.27 1.27)
				)
				(justify mirror)
			)
		)
		(property "Value" "SN74LVC1G08DCKR-GP"
			(at 2.3368 -8.6868 180)
			(unlocked yes)
			(layer "B.Fab")
			(hide yes)
			(effects
				(font
					(size 1.016 1.016)
					(thickness 0.1524)
				)
				(justify mirror)
			)
		)
		(property "Device Type" "SC70-5H44"
			(at 2.3114 -10.414 180)
			(unlocked yes)
			(layer "B.Fab")
			(hide yes)
			(effects
				(font
					(size 1.016 1.016)
					(thickness 0.1524)
				)
				(justify mirror)
			)
		)
		(duplicate_pad_numbers_are_jumpers no)
		(fp_line
			(start 1.27 1.7018)
			(end 1.27 -1.7018)
			(stroke
				(width 0.1524)
				(type default)
			)
			(layer "B.SilkS")
		)
		(fp_line
			(start 1.27 -1.7018)
			(end -1.27 -1.7018)
			(stroke
				(width 0.1524)
				(type default)
			)
			(layer "B.SilkS")
		)
		(fp_line
			(start -0.6604 -1.8034)
			(end -1.3843 -1.8034)
			(stroke
				(width 0.3302)
				(type default)
			)
			(layer "B.SilkS")
		)
		(fp_line
			(start -1.27 1.7018)
			(end 1.27 1.7018)
			(stroke
				(width 0.1524)
				(type default)
			)
			(layer "B.SilkS")
		)
		(fp_line
			(start -1.27 -1.7018)
			(end -1.27 1.7018)
			(stroke
				(width 0.1524)
				(type default)
			)
			(layer "B.SilkS")
		)
		(fp_line
			(start -1.3843 -1.8034)
			(end -1.3843 -1.1176)
			(stroke
				(width 0.3302)
				(type default)
			)
			(layer "B.SilkS")
		)
		(fp_rect
			(start 1.524 1.9558)
			(end -1.524 -1.9558)
			(stroke
				(width 0)
				(type default)
			)
			(fill no)
			(layer "B.CrtYd")
		)
		(fp_poly
			(pts
				(xy 1.524 -1.9558) (xy -1.524 -1.9558) (xy -1.524 1.9558) (xy 1.524 1.9558)
			)
			(stroke
				(width 0)
				(type default)
			)
			(fill no)
			(layer "B.Fab")
		)
		(pad "1" smd rect
			(at -0.65024 -0.8255)
			(size 0.4064 1.2192)
			(layers "B.Cu" "B.Mask" "B.Paste")
			(net "PE1_PERST#_R")
		)
		(pad "2" smd rect
			(at 0 -0.8255)
			(size 0.4064 1.2192)
			(layers "B.Cu" "B.Mask" "B.Paste")
			(net "PM8536_PG2_R")
		)
		(pad "3" smd rect
			(at 0.65024 -0.8255)
			(size 0.4064 1.2192)
			(layers "B.Cu" "B.Mask" "B.Paste")
			(net "GND")
		)
		(pad "4" smd rect
			(at 0.65024 0.8255)
			(size 0.4064 1.2192)
			(layers "B.Cu" "B.Mask" "B.Paste")
			(net "PM8536_RST#_AND")
		)
		(pad "5" smd rect
			(at -0.65024 0.8255)
			(size 0.4064 1.2192)
			(layers "B.Cu" "B.Mask" "B.Paste")
			(net "P3V3_STBY")
		)
	)
	(footprint ""
		(layer "B.Cu")
		(at 246.59463 -60.071)
		(property "Reference" "C603"
			(at 0 0 0)
			(layer "B.SilkS")
			(hide yes)
			(effects
				(font
					(size 1.27 1.27)
				)
				(justify mirror)
			)
		)
		(property "Value" "SCD1U16V1KX-1-GP"
			(at 2.8321 -1.7399 0)
			(unlocked yes)
			(layer "B.Fab")
			(hide yes)
			(effects
				(font
					(size 1.016 1.016)
					(thickness 0.1524)
				)
				(justify mirror)
			)
		)
		(property "Device Type" "C0201H13"
			(at 2.8321 -3.2639 0)
			(unlocked yes)
			(layer "B.Fab")
			(hide yes)
			(effects
				(font
					(size 1.016 1.016)
					(thickness 0.1524)
				)
				(justify mirror)
			)
		)
		(duplicate_pad_numbers_are_jumpers no)
		(fp_rect
			(start 0.2794 0.6477)
			(end -0.2794 -0.6477)
			(stroke
				(width 0)
				(type default)
			)
			(fill no)
			(layer "B.CrtYd")
		)
		(fp_rect
			(start 0.2794 0.6477)
			(end -0.2794 -0.6477)
			(stroke
				(width 0)
				(type default)
			)
			(fill no)
			(layer "B.Fab")
		)
		(pad "1" smd custom
			(at 0 -0.2794 180)
			(size 0.0762 0.0762)
			(layers "B.Cu" "B.Mask" "B.Paste")
			(net "DUT_AVD_PCIE")
			(options
				(clearance outline)
				(anchor circle)
			)
			(primitives
				(gr_poly
					(pts
						(arc
							(start 0.1524 0.127)
							(mid 0.137521 0.162921)
							(end 0.1016 0.1778)
						)
						(arc
							(start -0.1016 0.1778)
							(mid -0.137521 0.162921)
							(end -0.1524 0.127)
						)
						(arc
							(start -0.1524 -0.127)
							(mid -0.137521 -0.162921)
							(end -0.1016 -0.1778)
						)
						(arc
							(start 0.1016 -0.1778)
							(mid 0.137521 -0.162921)
							(end 0.1524 -0.127)
						)
					)
					(width 0)
					(fill yes)
				)
			)
		)
		(pad "2" smd custom
			(at 0 0.2794 180)
			(size 0.0762 0.0762)
			(layers "B.Cu" "B.Mask" "B.Paste")
			(net "GND")
			(options
				(clearance outline)
				(anchor circle)
			)
			(primitives
				(gr_poly
					(pts
						(arc
							(start 0.1524 0.127)
							(mid 0.137521 0.162921)
							(end 0.1016 0.1778)
						)
						(arc
							(start -0.1016 0.1778)
							(mid -0.137521 0.162921)
							(end -0.1524 0.127)
						)
						(arc
							(start -0.1524 -0.127)
							(mid -0.137521 -0.162921)
							(end -0.1016 -0.1778)
						)
						(arc
							(start 0.1016 -0.1778)
							(mid 0.137521 -0.162921)
							(end 0.1524 -0.127)
						)
					)
					(width 0)
					(fill yes)
				)
			)
		)
	)
	(footprint ""
		(layer "B.Cu")
		(at 53.721 -133.477 -90)
		(property "Reference" "R316"
			(at 0 0 90)
			(layer "B.SilkS")
			(hide yes)
			(effects
				(font
					(size 1.27 1.27)
				)
				(justify mirror)
			)
		)
		(property "Value" "0R2J-2-GP"
			(at -0.064008 -3.993896 270)
			(unlocked yes)
			(layer "B.Fab")
			(hide yes)
			(effects
				(font
					(size 1.016 1.016)
					(thickness 0.1524)
				)
				(justify mirror)
			)
		)
		(property "Device Type" "R402H16"
			(at -0.064008 -5.517896 270)
			(unlocked yes)
			(layer "B.Fab")
			(hide yes)
			(effects
				(font
					(size 1.016 1.016)
					(thickness 0.1524)
				)
				(justify mirror)
			)
		)
		(duplicate_pad_numbers_are_jumpers no)
		(fp_line
			(start -0.508 -0.9398)
			(end 0.508 -0.9398)
			(stroke
				(width 0.1524)
				(type default)
			)
			(layer "B.SilkS")
		)
		(fp_line
			(start 0.508 -0.9398)
			(end 0.508 0.9398)
			(stroke
				(width 0.1524)
				(type default)
			)
			(layer "B.SilkS")
		)
		(fp_rect
			(start 0.508 0.9398)
			(end -0.508 -0.9398)
			(stroke
				(width 0)
				(type default)
			)
			(fill no)
			(layer "B.CrtYd")
		)
		(fp_rect
			(start 0.508 0.9398)
			(end -0.508 -0.9398)
			(stroke
				(width 0)
				(type default)
			)
			(fill no)
			(layer "B.Fab")
		)
		(pad "1" smd custom
			(at 0 -0.4445 90)
			(size 0.1397 0.1397)
			(layers "B.Cu" "B.Mask" "B.Paste")
			(net "ADC_P5V_STBY")
			(options
				(clearance outline)
				(anchor circle)
			)
			(primitives
				(gr_poly
					(pts
						(arc
							(start -0.1778 0.2794)
							(mid -0.249642 0.249642)
							(end -0.2794 0.1778)
						)
						(arc
							(start -0.2794 -0.1778)
							(mid -0.249642 -0.249642)
							(end -0.1778 -0.2794)
						)
						(arc
							(start 0.1778 -0.2794)
							(mid 0.249642 -0.249642)
							(end 0.2794 -0.1778)
						)
						(arc
							(start 0.2794 0.1778)
							(mid 0.249642 0.249642)
							(end 0.1778 0.2794)
						)
					)
					(width 0)
					(fill yes)
				)
			)
		)
		(pad "2" smd custom
			(at 0 0.4445 90)
			(size 0.1397 0.1397)
			(layers "B.Cu" "B.Mask" "B.Paste")
			(net "ADC_P5V_STBY_BMC")
			(options
				(clearance outline)
				(anchor circle)
			)
			(primitives
				(gr_poly
					(pts
						(arc
							(start -0.1778 0.2794)
							(mid -0.249642 0.249642)
							(end -0.2794 0.1778)
						)
						(arc
							(start -0.2794 -0.1778)
							(mid -0.249642 -0.249642)
							(end -0.1778 -0.2794)
						)
						(arc
							(start 0.1778 -0.2794)
							(mid 0.249642 -0.249642)
							(end 0.2794 -0.1778)
						)
						(arc
							(start 0.2794 0.1778)
							(mid 0.249642 0.249642)
							(end 0.1778 0.2794)
						)
					)
					(width 0)
					(fill yes)
				)
			)
		)
	)
	(footprint ""
		(layer "B.Cu")
		(at 310.007 -65.405 180)
		(property "Reference" "PG66"
			(at 0 0 0)
			(layer "B.SilkS")
			(hide yes)
			(effects
				(font
					(size 1.27 1.27)
				)
				(justify mirror)
			)
		)
		(property "Value" "GAP-CLOSE-PWR-3-GP"
			(at -0.0254 -6.5786 180)
			(unlocked yes)
			(layer "B.Fab")
			(hide yes)
			(effects
				(font
					(size 1.016 1.016)
					(thickness 0.1524)
				)
				(justify mirror)
			)
		)
		(property "Device Type" "GAP-CLOSE-PWR-3"
			(at -0.0254 -8.255 180)
			(unlocked yes)
			(layer "B.Fab")
			(hide yes)
			(effects
				(font
					(size 1.016 1.016)
					(thickness 0.1524)
				)
				(justify mirror)
			)
		)
		(duplicate_pad_numbers_are_jumpers no)
		(fp_rect
			(start 0.7112 0.4572)
			(end -0.7112 -0.4572)
			(stroke
				(width 0)
				(type default)
			)
			(fill no)
			(layer "B.CrtYd")
		)
		(fp_poly
			(pts
				(xy 0.7112 -0.4572) (xy -0.7112 -0.4572) (xy -0.7112 0.4572) (xy 0.7112 0.4572)
			)
			(stroke
				(width 0)
				(type default)
			)
			(fill no)
			(layer "B.Fab")
		)
		(pad "1" smd rect
			(at 0.3048 0)
			(size 0.6604 0.762)
			(layers "B.Cu" "B.Mask" "B.Paste")
			(net "DUT_VDD")
		)
		(pad "2" smd rect
			(at -0.3048 0)
			(size 0.6604 0.762)
			(layers "B.Cu" "B.Mask" "B.Paste")
			(net "P0V9_E")
		)
	)
	(footprint ""
		(layer "B.Cu")
		(at 217.654124 -190.601092 180)
		(property "Reference" "R555"
			(at 0 0 0)
			(layer "B.SilkS")
			(hide yes)
			(effects
				(font
					(size 1.27 1.27)
				)
				(justify mirror)
			)
		)
		(property "Value" "10KR2F-2-GP"
			(at -0.064008 -3.993896 180)
			(unlocked yes)
			(layer "B.Fab")
			(hide yes)
			(effects
				(font
					(size 1.016 1.016)
					(thickness 0.1524)
				)
				(justify mirror)
			)
		)
		(property "Device Type" "R402H16"
			(at -0.064008 -5.517896 180)
			(unlocked yes)
			(layer "B.Fab")
			(hide yes)
			(effects
				(font
					(size 1.016 1.016)
					(thickness 0.1524)
				)
				(justify mirror)
			)
		)
		(duplicate_pad_numbers_are_jumpers no)
		(fp_line
			(start 0.508 -0.9398)
			(end 0.508 0.9398)
			(stroke
				(width 0.1524)
				(type default)
			)
			(layer "B.SilkS")
		)
		(fp_line
			(start -0.508 -0.9398)
			(end 0.508 -0.9398)
			(stroke
				(width 0.1524)
				(type default)
			)
			(layer "B.SilkS")
		)
		(fp_rect
			(start 0.508 0.9398)
			(end -0.508 -0.9398)
			(stroke
				(width 0)
				(type default)
			)
			(fill no)
			(layer "B.CrtYd")
		)
		(fp_rect
			(start 0.508 0.9398)
			(end -0.508 -0.9398)
			(stroke
				(width 0)
				(type default)
			)
			(fill no)
			(layer "B.Fab")
		)
		(pad "1" smd custom
			(at 0 -0.4445)
			(size 0.1397 0.1397)
			(layers "B.Cu" "B.Mask" "B.Paste")
			(net "P3V3_STBY")
			(options
				(clearance outline)
				(anchor circle)
			)
			(primitives
				(gr_poly
					(pts
						(arc
							(start -0.1778 0.2794)
							(mid -0.249642 0.249642)
							(end -0.2794 0.1778)
						)
						(arc
							(start -0.2794 -0.1778)
							(mid -0.249642 -0.249642)
							(end -0.1778 -0.2794)
						)
						(arc
							(start 0.1778 -0.2794)
							(mid 0.249642 -0.249642)
							(end 0.2794 -0.1778)
						)
						(arc
							(start 0.2794 0.1778)
							(mid 0.249642 0.249642)
							(end 0.1778 0.2794)
						)
					)
					(width 0)
					(fill yes)
				)
			)
		)
		(pad "2" smd custom
			(at 0 0.4445)
			(size 0.1397 0.1397)
			(layers "B.Cu" "B.Mask" "B.Paste")
			(net "IOEXP3_AD1")
			(options
				(clearance outline)
				(anchor circle)
			)
			(primitives
				(gr_poly
					(pts
						(arc
							(start -0.1778 0.2794)
							(mid -0.249642 0.249642)
							(end -0.2794 0.1778)
						)
						(arc
							(start -0.2794 -0.1778)
							(mid -0.249642 -0.249642)
							(end -0.1778 -0.2794)
						)
						(arc
							(start 0.1778 -0.2794)
							(mid 0.249642 -0.249642)
							(end 0.2794 -0.1778)
						)
						(arc
							(start 0.2794 0.1778)
							(mid 0.249642 0.249642)
							(end 0.1778 0.2794)
						)
					)
					(width 0)
					(fill yes)
				)
			)
		)
	)
	(footprint ""
		(layer "B.Cu")
		(at 182.14086 -6.47446 -90)
		(property "Reference" "R2936"
			(at 0 0 90)
			(layer "B.SilkS")
			(hide yes)
			(effects
				(font
					(size 1.27 1.27)
				)
				(justify mirror)
			)
		)
		(property "Value" "0R2J-2-GP"
			(at -0.064008 -3.993896 270)
			(unlocked yes)
			(layer "B.Fab")
			(hide yes)
			(effects
				(font
					(size 1.016 1.016)
					(thickness 0.1524)
				)
				(justify mirror)
			)
		)
		(property "Device Type" "R402H16"
			(at -0.064008 -5.517896 270)
			(unlocked yes)
			(layer "B.Fab")
			(hide yes)
			(effects
				(font
					(size 1.016 1.016)
					(thickness 0.1524)
				)
				(justify mirror)
			)
		)
		(duplicate_pad_numbers_are_jumpers no)
		(fp_line
			(start -0.508 -0.9398)
			(end 0.508 -0.9398)
			(stroke
				(width 0.1524)
				(type default)
			)
			(layer "B.SilkS")
		)
		(fp_line
			(start 0.508 -0.9398)
			(end 0.508 0.9398)
			(stroke
				(width 0.1524)
				(type default)
			)
			(layer "B.SilkS")
		)
		(fp_rect
			(start 0.508 0.9398)
			(end -0.508 -0.9398)
			(stroke
				(width 0)
				(type default)
			)
			(fill no)
			(layer "B.CrtYd")
		)
		(fp_rect
			(start 0.508 0.9398)
			(end -0.508 -0.9398)
			(stroke
				(width 0)
				(type default)
			)
			(fill no)
			(layer "B.Fab")
		)
		(pad "1" smd custom
			(at 0 -0.4445 90)
			(size 0.1397 0.1397)
			(layers "B.Cu" "B.Mask" "B.Paste")
			(net "PCIE_REFCLK_H2_P")
			(options
				(clearance outline)
				(anchor circle)
			)
			(primitives
				(gr_poly
					(pts
						(arc
							(start -0.1778 0.2794)
							(mid -0.249642 0.249642)
							(end -0.2794 0.1778)
						)
						(arc
							(start -0.2794 -0.1778)
							(mid -0.249642 -0.249642)
							(end -0.1778 -0.2794)
						)
						(arc
							(start 0.1778 -0.2794)
							(mid 0.249642 -0.249642)
							(end 0.2794 -0.1778)
						)
						(arc
							(start 0.2794 0.1778)
							(mid 0.249642 0.249642)
							(end 0.1778 0.2794)
						)
					)
					(width 0)
					(fill yes)
				)
			)
		)
		(pad "2" smd custom
			(at 0 0.4445 90)
			(size 0.1397 0.1397)
			(layers "B.Cu" "B.Mask" "B.Paste")
			(net "PCIE_REFCLK_H2_P_R")
			(options
				(clearance outline)
				(anchor circle)
			)
			(primitives
				(gr_poly
					(pts
						(arc
							(start -0.1778 0.2794)
							(mid -0.249642 0.249642)
							(end -0.2794 0.1778)
						)
						(arc
							(start -0.2794 -0.1778)
							(mid -0.249642 -0.249642)
							(end -0.1778 -0.2794)
						)
						(arc
							(start 0.1778 -0.2794)
							(mid 0.249642 -0.249642)
							(end 0.2794 -0.1778)
						)
						(arc
							(start 0.2794 0.1778)
							(mid 0.249642 0.249642)
							(end 0.1778 0.2794)
						)
					)
					(width 0)
					(fill yes)
				)
			)
		)
	)
	(footprint ""
		(layer "B.Cu")
		(at 122.428 -205.74)
		(property "Reference" "R3223"
			(at 0 0 0)
			(layer "B.SilkS")
			(hide yes)
			(effects
				(font
					(size 1.27 1.27)
				)
				(justify mirror)
			)
		)
		(property "Value" "0R2J-2-GP"
			(at -0.064008 -3.993896 0)
			(unlocked yes)
			(layer "B.Fab")
			(hide yes)
			(effects
				(font
					(size 1.016 1.016)
					(thickness 0.1524)
				)
				(justify mirror)
			)
		)
		(property "Device Type" "R402H16"
			(at -0.064008 -5.517896 0)
			(unlocked yes)
			(layer "B.Fab")
			(hide yes)
			(effects
				(font
					(size 1.016 1.016)
					(thickness 0.1524)
				)
				(justify mirror)
			)
		)
		(duplicate_pad_numbers_are_jumpers no)
		(fp_line
			(start -0.508 -0.9398)
			(end 0.508 -0.9398)
			(stroke
				(width 0.1524)
				(type default)
			)
			(layer "B.SilkS")
		)
		(fp_line
			(start 0.508 -0.9398)
			(end 0.508 0.9398)
			(stroke
				(width 0.1524)
				(type default)
			)
			(layer "B.SilkS")
		)
		(fp_rect
			(start 0.508 0.9398)
			(end -0.508 -0.9398)
			(stroke
				(width 0)
				(type default)
			)
			(fill no)
			(layer "B.CrtYd")
		)
		(fp_rect
			(start 0.508 0.9398)
			(end -0.508 -0.9398)
			(stroke
				(width 0)
				(type default)
			)
			(fill no)
			(layer "B.Fab")
		)
		(pad "1" smd custom
			(at 0 -0.4445 180)
			(size 0.1397 0.1397)
			(layers "B.Cu" "B.Mask" "B.Paste")
			(net "BMC_SSD_RST#7")
			(options
				(clearance outline)
				(anchor circle)
			)
			(primitives
				(gr_poly
					(pts
						(arc
							(start -0.1778 0.2794)
							(mid -0.249642 0.249642)
							(end -0.2794 0.1778)
						)
						(arc
							(start -0.2794 -0.1778)
							(mid -0.249642 -0.249642)
							(end -0.1778 -0.2794)
						)
						(arc
							(start 0.1778 -0.2794)
							(mid 0.249642 -0.249642)
							(end 0.2794 -0.1778)
						)
						(arc
							(start 0.2794 0.1778)
							(mid 0.249642 0.249642)
							(end 0.1778 0.2794)
						)
					)
					(width 0)
					(fill yes)
				)
			)
		)
		(pad "2" smd custom
			(at 0 0.4445 180)
			(size 0.1397 0.1397)
			(layers "B.Cu" "B.Mask" "B.Paste")
			(net "BMC_SSD_RST#0_A7")
			(options
				(clearance outline)
				(anchor circle)
			)
			(primitives
				(gr_poly
					(pts
						(arc
							(start -0.1778 0.2794)
							(mid -0.249642 0.249642)
							(end -0.2794 0.1778)
						)
						(arc
							(start -0.2794 -0.1778)
							(mid -0.249642 -0.249642)
							(end -0.1778 -0.2794)
						)
						(arc
							(start 0.1778 -0.2794)
							(mid 0.249642 -0.249642)
							(end 0.2794 -0.1778)
						)
						(arc
							(start 0.2794 0.1778)
							(mid 0.249642 0.249642)
							(end 0.1778 0.2794)
						)
					)
					(width 0)
					(fill yes)
				)
			)
		)
	)
	(footprint ""
		(layer "B.Cu")
		(at 237.5408 -32.9946 -90)
		(property "Reference" "C467"
			(at 0 0 90)
			(layer "B.SilkS")
			(hide yes)
			(effects
				(font
					(size 1.27 1.27)
				)
				(justify mirror)
			)
		)
		(property "Value" "SCD1U16V1KX-1-GP"
			(at 2.8321 -1.7399 270)
			(unlocked yes)
			(layer "B.Fab")
			(hide yes)
			(effects
				(font
					(size 1.016 1.016)
					(thickness 0.1524)
				)
				(justify mirror)
			)
		)
		(property "Device Type" "C0201H13"
			(at 2.8321 -3.2639 270)
			(unlocked yes)
			(layer "B.Fab")
			(hide yes)
			(effects
				(font
					(size 1.016 1.016)
					(thickness 0.1524)
				)
				(justify mirror)
			)
		)
		(duplicate_pad_numbers_are_jumpers no)
		(fp_rect
			(start 0.2794 0.6477)
			(end -0.2794 -0.6477)
			(stroke
				(width 0)
				(type default)
			)
			(fill no)
			(layer "B.CrtYd")
		)
		(fp_rect
			(start 0.2794 0.6477)
			(end -0.2794 -0.6477)
			(stroke
				(width 0)
				(type default)
			)
			(fill no)
			(layer "B.Fab")
		)
		(pad "1" smd custom
			(at 0 -0.2794 90)
			(size 0.0762 0.0762)
			(layers "B.Cu" "B.Mask" "B.Paste")
			(net "DUT_VDDO_REF")
			(options
				(clearance outline)
				(anchor circle)
			)
			(primitives
				(gr_poly
					(pts
						(arc
							(start 0.1524 0.127)
							(mid 0.137521 0.162921)
							(end 0.1016 0.1778)
						)
						(arc
							(start -0.1016 0.1778)
							(mid -0.137521 0.162921)
							(end -0.1524 0.127)
						)
						(arc
							(start -0.1524 -0.127)
							(mid -0.137521 -0.162921)
							(end -0.1016 -0.1778)
						)
						(arc
							(start 0.1016 -0.1778)
							(mid 0.137521 -0.162921)
							(end 0.1524 -0.127)
						)
					)
					(width 0)
					(fill yes)
				)
			)
		)
		(pad "2" smd custom
			(at 0 0.2794 90)
			(size 0.0762 0.0762)
			(layers "B.Cu" "B.Mask" "B.Paste")
			(net "GND")
			(options
				(clearance outline)
				(anchor circle)
			)
			(primitives
				(gr_poly
					(pts
						(arc
							(start 0.1524 0.127)
							(mid 0.137521 0.162921)
							(end 0.1016 0.1778)
						)
						(arc
							(start -0.1016 0.1778)
							(mid -0.137521 0.162921)
							(end -0.1524 0.127)
						)
						(arc
							(start -0.1524 -0.127)
							(mid -0.137521 -0.162921)
							(end -0.1016 -0.1778)
						)
						(arc
							(start 0.1016 -0.1778)
							(mid 0.137521 -0.162921)
							(end 0.1524 -0.127)
						)
					)
					(width 0)
					(fill yes)
				)
			)
		)
	)
	(footprint ""
		(layer "B.Cu")
		(at 151.527002 -65.178432 90)
		(property "Reference" "PC195"
			(at 0 0 90)
			(layer "B.SilkS")
			(hide yes)
			(effects
				(font
					(size 1.27 1.27)
				)
				(justify mirror)
			)
		)
		(property "Value" "SC10U25V5KX-GP"
			(at 0.0762 -6.1214 90)
			(unlocked yes)
			(layer "B.Fab")
			(hide yes)
			(effects
				(font
					(size 1.016 1.016)
					(thickness 0.1524)
				)
				(justify mirror)
			)
		)
		(property "Device Type" "C805H56"
			(at 0.0762 -8.1534 90)
			(unlocked yes)
			(layer "B.Fab")
			(hide yes)
			(effects
				(font
					(size 1.016 1.016)
					(thickness 0.1524)
				)
				(justify mirror)
			)
		)
		(duplicate_pad_numbers_are_jumpers no)
		(fp_line
			(start -0.635 0)
			(end 0.635 0)
			(stroke
				(width 0.508)
				(type default)
			)
			(layer "B.SilkS")
		)
		(fp_rect
			(start 0.9652 1.778)
			(end -0.9652 -1.778)
			(stroke
				(width 0)
				(type default)
			)
			(fill no)
			(layer "B.CrtYd")
		)
		(fp_poly
			(pts
				(xy 0.9652 -1.778) (xy -0.9652 -1.778) (xy -0.9652 1.778) (xy 0.9652 1.778)
			)
			(stroke
				(width 0)
				(type default)
			)
			(fill no)
			(layer "B.Fab")
		)
		(pad "1" smd rect
			(at 0 -0.9652 270)
			(size 1.397 1.143)
			(layers "B.Cu" "B.Mask" "B.Paste")
			(net "P0V9_VIN")
		)
		(pad "2" smd rect
			(at 0 0.9652 270)
			(size 1.397 1.143)
			(layers "B.Cu" "B.Mask" "B.Paste")
			(net "GND")
		)
	)
	(footprint ""
		(layer "B.Cu")
		(at 235.1024 -54.0004 -90)
		(property "Reference" "C29"
			(at 0 0 90)
			(layer "B.SilkS")
			(hide yes)
			(effects
				(font
					(size 1.27 1.27)
				)
				(justify mirror)
			)
		)
		(property "Value" "SCD1U16V1KX-1-GP"
			(at 2.8321 -1.7399 270)
			(unlocked yes)
			(layer "B.Fab")
			(hide yes)
			(effects
				(font
					(size 1.016 1.016)
					(thickness 0.1524)
				)
				(justify mirror)
			)
		)
		(property "Device Type" "C0201H13"
			(at 2.8321 -3.2639 270)
			(unlocked yes)
			(layer "B.Fab")
			(hide yes)
			(effects
				(font
					(size 1.016 1.016)
					(thickness 0.1524)
				)
				(justify mirror)
			)
		)
		(duplicate_pad_numbers_are_jumpers no)
		(fp_rect
			(start 0.2794 0.6477)
			(end -0.2794 -0.6477)
			(stroke
				(width 0)
				(type default)
			)
			(fill no)
			(layer "B.CrtYd")
		)
		(fp_rect
			(start 0.2794 0.6477)
			(end -0.2794 -0.6477)
			(stroke
				(width 0)
				(type default)
			)
			(fill no)
			(layer "B.Fab")
		)
		(pad "1" smd custom
			(at 0 -0.2794 90)
			(size 0.0762 0.0762)
			(layers "B.Cu" "B.Mask" "B.Paste")
			(net "DUT_VDD")
			(options
				(clearance outline)
				(anchor circle)
			)
			(primitives
				(gr_poly
					(pts
						(arc
							(start 0.1524 0.127)
							(mid 0.137521 0.162921)
							(end 0.1016 0.1778)
						)
						(arc
							(start -0.1016 0.1778)
							(mid -0.137521 0.162921)
							(end -0.1524 0.127)
						)
						(arc
							(start -0.1524 -0.127)
							(mid -0.137521 -0.162921)
							(end -0.1016 -0.1778)
						)
						(arc
							(start 0.1016 -0.1778)
							(mid 0.137521 -0.162921)
							(end 0.1524 -0.127)
						)
					)
					(width 0)
					(fill yes)
				)
			)
		)
		(pad "2" smd custom
			(at 0 0.2794 90)
			(size 0.0762 0.0762)
			(layers "B.Cu" "B.Mask" "B.Paste")
			(net "GND")
			(options
				(clearance outline)
				(anchor circle)
			)
			(primitives
				(gr_poly
					(pts
						(arc
							(start 0.1524 0.127)
							(mid 0.137521 0.162921)
							(end 0.1016 0.1778)
						)
						(arc
							(start -0.1016 0.1778)
							(mid -0.137521 0.162921)
							(end -0.1524 0.127)
						)
						(arc
							(start -0.1524 -0.127)
							(mid -0.137521 -0.162921)
							(end -0.1016 -0.1778)
						)
						(arc
							(start 0.1016 -0.1778)
							(mid 0.137521 -0.162921)
							(end 0.1524 -0.127)
						)
					)
					(width 0)
					(fill yes)
				)
			)
		)
	)
	(footprint ""
		(layer "B.Cu")
		(at 37.32784 -126.95682 180)
		(property "Reference" "C218"
			(at 0 0 0)
			(layer "B.SilkS")
			(hide yes)
			(effects
				(font
					(size 1.27 1.27)
				)
				(justify mirror)
			)
		)
		(property "Value" "SC1U10V2KX-4-GP"
			(at -1.1811 -2.7051 180)
			(unlocked yes)
			(layer "B.Fab")
			(hide yes)
			(effects
				(font
					(size 1.016 1.016)
					(thickness 0.1524)
				)
				(justify mirror)
			)
		)
		(property "Device Type" "C402H22"
			(at -1.1811 -4.2291 180)
			(unlocked yes)
			(layer "B.Fab")
			(hide yes)
			(effects
				(font
					(size 1.016 1.016)
					(thickness 0.1524)
				)
				(justify mirror)
			)
		)
		(duplicate_pad_numbers_are_jumpers no)
		(fp_rect
			(start 0.4318 0.9525)
			(end -0.4318 -0.9525)
			(stroke
				(width 0)
				(type default)
			)
			(fill no)
			(layer "B.CrtYd")
		)
		(fp_rect
			(start 0.4318 0.9525)
			(end -0.4318 -0.9525)
			(stroke
				(width 0)
				(type default)
			)
			(fill no)
			(layer "B.Fab")
		)
		(pad "1" smd custom
			(at 0 -0.4445)
			(size 0.1524 0.1524)
			(layers "B.Cu" "B.Mask" "B.Paste")
			(net "P3V3_STBY")
			(options
				(clearance outline)
				(anchor circle)
			)
			(primitives
				(gr_poly
					(pts
						(arc
							(start 0.3048 0.2032)
							(mid 0.275042 0.275042)
							(end 0.2032 0.3048)
						)
						(arc
							(start -0.2032 0.3048)
							(mid -0.275042 0.275042)
							(end -0.3048 0.2032)
						)
						(arc
							(start -0.3048 -0.2032)
							(mid -0.275042 -0.275042)
							(end -0.2032 -0.3048)
						)
						(arc
							(start 0.2032 -0.3048)
							(mid 0.275042 -0.275042)
							(end 0.3048 -0.2032)
						)
					)
					(width 0)
					(fill yes)
				)
			)
		)
		(pad "2" smd custom
			(at 0 0.4445)
			(size 0.1524 0.1524)
			(layers "B.Cu" "B.Mask" "B.Paste")
			(net "GND")
			(options
				(clearance outline)
				(anchor circle)
			)
			(primitives
				(gr_poly
					(pts
						(arc
							(start 0.3048 0.2032)
							(mid 0.275042 0.275042)
							(end 0.2032 0.3048)
						)
						(arc
							(start -0.2032 0.3048)
							(mid -0.275042 0.275042)
							(end -0.3048 0.2032)
						)
						(arc
							(start -0.3048 -0.2032)
							(mid -0.275042 -0.275042)
							(end -0.2032 -0.3048)
						)
						(arc
							(start 0.2032 -0.3048)
							(mid 0.275042 -0.275042)
							(end 0.3048 -0.2032)
						)
					)
					(width 0)
					(fill yes)
				)
			)
		)
	)
	(footprint ""
		(layer "B.Cu")
		(at 318.135 -68.58 180)
		(property "Reference" "PC181"
			(at 0 0 0)
			(layer "B.SilkS")
			(hide yes)
			(effects
				(font
					(size 1.27 1.27)
				)
				(justify mirror)
			)
		)
		(property "Value" "SC22U6D3V5MX-5-GP"
			(at 0.0762 -6.1214 180)
			(unlocked yes)
			(layer "B.Fab")
			(hide yes)
			(effects
				(font
					(size 1.016 1.016)
					(thickness 0.1524)
				)
				(justify mirror)
			)
		)
		(property "Device Type" "C805H56"
			(at 0.0762 -8.1534 180)
			(unlocked yes)
			(layer "B.Fab")
			(hide yes)
			(effects
				(font
					(size 1.016 1.016)
					(thickness 0.1524)
				)
				(justify mirror)
			)
		)
		(duplicate_pad_numbers_are_jumpers no)
		(fp_line
			(start -0.635 0)
			(end 0.635 0)
			(stroke
				(width 0.508)
				(type default)
			)
			(layer "B.SilkS")
		)
		(fp_rect
			(start 0.9652 1.778)
			(end -0.9652 -1.778)
			(stroke
				(width 0)
				(type default)
			)
			(fill no)
			(layer "B.CrtYd")
		)
		(fp_poly
			(pts
				(xy 0.9652 -1.778) (xy -0.9652 -1.778) (xy -0.9652 1.778) (xy 0.9652 1.778)
			)
			(stroke
				(width 0)
				(type default)
			)
			(fill no)
			(layer "B.Fab")
		)
		(pad "1" smd rect
			(at 0 -0.9652)
			(size 1.397 1.143)
			(layers "B.Cu" "B.Mask" "B.Paste")
			(net "P0V9_E")
		)
		(pad "2" smd rect
			(at 0 0.9652)
			(size 1.397 1.143)
			(layers "B.Cu" "B.Mask" "B.Paste")
			(net "GND")
		)
	)
	(footprint ""
		(layer "B.Cu")
		(at 125.960124 -196.443092)
		(property "Reference" "R4129"
			(at 0 0 0)
			(layer "B.SilkS")
			(hide yes)
			(effects
				(font
					(size 1.27 1.27)
				)
				(justify mirror)
			)
		)
		(property "Value" "4K7R2F-GP"
			(at -0.064008 -3.993896 0)
			(unlocked yes)
			(layer "B.Fab")
			(hide yes)
			(effects
				(font
					(size 1.016 1.016)
					(thickness 0.1524)
				)
				(justify mirror)
			)
		)
		(property "Device Type" "R402H16"
			(at -0.064008 -5.517896 0)
			(unlocked yes)
			(layer "B.Fab")
			(hide yes)
			(effects
				(font
					(size 1.016 1.016)
					(thickness 0.1524)
				)
				(justify mirror)
			)
		)
		(duplicate_pad_numbers_are_jumpers no)
		(fp_line
			(start -0.508 -0.9398)
			(end 0.508 -0.9398)
			(stroke
				(width 0.1524)
				(type default)
			)
			(layer "B.SilkS")
		)
		(fp_line
			(start 0.508 -0.9398)
			(end 0.508 0.9398)
			(stroke
				(width 0.1524)
				(type default)
			)
			(layer "B.SilkS")
		)
		(fp_rect
			(start 0.508 0.9398)
			(end -0.508 -0.9398)
			(stroke
				(width 0)
				(type default)
			)
			(fill no)
			(layer "B.CrtYd")
		)
		(fp_rect
			(start 0.508 0.9398)
			(end -0.508 -0.9398)
			(stroke
				(width 0)
				(type default)
			)
			(fill no)
			(layer "B.Fab")
		)
		(pad "1" smd custom
			(at 0 -0.4445 180)
			(size 0.1397 0.1397)
			(layers "B.Cu" "B.Mask" "B.Paste")
			(net "SSD_PRSNT#1")
			(options
				(clearance outline)
				(anchor circle)
			)
			(primitives
				(gr_poly
					(pts
						(arc
							(start -0.1778 0.2794)
							(mid -0.249642 0.249642)
							(end -0.2794 0.1778)
						)
						(arc
							(start -0.2794 -0.1778)
							(mid -0.249642 -0.249642)
							(end -0.1778 -0.2794)
						)
						(arc
							(start 0.1778 -0.2794)
							(mid 0.249642 -0.249642)
							(end 0.2794 -0.1778)
						)
						(arc
							(start 0.2794 0.1778)
							(mid 0.249642 0.249642)
							(end 0.1778 0.2794)
						)
					)
					(width 0)
					(fill yes)
				)
			)
		)
		(pad "2" smd custom
			(at 0 0.4445 180)
			(size 0.1397 0.1397)
			(layers "B.Cu" "B.Mask" "B.Paste")
			(net "P3V3_STBY")
			(options
				(clearance outline)
				(anchor circle)
			)
			(primitives
				(gr_poly
					(pts
						(arc
							(start -0.1778 0.2794)
							(mid -0.249642 0.249642)
							(end -0.2794 0.1778)
						)
						(arc
							(start -0.2794 -0.1778)
							(mid -0.249642 -0.249642)
							(end -0.1778 -0.2794)
						)
						(arc
							(start 0.1778 -0.2794)
							(mid 0.249642 -0.249642)
							(end 0.2794 -0.1778)
						)
						(arc
							(start 0.2794 0.1778)
							(mid 0.249642 0.249642)
							(end 0.1778 0.2794)
						)
					)
					(width 0)
					(fill yes)
				)
			)
		)
	)
	(footprint ""
		(layer "B.Cu")
		(at 27.94 -73.533 180)
		(property "Reference" "PR66"
			(at 0 0 0)
			(layer "B.SilkS")
			(hide yes)
			(effects
				(font
					(size 1.27 1.27)
				)
				(justify mirror)
			)
		)
		(property "Value" "10KR2F-2-GP"
			(at -0.064008 -3.993896 180)
			(unlocked yes)
			(layer "B.Fab")
			(hide yes)
			(effects
				(font
					(size 1.016 1.016)
					(thickness 0.1524)
				)
				(justify mirror)
			)
		)
		(property "Device Type" "R402H16"
			(at -0.064008 -5.517896 180)
			(unlocked yes)
			(layer "B.Fab")
			(hide yes)
			(effects
				(font
					(size 1.016 1.016)
					(thickness 0.1524)
				)
				(justify mirror)
			)
		)
		(duplicate_pad_numbers_are_jumpers no)
		(fp_line
			(start 0.508 -0.9398)
			(end 0.508 0.9398)
			(stroke
				(width 0.1524)
				(type default)
			)
			(layer "B.SilkS")
		)
		(fp_line
			(start -0.508 -0.9398)
			(end 0.508 -0.9398)
			(stroke
				(width 0.1524)
				(type default)
			)
			(layer "B.SilkS")
		)
		(fp_rect
			(start 0.508 0.9398)
			(end -0.508 -0.9398)
			(stroke
				(width 0)
				(type default)
			)
			(fill no)
			(layer "B.CrtYd")
		)
		(fp_rect
			(start 0.508 0.9398)
			(end -0.508 -0.9398)
			(stroke
				(width 0)
				(type default)
			)
			(fill no)
			(layer "B.Fab")
		)
		(pad "1" smd custom
			(at 0 -0.4445)
			(size 0.1397 0.1397)
			(layers "B.Cu" "B.Mask" "B.Paste")
			(net "P5V_STBY_EN")
			(options
				(clearance outline)
				(anchor circle)
			)
			(primitives
				(gr_poly
					(pts
						(arc
							(start -0.1778 0.2794)
							(mid -0.249642 0.249642)
							(end -0.2794 0.1778)
						)
						(arc
							(start -0.2794 -0.1778)
							(mid -0.249642 -0.249642)
							(end -0.1778 -0.2794)
						)
						(arc
							(start 0.1778 -0.2794)
							(mid 0.249642 -0.249642)
							(end 0.2794 -0.1778)
						)
						(arc
							(start 0.2794 0.1778)
							(mid 0.249642 0.249642)
							(end 0.1778 0.2794)
						)
					)
					(width 0)
					(fill yes)
				)
			)
		)
		(pad "2" smd custom
			(at 0 0.4445)
			(size 0.1397 0.1397)
			(layers "B.Cu" "B.Mask" "B.Paste")
			(net "GND")
			(options
				(clearance outline)
				(anchor circle)
			)
			(primitives
				(gr_poly
					(pts
						(arc
							(start -0.1778 0.2794)
							(mid -0.249642 0.249642)
							(end -0.2794 0.1778)
						)
						(arc
							(start -0.2794 -0.1778)
							(mid -0.249642 -0.249642)
							(end -0.1778 -0.2794)
						)
						(arc
							(start 0.1778 -0.2794)
							(mid 0.249642 -0.249642)
							(end 0.2794 -0.1778)
						)
						(arc
							(start 0.2794 0.1778)
							(mid 0.249642 0.249642)
							(end 0.1778 0.2794)
						)
					)
					(width 0)
					(fill yes)
				)
			)
		)
	)
	(footprint ""
		(layer "B.Cu")
		(at 34.163 -118.364)
		(property "Reference" "TP226"
			(at 0 0 0)
			(layer "B.SilkS")
			(hide yes)
			(effects
				(font
					(size 1.27 1.27)
				)
				(justify mirror)
			)
		)
		(property "Value" "TPAD28-2-GP"
			(at 0.0127 -1.6637 0)
			(unlocked yes)
			(layer "B.Fab")
			(hide yes)
			(effects
				(font
					(size 1.016 1.016)
					(thickness 0.1524)
				)
				(justify mirror)
			)
		)
		(property "Device Type" "TPAD28"
			(at 0.0127 -3.1877 0)
			(unlocked yes)
			(layer "B.Fab")
			(hide yes)
			(effects
				(font
					(size 1.016 1.016)
					(thickness 0.1524)
				)
				(justify mirror)
			)
		)
		(duplicate_pad_numbers_are_jumpers no)
		(fp_poly
			(pts
				(arc
					(start 0.3556 0)
					(mid -0.3556 0)
					(end 0.3556 0)
				)
			)
			(stroke
				(width 0)
				(type default)
			)
			(fill no)
			(layer "B.CrtYd")
		)
		(fp_poly
			(pts
				(arc
					(start 0.6096 0)
					(mid -0.6096 0)
					(end 0.6096 0)
				)
			)
			(stroke
				(width 0)
				(type default)
			)
			(fill no)
			(layer "B.Fab")
		)
		(pad "1" smd circle
			(at 0 0 180)
			(size 0.7112 0.7112)
			(layers "B.Cu" "B.Mask" "B.Paste")
			(net "TP_GPIOE1")
		)
	)
	(footprint ""
		(layer "B.Cu")
		(at 8.9154 -68.2752 -90)
		(property "Reference" "C423"
			(at 0 0 90)
			(layer "B.SilkS")
			(hide yes)
			(effects
				(font
					(size 1.27 1.27)
				)
				(justify mirror)
			)
		)
		(property "Value" "SC47U4V5MX-2-GP"
			(at 0.0762 -6.1214 270)
			(unlocked yes)
			(layer "B.Fab")
			(hide yes)
			(effects
				(font
					(size 1.016 1.016)
					(thickness 0.1524)
				)
				(justify mirror)
			)
		)
		(property "Device Type" "C805H58"
			(at 0.0762 -8.1534 270)
			(unlocked yes)
			(layer "B.Fab")
			(hide yes)
			(effects
				(font
					(size 1.016 1.016)
					(thickness 0.1524)
				)
				(justify mirror)
			)
		)
		(duplicate_pad_numbers_are_jumpers no)
		(fp_line
			(start -0.635 0)
			(end 0.635 0)
			(stroke
				(width 0.508)
				(type default)
			)
			(layer "B.SilkS")
		)
		(fp_rect
			(start 0.9652 1.778)
			(end -0.9652 -1.778)
			(stroke
				(width 0)
				(type default)
			)
			(fill no)
			(layer "B.CrtYd")
		)
		(fp_poly
			(pts
				(xy 0.9652 -1.778) (xy -0.9652 -1.778) (xy -0.9652 1.778) (xy 0.9652 1.778)
			)
			(stroke
				(width 0)
				(type default)
			)
			(fill no)
			(layer "B.Fab")
		)
		(pad "1" smd rect
			(at 0 -0.9652 90)
			(size 1.397 1.143)
			(layers "B.Cu" "B.Mask" "B.Paste")
			(net "P1V5_I210")
		)
		(pad "2" smd rect
			(at 0 0.9652 90)
			(size 1.397 1.143)
			(layers "B.Cu" "B.Mask" "B.Paste")
			(net "GND")
		)
	)
	(footprint ""
		(layer "B.Cu")
		(at 247.5992 -60.071)
		(property "Reference" "C602"
			(at 0 0 0)
			(layer "B.SilkS")
			(hide yes)
			(effects
				(font
					(size 1.27 1.27)
				)
				(justify mirror)
			)
		)
		(property "Value" "SCD1U16V1KX-1-GP"
			(at 2.8321 -1.7399 0)
			(unlocked yes)
			(layer "B.Fab")
			(hide yes)
			(effects
				(font
					(size 1.016 1.016)
					(thickness 0.1524)
				)
				(justify mirror)
			)
		)
		(property "Device Type" "C0201H13"
			(at 2.8321 -3.2639 0)
			(unlocked yes)
			(layer "B.Fab")
			(hide yes)
			(effects
				(font
					(size 1.016 1.016)
					(thickness 0.1524)
				)
				(justify mirror)
			)
		)
		(duplicate_pad_numbers_are_jumpers no)
		(fp_rect
			(start 0.2794 0.6477)
			(end -0.2794 -0.6477)
			(stroke
				(width 0)
				(type default)
			)
			(fill no)
			(layer "B.CrtYd")
		)
		(fp_rect
			(start 0.2794 0.6477)
			(end -0.2794 -0.6477)
			(stroke
				(width 0)
				(type default)
			)
			(fill no)
			(layer "B.Fab")
		)
		(pad "1" smd custom
			(at 0 -0.2794 180)
			(size 0.0762 0.0762)
			(layers "B.Cu" "B.Mask" "B.Paste")
			(net "DUT_AVD_PCIE")
			(options
				(clearance outline)
				(anchor circle)
			)
			(primitives
				(gr_poly
					(pts
						(arc
							(start 0.1524 0.127)
							(mid 0.137521 0.162921)
							(end 0.1016 0.1778)
						)
						(arc
							(start -0.1016 0.1778)
							(mid -0.137521 0.162921)
							(end -0.1524 0.127)
						)
						(arc
							(start -0.1524 -0.127)
							(mid -0.137521 -0.162921)
							(end -0.1016 -0.1778)
						)
						(arc
							(start 0.1016 -0.1778)
							(mid 0.137521 -0.162921)
							(end 0.1524 -0.127)
						)
					)
					(width 0)
					(fill yes)
				)
			)
		)
		(pad "2" smd custom
			(at 0 0.2794 180)
			(size 0.0762 0.0762)
			(layers "B.Cu" "B.Mask" "B.Paste")
			(net "GND")
			(options
				(clearance outline)
				(anchor circle)
			)
			(primitives
				(gr_poly
					(pts
						(arc
							(start 0.1524 0.127)
							(mid 0.137521 0.162921)
							(end 0.1016 0.1778)
						)
						(arc
							(start -0.1016 0.1778)
							(mid -0.137521 0.162921)
							(end -0.1524 0.127)
						)
						(arc
							(start -0.1524 -0.127)
							(mid -0.137521 -0.162921)
							(end -0.1016 -0.1778)
						)
						(arc
							(start 0.1016 -0.1778)
							(mid 0.137521 -0.162921)
							(end 0.1524 -0.127)
						)
					)
					(width 0)
					(fill yes)
				)
			)
		)
	)
	(footprint ""
		(layer "B.Cu")
		(at 146.930618 -33.53562)
		(property "Reference" "R2928"
			(at 0 0 0)
			(layer "B.SilkS")
			(hide yes)
			(effects
				(font
					(size 1.27 1.27)
				)
				(justify mirror)
			)
		)
		(property "Value" "0R2J-2-GP"
			(at -0.064008 -3.993896 0)
			(unlocked yes)
			(layer "B.Fab")
			(hide yes)
			(effects
				(font
					(size 1.016 1.016)
					(thickness 0.1524)
				)
				(justify mirror)
			)
		)
		(property "Device Type" "R402H16"
			(at -0.064008 -5.517896 0)
			(unlocked yes)
			(layer "B.Fab")
			(hide yes)
			(effects
				(font
					(size 1.016 1.016)
					(thickness 0.1524)
				)
				(justify mirror)
			)
		)
		(duplicate_pad_numbers_are_jumpers no)
		(fp_line
			(start -0.508 -0.9398)
			(end 0.508 -0.9398)
			(stroke
				(width 0.1524)
				(type default)
			)
			(layer "B.SilkS")
		)
		(fp_line
			(start 0.508 -0.9398)
			(end 0.508 0.9398)
			(stroke
				(width 0.1524)
				(type default)
			)
			(layer "B.SilkS")
		)
		(fp_rect
			(start 0.508 0.9398)
			(end -0.508 -0.9398)
			(stroke
				(width 0)
				(type default)
			)
			(fill no)
			(layer "B.CrtYd")
		)
		(fp_rect
			(start 0.508 0.9398)
			(end -0.508 -0.9398)
			(stroke
				(width 0)
				(type default)
			)
			(fill no)
			(layer "B.Fab")
		)
		(pad "1" smd custom
			(at 0 -0.4445 180)
			(size 0.1397 0.1397)
			(layers "B.Cu" "B.Mask" "B.Paste")
			(net "BMC_I2C2_MINI2_SDA")
			(options
				(clearance outline)
				(anchor circle)
			)
			(primitives
				(gr_poly
					(pts
						(arc
							(start -0.1778 0.2794)
							(mid -0.249642 0.249642)
							(end -0.2794 0.1778)
						)
						(arc
							(start -0.2794 -0.1778)
							(mid -0.249642 -0.249642)
							(end -0.1778 -0.2794)
						)
						(arc
							(start 0.1778 -0.2794)
							(mid 0.249642 -0.249642)
							(end 0.2794 -0.1778)
						)
						(arc
							(start 0.2794 0.1778)
							(mid 0.249642 0.249642)
							(end 0.1778 0.2794)
						)
					)
					(width 0)
					(fill yes)
				)
			)
		)
		(pad "2" smd custom
			(at 0 0.4445 180)
			(size 0.1397 0.1397)
			(layers "B.Cu" "B.Mask" "B.Paste")
			(net "8644_CBL_PRSNT_R_2")
			(options
				(clearance outline)
				(anchor circle)
			)
			(primitives
				(gr_poly
					(pts
						(arc
							(start -0.1778 0.2794)
							(mid -0.249642 0.249642)
							(end -0.2794 0.1778)
						)
						(arc
							(start -0.2794 -0.1778)
							(mid -0.249642 -0.249642)
							(end -0.1778 -0.2794)
						)
						(arc
							(start 0.1778 -0.2794)
							(mid 0.249642 -0.249642)
							(end 0.2794 -0.1778)
						)
						(arc
							(start 0.2794 0.1778)
							(mid 0.249642 0.249642)
							(end 0.1778 0.2794)
						)
					)
					(width 0)
					(fill yes)
				)
			)
		)
	)
	(footprint ""
		(layer "B.Cu")
		(at 229.599998 -36.999164 -90)
		(property "Reference" "TP124"
			(at 0 0 90)
			(layer "B.SilkS")
			(hide yes)
			(effects
				(font
					(size 1.27 1.27)
				)
				(justify mirror)
			)
		)
		(property "Value" "TPAD28-2-GP"
			(at 0.0127 -1.6637 270)
			(unlocked yes)
			(layer "B.Fab")
			(hide yes)
			(effects
				(font
					(size 1.016 1.016)
					(thickness 0.1524)
				)
				(justify mirror)
			)
		)
		(property "Device Type" "TPAD28"
			(at 0.0127 -3.1877 270)
			(unlocked yes)
			(layer "B.Fab")
			(hide yes)
			(effects
				(font
					(size 1.016 1.016)
					(thickness 0.1524)
				)
				(justify mirror)
			)
		)
		(duplicate_pad_numbers_are_jumpers no)
		(fp_poly
			(pts
				(arc
					(start 0 -0.3556)
					(mid 0 0.3556)
					(end 0 -0.3556)
				)
			)
			(stroke
				(width 0)
				(type default)
			)
			(fill no)
			(layer "B.CrtYd")
		)
		(fp_poly
			(pts
				(arc
					(start 0 -0.6096)
					(mid 0 0.6096)
					(end 0 -0.6096)
				)
			)
			(stroke
				(width 0)
				(type default)
			)
			(fill no)
			(layer "B.Fab")
		)
		(pad "1" smd circle
			(at 0 0 90)
			(size 0.7112 0.7112)
			(layers "B.Cu" "B.Mask" "B.Paste")
			(net "LBI_DATA10")
		)
	)
	(footprint ""
		(layer "B.Cu")
		(at 228.6254 -43.997372 90)
		(property "Reference" "C573"
			(at 0 0 90)
			(layer "B.SilkS")
			(hide yes)
			(effects
				(font
					(size 1.27 1.27)
				)
				(justify mirror)
			)
		)
		(property "Value" "SCD1U16V1KX-1-GP"
			(at 2.8321 -1.7399 90)
			(unlocked yes)
			(layer "B.Fab")
			(hide yes)
			(effects
				(font
					(size 1.016 1.016)
					(thickness 0.1524)
				)
				(justify mirror)
			)
		)
		(property "Device Type" "C0201H13"
			(at 2.8321 -3.2639 90)
			(unlocked yes)
			(layer "B.Fab")
			(hide yes)
			(effects
				(font
					(size 1.016 1.016)
					(thickness 0.1524)
				)
				(justify mirror)
			)
		)
		(duplicate_pad_numbers_are_jumpers no)
		(fp_rect
			(start 0.2794 0.6477)
			(end -0.2794 -0.6477)
			(stroke
				(width 0)
				(type default)
			)
			(fill no)
			(layer "B.CrtYd")
		)
		(fp_rect
			(start 0.2794 0.6477)
			(end -0.2794 -0.6477)
			(stroke
				(width 0)
				(type default)
			)
			(fill no)
			(layer "B.Fab")
		)
		(pad "1" smd custom
			(at 0 -0.2794 270)
			(size 0.0762 0.0762)
			(layers "B.Cu" "B.Mask" "B.Paste")
			(net "DUT_AVD_PCIE")
			(options
				(clearance outline)
				(anchor circle)
			)
			(primitives
				(gr_poly
					(pts
						(arc
							(start 0.1524 0.127)
							(mid 0.137521 0.162921)
							(end 0.1016 0.1778)
						)
						(arc
							(start -0.1016 0.1778)
							(mid -0.137521 0.162921)
							(end -0.1524 0.127)
						)
						(arc
							(start -0.1524 -0.127)
							(mid -0.137521 -0.162921)
							(end -0.1016 -0.1778)
						)
						(arc
							(start 0.1016 -0.1778)
							(mid 0.137521 -0.162921)
							(end 0.1524 -0.127)
						)
					)
					(width 0)
					(fill yes)
				)
			)
		)
		(pad "2" smd custom
			(at 0 0.2794 270)
			(size 0.0762 0.0762)
			(layers "B.Cu" "B.Mask" "B.Paste")
			(net "GND")
			(options
				(clearance outline)
				(anchor circle)
			)
			(primitives
				(gr_poly
					(pts
						(arc
							(start 0.1524 0.127)
							(mid 0.137521 0.162921)
							(end 0.1016 0.1778)
						)
						(arc
							(start -0.1016 0.1778)
							(mid -0.137521 0.162921)
							(end -0.1524 0.127)
						)
						(arc
							(start -0.1524 -0.127)
							(mid -0.137521 -0.162921)
							(end -0.1016 -0.1778)
						)
						(arc
							(start 0.1016 -0.1778)
							(mid 0.137521 -0.162921)
							(end 0.1524 -0.127)
						)
					)
					(width 0)
					(fill yes)
				)
			)
		)
	)
	(footprint ""
		(layer "B.Cu")
		(at 242.599972 -35.999928 90)
		(property "Reference" "TP164"
			(at 0 0 90)
			(layer "B.SilkS")
			(hide yes)
			(effects
				(font
					(size 1.27 1.27)
				)
				(justify mirror)
			)
		)
		(property "Value" "TPAD28-2-GP"
			(at 0.0127 -1.6637 90)
			(unlocked yes)
			(layer "B.Fab")
			(hide yes)
			(effects
				(font
					(size 1.016 1.016)
					(thickness 0.1524)
				)
				(justify mirror)
			)
		)
		(property "Device Type" "TPAD28"
			(at 0.0127 -3.1877 90)
			(unlocked yes)
			(layer "B.Fab")
			(hide yes)
			(effects
				(font
					(size 1.016 1.016)
					(thickness 0.1524)
				)
				(justify mirror)
			)
		)
		(duplicate_pad_numbers_are_jumpers no)
		(fp_poly
			(pts
				(arc
					(start 0 0.3556)
					(mid 0 -0.3556)
					(end 0 0.3556)
				)
			)
			(stroke
				(width 0)
				(type default)
			)
			(fill no)
			(layer "B.CrtYd")
		)
		(fp_poly
			(pts
				(arc
					(start 0 0.6096)
					(mid 0 -0.6096)
					(end 0 0.6096)
				)
			)
			(stroke
				(width 0)
				(type default)
			)
			(fill no)
			(layer "B.Fab")
		)
		(pad "1" smd circle
			(at 0 0 270)
			(size 0.7112 0.7112)
			(layers "B.Cu" "B.Mask" "B.Paste")
			(net "LBI_BYTEN#")
		)
	)
	(footprint ""
		(layer "B.Cu")
		(at 243.59997 -32.999934)
		(property "Reference" "TP222"
			(at 0 0 0)
			(layer "B.SilkS")
			(hide yes)
			(effects
				(font
					(size 1.27 1.27)
				)
				(justify mirror)
			)
		)
		(property "Value" "TPAD28-2-GP"
			(at 0.0127 -1.6637 0)
			(unlocked yes)
			(layer "B.Fab")
			(hide yes)
			(effects
				(font
					(size 1.016 1.016)
					(thickness 0.1524)
				)
				(justify mirror)
			)
		)
		(property "Device Type" "TPAD28"
			(at 0.0127 -3.1877 0)
			(unlocked yes)
			(layer "B.Fab")
			(hide yes)
			(effects
				(font
					(size 1.016 1.016)
					(thickness 0.1524)
				)
				(justify mirror)
			)
		)
		(duplicate_pad_numbers_are_jumpers no)
		(fp_poly
			(pts
				(arc
					(start 0.3556 0)
					(mid -0.3556 0)
					(end 0.3556 0)
				)
			)
			(stroke
				(width 0)
				(type default)
			)
			(fill no)
			(layer "B.CrtYd")
		)
		(fp_poly
			(pts
				(arc
					(start 0.6096 0)
					(mid -0.6096 0)
					(end 0.6096 0)
				)
			)
			(stroke
				(width 0)
				(type default)
			)
			(fill no)
			(layer "B.Fab")
		)
		(pad "1" smd circle
			(at 0 0 180)
			(size 0.7112 0.7112)
			(layers "B.Cu" "B.Mask" "B.Paste")
			(net "LBI_DATA_3")
		)
	)
	(footprint ""
		(layer "B.Cu")
		(at 235.331 -69.85 -90)
		(property "Reference" "C494"
			(at 0 0 90)
			(layer "B.SilkS")
			(hide yes)
			(effects
				(font
					(size 1.27 1.27)
				)
				(justify mirror)
			)
		)
		(property "Value" "SC100U4V5MX-1-GP"
			(at 0.0762 -6.1214 270)
			(unlocked yes)
			(layer "B.Fab")
			(hide yes)
			(effects
				(font
					(size 1.016 1.016)
					(thickness 0.1524)
				)
				(justify mirror)
			)
		)
		(property "Device Type" "C805H58"
			(at 0.0762 -8.1534 270)
			(unlocked yes)
			(layer "B.Fab")
			(hide yes)
			(effects
				(font
					(size 1.016 1.016)
					(thickness 0.1524)
				)
				(justify mirror)
			)
		)
		(duplicate_pad_numbers_are_jumpers no)
		(fp_line
			(start -0.635 0)
			(end 0.635 0)
			(stroke
				(width 0.508)
				(type default)
			)
			(layer "B.SilkS")
		)
		(fp_rect
			(start 0.9652 1.778)
			(end -0.9652 -1.778)
			(stroke
				(width 0)
				(type default)
			)
			(fill no)
			(layer "B.CrtYd")
		)
		(fp_poly
			(pts
				(xy 0.9652 -1.778) (xy -0.9652 -1.778) (xy -0.9652 1.778) (xy 0.9652 1.778)
			)
			(stroke
				(width 0)
				(type default)
			)
			(fill no)
			(layer "B.Fab")
		)
		(pad "1" smd rect
			(at 0 -0.9652 90)
			(size 1.397 1.143)
			(layers "B.Cu" "B.Mask" "B.Paste")
			(net "DUT_AVD_TX")
		)
		(pad "2" smd rect
			(at 0 0.9652 90)
			(size 1.397 1.143)
			(layers "B.Cu" "B.Mask" "B.Paste")
			(net "GND")
		)
	)
	(footprint ""
		(layer "B.Cu")
		(at 237.617 -56.9976 90)
		(property "Reference" "C520"
			(at 0 0 90)
			(layer "B.SilkS")
			(hide yes)
			(effects
				(font
					(size 1.27 1.27)
				)
				(justify mirror)
			)
		)
		(property "Value" "SCD1U16V1KX-1-GP"
			(at 2.8321 -1.7399 90)
			(unlocked yes)
			(layer "B.Fab")
			(hide yes)
			(effects
				(font
					(size 1.016 1.016)
					(thickness 0.1524)
				)
				(justify mirror)
			)
		)
		(property "Device Type" "C0201H13"
			(at 2.8321 -3.2639 90)
			(unlocked yes)
			(layer "B.Fab")
			(hide yes)
			(effects
				(font
					(size 1.016 1.016)
					(thickness 0.1524)
				)
				(justify mirror)
			)
		)
		(duplicate_pad_numbers_are_jumpers no)
		(fp_rect
			(start 0.2794 0.6477)
			(end -0.2794 -0.6477)
			(stroke
				(width 0)
				(type default)
			)
			(fill no)
			(layer "B.CrtYd")
		)
		(fp_rect
			(start 0.2794 0.6477)
			(end -0.2794 -0.6477)
			(stroke
				(width 0)
				(type default)
			)
			(fill no)
			(layer "B.Fab")
		)
		(pad "1" smd custom
			(at 0 -0.2794 270)
			(size 0.0762 0.0762)
			(layers "B.Cu" "B.Mask" "B.Paste")
			(net "DUT_AVD_TX")
			(options
				(clearance outline)
				(anchor circle)
			)
			(primitives
				(gr_poly
					(pts
						(arc
							(start 0.1524 0.127)
							(mid 0.137521 0.162921)
							(end 0.1016 0.1778)
						)
						(arc
							(start -0.1016 0.1778)
							(mid -0.137521 0.162921)
							(end -0.1524 0.127)
						)
						(arc
							(start -0.1524 -0.127)
							(mid -0.137521 -0.162921)
							(end -0.1016 -0.1778)
						)
						(arc
							(start 0.1016 -0.1778)
							(mid 0.137521 -0.162921)
							(end 0.1524 -0.127)
						)
					)
					(width 0)
					(fill yes)
				)
			)
		)
		(pad "2" smd custom
			(at 0 0.2794 270)
			(size 0.0762 0.0762)
			(layers "B.Cu" "B.Mask" "B.Paste")
			(net "GND")
			(options
				(clearance outline)
				(anchor circle)
			)
			(primitives
				(gr_poly
					(pts
						(arc
							(start 0.1524 0.127)
							(mid 0.137521 0.162921)
							(end 0.1016 0.1778)
						)
						(arc
							(start -0.1016 0.1778)
							(mid -0.137521 0.162921)
							(end -0.1524 0.127)
						)
						(arc
							(start -0.1524 -0.127)
							(mid -0.137521 -0.162921)
							(end -0.1016 -0.1778)
						)
						(arc
							(start 0.1016 -0.1778)
							(mid 0.137521 -0.162921)
							(end 0.1524 -0.127)
						)
					)
					(width 0)
					(fill yes)
				)
			)
		)
	)
	(footprint ""
		(layer "B.Cu")
		(at 249.555 -54.99227 90)
		(property "Reference" "C488"
			(at 0 0 90)
			(layer "B.SilkS")
			(hide yes)
			(effects
				(font
					(size 1.27 1.27)
				)
				(justify mirror)
			)
		)
		(property "Value" "SCD1U16V1KX-1-GP"
			(at 2.8321 -1.7399 90)
			(unlocked yes)
			(layer "B.Fab")
			(hide yes)
			(effects
				(font
					(size 1.016 1.016)
					(thickness 0.1524)
				)
				(justify mirror)
			)
		)
		(property "Device Type" "C0201H13"
			(at 2.8321 -3.2639 90)
			(unlocked yes)
			(layer "B.Fab")
			(hide yes)
			(effects
				(font
					(size 1.016 1.016)
					(thickness 0.1524)
				)
				(justify mirror)
			)
		)
		(duplicate_pad_numbers_are_jumpers no)
		(fp_rect
			(start 0.2794 0.6477)
			(end -0.2794 -0.6477)
			(stroke
				(width 0)
				(type default)
			)
			(fill no)
			(layer "B.CrtYd")
		)
		(fp_rect
			(start 0.2794 0.6477)
			(end -0.2794 -0.6477)
			(stroke
				(width 0)
				(type default)
			)
			(fill no)
			(layer "B.Fab")
		)
		(pad "1" smd custom
			(at 0 -0.2794 270)
			(size 0.0762 0.0762)
			(layers "B.Cu" "B.Mask" "B.Paste")
			(net "DUT_AVD_PCIE_Q")
			(options
				(clearance outline)
				(anchor circle)
			)
			(primitives
				(gr_poly
					(pts
						(arc
							(start 0.1524 0.127)
							(mid 0.137521 0.162921)
							(end 0.1016 0.1778)
						)
						(arc
							(start -0.1016 0.1778)
							(mid -0.137521 0.162921)
							(end -0.1524 0.127)
						)
						(arc
							(start -0.1524 -0.127)
							(mid -0.137521 -0.162921)
							(end -0.1016 -0.1778)
						)
						(arc
							(start 0.1016 -0.1778)
							(mid 0.137521 -0.162921)
							(end 0.1524 -0.127)
						)
					)
					(width 0)
					(fill yes)
				)
			)
		)
		(pad "2" smd custom
			(at 0 0.2794 270)
			(size 0.0762 0.0762)
			(layers "B.Cu" "B.Mask" "B.Paste")
			(net "GND")
			(options
				(clearance outline)
				(anchor circle)
			)
			(primitives
				(gr_poly
					(pts
						(arc
							(start 0.1524 0.127)
							(mid 0.137521 0.162921)
							(end 0.1016 0.1778)
						)
						(arc
							(start -0.1016 0.1778)
							(mid -0.137521 0.162921)
							(end -0.1524 0.127)
						)
						(arc
							(start -0.1524 -0.127)
							(mid -0.137521 -0.162921)
							(end -0.1016 -0.1778)
						)
						(arc
							(start 0.1016 -0.1778)
							(mid 0.137521 -0.162921)
							(end 0.1524 -0.127)
						)
					)
					(width 0)
					(fill yes)
				)
			)
		)
	)
	(footprint ""
		(layer "B.Cu")
		(at 245.1354 -48.9966 -90)
		(property "Reference" "C446"
			(at 0 0 90)
			(layer "B.SilkS")
			(hide yes)
			(effects
				(font
					(size 1.27 1.27)
				)
				(justify mirror)
			)
		)
		(property "Value" "SCD1U16V1KX-1-GP"
			(at 2.8321 -1.7399 270)
			(unlocked yes)
			(layer "B.Fab")
			(hide yes)
			(effects
				(font
					(size 1.016 1.016)
					(thickness 0.1524)
				)
				(justify mirror)
			)
		)
		(property "Device Type" "C0201H13"
			(at 2.8321 -3.2639 270)
			(unlocked yes)
			(layer "B.Fab")
			(hide yes)
			(effects
				(font
					(size 1.016 1.016)
					(thickness 0.1524)
				)
				(justify mirror)
			)
		)
		(duplicate_pad_numbers_are_jumpers no)
		(fp_rect
			(start 0.2794 0.6477)
			(end -0.2794 -0.6477)
			(stroke
				(width 0)
				(type default)
			)
			(fill no)
			(layer "B.CrtYd")
		)
		(fp_rect
			(start 0.2794 0.6477)
			(end -0.2794 -0.6477)
			(stroke
				(width 0)
				(type default)
			)
			(fill no)
			(layer "B.Fab")
		)
		(pad "1" smd custom
			(at 0 -0.2794 90)
			(size 0.0762 0.0762)
			(layers "B.Cu" "B.Mask" "B.Paste")
			(net "DUT_VDD")
			(options
				(clearance outline)
				(anchor circle)
			)
			(primitives
				(gr_poly
					(pts
						(arc
							(start 0.1524 0.127)
							(mid 0.137521 0.162921)
							(end 0.1016 0.1778)
						)
						(arc
							(start -0.1016 0.1778)
							(mid -0.137521 0.162921)
							(end -0.1524 0.127)
						)
						(arc
							(start -0.1524 -0.127)
							(mid -0.137521 -0.162921)
							(end -0.1016 -0.1778)
						)
						(arc
							(start 0.1016 -0.1778)
							(mid 0.137521 -0.162921)
							(end 0.1524 -0.127)
						)
					)
					(width 0)
					(fill yes)
				)
			)
		)
		(pad "2" smd custom
			(at 0 0.2794 90)
			(size 0.0762 0.0762)
			(layers "B.Cu" "B.Mask" "B.Paste")
			(net "GND")
			(options
				(clearance outline)
				(anchor circle)
			)
			(primitives
				(gr_poly
					(pts
						(arc
							(start 0.1524 0.127)
							(mid 0.137521 0.162921)
							(end 0.1016 0.1778)
						)
						(arc
							(start -0.1016 0.1778)
							(mid -0.137521 0.162921)
							(end -0.1524 0.127)
						)
						(arc
							(start -0.1524 -0.127)
							(mid -0.137521 -0.162921)
							(end -0.1016 -0.1778)
						)
						(arc
							(start 0.1016 -0.1778)
							(mid 0.137521 -0.162921)
							(end 0.1524 -0.127)
						)
					)
					(width 0)
					(fill yes)
				)
			)
		)
	)
	(footprint ""
		(layer "B.Cu")
		(at 120.9548 -96.1898 180)
		(property "Reference" "R432"
			(at 0 0 0)
			(layer "B.SilkS")
			(hide yes)
			(effects
				(font
					(size 1.27 1.27)
				)
				(justify mirror)
			)
		)
		(property "Value" "0R2J-2-GP"
			(at -0.064008 -3.993896 180)
			(unlocked yes)
			(layer "B.Fab")
			(hide yes)
			(effects
				(font
					(size 1.016 1.016)
					(thickness 0.1524)
				)
				(justify mirror)
			)
		)
		(property "Device Type" "R402H16"
			(at -0.064008 -5.517896 180)
			(unlocked yes)
			(layer "B.Fab")
			(hide yes)
			(effects
				(font
					(size 1.016 1.016)
					(thickness 0.1524)
				)
				(justify mirror)
			)
		)
		(duplicate_pad_numbers_are_jumpers no)
		(fp_line
			(start 0.508 -0.9398)
			(end 0.508 0.9398)
			(stroke
				(width 0.1524)
				(type default)
			)
			(layer "B.SilkS")
		)
		(fp_line
			(start -0.508 -0.9398)
			(end 0.508 -0.9398)
			(stroke
				(width 0.1524)
				(type default)
			)
			(layer "B.SilkS")
		)
		(fp_rect
			(start 0.508 0.9398)
			(end -0.508 -0.9398)
			(stroke
				(width 0)
				(type default)
			)
			(fill no)
			(layer "B.CrtYd")
		)
		(fp_rect
			(start 0.508 0.9398)
			(end -0.508 -0.9398)
			(stroke
				(width 0)
				(type default)
			)
			(fill no)
			(layer "B.Fab")
		)
		(pad "1" smd custom
			(at 0 -0.4445)
			(size 0.1397 0.1397)
			(layers "B.Cu" "B.Mask" "B.Paste")
			(net "BMC_I2C10_8536_SDA")
			(options
				(clearance outline)
				(anchor circle)
			)
			(primitives
				(gr_poly
					(pts
						(arc
							(start -0.1778 0.2794)
							(mid -0.249642 0.249642)
							(end -0.2794 0.1778)
						)
						(arc
							(start -0.2794 -0.1778)
							(mid -0.249642 -0.249642)
							(end -0.1778 -0.2794)
						)
						(arc
							(start 0.1778 -0.2794)
							(mid 0.249642 -0.249642)
							(end 0.2794 -0.1778)
						)
						(arc
							(start 0.2794 0.1778)
							(mid 0.249642 0.249642)
							(end 0.1778 0.2794)
						)
					)
					(width 0)
					(fill yes)
				)
			)
		)
		(pad "2" smd custom
			(at 0 0.4445)
			(size 0.1397 0.1397)
			(layers "B.Cu" "B.Mask" "B.Paste")
			(net "TWI_SDA0")
			(options
				(clearance outline)
				(anchor circle)
			)
			(primitives
				(gr_poly
					(pts
						(arc
							(start -0.1778 0.2794)
							(mid -0.249642 0.249642)
							(end -0.2794 0.1778)
						)
						(arc
							(start -0.2794 -0.1778)
							(mid -0.249642 -0.249642)
							(end -0.1778 -0.2794)
						)
						(arc
							(start 0.1778 -0.2794)
							(mid 0.249642 -0.249642)
							(end 0.2794 -0.1778)
						)
						(arc
							(start 0.2794 0.1778)
							(mid 0.249642 0.249642)
							(end 0.1778 0.2794)
						)
					)
					(width 0)
					(fill yes)
				)
			)
		)
	)
	(footprint ""
		(layer "B.Cu")
		(at 265.065002 -0.748792 90)
		(property "Reference" "R204"
			(at 0 0 90)
			(layer "B.SilkS")
			(hide yes)
			(effects
				(font
					(size 1.27 1.27)
				)
				(justify mirror)
			)
		)
		(property "Value" "0R2J-2-GP"
			(at -0.064008 -3.993896 90)
			(unlocked yes)
			(layer "B.Fab")
			(hide yes)
			(effects
				(font
					(size 1.016 1.016)
					(thickness 0.1524)
				)
				(justify mirror)
			)
		)
		(property "Device Type" "R402H16"
			(at -0.064008 -5.517896 90)
			(unlocked yes)
			(layer "B.Fab")
			(hide yes)
			(effects
				(font
					(size 1.016 1.016)
					(thickness 0.1524)
				)
				(justify mirror)
			)
		)
		(duplicate_pad_numbers_are_jumpers no)
		(fp_line
			(start 0.508 -0.9398)
			(end 0.508 0.9398)
			(stroke
				(width 0.1524)
				(type default)
			)
			(layer "B.SilkS")
		)
		(fp_line
			(start -0.508 -0.9398)
			(end 0.508 -0.9398)
			(stroke
				(width 0.1524)
				(type default)
			)
			(layer "B.SilkS")
		)
		(fp_rect
			(start 0.508 0.9398)
			(end -0.508 -0.9398)
			(stroke
				(width 0)
				(type default)
			)
			(fill no)
			(layer "B.CrtYd")
		)
		(fp_rect
			(start 0.508 0.9398)
			(end -0.508 -0.9398)
			(stroke
				(width 0)
				(type default)
			)
			(fill no)
			(layer "B.Fab")
		)
		(pad "1" smd custom
			(at 0 -0.4445 270)
			(size 0.1397 0.1397)
			(layers "B.Cu" "B.Mask" "B.Paste")
			(net "TEMP_SENSOR_C")
			(options
				(clearance outline)
				(anchor circle)
			)
			(primitives
				(gr_poly
					(pts
						(arc
							(start -0.1778 0.2794)
							(mid -0.249642 0.249642)
							(end -0.2794 0.1778)
						)
						(arc
							(start -0.2794 -0.1778)
							(mid -0.249642 -0.249642)
							(end -0.1778 -0.2794)
						)
						(arc
							(start 0.1778 -0.2794)
							(mid 0.249642 -0.249642)
							(end 0.2794 -0.1778)
						)
						(arc
							(start 0.2794 0.1778)
							(mid 0.249642 0.249642)
							(end 0.1778 0.2794)
						)
					)
					(width 0)
					(fill yes)
				)
			)
		)
		(pad "2" smd custom
			(at 0 0.4445 270)
			(size 0.1397 0.1397)
			(layers "B.Cu" "B.Mask" "B.Paste")
			(net "TEMP_SENSOR_DXN_BJT")
			(options
				(clearance outline)
				(anchor circle)
			)
			(primitives
				(gr_poly
					(pts
						(arc
							(start -0.1778 0.2794)
							(mid -0.249642 0.249642)
							(end -0.2794 0.1778)
						)
						(arc
							(start -0.2794 -0.1778)
							(mid -0.249642 -0.249642)
							(end -0.1778 -0.2794)
						)
						(arc
							(start 0.1778 -0.2794)
							(mid 0.249642 -0.249642)
							(end 0.2794 -0.1778)
						)
						(arc
							(start 0.2794 0.1778)
							(mid 0.249642 0.249642)
							(end 0.1778 0.2794)
						)
					)
					(width 0)
					(fill yes)
				)
			)
		)
	)
	(footprint ""
		(layer "B.Cu")
		(at 227.179124 -203.047092 180)
		(property "Reference" "R4136"
			(at 0 0 0)
			(layer "B.SilkS")
			(hide yes)
			(effects
				(font
					(size 1.27 1.27)
				)
				(justify mirror)
			)
		)
		(property "Value" "4K7R2F-GP"
			(at -0.064008 -3.993896 180)
			(unlocked yes)
			(layer "B.Fab")
			(hide yes)
			(effects
				(font
					(size 1.016 1.016)
					(thickness 0.1524)
				)
				(justify mirror)
			)
		)
		(property "Device Type" "R402H16"
			(at -0.064008 -5.517896 180)
			(unlocked yes)
			(layer "B.Fab")
			(hide yes)
			(effects
				(font
					(size 1.016 1.016)
					(thickness 0.1524)
				)
				(justify mirror)
			)
		)
		(duplicate_pad_numbers_are_jumpers no)
		(fp_line
			(start 0.508 -0.9398)
			(end 0.508 0.9398)
			(stroke
				(width 0.1524)
				(type default)
			)
			(layer "B.SilkS")
		)
		(fp_line
			(start -0.508 -0.9398)
			(end 0.508 -0.9398)
			(stroke
				(width 0.1524)
				(type default)
			)
			(layer "B.SilkS")
		)
		(fp_rect
			(start 0.508 0.9398)
			(end -0.508 -0.9398)
			(stroke
				(width 0)
				(type default)
			)
			(fill no)
			(layer "B.CrtYd")
		)
		(fp_rect
			(start 0.508 0.9398)
			(end -0.508 -0.9398)
			(stroke
				(width 0)
				(type default)
			)
			(fill no)
			(layer "B.Fab")
		)
		(pad "1" smd custom
			(at 0 -0.4445)
			(size 0.1397 0.1397)
			(layers "B.Cu" "B.Mask" "B.Paste")
			(net "SSD_ATNLED#12")
			(options
				(clearance outline)
				(anchor circle)
			)
			(primitives
				(gr_poly
					(pts
						(arc
							(start -0.1778 0.2794)
							(mid -0.249642 0.249642)
							(end -0.2794 0.1778)
						)
						(arc
							(start -0.2794 -0.1778)
							(mid -0.249642 -0.249642)
							(end -0.1778 -0.2794)
						)
						(arc
							(start 0.1778 -0.2794)
							(mid 0.249642 -0.249642)
							(end 0.2794 -0.1778)
						)
						(arc
							(start 0.2794 0.1778)
							(mid 0.249642 0.249642)
							(end 0.1778 0.2794)
						)
					)
					(width 0)
					(fill yes)
				)
			)
		)
		(pad "2" smd custom
			(at 0 0.4445)
			(size 0.1397 0.1397)
			(layers "B.Cu" "B.Mask" "B.Paste")
			(net "P3V3_STBY")
			(options
				(clearance outline)
				(anchor circle)
			)
			(primitives
				(gr_poly
					(pts
						(arc
							(start -0.1778 0.2794)
							(mid -0.249642 0.249642)
							(end -0.2794 0.1778)
						)
						(arc
							(start -0.2794 -0.1778)
							(mid -0.249642 -0.249642)
							(end -0.1778 -0.2794)
						)
						(arc
							(start 0.1778 -0.2794)
							(mid 0.249642 -0.249642)
							(end 0.2794 -0.1778)
						)
						(arc
							(start 0.2794 0.1778)
							(mid 0.249642 0.249642)
							(end 0.1778 0.2794)
						)
					)
					(width 0)
					(fill yes)
				)
			)
		)
	)
	(footprint ""
		(layer "B.Cu")
		(at 23.90648 -139.618974 90)
		(property "Reference" "R370"
			(at 0 0 90)
			(layer "B.SilkS")
			(hide yes)
			(effects
				(font
					(size 1.27 1.27)
				)
				(justify mirror)
			)
		)
		(property "Value" "3K3R2F-2-GP"
			(at -0.064008 -3.993896 90)
			(unlocked yes)
			(layer "B.Fab")
			(hide yes)
			(effects
				(font
					(size 1.016 1.016)
					(thickness 0.1524)
				)
				(justify mirror)
			)
		)
		(property "Device Type" "R402H16"
			(at -0.064008 -5.517896 90)
			(unlocked yes)
			(layer "B.Fab")
			(hide yes)
			(effects
				(font
					(size 1.016 1.016)
					(thickness 0.1524)
				)
				(justify mirror)
			)
		)
		(duplicate_pad_numbers_are_jumpers no)
		(fp_line
			(start 0.508 -0.9398)
			(end 0.508 0.9398)
			(stroke
				(width 0.1524)
				(type default)
			)
			(layer "B.SilkS")
		)
		(fp_line
			(start -0.508 -0.9398)
			(end 0.508 -0.9398)
			(stroke
				(width 0.1524)
				(type default)
			)
			(layer "B.SilkS")
		)
		(fp_rect
			(start 0.508 0.9398)
			(end -0.508 -0.9398)
			(stroke
				(width 0)
				(type default)
			)
			(fill no)
			(layer "B.CrtYd")
		)
		(fp_rect
			(start 0.508 0.9398)
			(end -0.508 -0.9398)
			(stroke
				(width 0)
				(type default)
			)
			(fill no)
			(layer "B.Fab")
		)
		(pad "1" smd custom
			(at 0 -0.4445 270)
			(size 0.1397 0.1397)
			(layers "B.Cu" "B.Mask" "B.Paste")
			(net "P3V3_STBY")
			(options
				(clearance outline)
				(anchor circle)
			)
			(primitives
				(gr_poly
					(pts
						(arc
							(start -0.1778 0.2794)
							(mid -0.249642 0.249642)
							(end -0.2794 0.1778)
						)
						(arc
							(start -0.2794 -0.1778)
							(mid -0.249642 -0.249642)
							(end -0.1778 -0.2794)
						)
						(arc
							(start 0.1778 -0.2794)
							(mid 0.249642 -0.249642)
							(end 0.2794 -0.1778)
						)
						(arc
							(start 0.2794 0.1778)
							(mid 0.249642 0.249642)
							(end 0.1778 0.2794)
						)
					)
					(width 0)
					(fill yes)
				)
			)
		)
		(pad "2" smd custom
			(at 0 0.4445 270)
			(size 0.1397 0.1397)
			(layers "B.Cu" "B.Mask" "B.Paste")
			(net "ROMD7")
			(options
				(clearance outline)
				(anchor circle)
			)
			(primitives
				(gr_poly
					(pts
						(arc
							(start -0.1778 0.2794)
							(mid -0.249642 0.249642)
							(end -0.2794 0.1778)
						)
						(arc
							(start -0.2794 -0.1778)
							(mid -0.249642 -0.249642)
							(end -0.1778 -0.2794)
						)
						(arc
							(start 0.1778 -0.2794)
							(mid 0.249642 -0.249642)
							(end 0.2794 -0.1778)
						)
						(arc
							(start 0.2794 0.1778)
							(mid 0.249642 0.249642)
							(end 0.1778 0.2794)
						)
					)
					(width 0)
					(fill yes)
				)
			)
		)
	)
	(footprint ""
		(layer "B.Cu")
		(at 245.5926 -59.9948 90)
		(property "Reference" "C504"
			(at 0 0 90)
			(layer "B.SilkS")
			(hide yes)
			(effects
				(font
					(size 1.27 1.27)
				)
				(justify mirror)
			)
		)
		(property "Value" "SCD1U16V1KX-1-GP"
			(at 2.8321 -1.7399 90)
			(unlocked yes)
			(layer "B.Fab")
			(hide yes)
			(effects
				(font
					(size 1.016 1.016)
					(thickness 0.1524)
				)
				(justify mirror)
			)
		)
		(property "Device Type" "C0201H13"
			(at 2.8321 -3.2639 90)
			(unlocked yes)
			(layer "B.Fab")
			(hide yes)
			(effects
				(font
					(size 1.016 1.016)
					(thickness 0.1524)
				)
				(justify mirror)
			)
		)
		(duplicate_pad_numbers_are_jumpers no)
		(fp_rect
			(start 0.2794 0.6477)
			(end -0.2794 -0.6477)
			(stroke
				(width 0)
				(type default)
			)
			(fill no)
			(layer "B.CrtYd")
		)
		(fp_rect
			(start 0.2794 0.6477)
			(end -0.2794 -0.6477)
			(stroke
				(width 0)
				(type default)
			)
			(fill no)
			(layer "B.Fab")
		)
		(pad "1" smd custom
			(at 0 -0.2794 270)
			(size 0.0762 0.0762)
			(layers "B.Cu" "B.Mask" "B.Paste")
			(net "DUT_AVD_TX")
			(options
				(clearance outline)
				(anchor circle)
			)
			(primitives
				(gr_poly
					(pts
						(arc
							(start 0.1524 0.127)
							(mid 0.137521 0.162921)
							(end 0.1016 0.1778)
						)
						(arc
							(start -0.1016 0.1778)
							(mid -0.137521 0.162921)
							(end -0.1524 0.127)
						)
						(arc
							(start -0.1524 -0.127)
							(mid -0.137521 -0.162921)
							(end -0.1016 -0.1778)
						)
						(arc
							(start 0.1016 -0.1778)
							(mid 0.137521 -0.162921)
							(end 0.1524 -0.127)
						)
					)
					(width 0)
					(fill yes)
				)
			)
		)
		(pad "2" smd custom
			(at 0 0.2794 270)
			(size 0.0762 0.0762)
			(layers "B.Cu" "B.Mask" "B.Paste")
			(net "GND")
			(options
				(clearance outline)
				(anchor circle)
			)
			(primitives
				(gr_poly
					(pts
						(arc
							(start 0.1524 0.127)
							(mid 0.137521 0.162921)
							(end 0.1016 0.1778)
						)
						(arc
							(start -0.1016 0.1778)
							(mid -0.137521 0.162921)
							(end -0.1524 0.127)
						)
						(arc
							(start -0.1524 -0.127)
							(mid -0.137521 -0.162921)
							(end -0.1016 -0.1778)
						)
						(arc
							(start 0.1016 -0.1778)
							(mid 0.137521 -0.162921)
							(end 0.1524 -0.127)
						)
					)
					(width 0)
					(fill yes)
				)
			)
		)
	)
	(footprint ""
		(layer "B.Cu")
		(at 136.824212 -205.849474)
		(property "Reference" "R3219"
			(at 0 0 0)
			(layer "B.SilkS")
			(hide yes)
			(effects
				(font
					(size 1.27 1.27)
				)
				(justify mirror)
			)
		)
		(property "Value" "0R2J-2-GP"
			(at -0.064008 -3.993896 0)
			(unlocked yes)
			(layer "B.Fab")
			(hide yes)
			(effects
				(font
					(size 1.016 1.016)
					(thickness 0.1524)
				)
				(justify mirror)
			)
		)
		(property "Device Type" "R402H16"
			(at -0.064008 -5.517896 0)
			(unlocked yes)
			(layer "B.Fab")
			(hide yes)
			(effects
				(font
					(size 1.016 1.016)
					(thickness 0.1524)
				)
				(justify mirror)
			)
		)
		(duplicate_pad_numbers_are_jumpers no)
		(fp_line
			(start -0.508 -0.9398)
			(end 0.508 -0.9398)
			(stroke
				(width 0.1524)
				(type default)
			)
			(layer "B.SilkS")
		)
		(fp_line
			(start 0.508 -0.9398)
			(end 0.508 0.9398)
			(stroke
				(width 0.1524)
				(type default)
			)
			(layer "B.SilkS")
		)
		(fp_rect
			(start 0.508 0.9398)
			(end -0.508 -0.9398)
			(stroke
				(width 0)
				(type default)
			)
			(fill no)
			(layer "B.CrtYd")
		)
		(fp_rect
			(start 0.508 0.9398)
			(end -0.508 -0.9398)
			(stroke
				(width 0)
				(type default)
			)
			(fill no)
			(layer "B.Fab")
		)
		(pad "1" smd custom
			(at 0 -0.4445 180)
			(size 0.1397 0.1397)
			(layers "B.Cu" "B.Mask" "B.Paste")
			(net "SSD_PERST#6")
			(options
				(clearance outline)
				(anchor circle)
			)
			(primitives
				(gr_poly
					(pts
						(arc
							(start -0.1778 0.2794)
							(mid -0.249642 0.249642)
							(end -0.2794 0.1778)
						)
						(arc
							(start -0.2794 -0.1778)
							(mid -0.249642 -0.249642)
							(end -0.1778 -0.2794)
						)
						(arc
							(start 0.1778 -0.2794)
							(mid 0.249642 -0.249642)
							(end 0.2794 -0.1778)
						)
						(arc
							(start 0.2794 0.1778)
							(mid 0.249642 0.249642)
							(end 0.1778 0.2794)
						)
					)
					(width 0)
					(fill yes)
				)
			)
		)
		(pad "2" smd custom
			(at 0 0.4445 180)
			(size 0.1397 0.1397)
			(layers "B.Cu" "B.Mask" "B.Paste")
			(net "SSD_PERST#0_B6")
			(options
				(clearance outline)
				(anchor circle)
			)
			(primitives
				(gr_poly
					(pts
						(arc
							(start -0.1778 0.2794)
							(mid -0.249642 0.249642)
							(end -0.2794 0.1778)
						)
						(arc
							(start -0.2794 -0.1778)
							(mid -0.249642 -0.249642)
							(end -0.1778 -0.2794)
						)
						(arc
							(start 0.1778 -0.2794)
							(mid 0.249642 -0.249642)
							(end 0.2794 -0.1778)
						)
						(arc
							(start 0.2794 0.1778)
							(mid 0.249642 0.249642)
							(end 0.1778 0.2794)
						)
					)
					(width 0)
					(fill yes)
				)
			)
		)
	)
	(footprint ""
		(layer "B.Cu")
		(at 40.005 -116.332)
		(property "Reference" "TP324"
			(at 0 0 0)
			(layer "B.SilkS")
			(hide yes)
			(effects
				(font
					(size 1.27 1.27)
				)
				(justify mirror)
			)
		)
		(property "Value" "TPAD28-2-GP"
			(at 0.0127 -1.6637 0)
			(unlocked yes)
			(layer "B.Fab")
			(hide yes)
			(effects
				(font
					(size 1.016 1.016)
					(thickness 0.1524)
				)
				(justify mirror)
			)
		)
		(property "Device Type" "TPAD28"
			(at 0.0127 -3.1877 0)
			(unlocked yes)
			(layer "B.Fab")
			(hide yes)
			(effects
				(font
					(size 1.016 1.016)
					(thickness 0.1524)
				)
				(justify mirror)
			)
		)
		(duplicate_pad_numbers_are_jumpers no)
		(fp_poly
			(pts
				(arc
					(start 0.3556 0)
					(mid -0.3556 0)
					(end 0.3556 0)
				)
			)
			(stroke
				(width 0)
				(type default)
			)
			(fill no)
			(layer "B.CrtYd")
		)
		(fp_poly
			(pts
				(arc
					(start 0.6096 0)
					(mid -0.6096 0)
					(end 0.6096 0)
				)
			)
			(stroke
				(width 0)
				(type default)
			)
			(fill no)
			(layer "B.Fab")
		)
		(pad "1" smd circle
			(at 0 0 180)
			(size 0.7112 0.7112)
			(layers "B.Cu" "B.Mask" "B.Paste")
			(net "TP_GPIOT6")
		)
	)
	(footprint ""
		(layer "B.Cu")
		(at 231.394 -20.447)
		(property "Reference" "R821"
			(at 0 0 0)
			(layer "B.SilkS")
			(hide yes)
			(effects
				(font
					(size 1.27 1.27)
				)
				(justify mirror)
			)
		)
		(property "Value" "4K7R2F-GP"
			(at -0.064008 -3.993896 0)
			(unlocked yes)
			(layer "B.Fab")
			(hide yes)
			(effects
				(font
					(size 1.016 1.016)
					(thickness 0.1524)
				)
				(justify mirror)
			)
		)
		(property "Device Type" "R402H16"
			(at -0.064008 -5.517896 0)
			(unlocked yes)
			(layer "B.Fab")
			(hide yes)
			(effects
				(font
					(size 1.016 1.016)
					(thickness 0.1524)
				)
				(justify mirror)
			)
		)
		(duplicate_pad_numbers_are_jumpers no)
		(fp_line
			(start -0.508 -0.9398)
			(end 0.508 -0.9398)
			(stroke
				(width 0.1524)
				(type default)
			)
			(layer "B.SilkS")
		)
		(fp_line
			(start 0.508 -0.9398)
			(end 0.508 0.9398)
			(stroke
				(width 0.1524)
				(type default)
			)
			(layer "B.SilkS")
		)
		(fp_rect
			(start 0.508 0.9398)
			(end -0.508 -0.9398)
			(stroke
				(width 0)
				(type default)
			)
			(fill no)
			(layer "B.CrtYd")
		)
		(fp_rect
			(start 0.508 0.9398)
			(end -0.508 -0.9398)
			(stroke
				(width 0)
				(type default)
			)
			(fill no)
			(layer "B.Fab")
		)
		(pad "1" smd custom
			(at 0 -0.4445 180)
			(size 0.1397 0.1397)
			(layers "B.Cu" "B.Mask" "B.Paste")
			(net "BOOTSTRAP10")
			(options
				(clearance outline)
				(anchor circle)
			)
			(primitives
				(gr_poly
					(pts
						(arc
							(start -0.1778 0.2794)
							(mid -0.249642 0.249642)
							(end -0.2794 0.1778)
						)
						(arc
							(start -0.2794 -0.1778)
							(mid -0.249642 -0.249642)
							(end -0.1778 -0.2794)
						)
						(arc
							(start 0.1778 -0.2794)
							(mid 0.249642 -0.249642)
							(end 0.2794 -0.1778)
						)
						(arc
							(start 0.2794 0.1778)
							(mid 0.249642 0.249642)
							(end 0.1778 0.2794)
						)
					)
					(width 0)
					(fill yes)
				)
			)
		)
		(pad "2" smd custom
			(at 0 0.4445 180)
			(size 0.1397 0.1397)
			(layers "B.Cu" "B.Mask" "B.Paste")
			(net "DUT_VDDO")
			(options
				(clearance outline)
				(anchor circle)
			)
			(primitives
				(gr_poly
					(pts
						(arc
							(start -0.1778 0.2794)
							(mid -0.249642 0.249642)
							(end -0.2794 0.1778)
						)
						(arc
							(start -0.2794 -0.1778)
							(mid -0.249642 -0.249642)
							(end -0.1778 -0.2794)
						)
						(arc
							(start 0.1778 -0.2794)
							(mid 0.249642 -0.249642)
							(end 0.2794 -0.1778)
						)
						(arc
							(start 0.2794 0.1778)
							(mid 0.249642 0.249642)
							(end 0.1778 0.2794)
						)
					)
					(width 0)
					(fill yes)
				)
			)
		)
	)
	(footprint ""
		(layer "B.Cu")
		(at 215.4174 -21.8186 180)
		(property "Reference" "R29"
			(at 0 0 0)
			(layer "B.SilkS")
			(hide yes)
			(effects
				(font
					(size 1.27 1.27)
				)
				(justify mirror)
			)
		)
		(property "Value" "100KR2F-L1-GP"
			(at -0.064008 -3.993896 180)
			(unlocked yes)
			(layer "B.Fab")
			(hide yes)
			(effects
				(font
					(size 1.016 1.016)
					(thickness 0.1524)
				)
				(justify mirror)
			)
		)
		(property "Device Type" "R402H16"
			(at -0.064008 -5.517896 180)
			(unlocked yes)
			(layer "B.Fab")
			(hide yes)
			(effects
				(font
					(size 1.016 1.016)
					(thickness 0.1524)
				)
				(justify mirror)
			)
		)
		(duplicate_pad_numbers_are_jumpers no)
		(fp_line
			(start 0.508 -0.9398)
			(end 0.508 0.9398)
			(stroke
				(width 0.1524)
				(type default)
			)
			(layer "B.SilkS")
		)
		(fp_line
			(start -0.508 -0.9398)
			(end 0.508 -0.9398)
			(stroke
				(width 0.1524)
				(type default)
			)
			(layer "B.SilkS")
		)
		(fp_rect
			(start 0.508 0.9398)
			(end -0.508 -0.9398)
			(stroke
				(width 0)
				(type default)
			)
			(fill no)
			(layer "B.CrtYd")
		)
		(fp_rect
			(start 0.508 0.9398)
			(end -0.508 -0.9398)
			(stroke
				(width 0)
				(type default)
			)
			(fill no)
			(layer "B.Fab")
		)
		(pad "1" smd custom
			(at 0 -0.4445)
			(size 0.1397 0.1397)
			(layers "B.Cu" "B.Mask" "B.Paste")
			(net "GND")
			(options
				(clearance outline)
				(anchor circle)
			)
			(primitives
				(gr_poly
					(pts
						(arc
							(start -0.1778 0.2794)
							(mid -0.249642 0.249642)
							(end -0.2794 0.1778)
						)
						(arc
							(start -0.2794 -0.1778)
							(mid -0.249642 -0.249642)
							(end -0.1778 -0.2794)
						)
						(arc
							(start 0.1778 -0.2794)
							(mid 0.249642 -0.249642)
							(end 0.2794 -0.1778)
						)
						(arc
							(start 0.2794 0.1778)
							(mid 0.249642 0.249642)
							(end 0.1778 0.2794)
						)
					)
					(width 0)
					(fill yes)
				)
			)
		)
		(pad "2" smd custom
			(at 0 0.4445)
			(size 0.1397 0.1397)
			(layers "B.Cu" "B.Mask" "B.Paste")
			(net "PM8536_RST#")
			(options
				(clearance outline)
				(anchor circle)
			)
			(primitives
				(gr_poly
					(pts
						(arc
							(start -0.1778 0.2794)
							(mid -0.249642 0.249642)
							(end -0.2794 0.1778)
						)
						(arc
							(start -0.2794 -0.1778)
							(mid -0.249642 -0.249642)
							(end -0.1778 -0.2794)
						)
						(arc
							(start 0.1778 -0.2794)
							(mid 0.249642 -0.249642)
							(end 0.2794 -0.1778)
						)
						(arc
							(start 0.2794 0.1778)
							(mid 0.249642 0.249642)
							(end 0.1778 0.2794)
						)
					)
					(width 0)
					(fill yes)
				)
			)
		)
	)
	(footprint ""
		(layer "B.Cu")
		(at 152.532588 -33.541462 180)
		(property "Reference" "C226"
			(at 0 0 0)
			(layer "B.SilkS")
			(hide yes)
			(effects
				(font
					(size 1.27 1.27)
				)
				(justify mirror)
			)
		)
		(property "Value" "SCD1U10V2KX-5GP"
			(at -1.1811 -2.7051 180)
			(unlocked yes)
			(layer "B.Fab")
			(hide yes)
			(effects
				(font
					(size 1.016 1.016)
					(thickness 0.1524)
				)
				(justify mirror)
			)
		)
		(property "Device Type" "C402H22"
			(at -1.1811 -4.2291 180)
			(unlocked yes)
			(layer "B.Fab")
			(hide yes)
			(effects
				(font
					(size 1.016 1.016)
					(thickness 0.1524)
				)
				(justify mirror)
			)
		)
		(duplicate_pad_numbers_are_jumpers no)
		(fp_rect
			(start 0.4318 0.9525)
			(end -0.4318 -0.9525)
			(stroke
				(width 0)
				(type default)
			)
			(fill no)
			(layer "B.CrtYd")
		)
		(fp_rect
			(start 0.4318 0.9525)
			(end -0.4318 -0.9525)
			(stroke
				(width 0)
				(type default)
			)
			(fill no)
			(layer "B.Fab")
		)
		(pad "1" smd custom
			(at 0 -0.4445)
			(size 0.1524 0.1524)
			(layers "B.Cu" "B.Mask" "B.Paste")
			(net "GND")
			(options
				(clearance outline)
				(anchor circle)
			)
			(primitives
				(gr_poly
					(pts
						(arc
							(start 0.3048 0.2032)
							(mid 0.275042 0.275042)
							(end 0.2032 0.3048)
						)
						(arc
							(start -0.2032 0.3048)
							(mid -0.275042 0.275042)
							(end -0.3048 0.2032)
						)
						(arc
							(start -0.3048 -0.2032)
							(mid -0.275042 -0.275042)
							(end -0.2032 -0.3048)
						)
						(arc
							(start 0.2032 -0.3048)
							(mid 0.275042 -0.275042)
							(end 0.3048 -0.2032)
						)
					)
					(width 0)
					(fill yes)
				)
			)
		)
		(pad "2" smd custom
			(at 0 0.4445)
			(size 0.1524 0.1524)
			(layers "B.Cu" "B.Mask" "B.Paste")
			(net "P3V3_STBY")
			(options
				(clearance outline)
				(anchor circle)
			)
			(primitives
				(gr_poly
					(pts
						(arc
							(start 0.3048 0.2032)
							(mid 0.275042 0.275042)
							(end 0.2032 0.3048)
						)
						(arc
							(start -0.2032 0.3048)
							(mid -0.275042 0.275042)
							(end -0.3048 0.2032)
						)
						(arc
							(start -0.3048 -0.2032)
							(mid -0.275042 -0.275042)
							(end -0.2032 -0.3048)
						)
						(arc
							(start 0.2032 -0.3048)
							(mid 0.275042 -0.275042)
							(end 0.3048 -0.2032)
						)
					)
					(width 0)
					(fill yes)
				)
			)
		)
	)
	(footprint ""
		(layer "B.Cu")
		(at 73.787 -183.261)
		(property "Reference" "R9029"
			(at 0 0 0)
			(layer "B.SilkS")
			(hide yes)
			(effects
				(font
					(size 1.27 1.27)
				)
				(justify mirror)
			)
		)
		(property "Value" "4K7R2F-GP"
			(at -0.064008 -3.993896 0)
			(unlocked yes)
			(layer "B.Fab")
			(hide yes)
			(effects
				(font
					(size 1.016 1.016)
					(thickness 0.1524)
				)
				(justify mirror)
			)
		)
		(property "Device Type" "R402H16"
			(at -0.064008 -5.517896 0)
			(unlocked yes)
			(layer "B.Fab")
			(hide yes)
			(effects
				(font
					(size 1.016 1.016)
					(thickness 0.1524)
				)
				(justify mirror)
			)
		)
		(duplicate_pad_numbers_are_jumpers no)
		(fp_line
			(start -0.508 -0.9398)
			(end 0.508 -0.9398)
			(stroke
				(width 0.1524)
				(type default)
			)
			(layer "B.SilkS")
		)
		(fp_line
			(start 0.508 -0.9398)
			(end 0.508 0.9398)
			(stroke
				(width 0.1524)
				(type default)
			)
			(layer "B.SilkS")
		)
		(fp_rect
			(start 0.508 0.9398)
			(end -0.508 -0.9398)
			(stroke
				(width 0)
				(type default)
			)
			(fill no)
			(layer "B.CrtYd")
		)
		(fp_rect
			(start 0.508 0.9398)
			(end -0.508 -0.9398)
			(stroke
				(width 0)
				(type default)
			)
			(fill no)
			(layer "B.Fab")
		)
		(pad "1" smd custom
			(at 0 -0.4445 180)
			(size 0.1397 0.1397)
			(layers "B.Cu" "B.Mask" "B.Paste")
			(net "SSD_PERST#0")
			(options
				(clearance outline)
				(anchor circle)
			)
			(primitives
				(gr_poly
					(pts
						(arc
							(start -0.1778 0.2794)
							(mid -0.249642 0.249642)
							(end -0.2794 0.1778)
						)
						(arc
							(start -0.2794 -0.1778)
							(mid -0.249642 -0.249642)
							(end -0.1778 -0.2794)
						)
						(arc
							(start 0.1778 -0.2794)
							(mid 0.249642 -0.249642)
							(end 0.2794 -0.1778)
						)
						(arc
							(start 0.2794 0.1778)
							(mid 0.249642 0.249642)
							(end 0.1778 0.2794)
						)
					)
					(width 0)
					(fill yes)
				)
			)
		)
		(pad "2" smd custom
			(at 0 0.4445 180)
			(size 0.1397 0.1397)
			(layers "B.Cu" "B.Mask" "B.Paste")
			(net "GND")
			(options
				(clearance outline)
				(anchor circle)
			)
			(primitives
				(gr_poly
					(pts
						(arc
							(start -0.1778 0.2794)
							(mid -0.249642 0.249642)
							(end -0.2794 0.1778)
						)
						(arc
							(start -0.2794 -0.1778)
							(mid -0.249642 -0.249642)
							(end -0.1778 -0.2794)
						)
						(arc
							(start 0.1778 -0.2794)
							(mid 0.249642 -0.249642)
							(end 0.2794 -0.1778)
						)
						(arc
							(start 0.2794 0.1778)
							(mid 0.249642 0.249642)
							(end 0.1778 0.2794)
						)
					)
					(width 0)
					(fill yes)
				)
			)
		)
	)
	(footprint ""
		(layer "B.Cu")
		(at 32.738568 -119.55272 90)
		(property "Reference" "R564"
			(at 0 0 90)
			(layer "B.SilkS")
			(hide yes)
			(effects
				(font
					(size 1.27 1.27)
				)
				(justify mirror)
			)
		)
		(property "Value" "0R2J-2-GP"
			(at -0.064008 -3.993896 90)
			(unlocked yes)
			(layer "B.Fab")
			(hide yes)
			(effects
				(font
					(size 1.016 1.016)
					(thickness 0.1524)
				)
				(justify mirror)
			)
		)
		(property "Device Type" "R402H16"
			(at -0.064008 -5.517896 90)
			(unlocked yes)
			(layer "B.Fab")
			(hide yes)
			(effects
				(font
					(size 1.016 1.016)
					(thickness 0.1524)
				)
				(justify mirror)
			)
		)
		(duplicate_pad_numbers_are_jumpers no)
		(fp_line
			(start 0.508 -0.9398)
			(end 0.508 0.9398)
			(stroke
				(width 0.1524)
				(type default)
			)
			(layer "B.SilkS")
		)
		(fp_line
			(start -0.508 -0.9398)
			(end 0.508 -0.9398)
			(stroke
				(width 0.1524)
				(type default)
			)
			(layer "B.SilkS")
		)
		(fp_rect
			(start 0.508 0.9398)
			(end -0.508 -0.9398)
			(stroke
				(width 0)
				(type default)
			)
			(fill no)
			(layer "B.CrtYd")
		)
		(fp_rect
			(start 0.508 0.9398)
			(end -0.508 -0.9398)
			(stroke
				(width 0)
				(type default)
			)
			(fill no)
			(layer "B.Fab")
		)
		(pad "1" smd custom
			(at 0 -0.4445 270)
			(size 0.1397 0.1397)
			(layers "B.Cu" "B.Mask" "B.Paste")
			(net "FLA1_WPN")
			(options
				(clearance outline)
				(anchor circle)
			)
			(primitives
				(gr_poly
					(pts
						(arc
							(start -0.1778 0.2794)
							(mid -0.249642 0.249642)
							(end -0.2794 0.1778)
						)
						(arc
							(start -0.2794 -0.1778)
							(mid -0.249642 -0.249642)
							(end -0.1778 -0.2794)
						)
						(arc
							(start 0.1778 -0.2794)
							(mid 0.249642 -0.249642)
							(end 0.2794 -0.1778)
						)
						(arc
							(start 0.2794 0.1778)
							(mid 0.249642 0.249642)
							(end 0.1778 0.2794)
						)
					)
					(width 0)
					(fill yes)
				)
			)
		)
		(pad "2" smd custom
			(at 0 0.4445 270)
			(size 0.1397 0.1397)
			(layers "B.Cu" "B.Mask" "B.Paste")
			(net "FLA1_WPN_R")
			(options
				(clearance outline)
				(anchor circle)
			)
			(primitives
				(gr_poly
					(pts
						(arc
							(start -0.1778 0.2794)
							(mid -0.249642 0.249642)
							(end -0.2794 0.1778)
						)
						(arc
							(start -0.2794 -0.1778)
							(mid -0.249642 -0.249642)
							(end -0.1778 -0.2794)
						)
						(arc
							(start 0.1778 -0.2794)
							(mid 0.249642 -0.249642)
							(end 0.2794 -0.1778)
						)
						(arc
							(start 0.2794 0.1778)
							(mid 0.249642 0.249642)
							(end 0.1778 0.2794)
						)
					)
					(width 0)
					(fill yes)
				)
			)
		)
	)
	(footprint ""
		(layer "B.Cu")
		(at 241.599974 -38.999922 90)
		(property "Reference" "TP192"
			(at 0 0 90)
			(layer "B.SilkS")
			(hide yes)
			(effects
				(font
					(size 1.27 1.27)
				)
				(justify mirror)
			)
		)
		(property "Value" "TPAD28-2-GP"
			(at 0.0127 -1.6637 90)
			(unlocked yes)
			(layer "B.Fab")
			(hide yes)
			(effects
				(font
					(size 1.016 1.016)
					(thickness 0.1524)
				)
				(justify mirror)
			)
		)
		(property "Device Type" "TPAD28"
			(at 0.0127 -3.1877 90)
			(unlocked yes)
			(layer "B.Fab")
			(hide yes)
			(effects
				(font
					(size 1.016 1.016)
					(thickness 0.1524)
				)
				(justify mirror)
			)
		)
		(duplicate_pad_numbers_are_jumpers no)
		(fp_poly
			(pts
				(arc
					(start 0 0.3556)
					(mid 0 -0.3556)
					(end 0 0.3556)
				)
			)
			(stroke
				(width 0)
				(type default)
			)
			(fill no)
			(layer "B.CrtYd")
		)
		(fp_poly
			(pts
				(arc
					(start 0 0.6096)
					(mid 0 -0.6096)
					(end 0 0.6096)
				)
			)
			(stroke
				(width 0)
				(type default)
			)
			(fill no)
			(layer "B.Fab")
		)
		(pad "1" smd circle
			(at 0 0 270)
			(size 0.7112 0.7112)
			(layers "B.Cu" "B.Mask" "B.Paste")
			(net "LBI_WE#")
		)
	)
	(footprint ""
		(layer "B.Cu")
		(at 220.5736 -194.5132 90)
		(property "Reference" "R3212"
			(at 0 0 90)
			(layer "B.SilkS")
			(hide yes)
			(effects
				(font
					(size 1.27 1.27)
				)
				(justify mirror)
			)
		)
		(property "Value" "0R2J-2-GP"
			(at -0.064008 -3.993896 90)
			(unlocked yes)
			(layer "B.Fab")
			(hide yes)
			(effects
				(font
					(size 1.016 1.016)
					(thickness 0.1524)
				)
				(justify mirror)
			)
		)
		(property "Device Type" "R402H16"
			(at -0.064008 -5.517896 90)
			(unlocked yes)
			(layer "B.Fab")
			(hide yes)
			(effects
				(font
					(size 1.016 1.016)
					(thickness 0.1524)
				)
				(justify mirror)
			)
		)
		(duplicate_pad_numbers_are_jumpers no)
		(fp_line
			(start 0.508 -0.9398)
			(end 0.508 0.9398)
			(stroke
				(width 0.1524)
				(type default)
			)
			(layer "B.SilkS")
		)
		(fp_line
			(start -0.508 -0.9398)
			(end 0.508 -0.9398)
			(stroke
				(width 0.1524)
				(type default)
			)
			(layer "B.SilkS")
		)
		(fp_rect
			(start 0.508 0.9398)
			(end -0.508 -0.9398)
			(stroke
				(width 0)
				(type default)
			)
			(fill no)
			(layer "B.CrtYd")
		)
		(fp_rect
			(start 0.508 0.9398)
			(end -0.508 -0.9398)
			(stroke
				(width 0)
				(type default)
			)
			(fill no)
			(layer "B.Fab")
		)
		(pad "1" smd custom
			(at 0 -0.4445 270)
			(size 0.1397 0.1397)
			(layers "B.Cu" "B.Mask" "B.Paste")
			(net "SSD_PERST_Y3")
			(options
				(clearance outline)
				(anchor circle)
			)
			(primitives
				(gr_poly
					(pts
						(arc
							(start -0.1778 0.2794)
							(mid -0.249642 0.249642)
							(end -0.2794 0.1778)
						)
						(arc
							(start -0.2794 -0.1778)
							(mid -0.249642 -0.249642)
							(end -0.1778 -0.2794)
						)
						(arc
							(start 0.1778 -0.2794)
							(mid 0.249642 -0.249642)
							(end 0.2794 -0.1778)
						)
						(arc
							(start 0.2794 0.1778)
							(mid 0.249642 0.249642)
							(end 0.1778 0.2794)
						)
					)
					(width 0)
					(fill yes)
				)
			)
		)
		(pad "2" smd custom
			(at 0 0.4445 270)
			(size 0.1397 0.1397)
			(layers "B.Cu" "B.Mask" "B.Paste")
			(net "SSD_PERST#3_R")
			(options
				(clearance outline)
				(anchor circle)
			)
			(primitives
				(gr_poly
					(pts
						(arc
							(start -0.1778 0.2794)
							(mid -0.249642 0.249642)
							(end -0.2794 0.1778)
						)
						(arc
							(start -0.2794 -0.1778)
							(mid -0.249642 -0.249642)
							(end -0.1778 -0.2794)
						)
						(arc
							(start 0.1778 -0.2794)
							(mid 0.249642 -0.249642)
							(end 0.2794 -0.1778)
						)
						(arc
							(start 0.2794 0.1778)
							(mid 0.249642 0.249642)
							(end 0.1778 0.2794)
						)
					)
					(width 0)
					(fill yes)
				)
			)
		)
	)
	(footprint ""
		(layer "B.Cu")
		(at 339.884512 -172.432218)
		(property "Reference" "R4161"
			(at 0 0 0)
			(layer "B.SilkS")
			(hide yes)
			(effects
				(font
					(size 1.27 1.27)
				)
				(justify mirror)
			)
		)
		(property "Value" "4K7R2F-GP"
			(at -0.064008 -3.993896 0)
			(unlocked yes)
			(layer "B.Fab")
			(hide yes)
			(effects
				(font
					(size 1.016 1.016)
					(thickness 0.1524)
				)
				(justify mirror)
			)
		)
		(property "Device Type" "R402H16"
			(at -0.064008 -5.517896 0)
			(unlocked yes)
			(layer "B.Fab")
			(hide yes)
			(effects
				(font
					(size 1.016 1.016)
					(thickness 0.1524)
				)
				(justify mirror)
			)
		)
		(duplicate_pad_numbers_are_jumpers no)
		(fp_line
			(start -0.508 -0.9398)
			(end 0.508 -0.9398)
			(stroke
				(width 0.1524)
				(type default)
			)
			(layer "B.SilkS")
		)
		(fp_line
			(start 0.508 -0.9398)
			(end 0.508 0.9398)
			(stroke
				(width 0.1524)
				(type default)
			)
			(layer "B.SilkS")
		)
		(fp_rect
			(start 0.508 0.9398)
			(end -0.508 -0.9398)
			(stroke
				(width 0)
				(type default)
			)
			(fill no)
			(layer "B.CrtYd")
		)
		(fp_rect
			(start 0.508 0.9398)
			(end -0.508 -0.9398)
			(stroke
				(width 0)
				(type default)
			)
			(fill no)
			(layer "B.Fab")
		)
		(pad "1" smd custom
			(at 0 -0.4445 180)
			(size 0.1397 0.1397)
			(layers "B.Cu" "B.Mask" "B.Paste")
			(net "SSD_PERST#9")
			(options
				(clearance outline)
				(anchor circle)
			)
			(primitives
				(gr_poly
					(pts
						(arc
							(start -0.1778 0.2794)
							(mid -0.249642 0.249642)
							(end -0.2794 0.1778)
						)
						(arc
							(start -0.2794 -0.1778)
							(mid -0.249642 -0.249642)
							(end -0.1778 -0.2794)
						)
						(arc
							(start 0.1778 -0.2794)
							(mid 0.249642 -0.249642)
							(end 0.2794 -0.1778)
						)
						(arc
							(start 0.2794 0.1778)
							(mid 0.249642 0.249642)
							(end 0.1778 0.2794)
						)
					)
					(width 0)
					(fill yes)
				)
			)
		)
		(pad "2" smd custom
			(at 0 0.4445 180)
			(size 0.1397 0.1397)
			(layers "B.Cu" "B.Mask" "B.Paste")
			(net "P3V3_STBY")
			(options
				(clearance outline)
				(anchor circle)
			)
			(primitives
				(gr_poly
					(pts
						(arc
							(start -0.1778 0.2794)
							(mid -0.249642 0.249642)
							(end -0.2794 0.1778)
						)
						(arc
							(start -0.2794 -0.1778)
							(mid -0.249642 -0.249642)
							(end -0.1778 -0.2794)
						)
						(arc
							(start 0.1778 -0.2794)
							(mid 0.249642 -0.249642)
							(end 0.2794 -0.1778)
						)
						(arc
							(start 0.2794 0.1778)
							(mid 0.249642 0.249642)
							(end 0.1778 0.2794)
						)
					)
					(width 0)
					(fill yes)
				)
			)
		)
	)
	(footprint ""
		(layer "B.Cu")
		(at 51.5366 -128.7272 90)
		(property "Reference" "R530"
			(at 0 0 90)
			(layer "B.SilkS")
			(hide yes)
			(effects
				(font
					(size 1.27 1.27)
				)
				(justify mirror)
			)
		)
		(property "Value" "0R2J-2-GP"
			(at -0.064008 -3.993896 90)
			(unlocked yes)
			(layer "B.Fab")
			(hide yes)
			(effects
				(font
					(size 1.016 1.016)
					(thickness 0.1524)
				)
				(justify mirror)
			)
		)
		(property "Device Type" "R402H16"
			(at -0.064008 -5.517896 90)
			(unlocked yes)
			(layer "B.Fab")
			(hide yes)
			(effects
				(font
					(size 1.016 1.016)
					(thickness 0.1524)
				)
				(justify mirror)
			)
		)
		(duplicate_pad_numbers_are_jumpers no)
		(fp_line
			(start 0.508 -0.9398)
			(end 0.508 0.9398)
			(stroke
				(width 0.1524)
				(type default)
			)
			(layer "B.SilkS")
		)
		(fp_line
			(start -0.508 -0.9398)
			(end 0.508 -0.9398)
			(stroke
				(width 0.1524)
				(type default)
			)
			(layer "B.SilkS")
		)
		(fp_rect
			(start 0.508 0.9398)
			(end -0.508 -0.9398)
			(stroke
				(width 0)
				(type default)
			)
			(fill no)
			(layer "B.CrtYd")
		)
		(fp_rect
			(start 0.508 0.9398)
			(end -0.508 -0.9398)
			(stroke
				(width 0)
				(type default)
			)
			(fill no)
			(layer "B.Fab")
		)
		(pad "1" smd custom
			(at 0 -0.4445 270)
			(size 0.1397 0.1397)
			(layers "B.Cu" "B.Mask" "B.Paste")
			(net "BMC0_SMB14_CLK")
			(options
				(clearance outline)
				(anchor circle)
			)
			(primitives
				(gr_poly
					(pts
						(arc
							(start -0.1778 0.2794)
							(mid -0.249642 0.249642)
							(end -0.2794 0.1778)
						)
						(arc
							(start -0.2794 -0.1778)
							(mid -0.249642 -0.249642)
							(end -0.1778 -0.2794)
						)
						(arc
							(start 0.1778 -0.2794)
							(mid 0.249642 -0.249642)
							(end 0.2794 -0.1778)
						)
						(arc
							(start 0.2794 0.1778)
							(mid 0.249642 0.249642)
							(end 0.1778 0.2794)
						)
					)
					(width 0)
					(fill yes)
				)
			)
		)
		(pad "2" smd custom
			(at 0 0.4445 270)
			(size 0.1397 0.1397)
			(layers "B.Cu" "B.Mask" "B.Paste")
			(net "BMC_I2C14_MINI8_SCL_S")
			(options
				(clearance outline)
				(anchor circle)
			)
			(primitives
				(gr_poly
					(pts
						(arc
							(start -0.1778 0.2794)
							(mid -0.249642 0.249642)
							(end -0.2794 0.1778)
						)
						(arc
							(start -0.2794 -0.1778)
							(mid -0.249642 -0.249642)
							(end -0.1778 -0.2794)
						)
						(arc
							(start 0.1778 -0.2794)
							(mid 0.249642 -0.249642)
							(end 0.2794 -0.1778)
						)
						(arc
							(start 0.2794 0.1778)
							(mid 0.249642 0.249642)
							(end 0.1778 0.2794)
						)
					)
					(width 0)
					(fill yes)
				)
			)
		)
	)
	(footprint ""
		(layer "B.Cu")
		(at 220.702124 -190.601092)
		(property "Reference" "R4135"
			(at 0 0 0)
			(layer "B.SilkS")
			(hide yes)
			(effects
				(font
					(size 1.27 1.27)
				)
				(justify mirror)
			)
		)
		(property "Value" "4K7R2F-GP"
			(at -0.064008 -3.993896 0)
			(unlocked yes)
			(layer "B.Fab")
			(hide yes)
			(effects
				(font
					(size 1.016 1.016)
					(thickness 0.1524)
				)
				(justify mirror)
			)
		)
		(property "Device Type" "R402H16"
			(at -0.064008 -5.517896 0)
			(unlocked yes)
			(layer "B.Fab")
			(hide yes)
			(effects
				(font
					(size 1.016 1.016)
					(thickness 0.1524)
				)
				(justify mirror)
			)
		)
		(duplicate_pad_numbers_are_jumpers no)
		(fp_line
			(start -0.508 -0.9398)
			(end 0.508 -0.9398)
			(stroke
				(width 0.1524)
				(type default)
			)
			(layer "B.SilkS")
		)
		(fp_line
			(start 0.508 -0.9398)
			(end 0.508 0.9398)
			(stroke
				(width 0.1524)
				(type default)
			)
			(layer "B.SilkS")
		)
		(fp_rect
			(start 0.508 0.9398)
			(end -0.508 -0.9398)
			(stroke
				(width 0)
				(type default)
			)
			(fill no)
			(layer "B.CrtYd")
		)
		(fp_rect
			(start 0.508 0.9398)
			(end -0.508 -0.9398)
			(stroke
				(width 0)
				(type default)
			)
			(fill no)
			(layer "B.Fab")
		)
		(pad "1" smd custom
			(at 0 -0.4445 180)
			(size 0.1397 0.1397)
			(layers "B.Cu" "B.Mask" "B.Paste")
			(net "SSD_ATNLED#3")
			(options
				(clearance outline)
				(anchor circle)
			)
			(primitives
				(gr_poly
					(pts
						(arc
							(start -0.1778 0.2794)
							(mid -0.249642 0.249642)
							(end -0.2794 0.1778)
						)
						(arc
							(start -0.2794 -0.1778)
							(mid -0.249642 -0.249642)
							(end -0.1778 -0.2794)
						)
						(arc
							(start 0.1778 -0.2794)
							(mid 0.249642 -0.249642)
							(end 0.2794 -0.1778)
						)
						(arc
							(start 0.2794 0.1778)
							(mid 0.249642 0.249642)
							(end 0.1778 0.2794)
						)
					)
					(width 0)
					(fill yes)
				)
			)
		)
		(pad "2" smd custom
			(at 0 0.4445 180)
			(size 0.1397 0.1397)
			(layers "B.Cu" "B.Mask" "B.Paste")
			(net "P3V3_STBY")
			(options
				(clearance outline)
				(anchor circle)
			)
			(primitives
				(gr_poly
					(pts
						(arc
							(start -0.1778 0.2794)
							(mid -0.249642 0.249642)
							(end -0.2794 0.1778)
						)
						(arc
							(start -0.2794 -0.1778)
							(mid -0.249642 -0.249642)
							(end -0.1778 -0.2794)
						)
						(arc
							(start 0.1778 -0.2794)
							(mid 0.249642 -0.249642)
							(end 0.2794 -0.1778)
						)
						(arc
							(start 0.2794 0.1778)
							(mid 0.249642 0.249642)
							(end 0.1778 0.2794)
						)
					)
					(width 0)
					(fill yes)
				)
			)
		)
	)
	(footprint ""
		(layer "B.Cu")
		(at 74.804524 -183.235092)
		(property "Reference" "R4104"
			(at 0 0 0)
			(layer "B.SilkS")
			(hide yes)
			(effects
				(font
					(size 1.27 1.27)
				)
				(justify mirror)
			)
		)
		(property "Value" "4K7R2F-GP"
			(at -0.064008 -3.993896 0)
			(unlocked yes)
			(layer "B.Fab")
			(hide yes)
			(effects
				(font
					(size 1.016 1.016)
					(thickness 0.1524)
				)
				(justify mirror)
			)
		)
		(property "Device Type" "R402H16"
			(at -0.064008 -5.517896 0)
			(unlocked yes)
			(layer "B.Fab")
			(hide yes)
			(effects
				(font
					(size 1.016 1.016)
					(thickness 0.1524)
				)
				(justify mirror)
			)
		)
		(duplicate_pad_numbers_are_jumpers no)
		(fp_line
			(start -0.508 -0.9398)
			(end 0.508 -0.9398)
			(stroke
				(width 0.1524)
				(type default)
			)
			(layer "B.SilkS")
		)
		(fp_line
			(start 0.508 -0.9398)
			(end 0.508 0.9398)
			(stroke
				(width 0.1524)
				(type default)
			)
			(layer "B.SilkS")
		)
		(fp_rect
			(start 0.508 0.9398)
			(end -0.508 -0.9398)
			(stroke
				(width 0)
				(type default)
			)
			(fill no)
			(layer "B.CrtYd")
		)
		(fp_rect
			(start 0.508 0.9398)
			(end -0.508 -0.9398)
			(stroke
				(width 0)
				(type default)
			)
			(fill no)
			(layer "B.Fab")
		)
		(pad "1" smd custom
			(at 0 -0.4445 180)
			(size 0.1397 0.1397)
			(layers "B.Cu" "B.Mask" "B.Paste")
			(net "SSD_PERST#0")
			(options
				(clearance outline)
				(anchor circle)
			)
			(primitives
				(gr_poly
					(pts
						(arc
							(start -0.1778 0.2794)
							(mid -0.249642 0.249642)
							(end -0.2794 0.1778)
						)
						(arc
							(start -0.2794 -0.1778)
							(mid -0.249642 -0.249642)
							(end -0.1778 -0.2794)
						)
						(arc
							(start 0.1778 -0.2794)
							(mid 0.249642 -0.249642)
							(end 0.2794 -0.1778)
						)
						(arc
							(start 0.2794 0.1778)
							(mid 0.249642 0.249642)
							(end 0.1778 0.2794)
						)
					)
					(width 0)
					(fill yes)
				)
			)
		)
		(pad "2" smd custom
			(at 0 0.4445 180)
			(size 0.1397 0.1397)
			(layers "B.Cu" "B.Mask" "B.Paste")
			(net "P3V3_STBY")
			(options
				(clearance outline)
				(anchor circle)
			)
			(primitives
				(gr_poly
					(pts
						(arc
							(start -0.1778 0.2794)
							(mid -0.249642 0.249642)
							(end -0.2794 0.1778)
						)
						(arc
							(start -0.2794 -0.1778)
							(mid -0.249642 -0.249642)
							(end -0.1778 -0.2794)
						)
						(arc
							(start 0.1778 -0.2794)
							(mid 0.249642 -0.249642)
							(end 0.2794 -0.1778)
						)
						(arc
							(start 0.2794 0.1778)
							(mid 0.249642 0.249642)
							(end 0.1778 0.2794)
						)
					)
					(width 0)
					(fill yes)
				)
			)
		)
	)
	(footprint ""
		(layer "B.Cu")
		(at 50.673 -195.58 180)
		(property "Reference" "R892"
			(at 0 0 0)
			(layer "B.SilkS")
			(hide yes)
			(effects
				(font
					(size 1.27 1.27)
				)
				(justify mirror)
			)
		)
		(property "Value" "0R2J-2-GP"
			(at -0.064008 -3.993896 180)
			(unlocked yes)
			(layer "B.Fab")
			(hide yes)
			(effects
				(font
					(size 1.016 1.016)
					(thickness 0.1524)
				)
				(justify mirror)
			)
		)
		(property "Device Type" "R402H16"
			(at -0.064008 -5.517896 180)
			(unlocked yes)
			(layer "B.Fab")
			(hide yes)
			(effects
				(font
					(size 1.016 1.016)
					(thickness 0.1524)
				)
				(justify mirror)
			)
		)
		(duplicate_pad_numbers_are_jumpers no)
		(fp_line
			(start 0.508 -0.9398)
			(end 0.508 0.9398)
			(stroke
				(width 0.1524)
				(type default)
			)
			(layer "B.SilkS")
		)
		(fp_line
			(start -0.508 -0.9398)
			(end 0.508 -0.9398)
			(stroke
				(width 0.1524)
				(type default)
			)
			(layer "B.SilkS")
		)
		(fp_rect
			(start 0.508 0.9398)
			(end -0.508 -0.9398)
			(stroke
				(width 0)
				(type default)
			)
			(fill no)
			(layer "B.CrtYd")
		)
		(fp_rect
			(start 0.508 0.9398)
			(end -0.508 -0.9398)
			(stroke
				(width 0)
				(type default)
			)
			(fill no)
			(layer "B.Fab")
		)
		(pad "1" smd custom
			(at 0 -0.4445)
			(size 0.1397 0.1397)
			(layers "B.Cu" "B.Mask" "B.Paste")
			(net "BMC_I2C7_B_DPB_SDA")
			(options
				(clearance outline)
				(anchor circle)
			)
			(primitives
				(gr_poly
					(pts
						(arc
							(start -0.1778 0.2794)
							(mid -0.249642 0.249642)
							(end -0.2794 0.1778)
						)
						(arc
							(start -0.2794 -0.1778)
							(mid -0.249642 -0.249642)
							(end -0.1778 -0.2794)
						)
						(arc
							(start 0.1778 -0.2794)
							(mid 0.249642 -0.249642)
							(end 0.2794 -0.1778)
						)
						(arc
							(start 0.2794 0.1778)
							(mid 0.249642 0.249642)
							(end 0.1778 0.2794)
						)
					)
					(width 0)
					(fill yes)
				)
			)
		)
		(pad "2" smd custom
			(at 0 0.4445)
			(size 0.1397 0.1397)
			(layers "B.Cu" "B.Mask" "B.Paste")
			(net "BUF_I2C7_B_DPB_SDA")
			(options
				(clearance outline)
				(anchor circle)
			)
			(primitives
				(gr_poly
					(pts
						(arc
							(start -0.1778 0.2794)
							(mid -0.249642 0.249642)
							(end -0.2794 0.1778)
						)
						(arc
							(start -0.2794 -0.1778)
							(mid -0.249642 -0.249642)
							(end -0.1778 -0.2794)
						)
						(arc
							(start 0.1778 -0.2794)
							(mid 0.249642 -0.249642)
							(end 0.2794 -0.1778)
						)
						(arc
							(start 0.2794 0.1778)
							(mid 0.249642 0.249642)
							(end 0.1778 0.2794)
						)
					)
					(width 0)
					(fill yes)
				)
			)
		)
	)
	(footprint ""
		(layer "B.Cu")
		(at 74.422 -189.611)
		(property "Reference" "U64"
			(at 0 0 0)
			(layer "B.SilkS")
			(hide yes)
			(effects
				(font
					(size 1.27 1.27)
				)
				(justify mirror)
			)
		)
		(property "Value" "SN74LVC1G08DCKR-GP"
			(at 2.3368 -8.6868 0)
			(unlocked yes)
			(layer "B.Fab")
			(hide yes)
			(effects
				(font
					(size 1.016 1.016)
					(thickness 0.1524)
				)
				(justify mirror)
			)
		)
		(property "Device Type" "SC70-5H44"
			(at 2.3114 -10.414 0)
			(unlocked yes)
			(layer "B.Fab")
			(hide yes)
			(effects
				(font
					(size 1.016 1.016)
					(thickness 0.1524)
				)
				(justify mirror)
			)
		)
		(duplicate_pad_numbers_are_jumpers no)
		(fp_line
			(start -1.3843 -1.8034)
			(end -1.3843 -1.1176)
			(stroke
				(width 0.3302)
				(type default)
			)
			(layer "B.SilkS")
		)
		(fp_line
			(start -1.27 -1.7018)
			(end -1.27 1.7018)
			(stroke
				(width 0.1524)
				(type default)
			)
			(layer "B.SilkS")
		)
		(fp_line
			(start -1.27 1.7018)
			(end 1.27 1.7018)
			(stroke
				(width 0.1524)
				(type default)
			)
			(layer "B.SilkS")
		)
		(fp_line
			(start -0.6604 -1.8034)
			(end -1.3843 -1.8034)
			(stroke
				(width 0.3302)
				(type default)
			)
			(layer "B.SilkS")
		)
		(fp_line
			(start 1.27 -1.7018)
			(end -1.27 -1.7018)
			(stroke
				(width 0.1524)
				(type default)
			)
			(layer "B.SilkS")
		)
		(fp_line
			(start 1.27 1.7018)
			(end 1.27 -1.7018)
			(stroke
				(width 0.1524)
				(type default)
			)
			(layer "B.SilkS")
		)
		(fp_rect
			(start 1.524 1.9558)
			(end -1.524 -1.9558)
			(stroke
				(width 0)
				(type default)
			)
			(fill no)
			(layer "B.CrtYd")
		)
		(fp_poly
			(pts
				(xy 1.524 -1.9558) (xy -1.524 -1.9558) (xy -1.524 1.9558) (xy 1.524 1.9558)
			)
			(stroke
				(width 0)
				(type default)
			)
			(fill no)
			(layer "B.Fab")
		)
		(pad "1" smd rect
			(at -0.65024 -0.8255 180)
			(size 0.4064 1.2192)
			(layers "B.Cu" "B.Mask" "B.Paste")
			(net "BMC_SSD_RST#0_A0")
		)
		(pad "2" smd rect
			(at 0 -0.8255 180)
			(size 0.4064 1.2192)
			(layers "B.Cu" "B.Mask" "B.Paste")
			(net "SSD_PERST#0_B0")
		)
		(pad "3" smd rect
			(at 0.65024 -0.8255 180)
			(size 0.4064 1.2192)
			(layers "B.Cu" "B.Mask" "B.Paste")
			(net "GND")
		)
		(pad "4" smd rect
			(at 0.65024 0.8255 180)
			(size 0.4064 1.2192)
			(layers "B.Cu" "B.Mask" "B.Paste")
			(net "SSD_PERST_Y0")
		)
		(pad "5" smd rect
			(at -0.65024 0.8255 180)
			(size 0.4064 1.2192)
			(layers "B.Cu" "B.Mask" "B.Paste")
			(net "P3V3_STBY")
		)
	)
	(footprint ""
		(layer "B.Cu")
		(at 219.806012 -203.055474)
		(property "Reference" "R551"
			(at 0 0 0)
			(layer "B.SilkS")
			(hide yes)
			(effects
				(font
					(size 1.27 1.27)
				)
				(justify mirror)
			)
		)
		(property "Value" "10KR2F-2-GP"
			(at -0.064008 -3.993896 0)
			(unlocked yes)
			(layer "B.Fab")
			(hide yes)
			(effects
				(font
					(size 1.016 1.016)
					(thickness 0.1524)
				)
				(justify mirror)
			)
		)
		(property "Device Type" "R402H16"
			(at -0.064008 -5.517896 0)
			(unlocked yes)
			(layer "B.Fab")
			(hide yes)
			(effects
				(font
					(size 1.016 1.016)
					(thickness 0.1524)
				)
				(justify mirror)
			)
		)
		(duplicate_pad_numbers_are_jumpers no)
		(fp_line
			(start -0.508 -0.9398)
			(end 0.508 -0.9398)
			(stroke
				(width 0.1524)
				(type default)
			)
			(layer "B.SilkS")
		)
		(fp_line
			(start 0.508 -0.9398)
			(end 0.508 0.9398)
			(stroke
				(width 0.1524)
				(type default)
			)
			(layer "B.SilkS")
		)
		(fp_rect
			(start 0.508 0.9398)
			(end -0.508 -0.9398)
			(stroke
				(width 0)
				(type default)
			)
			(fill no)
			(layer "B.CrtYd")
		)
		(fp_rect
			(start 0.508 0.9398)
			(end -0.508 -0.9398)
			(stroke
				(width 0)
				(type default)
			)
			(fill no)
			(layer "B.Fab")
		)
		(pad "1" smd custom
			(at 0 -0.4445 180)
			(size 0.1397 0.1397)
			(layers "B.Cu" "B.Mask" "B.Paste")
			(net "P3V3_STBY")
			(options
				(clearance outline)
				(anchor circle)
			)
			(primitives
				(gr_poly
					(pts
						(arc
							(start -0.1778 0.2794)
							(mid -0.249642 0.249642)
							(end -0.2794 0.1778)
						)
						(arc
							(start -0.2794 -0.1778)
							(mid -0.249642 -0.249642)
							(end -0.1778 -0.2794)
						)
						(arc
							(start 0.1778 -0.2794)
							(mid 0.249642 -0.249642)
							(end 0.2794 -0.1778)
						)
						(arc
							(start 0.2794 0.1778)
							(mid 0.249642 0.249642)
							(end 0.1778 0.2794)
						)
					)
					(width 0)
					(fill yes)
				)
			)
		)
		(pad "2" smd custom
			(at 0 0.4445 180)
			(size 0.1397 0.1397)
			(layers "B.Cu" "B.Mask" "B.Paste")
			(net "IOEXP3_AD0")
			(options
				(clearance outline)
				(anchor circle)
			)
			(primitives
				(gr_poly
					(pts
						(arc
							(start -0.1778 0.2794)
							(mid -0.249642 0.249642)
							(end -0.2794 0.1778)
						)
						(arc
							(start -0.2794 -0.1778)
							(mid -0.249642 -0.249642)
							(end -0.1778 -0.2794)
						)
						(arc
							(start 0.1778 -0.2794)
							(mid 0.249642 -0.249642)
							(end 0.2794 -0.1778)
						)
						(arc
							(start 0.2794 0.1778)
							(mid 0.249642 0.249642)
							(end 0.1778 0.2794)
						)
					)
					(width 0)
					(fill yes)
				)
			)
		)
	)
	(footprint ""
		(layer "B.Cu")
		(at 267.5128 -9.30021 90)
		(property "Reference" "R725"
			(at 0 0 90)
			(layer "B.SilkS")
			(hide yes)
			(effects
				(font
					(size 1.27 1.27)
				)
				(justify mirror)
			)
		)
		(property "Value" "0R2J-2-GP"
			(at -0.064008 -3.993896 90)
			(unlocked yes)
			(layer "B.Fab")
			(hide yes)
			(effects
				(font
					(size 1.016 1.016)
					(thickness 0.1524)
				)
				(justify mirror)
			)
		)
		(property "Device Type" "R402H16"
			(at -0.064008 -5.517896 90)
			(unlocked yes)
			(layer "B.Fab")
			(hide yes)
			(effects
				(font
					(size 1.016 1.016)
					(thickness 0.1524)
				)
				(justify mirror)
			)
		)
		(duplicate_pad_numbers_are_jumpers no)
		(fp_line
			(start 0.508 -0.9398)
			(end 0.508 0.9398)
			(stroke
				(width 0.1524)
				(type default)
			)
			(layer "B.SilkS")
		)
		(fp_line
			(start -0.508 -0.9398)
			(end 0.508 -0.9398)
			(stroke
				(width 0.1524)
				(type default)
			)
			(layer "B.SilkS")
		)
		(fp_rect
			(start 0.508 0.9398)
			(end -0.508 -0.9398)
			(stroke
				(width 0)
				(type default)
			)
			(fill no)
			(layer "B.CrtYd")
		)
		(fp_rect
			(start 0.508 0.9398)
			(end -0.508 -0.9398)
			(stroke
				(width 0)
				(type default)
			)
			(fill no)
			(layer "B.Fab")
		)
		(pad "1" smd custom
			(at 0 -0.4445 270)
			(size 0.1397 0.1397)
			(layers "B.Cu" "B.Mask" "B.Paste")
			(net "HOST8_RST_N_C")
			(options
				(clearance outline)
				(anchor circle)
			)
			(primitives
				(gr_poly
					(pts
						(arc
							(start -0.1778 0.2794)
							(mid -0.249642 0.249642)
							(end -0.2794 0.1778)
						)
						(arc
							(start -0.2794 -0.1778)
							(mid -0.249642 -0.249642)
							(end -0.1778 -0.2794)
						)
						(arc
							(start 0.1778 -0.2794)
							(mid 0.249642 -0.249642)
							(end 0.2794 -0.1778)
						)
						(arc
							(start 0.2794 0.1778)
							(mid 0.249642 0.249642)
							(end 0.1778 0.2794)
						)
					)
					(width 0)
					(fill yes)
				)
			)
		)
		(pad "2" smd custom
			(at 0 0.4445 270)
			(size 0.1397 0.1397)
			(layers "B.Cu" "B.Mask" "B.Paste")
			(net "P3V3_STBY")
			(options
				(clearance outline)
				(anchor circle)
			)
			(primitives
				(gr_poly
					(pts
						(arc
							(start -0.1778 0.2794)
							(mid -0.249642 0.249642)
							(end -0.2794 0.1778)
						)
						(arc
							(start -0.2794 -0.1778)
							(mid -0.249642 -0.249642)
							(end -0.1778 -0.2794)
						)
						(arc
							(start 0.1778 -0.2794)
							(mid 0.249642 -0.249642)
							(end 0.2794 -0.1778)
						)
						(arc
							(start 0.2794 0.1778)
							(mid 0.249642 0.249642)
							(end 0.1778 0.2794)
						)
					)
					(width 0)
					(fill yes)
				)
			)
		)
	)
	(footprint ""
		(layer "B.Cu")
		(at 41.656 -129.286 -90)
		(property "Reference" "C208"
			(at 0 0 90)
			(layer "B.SilkS")
			(hide yes)
			(effects
				(font
					(size 1.27 1.27)
				)
				(justify mirror)
			)
		)
		(property "Value" "SC1U10V2KX-4-GP"
			(at -1.1811 -2.7051 270)
			(unlocked yes)
			(layer "B.Fab")
			(hide yes)
			(effects
				(font
					(size 1.016 1.016)
					(thickness 0.1524)
				)
				(justify mirror)
			)
		)
		(property "Device Type" "C402H22"
			(at -1.1811 -4.2291 270)
			(unlocked yes)
			(layer "B.Fab")
			(hide yes)
			(effects
				(font
					(size 1.016 1.016)
					(thickness 0.1524)
				)
				(justify mirror)
			)
		)
		(duplicate_pad_numbers_are_jumpers no)
		(fp_rect
			(start 0.4318 0.9525)
			(end -0.4318 -0.9525)
			(stroke
				(width 0)
				(type default)
			)
			(fill no)
			(layer "B.CrtYd")
		)
		(fp_rect
			(start 0.4318 0.9525)
			(end -0.4318 -0.9525)
			(stroke
				(width 0)
				(type default)
			)
			(fill no)
			(layer "B.Fab")
		)
		(pad "1" smd custom
			(at 0 -0.4445 90)
			(size 0.1524 0.1524)
			(layers "B.Cu" "B.Mask" "B.Paste")
			(net "P3V3_STBY")
			(options
				(clearance outline)
				(anchor circle)
			)
			(primitives
				(gr_poly
					(pts
						(arc
							(start 0.3048 0.2032)
							(mid 0.275042 0.275042)
							(end 0.2032 0.3048)
						)
						(arc
							(start -0.2032 0.3048)
							(mid -0.275042 0.275042)
							(end -0.3048 0.2032)
						)
						(arc
							(start -0.3048 -0.2032)
							(mid -0.275042 -0.275042)
							(end -0.2032 -0.3048)
						)
						(arc
							(start 0.2032 -0.3048)
							(mid 0.275042 -0.275042)
							(end 0.3048 -0.2032)
						)
					)
					(width 0)
					(fill yes)
				)
			)
		)
		(pad "2" smd custom
			(at 0 0.4445 90)
			(size 0.1524 0.1524)
			(layers "B.Cu" "B.Mask" "B.Paste")
			(net "GND")
			(options
				(clearance outline)
				(anchor circle)
			)
			(primitives
				(gr_poly
					(pts
						(arc
							(start 0.3048 0.2032)
							(mid 0.275042 0.275042)
							(end 0.2032 0.3048)
						)
						(arc
							(start -0.2032 0.3048)
							(mid -0.275042 0.275042)
							(end -0.3048 0.2032)
						)
						(arc
							(start -0.3048 -0.2032)
							(mid -0.275042 -0.275042)
							(end -0.2032 -0.3048)
						)
						(arc
							(start 0.2032 -0.3048)
							(mid 0.275042 -0.275042)
							(end 0.3048 -0.2032)
						)
					)
					(width 0)
					(fill yes)
				)
			)
		)
	)
	(footprint ""
		(layer "B.Cu")
		(at 227.629212 -200.007474)
		(property "Reference" "R3237"
			(at 0 0 0)
			(layer "B.SilkS")
			(hide yes)
			(effects
				(font
					(size 1.27 1.27)
				)
				(justify mirror)
			)
		)
		(property "Value" "0R2J-2-GP"
			(at -0.064008 -3.993896 0)
			(unlocked yes)
			(layer "B.Fab")
			(hide yes)
			(effects
				(font
					(size 1.016 1.016)
					(thickness 0.1524)
				)
				(justify mirror)
			)
		)
		(property "Device Type" "R402H16"
			(at -0.064008 -5.517896 0)
			(unlocked yes)
			(layer "B.Fab")
			(hide yes)
			(effects
				(font
					(size 1.016 1.016)
					(thickness 0.1524)
				)
				(justify mirror)
			)
		)
		(duplicate_pad_numbers_are_jumpers no)
		(fp_line
			(start -0.508 -0.9398)
			(end 0.508 -0.9398)
			(stroke
				(width 0.1524)
				(type default)
			)
			(layer "B.SilkS")
		)
		(fp_line
			(start 0.508 -0.9398)
			(end 0.508 0.9398)
			(stroke
				(width 0.1524)
				(type default)
			)
			(layer "B.SilkS")
		)
		(fp_rect
			(start 0.508 0.9398)
			(end -0.508 -0.9398)
			(stroke
				(width 0)
				(type default)
			)
			(fill no)
			(layer "B.CrtYd")
		)
		(fp_rect
			(start 0.508 0.9398)
			(end -0.508 -0.9398)
			(stroke
				(width 0)
				(type default)
			)
			(fill no)
			(layer "B.Fab")
		)
		(pad "1" smd custom
			(at 0 -0.4445 180)
			(size 0.1397 0.1397)
			(layers "B.Cu" "B.Mask" "B.Paste")
			(net "SSD_PERST#12")
			(options
				(clearance outline)
				(anchor circle)
			)
			(primitives
				(gr_poly
					(pts
						(arc
							(start -0.1778 0.2794)
							(mid -0.249642 0.249642)
							(end -0.2794 0.1778)
						)
						(arc
							(start -0.2794 -0.1778)
							(mid -0.249642 -0.249642)
							(end -0.1778 -0.2794)
						)
						(arc
							(start 0.1778 -0.2794)
							(mid 0.249642 -0.249642)
							(end 0.2794 -0.1778)
						)
						(arc
							(start 0.2794 0.1778)
							(mid 0.249642 0.249642)
							(end 0.1778 0.2794)
						)
					)
					(width 0)
					(fill yes)
				)
			)
		)
		(pad "2" smd custom
			(at 0 0.4445 180)
			(size 0.1397 0.1397)
			(layers "B.Cu" "B.Mask" "B.Paste")
			(net "SSD_PERST#0_B12")
			(options
				(clearance outline)
				(anchor circle)
			)
			(primitives
				(gr_poly
					(pts
						(arc
							(start -0.1778 0.2794)
							(mid -0.249642 0.249642)
							(end -0.2794 0.1778)
						)
						(arc
							(start -0.2794 -0.1778)
							(mid -0.249642 -0.249642)
							(end -0.1778 -0.2794)
						)
						(arc
							(start 0.1778 -0.2794)
							(mid 0.249642 -0.249642)
							(end 0.2794 -0.1778)
						)
						(arc
							(start 0.2794 0.1778)
							(mid 0.249642 0.249642)
							(end 0.1778 0.2794)
						)
					)
					(width 0)
					(fill yes)
				)
			)
		)
	)
	(footprint ""
		(layer "B.Cu")
		(at 247.591072 -32.004)
		(property "Reference" "C471"
			(at 0 0 0)
			(layer "B.SilkS")
			(hide yes)
			(effects
				(font
					(size 1.27 1.27)
				)
				(justify mirror)
			)
		)
		(property "Value" "SCD1U16V1KX-1-GP"
			(at 2.8321 -1.7399 0)
			(unlocked yes)
			(layer "B.Fab")
			(hide yes)
			(effects
				(font
					(size 1.016 1.016)
					(thickness 0.1524)
				)
				(justify mirror)
			)
		)
		(property "Device Type" "C0201H13"
			(at 2.8321 -3.2639 0)
			(unlocked yes)
			(layer "B.Fab")
			(hide yes)
			(effects
				(font
					(size 1.016 1.016)
					(thickness 0.1524)
				)
				(justify mirror)
			)
		)
		(duplicate_pad_numbers_are_jumpers no)
		(fp_rect
			(start 0.2794 0.6477)
			(end -0.2794 -0.6477)
			(stroke
				(width 0)
				(type default)
			)
			(fill no)
			(layer "B.CrtYd")
		)
		(fp_rect
			(start 0.2794 0.6477)
			(end -0.2794 -0.6477)
			(stroke
				(width 0)
				(type default)
			)
			(fill no)
			(layer "B.Fab")
		)
		(pad "1" smd custom
			(at 0 -0.2794 180)
			(size 0.0762 0.0762)
			(layers "B.Cu" "B.Mask" "B.Paste")
			(net "DUT_VDDO")
			(options
				(clearance outline)
				(anchor circle)
			)
			(primitives
				(gr_poly
					(pts
						(arc
							(start 0.1524 0.127)
							(mid 0.137521 0.162921)
							(end 0.1016 0.1778)
						)
						(arc
							(start -0.1016 0.1778)
							(mid -0.137521 0.162921)
							(end -0.1524 0.127)
						)
						(arc
							(start -0.1524 -0.127)
							(mid -0.137521 -0.162921)
							(end -0.1016 -0.1778)
						)
						(arc
							(start 0.1016 -0.1778)
							(mid 0.137521 -0.162921)
							(end 0.1524 -0.127)
						)
					)
					(width 0)
					(fill yes)
				)
			)
		)
		(pad "2" smd custom
			(at 0 0.2794 180)
			(size 0.0762 0.0762)
			(layers "B.Cu" "B.Mask" "B.Paste")
			(net "GND")
			(options
				(clearance outline)
				(anchor circle)
			)
			(primitives
				(gr_poly
					(pts
						(arc
							(start 0.1524 0.127)
							(mid 0.137521 0.162921)
							(end 0.1016 0.1778)
						)
						(arc
							(start -0.1016 0.1778)
							(mid -0.137521 0.162921)
							(end -0.1524 0.127)
						)
						(arc
							(start -0.1524 -0.127)
							(mid -0.137521 -0.162921)
							(end -0.1016 -0.1778)
						)
						(arc
							(start 0.1016 -0.1778)
							(mid 0.137521 -0.162921)
							(end 0.1524 -0.127)
						)
					)
					(width 0)
					(fill yes)
				)
			)
		)
	)
	(footprint ""
		(layer "B.Cu")
		(at 296.724578 -35.058604 180)
		(property "Reference" "C257"
			(at 0 0 0)
			(layer "B.SilkS")
			(hide yes)
			(effects
				(font
					(size 1.27 1.27)
				)
				(justify mirror)
			)
		)
		(property "Value" "SCD1U10V2KX-5GP"
			(at -1.1811 -2.7051 180)
			(unlocked yes)
			(layer "B.Fab")
			(hide yes)
			(effects
				(font
					(size 1.016 1.016)
					(thickness 0.1524)
				)
				(justify mirror)
			)
		)
		(property "Device Type" "C402H22"
			(at -1.1811 -4.2291 180)
			(unlocked yes)
			(layer "B.Fab")
			(hide yes)
			(effects
				(font
					(size 1.016 1.016)
					(thickness 0.1524)
				)
				(justify mirror)
			)
		)
		(duplicate_pad_numbers_are_jumpers no)
		(fp_rect
			(start 0.4318 0.9525)
			(end -0.4318 -0.9525)
			(stroke
				(width 0)
				(type default)
			)
			(fill no)
			(layer "B.CrtYd")
		)
		(fp_rect
			(start 0.4318 0.9525)
			(end -0.4318 -0.9525)
			(stroke
				(width 0)
				(type default)
			)
			(fill no)
			(layer "B.Fab")
		)
		(pad "1" smd custom
			(at 0 -0.4445)
			(size 0.1524 0.1524)
			(layers "B.Cu" "B.Mask" "B.Paste")
			(net "GND")
			(options
				(clearance outline)
				(anchor circle)
			)
			(primitives
				(gr_poly
					(pts
						(arc
							(start 0.3048 0.2032)
							(mid 0.275042 0.275042)
							(end 0.2032 0.3048)
						)
						(arc
							(start -0.2032 0.3048)
							(mid -0.275042 0.275042)
							(end -0.3048 0.2032)
						)
						(arc
							(start -0.3048 -0.2032)
							(mid -0.275042 -0.275042)
							(end -0.2032 -0.3048)
						)
						(arc
							(start 0.2032 -0.3048)
							(mid 0.275042 -0.275042)
							(end 0.3048 -0.2032)
						)
					)
					(width 0)
					(fill yes)
				)
			)
		)
		(pad "2" smd custom
			(at 0 0.4445)
			(size 0.1524 0.1524)
			(layers "B.Cu" "B.Mask" "B.Paste")
			(net "P3V3_STBY")
			(options
				(clearance outline)
				(anchor circle)
			)
			(primitives
				(gr_poly
					(pts
						(arc
							(start 0.3048 0.2032)
							(mid 0.275042 0.275042)
							(end 0.2032 0.3048)
						)
						(arc
							(start -0.2032 0.3048)
							(mid -0.275042 0.275042)
							(end -0.3048 0.2032)
						)
						(arc
							(start -0.3048 -0.2032)
							(mid -0.275042 -0.275042)
							(end -0.2032 -0.3048)
						)
						(arc
							(start 0.2032 -0.3048)
							(mid 0.275042 -0.275042)
							(end 0.3048 -0.2032)
						)
					)
					(width 0)
					(fill yes)
				)
			)
		)
	)
	(footprint ""
		(layer "B.Cu")
		(at 243.967 -26.67 90)
		(property "Reference" "TP197"
			(at 0 0 90)
			(layer "B.SilkS")
			(hide yes)
			(effects
				(font
					(size 1.27 1.27)
				)
				(justify mirror)
			)
		)
		(property "Value" "TPAD28-2-GP"
			(at 0.0127 -1.6637 90)
			(unlocked yes)
			(layer "B.Fab")
			(hide yes)
			(effects
				(font
					(size 1.016 1.016)
					(thickness 0.1524)
				)
				(justify mirror)
			)
		)
		(property "Device Type" "TPAD28"
			(at 0.0127 -3.1877 90)
			(unlocked yes)
			(layer "B.Fab")
			(hide yes)
			(effects
				(font
					(size 1.016 1.016)
					(thickness 0.1524)
				)
				(justify mirror)
			)
		)
		(duplicate_pad_numbers_are_jumpers no)
		(fp_poly
			(pts
				(arc
					(start 0 0.3556)
					(mid 0 -0.3556)
					(end 0 0.3556)
				)
			)
			(stroke
				(width 0)
				(type default)
			)
			(fill no)
			(layer "B.CrtYd")
		)
		(fp_poly
			(pts
				(arc
					(start 0 0.6096)
					(mid 0 -0.6096)
					(end 0 0.6096)
				)
			)
			(stroke
				(width 0)
				(type default)
			)
			(fill no)
			(layer "B.Fab")
		)
		(pad "1" smd circle
			(at 0 0 270)
			(size 0.7112 0.7112)
			(layers "B.Cu" "B.Mask" "B.Paste")
			(net "LBI_CE#3")
		)
	)
	(footprint ""
		(layer "B.Cu")
		(at 252.603 -54.995572 -90)
		(property "Reference" "C580"
			(at 0 0 90)
			(layer "B.SilkS")
			(hide yes)
			(effects
				(font
					(size 1.27 1.27)
				)
				(justify mirror)
			)
		)
		(property "Value" "SCD1U16V1KX-1-GP"
			(at 2.8321 -1.7399 270)
			(unlocked yes)
			(layer "B.Fab")
			(hide yes)
			(effects
				(font
					(size 1.016 1.016)
					(thickness 0.1524)
				)
				(justify mirror)
			)
		)
		(property "Device Type" "C0201H13"
			(at 2.8321 -3.2639 270)
			(unlocked yes)
			(layer "B.Fab")
			(hide yes)
			(effects
				(font
					(size 1.016 1.016)
					(thickness 0.1524)
				)
				(justify mirror)
			)
		)
		(duplicate_pad_numbers_are_jumpers no)
		(fp_rect
			(start 0.2794 0.6477)
			(end -0.2794 -0.6477)
			(stroke
				(width 0)
				(type default)
			)
			(fill no)
			(layer "B.CrtYd")
		)
		(fp_rect
			(start 0.2794 0.6477)
			(end -0.2794 -0.6477)
			(stroke
				(width 0)
				(type default)
			)
			(fill no)
			(layer "B.Fab")
		)
		(pad "1" smd custom
			(at 0 -0.2794 90)
			(size 0.0762 0.0762)
			(layers "B.Cu" "B.Mask" "B.Paste")
			(net "DUT_AVD_PCIE")
			(options
				(clearance outline)
				(anchor circle)
			)
			(primitives
				(gr_poly
					(pts
						(arc
							(start 0.1524 0.127)
							(mid 0.137521 0.162921)
							(end 0.1016 0.1778)
						)
						(arc
							(start -0.1016 0.1778)
							(mid -0.137521 0.162921)
							(end -0.1524 0.127)
						)
						(arc
							(start -0.1524 -0.127)
							(mid -0.137521 -0.162921)
							(end -0.1016 -0.1778)
						)
						(arc
							(start 0.1016 -0.1778)
							(mid 0.137521 -0.162921)
							(end 0.1524 -0.127)
						)
					)
					(width 0)
					(fill yes)
				)
			)
		)
		(pad "2" smd custom
			(at 0 0.2794 90)
			(size 0.0762 0.0762)
			(layers "B.Cu" "B.Mask" "B.Paste")
			(net "GND")
			(options
				(clearance outline)
				(anchor circle)
			)
			(primitives
				(gr_poly
					(pts
						(arc
							(start 0.1524 0.127)
							(mid 0.137521 0.162921)
							(end 0.1016 0.1778)
						)
						(arc
							(start -0.1016 0.1778)
							(mid -0.137521 0.162921)
							(end -0.1524 0.127)
						)
						(arc
							(start -0.1524 -0.127)
							(mid -0.137521 -0.162921)
							(end -0.1016 -0.1778)
						)
						(arc
							(start 0.1016 -0.1778)
							(mid 0.137521 -0.162921)
							(end 0.1524 -0.127)
						)
					)
					(width 0)
					(fill yes)
				)
			)
		)
	)
	(footprint ""
		(layer "B.Cu")
		(at 248.60504 -60.071)
		(property "Reference" "C601"
			(at 0 0 0)
			(layer "B.SilkS")
			(hide yes)
			(effects
				(font
					(size 1.27 1.27)
				)
				(justify mirror)
			)
		)
		(property "Value" "SCD1U16V1KX-1-GP"
			(at 2.8321 -1.7399 0)
			(unlocked yes)
			(layer "B.Fab")
			(hide yes)
			(effects
				(font
					(size 1.016 1.016)
					(thickness 0.1524)
				)
				(justify mirror)
			)
		)
		(property "Device Type" "C0201H13"
			(at 2.8321 -3.2639 0)
			(unlocked yes)
			(layer "B.Fab")
			(hide yes)
			(effects
				(font
					(size 1.016 1.016)
					(thickness 0.1524)
				)
				(justify mirror)
			)
		)
		(duplicate_pad_numbers_are_jumpers no)
		(fp_rect
			(start 0.2794 0.6477)
			(end -0.2794 -0.6477)
			(stroke
				(width 0)
				(type default)
			)
			(fill no)
			(layer "B.CrtYd")
		)
		(fp_rect
			(start 0.2794 0.6477)
			(end -0.2794 -0.6477)
			(stroke
				(width 0)
				(type default)
			)
			(fill no)
			(layer "B.Fab")
		)
		(pad "1" smd custom
			(at 0 -0.2794 180)
			(size 0.0762 0.0762)
			(layers "B.Cu" "B.Mask" "B.Paste")
			(net "DUT_AVD_PCIE")
			(options
				(clearance outline)
				(anchor circle)
			)
			(primitives
				(gr_poly
					(pts
						(arc
							(start 0.1524 0.127)
							(mid 0.137521 0.162921)
							(end 0.1016 0.1778)
						)
						(arc
							(start -0.1016 0.1778)
							(mid -0.137521 0.162921)
							(end -0.1524 0.127)
						)
						(arc
							(start -0.1524 -0.127)
							(mid -0.137521 -0.162921)
							(end -0.1016 -0.1778)
						)
						(arc
							(start 0.1016 -0.1778)
							(mid 0.137521 -0.162921)
							(end 0.1524 -0.127)
						)
					)
					(width 0)
					(fill yes)
				)
			)
		)
		(pad "2" smd custom
			(at 0 0.2794 180)
			(size 0.0762 0.0762)
			(layers "B.Cu" "B.Mask" "B.Paste")
			(net "GND")
			(options
				(clearance outline)
				(anchor circle)
			)
			(primitives
				(gr_poly
					(pts
						(arc
							(start 0.1524 0.127)
							(mid 0.137521 0.162921)
							(end 0.1016 0.1778)
						)
						(arc
							(start -0.1016 0.1778)
							(mid -0.137521 0.162921)
							(end -0.1524 0.127)
						)
						(arc
							(start -0.1524 -0.127)
							(mid -0.137521 -0.162921)
							(end -0.1016 -0.1778)
						)
						(arc
							(start 0.1016 -0.1778)
							(mid 0.137521 -0.162921)
							(end 0.1524 -0.127)
						)
					)
					(width 0)
					(fill yes)
				)
			)
		)
	)
	(footprint ""
		(layer "B.Cu")
		(at 54.010052 -112.22863 90)
		(property "Reference" "R40"
			(at 0 0 90)
			(layer "B.SilkS")
			(hide yes)
			(effects
				(font
					(size 1.27 1.27)
				)
				(justify mirror)
			)
		)
		(property "Value" "0R2J-2-GP"
			(at -0.064008 -3.993896 90)
			(unlocked yes)
			(layer "B.Fab")
			(hide yes)
			(effects
				(font
					(size 1.016 1.016)
					(thickness 0.1524)
				)
				(justify mirror)
			)
		)
		(property "Device Type" "R402H16"
			(at -0.064008 -5.517896 90)
			(unlocked yes)
			(layer "B.Fab")
			(hide yes)
			(effects
				(font
					(size 1.016 1.016)
					(thickness 0.1524)
				)
				(justify mirror)
			)
		)
		(duplicate_pad_numbers_are_jumpers no)
		(fp_line
			(start 0.508 -0.9398)
			(end 0.508 0.9398)
			(stroke
				(width 0.1524)
				(type default)
			)
			(layer "B.SilkS")
		)
		(fp_line
			(start -0.508 -0.9398)
			(end 0.508 -0.9398)
			(stroke
				(width 0.1524)
				(type default)
			)
			(layer "B.SilkS")
		)
		(fp_rect
			(start 0.508 0.9398)
			(end -0.508 -0.9398)
			(stroke
				(width 0)
				(type default)
			)
			(fill no)
			(layer "B.CrtYd")
		)
		(fp_rect
			(start 0.508 0.9398)
			(end -0.508 -0.9398)
			(stroke
				(width 0)
				(type default)
			)
			(fill no)
			(layer "B.Fab")
		)
		(pad "1" smd custom
			(at 0 -0.4445 270)
			(size 0.1397 0.1397)
			(layers "B.Cu" "B.Mask" "B.Paste")
			(net "BMC_I2C12_MINI6_SDA")
			(options
				(clearance outline)
				(anchor circle)
			)
			(primitives
				(gr_poly
					(pts
						(arc
							(start -0.1778 0.2794)
							(mid -0.249642 0.249642)
							(end -0.2794 0.1778)
						)
						(arc
							(start -0.2794 -0.1778)
							(mid -0.249642 -0.249642)
							(end -0.1778 -0.2794)
						)
						(arc
							(start 0.1778 -0.2794)
							(mid 0.249642 -0.249642)
							(end 0.2794 -0.1778)
						)
						(arc
							(start 0.2794 0.1778)
							(mid 0.249642 0.249642)
							(end 0.1778 0.2794)
						)
					)
					(width 0)
					(fill yes)
				)
			)
		)
		(pad "2" smd custom
			(at 0 0.4445 270)
			(size 0.1397 0.1397)
			(layers "B.Cu" "B.Mask" "B.Paste")
			(net "BMC_I2C12_MINI6_SDA_S")
			(options
				(clearance outline)
				(anchor circle)
			)
			(primitives
				(gr_poly
					(pts
						(arc
							(start -0.1778 0.2794)
							(mid -0.249642 0.249642)
							(end -0.2794 0.1778)
						)
						(arc
							(start -0.2794 -0.1778)
							(mid -0.249642 -0.249642)
							(end -0.1778 -0.2794)
						)
						(arc
							(start 0.1778 -0.2794)
							(mid 0.249642 -0.249642)
							(end 0.2794 -0.1778)
						)
						(arc
							(start 0.2794 0.1778)
							(mid 0.249642 0.249642)
							(end 0.1778 0.2794)
						)
					)
					(width 0)
					(fill yes)
				)
			)
		)
	)
	(footprint ""
		(layer "B.Cu")
		(at 227.6856 -41.004744 -90)
		(property "Reference" "C557"
			(at 0 0 90)
			(layer "B.SilkS")
			(hide yes)
			(effects
				(font
					(size 1.27 1.27)
				)
				(justify mirror)
			)
		)
		(property "Value" "SCD1U16V1KX-1-GP"
			(at 2.8321 -1.7399 270)
			(unlocked yes)
			(layer "B.Fab")
			(hide yes)
			(effects
				(font
					(size 1.016 1.016)
					(thickness 0.1524)
				)
				(justify mirror)
			)
		)
		(property "Device Type" "C0201H13"
			(at 2.8321 -3.2639 270)
			(unlocked yes)
			(layer "B.Fab")
			(hide yes)
			(effects
				(font
					(size 1.016 1.016)
					(thickness 0.1524)
				)
				(justify mirror)
			)
		)
		(duplicate_pad_numbers_are_jumpers no)
		(fp_rect
			(start 0.2794 0.6477)
			(end -0.2794 -0.6477)
			(stroke
				(width 0)
				(type default)
			)
			(fill no)
			(layer "B.CrtYd")
		)
		(fp_rect
			(start 0.2794 0.6477)
			(end -0.2794 -0.6477)
			(stroke
				(width 0)
				(type default)
			)
			(fill no)
			(layer "B.Fab")
		)
		(pad "1" smd custom
			(at 0 -0.2794 90)
			(size 0.0762 0.0762)
			(layers "B.Cu" "B.Mask" "B.Paste")
			(net "DUT_AVD_PCIE")
			(options
				(clearance outline)
				(anchor circle)
			)
			(primitives
				(gr_poly
					(pts
						(arc
							(start 0.1524 0.127)
							(mid 0.137521 0.162921)
							(end 0.1016 0.1778)
						)
						(arc
							(start -0.1016 0.1778)
							(mid -0.137521 0.162921)
							(end -0.1524 0.127)
						)
						(arc
							(start -0.1524 -0.127)
							(mid -0.137521 -0.162921)
							(end -0.1016 -0.1778)
						)
						(arc
							(start 0.1016 -0.1778)
							(mid 0.137521 -0.162921)
							(end 0.1524 -0.127)
						)
					)
					(width 0)
					(fill yes)
				)
			)
		)
		(pad "2" smd custom
			(at 0 0.2794 90)
			(size 0.0762 0.0762)
			(layers "B.Cu" "B.Mask" "B.Paste")
			(net "GND")
			(options
				(clearance outline)
				(anchor circle)
			)
			(primitives
				(gr_poly
					(pts
						(arc
							(start 0.1524 0.127)
							(mid 0.137521 0.162921)
							(end 0.1016 0.1778)
						)
						(arc
							(start -0.1016 0.1778)
							(mid -0.137521 0.162921)
							(end -0.1524 0.127)
						)
						(arc
							(start -0.1524 -0.127)
							(mid -0.137521 -0.162921)
							(end -0.1016 -0.1778)
						)
						(arc
							(start 0.1016 -0.1778)
							(mid 0.137521 -0.162921)
							(end 0.1524 -0.127)
						)
					)
					(width 0)
					(fill yes)
				)
			)
		)
	)
	(footprint ""
		(layer "B.Cu")
		(at 50.2412 -113.157)
		(property "Reference" "R411"
			(at 0 0 0)
			(layer "B.SilkS")
			(hide yes)
			(effects
				(font
					(size 1.27 1.27)
				)
				(justify mirror)
			)
		)
		(property "Value" "4K7R2F-GP"
			(at -0.064008 -3.993896 0)
			(unlocked yes)
			(layer "B.Fab")
			(hide yes)
			(effects
				(font
					(size 1.016 1.016)
					(thickness 0.1524)
				)
				(justify mirror)
			)
		)
		(property "Device Type" "R402H16"
			(at -0.064008 -5.517896 0)
			(unlocked yes)
			(layer "B.Fab")
			(hide yes)
			(effects
				(font
					(size 1.016 1.016)
					(thickness 0.1524)
				)
				(justify mirror)
			)
		)
		(duplicate_pad_numbers_are_jumpers no)
		(fp_line
			(start -0.508 -0.9398)
			(end 0.508 -0.9398)
			(stroke
				(width 0.1524)
				(type default)
			)
			(layer "B.SilkS")
		)
		(fp_line
			(start 0.508 -0.9398)
			(end 0.508 0.9398)
			(stroke
				(width 0.1524)
				(type default)
			)
			(layer "B.SilkS")
		)
		(fp_rect
			(start 0.508 0.9398)
			(end -0.508 -0.9398)
			(stroke
				(width 0)
				(type default)
			)
			(fill no)
			(layer "B.CrtYd")
		)
		(fp_rect
			(start 0.508 0.9398)
			(end -0.508 -0.9398)
			(stroke
				(width 0)
				(type default)
			)
			(fill no)
			(layer "B.Fab")
		)
		(pad "1" smd custom
			(at 0 -0.4445 180)
			(size 0.1397 0.1397)
			(layers "B.Cu" "B.Mask" "B.Paste")
			(net "BMC_I2C10_8536_SCL")
			(options
				(clearance outline)
				(anchor circle)
			)
			(primitives
				(gr_poly
					(pts
						(arc
							(start -0.1778 0.2794)
							(mid -0.249642 0.249642)
							(end -0.2794 0.1778)
						)
						(arc
							(start -0.2794 -0.1778)
							(mid -0.249642 -0.249642)
							(end -0.1778 -0.2794)
						)
						(arc
							(start 0.1778 -0.2794)
							(mid 0.249642 -0.249642)
							(end 0.2794 -0.1778)
						)
						(arc
							(start 0.2794 0.1778)
							(mid 0.249642 0.249642)
							(end 0.1778 0.2794)
						)
					)
					(width 0)
					(fill yes)
				)
			)
		)
		(pad "2" smd custom
			(at 0 0.4445 180)
			(size 0.1397 0.1397)
			(layers "B.Cu" "B.Mask" "B.Paste")
			(net "P3V3_STBY")
			(options
				(clearance outline)
				(anchor circle)
			)
			(primitives
				(gr_poly
					(pts
						(arc
							(start -0.1778 0.2794)
							(mid -0.249642 0.249642)
							(end -0.2794 0.1778)
						)
						(arc
							(start -0.2794 -0.1778)
							(mid -0.249642 -0.249642)
							(end -0.1778 -0.2794)
						)
						(arc
							(start 0.1778 -0.2794)
							(mid 0.249642 -0.249642)
							(end 0.2794 -0.1778)
						)
						(arc
							(start 0.2794 0.1778)
							(mid 0.249642 0.249642)
							(end 0.1778 0.2794)
						)
					)
					(width 0)
					(fill yes)
				)
			)
		)
	)
	(footprint ""
		(layer "B.Cu")
		(at 124.9426 -199.7456)
		(property "Reference" "R3224"
			(at 0 0 0)
			(layer "B.SilkS")
			(hide yes)
			(effects
				(font
					(size 1.27 1.27)
				)
				(justify mirror)
			)
		)
		(property "Value" "0R2J-2-GP"
			(at -0.064008 -3.993896 0)
			(unlocked yes)
			(layer "B.Fab")
			(hide yes)
			(effects
				(font
					(size 1.016 1.016)
					(thickness 0.1524)
				)
				(justify mirror)
			)
		)
		(property "Device Type" "R402H16"
			(at -0.064008 -5.517896 0)
			(unlocked yes)
			(layer "B.Fab")
			(hide yes)
			(effects
				(font
					(size 1.016 1.016)
					(thickness 0.1524)
				)
				(justify mirror)
			)
		)
		(duplicate_pad_numbers_are_jumpers no)
		(fp_line
			(start -0.508 -0.9398)
			(end 0.508 -0.9398)
			(stroke
				(width 0.1524)
				(type default)
			)
			(layer "B.SilkS")
		)
		(fp_line
			(start 0.508 -0.9398)
			(end 0.508 0.9398)
			(stroke
				(width 0.1524)
				(type default)
			)
			(layer "B.SilkS")
		)
		(fp_rect
			(start 0.508 0.9398)
			(end -0.508 -0.9398)
			(stroke
				(width 0)
				(type default)
			)
			(fill no)
			(layer "B.CrtYd")
		)
		(fp_rect
			(start 0.508 0.9398)
			(end -0.508 -0.9398)
			(stroke
				(width 0)
				(type default)
			)
			(fill no)
			(layer "B.Fab")
		)
		(pad "1" smd custom
			(at 0 -0.4445 180)
			(size 0.1397 0.1397)
			(layers "B.Cu" "B.Mask" "B.Paste")
			(net "SSD_PERST_Y7")
			(options
				(clearance outline)
				(anchor circle)
			)
			(primitives
				(gr_poly
					(pts
						(arc
							(start -0.1778 0.2794)
							(mid -0.249642 0.249642)
							(end -0.2794 0.1778)
						)
						(arc
							(start -0.2794 -0.1778)
							(mid -0.249642 -0.249642)
							(end -0.1778 -0.2794)
						)
						(arc
							(start 0.1778 -0.2794)
							(mid 0.249642 -0.249642)
							(end 0.2794 -0.1778)
						)
						(arc
							(start 0.2794 0.1778)
							(mid 0.249642 0.249642)
							(end 0.1778 0.2794)
						)
					)
					(width 0)
					(fill yes)
				)
			)
		)
		(pad "2" smd custom
			(at 0 0.4445 180)
			(size 0.1397 0.1397)
			(layers "B.Cu" "B.Mask" "B.Paste")
			(net "SSD_PERST#7_R")
			(options
				(clearance outline)
				(anchor circle)
			)
			(primitives
				(gr_poly
					(pts
						(arc
							(start -0.1778 0.2794)
							(mid -0.249642 0.249642)
							(end -0.2794 0.1778)
						)
						(arc
							(start -0.2794 -0.1778)
							(mid -0.249642 -0.249642)
							(end -0.1778 -0.2794)
						)
						(arc
							(start 0.1778 -0.2794)
							(mid 0.249642 -0.249642)
							(end 0.2794 -0.1778)
						)
						(arc
							(start 0.2794 0.1778)
							(mid 0.249642 0.249642)
							(end 0.1778 0.2794)
						)
					)
					(width 0)
					(fill yes)
				)
			)
		)
	)
	(footprint ""
		(layer "B.Cu")
		(at 20.914868 -117.741446 -90)
		(property "Reference" "R711"
			(at 0 0 90)
			(layer "B.SilkS")
			(hide yes)
			(effects
				(font
					(size 1.27 1.27)
				)
				(justify mirror)
			)
		)
		(property "Value" "0R2J-2-GP"
			(at -0.064008 -3.993896 270)
			(unlocked yes)
			(layer "B.Fab")
			(hide yes)
			(effects
				(font
					(size 1.016 1.016)
					(thickness 0.1524)
				)
				(justify mirror)
			)
		)
		(property "Device Type" "R402H16"
			(at -0.064008 -5.517896 270)
			(unlocked yes)
			(layer "B.Fab")
			(hide yes)
			(effects
				(font
					(size 1.016 1.016)
					(thickness 0.1524)
				)
				(justify mirror)
			)
		)
		(duplicate_pad_numbers_are_jumpers no)
		(fp_line
			(start -0.508 -0.9398)
			(end 0.508 -0.9398)
			(stroke
				(width 0.1524)
				(type default)
			)
			(layer "B.SilkS")
		)
		(fp_line
			(start 0.508 -0.9398)
			(end 0.508 0.9398)
			(stroke
				(width 0.1524)
				(type default)
			)
			(layer "B.SilkS")
		)
		(fp_rect
			(start 0.508 0.9398)
			(end -0.508 -0.9398)
			(stroke
				(width 0)
				(type default)
			)
			(fill no)
			(layer "B.CrtYd")
		)
		(fp_rect
			(start 0.508 0.9398)
			(end -0.508 -0.9398)
			(stroke
				(width 0)
				(type default)
			)
			(fill no)
			(layer "B.Fab")
		)
		(pad "1" smd custom
			(at 0 -0.4445 90)
			(size 0.1397 0.1397)
			(layers "B.Cu" "B.Mask" "B.Paste")
			(net "SPIDI_R")
			(options
				(clearance outline)
				(anchor circle)
			)
			(primitives
				(gr_poly
					(pts
						(arc
							(start -0.1778 0.2794)
							(mid -0.249642 0.249642)
							(end -0.2794 0.1778)
						)
						(arc
							(start -0.2794 -0.1778)
							(mid -0.249642 -0.249642)
							(end -0.1778 -0.2794)
						)
						(arc
							(start 0.1778 -0.2794)
							(mid 0.249642 -0.249642)
							(end 0.2794 -0.1778)
						)
						(arc
							(start 0.2794 0.1778)
							(mid 0.249642 0.249642)
							(end 0.1778 0.2794)
						)
					)
					(width 0)
					(fill yes)
				)
			)
		)
		(pad "2" smd custom
			(at 0 0.4445 90)
			(size 0.1397 0.1397)
			(layers "B.Cu" "B.Mask" "B.Paste")
			(net "SPIDI")
			(options
				(clearance outline)
				(anchor circle)
			)
			(primitives
				(gr_poly
					(pts
						(arc
							(start -0.1778 0.2794)
							(mid -0.249642 0.249642)
							(end -0.2794 0.1778)
						)
						(arc
							(start -0.2794 -0.1778)
							(mid -0.249642 -0.249642)
							(end -0.1778 -0.2794)
						)
						(arc
							(start 0.1778 -0.2794)
							(mid 0.249642 -0.249642)
							(end 0.2794 -0.1778)
						)
						(arc
							(start 0.2794 0.1778)
							(mid 0.249642 0.249642)
							(end 0.1778 0.2794)
						)
					)
					(width 0)
					(fill yes)
				)
			)
		)
	)
	(footprint ""
		(layer "B.Cu")
		(at 254.068072 -41.012872 90)
		(property "Reference" "C589"
			(at 0 0 90)
			(layer "B.SilkS")
			(hide yes)
			(effects
				(font
					(size 1.27 1.27)
				)
				(justify mirror)
			)
		)
		(property "Value" "SCD1U16V1KX-1-GP"
			(at 2.8321 -1.7399 90)
			(unlocked yes)
			(layer "B.Fab")
			(hide yes)
			(effects
				(font
					(size 1.016 1.016)
					(thickness 0.1524)
				)
				(justify mirror)
			)
		)
		(property "Device Type" "C0201H13"
			(at 2.8321 -3.2639 90)
			(unlocked yes)
			(layer "B.Fab")
			(hide yes)
			(effects
				(font
					(size 1.016 1.016)
					(thickness 0.1524)
				)
				(justify mirror)
			)
		)
		(duplicate_pad_numbers_are_jumpers no)
		(fp_rect
			(start 0.2794 0.6477)
			(end -0.2794 -0.6477)
			(stroke
				(width 0)
				(type default)
			)
			(fill no)
			(layer "B.CrtYd")
		)
		(fp_rect
			(start 0.2794 0.6477)
			(end -0.2794 -0.6477)
			(stroke
				(width 0)
				(type default)
			)
			(fill no)
			(layer "B.Fab")
		)
		(pad "1" smd custom
			(at 0 -0.2794 270)
			(size 0.0762 0.0762)
			(layers "B.Cu" "B.Mask" "B.Paste")
			(net "DUT_AVD_PCIE")
			(options
				(clearance outline)
				(anchor circle)
			)
			(primitives
				(gr_poly
					(pts
						(arc
							(start 0.1524 0.127)
							(mid 0.137521 0.162921)
							(end 0.1016 0.1778)
						)
						(arc
							(start -0.1016 0.1778)
							(mid -0.137521 0.162921)
							(end -0.1524 0.127)
						)
						(arc
							(start -0.1524 -0.127)
							(mid -0.137521 -0.162921)
							(end -0.1016 -0.1778)
						)
						(arc
							(start 0.1016 -0.1778)
							(mid 0.137521 -0.162921)
							(end 0.1524 -0.127)
						)
					)
					(width 0)
					(fill yes)
				)
			)
		)
		(pad "2" smd custom
			(at 0 0.2794 270)
			(size 0.0762 0.0762)
			(layers "B.Cu" "B.Mask" "B.Paste")
			(net "GND")
			(options
				(clearance outline)
				(anchor circle)
			)
			(primitives
				(gr_poly
					(pts
						(arc
							(start 0.1524 0.127)
							(mid 0.137521 0.162921)
							(end 0.1016 0.1778)
						)
						(arc
							(start -0.1016 0.1778)
							(mid -0.137521 0.162921)
							(end -0.1524 0.127)
						)
						(arc
							(start -0.1524 -0.127)
							(mid -0.137521 -0.162921)
							(end -0.1016 -0.1778)
						)
						(arc
							(start 0.1016 -0.1778)
							(mid 0.137521 -0.162921)
							(end 0.1524 -0.127)
						)
					)
					(width 0)
					(fill yes)
				)
			)
		)
	)
	(footprint ""
		(layer "B.Cu")
		(at 242.3414 -35.0012 -90)
		(property "Reference" "C474"
			(at 0 0 90)
			(layer "B.SilkS")
			(hide yes)
			(effects
				(font
					(size 1.27 1.27)
				)
				(justify mirror)
			)
		)
		(property "Value" "SCD1U16V1KX-1-GP"
			(at 2.8321 -1.7399 270)
			(unlocked yes)
			(layer "B.Fab")
			(hide yes)
			(effects
				(font
					(size 1.016 1.016)
					(thickness 0.1524)
				)
				(justify mirror)
			)
		)
		(property "Device Type" "C0201H13"
			(at 2.8321 -3.2639 270)
			(unlocked yes)
			(layer "B.Fab")
			(hide yes)
			(effects
				(font
					(size 1.016 1.016)
					(thickness 0.1524)
				)
				(justify mirror)
			)
		)
		(duplicate_pad_numbers_are_jumpers no)
		(fp_rect
			(start 0.2794 0.6477)
			(end -0.2794 -0.6477)
			(stroke
				(width 0)
				(type default)
			)
			(fill no)
			(layer "B.CrtYd")
		)
		(fp_rect
			(start 0.2794 0.6477)
			(end -0.2794 -0.6477)
			(stroke
				(width 0)
				(type default)
			)
			(fill no)
			(layer "B.Fab")
		)
		(pad "1" smd custom
			(at 0 -0.2794 90)
			(size 0.0762 0.0762)
			(layers "B.Cu" "B.Mask" "B.Paste")
			(net "DUT_VDDO")
			(options
				(clearance outline)
				(anchor circle)
			)
			(primitives
				(gr_poly
					(pts
						(arc
							(start 0.1524 0.127)
							(mid 0.137521 0.162921)
							(end 0.1016 0.1778)
						)
						(arc
							(start -0.1016 0.1778)
							(mid -0.137521 0.162921)
							(end -0.1524 0.127)
						)
						(arc
							(start -0.1524 -0.127)
							(mid -0.137521 -0.162921)
							(end -0.1016 -0.1778)
						)
						(arc
							(start 0.1016 -0.1778)
							(mid 0.137521 -0.162921)
							(end 0.1524 -0.127)
						)
					)
					(width 0)
					(fill yes)
				)
			)
		)
		(pad "2" smd custom
			(at 0 0.2794 90)
			(size 0.0762 0.0762)
			(layers "B.Cu" "B.Mask" "B.Paste")
			(net "GND")
			(options
				(clearance outline)
				(anchor circle)
			)
			(primitives
				(gr_poly
					(pts
						(arc
							(start 0.1524 0.127)
							(mid 0.137521 0.162921)
							(end 0.1016 0.1778)
						)
						(arc
							(start -0.1016 0.1778)
							(mid -0.137521 0.162921)
							(end -0.1524 0.127)
						)
						(arc
							(start -0.1524 -0.127)
							(mid -0.137521 -0.162921)
							(end -0.1016 -0.1778)
						)
						(arc
							(start 0.1016 -0.1778)
							(mid 0.137521 -0.162921)
							(end 0.1524 -0.127)
						)
					)
					(width 0)
					(fill yes)
				)
			)
		)
	)
	(footprint ""
		(layer "B.Cu")
		(at 237.1598 -51.9938 -90)
		(property "Reference" "C32"
			(at 0 0 90)
			(layer "B.SilkS")
			(hide yes)
			(effects
				(font
					(size 1.27 1.27)
				)
				(justify mirror)
			)
		)
		(property "Value" "SCD1U16V1KX-1-GP"
			(at 2.8321 -1.7399 270)
			(unlocked yes)
			(layer "B.Fab")
			(hide yes)
			(effects
				(font
					(size 1.016 1.016)
					(thickness 0.1524)
				)
				(justify mirror)
			)
		)
		(property "Device Type" "C0201H13"
			(at 2.8321 -3.2639 270)
			(unlocked yes)
			(layer "B.Fab")
			(hide yes)
			(effects
				(font
					(size 1.016 1.016)
					(thickness 0.1524)
				)
				(justify mirror)
			)
		)
		(duplicate_pad_numbers_are_jumpers no)
		(fp_rect
			(start 0.2794 0.6477)
			(end -0.2794 -0.6477)
			(stroke
				(width 0)
				(type default)
			)
			(fill no)
			(layer "B.CrtYd")
		)
		(fp_rect
			(start 0.2794 0.6477)
			(end -0.2794 -0.6477)
			(stroke
				(width 0)
				(type default)
			)
			(fill no)
			(layer "B.Fab")
		)
		(pad "1" smd custom
			(at 0 -0.2794 90)
			(size 0.0762 0.0762)
			(layers "B.Cu" "B.Mask" "B.Paste")
			(net "DUT_VDD")
			(options
				(clearance outline)
				(anchor circle)
			)
			(primitives
				(gr_poly
					(pts
						(arc
							(start 0.1524 0.127)
							(mid 0.137521 0.162921)
							(end 0.1016 0.1778)
						)
						(arc
							(start -0.1016 0.1778)
							(mid -0.137521 0.162921)
							(end -0.1524 0.127)
						)
						(arc
							(start -0.1524 -0.127)
							(mid -0.137521 -0.162921)
							(end -0.1016 -0.1778)
						)
						(arc
							(start 0.1016 -0.1778)
							(mid 0.137521 -0.162921)
							(end 0.1524 -0.127)
						)
					)
					(width 0)
					(fill yes)
				)
			)
		)
		(pad "2" smd custom
			(at 0 0.2794 90)
			(size 0.0762 0.0762)
			(layers "B.Cu" "B.Mask" "B.Paste")
			(net "GND")
			(options
				(clearance outline)
				(anchor circle)
			)
			(primitives
				(gr_poly
					(pts
						(arc
							(start 0.1524 0.127)
							(mid 0.137521 0.162921)
							(end 0.1016 0.1778)
						)
						(arc
							(start -0.1016 0.1778)
							(mid -0.137521 0.162921)
							(end -0.1524 0.127)
						)
						(arc
							(start -0.1524 -0.127)
							(mid -0.137521 -0.162921)
							(end -0.1016 -0.1778)
						)
						(arc
							(start 0.1016 -0.1778)
							(mid 0.137521 -0.162921)
							(end 0.1524 -0.127)
						)
					)
					(width 0)
					(fill yes)
				)
			)
		)
	)
	(footprint ""
		(layer "B.Cu")
		(at 16.149828 -74.982578 90)
		(property "Reference" "C636"
			(at 0 0 90)
			(layer "B.SilkS")
			(hide yes)
			(effects
				(font
					(size 1.27 1.27)
				)
				(justify mirror)
			)
		)
		(property "Value" "SCD1U16V2KX-3GP"
			(at -1.1811 -2.7051 90)
			(unlocked yes)
			(layer "B.Fab")
			(hide yes)
			(effects
				(font
					(size 1.016 1.016)
					(thickness 0.1524)
				)
				(justify mirror)
			)
		)
		(property "Device Type" "C402H22"
			(at -1.1811 -4.2291 90)
			(unlocked yes)
			(layer "B.Fab")
			(hide yes)
			(effects
				(font
					(size 1.016 1.016)
					(thickness 0.1524)
				)
				(justify mirror)
			)
		)
		(duplicate_pad_numbers_are_jumpers no)
		(fp_rect
			(start 0.4318 0.9525)
			(end -0.4318 -0.9525)
			(stroke
				(width 0)
				(type default)
			)
			(fill no)
			(layer "B.CrtYd")
		)
		(fp_rect
			(start 0.4318 0.9525)
			(end -0.4318 -0.9525)
			(stroke
				(width 0)
				(type default)
			)
			(fill no)
			(layer "B.Fab")
		)
		(pad "1" smd custom
			(at 0 -0.4445 270)
			(size 0.1524 0.1524)
			(layers "B.Cu" "B.Mask" "B.Paste")
			(net "P0V9_I210")
			(options
				(clearance outline)
				(anchor circle)
			)
			(primitives
				(gr_poly
					(pts
						(arc
							(start 0.3048 0.2032)
							(mid 0.275042 0.275042)
							(end 0.2032 0.3048)
						)
						(arc
							(start -0.2032 0.3048)
							(mid -0.275042 0.275042)
							(end -0.3048 0.2032)
						)
						(arc
							(start -0.3048 -0.2032)
							(mid -0.275042 -0.275042)
							(end -0.2032 -0.3048)
						)
						(arc
							(start 0.2032 -0.3048)
							(mid 0.275042 -0.275042)
							(end 0.3048 -0.2032)
						)
					)
					(width 0)
					(fill yes)
				)
			)
		)
		(pad "2" smd custom
			(at 0 0.4445 270)
			(size 0.1524 0.1524)
			(layers "B.Cu" "B.Mask" "B.Paste")
			(net "GND")
			(options
				(clearance outline)
				(anchor circle)
			)
			(primitives
				(gr_poly
					(pts
						(arc
							(start 0.3048 0.2032)
							(mid 0.275042 0.275042)
							(end 0.2032 0.3048)
						)
						(arc
							(start -0.2032 0.3048)
							(mid -0.275042 0.275042)
							(end -0.3048 0.2032)
						)
						(arc
							(start -0.3048 -0.2032)
							(mid -0.275042 -0.275042)
							(end -0.2032 -0.3048)
						)
						(arc
							(start 0.2032 -0.3048)
							(mid 0.275042 -0.275042)
							(end 0.3048 -0.2032)
						)
					)
					(width 0)
					(fill yes)
				)
			)
		)
	)
	(footprint ""
		(layer "B.Cu")
		(at 243.1288 -47.032672 90)
		(property "Reference" "C462"
			(at 0 0 90)
			(layer "B.SilkS")
			(hide yes)
			(effects
				(font
					(size 1.27 1.27)
				)
				(justify mirror)
			)
		)
		(property "Value" "SCD1U16V1KX-1-GP"
			(at 2.8321 -1.7399 90)
			(unlocked yes)
			(layer "B.Fab")
			(hide yes)
			(effects
				(font
					(size 1.016 1.016)
					(thickness 0.1524)
				)
				(justify mirror)
			)
		)
		(property "Device Type" "C0201H13"
			(at 2.8321 -3.2639 90)
			(unlocked yes)
			(layer "B.Fab")
			(hide yes)
			(effects
				(font
					(size 1.016 1.016)
					(thickness 0.1524)
				)
				(justify mirror)
			)
		)
		(duplicate_pad_numbers_are_jumpers no)
		(fp_rect
			(start 0.2794 0.6477)
			(end -0.2794 -0.6477)
			(stroke
				(width 0)
				(type default)
			)
			(fill no)
			(layer "B.CrtYd")
		)
		(fp_rect
			(start 0.2794 0.6477)
			(end -0.2794 -0.6477)
			(stroke
				(width 0)
				(type default)
			)
			(fill no)
			(layer "B.Fab")
		)
		(pad "1" smd custom
			(at 0 -0.2794 270)
			(size 0.0762 0.0762)
			(layers "B.Cu" "B.Mask" "B.Paste")
			(net "DUT_VDD")
			(options
				(clearance outline)
				(anchor circle)
			)
			(primitives
				(gr_poly
					(pts
						(arc
							(start 0.1524 0.127)
							(mid 0.137521 0.162921)
							(end 0.1016 0.1778)
						)
						(arc
							(start -0.1016 0.1778)
							(mid -0.137521 0.162921)
							(end -0.1524 0.127)
						)
						(arc
							(start -0.1524 -0.127)
							(mid -0.137521 -0.162921)
							(end -0.1016 -0.1778)
						)
						(arc
							(start 0.1016 -0.1778)
							(mid 0.137521 -0.162921)
							(end 0.1524 -0.127)
						)
					)
					(width 0)
					(fill yes)
				)
			)
		)
		(pad "2" smd custom
			(at 0 0.2794 270)
			(size 0.0762 0.0762)
			(layers "B.Cu" "B.Mask" "B.Paste")
			(net "GND")
			(options
				(clearance outline)
				(anchor circle)
			)
			(primitives
				(gr_poly
					(pts
						(arc
							(start 0.1524 0.127)
							(mid 0.137521 0.162921)
							(end 0.1016 0.1778)
						)
						(arc
							(start -0.1016 0.1778)
							(mid -0.137521 0.162921)
							(end -0.1524 0.127)
						)
						(arc
							(start -0.1524 -0.127)
							(mid -0.137521 -0.162921)
							(end -0.1016 -0.1778)
						)
						(arc
							(start 0.1016 -0.1778)
							(mid 0.137521 -0.162921)
							(end 0.1524 -0.127)
						)
					)
					(width 0)
					(fill yes)
				)
			)
		)
	)
	(footprint ""
		(layer "B.Cu")
		(at 219.120212 -194.038474)
		(property "Reference" "C416"
			(at 0 0 0)
			(layer "B.SilkS")
			(hide yes)
			(effects
				(font
					(size 1.27 1.27)
				)
				(justify mirror)
			)
		)
		(property "Value" "SCD1U25V2KX-2-GP"
			(at -1.1811 -2.7051 0)
			(unlocked yes)
			(layer "B.Fab")
			(hide yes)
			(effects
				(font
					(size 1.016 1.016)
					(thickness 0.1524)
				)
				(justify mirror)
			)
		)
		(property "Device Type" "C402H22"
			(at -1.1811 -4.2291 0)
			(unlocked yes)
			(layer "B.Fab")
			(hide yes)
			(effects
				(font
					(size 1.016 1.016)
					(thickness 0.1524)
				)
				(justify mirror)
			)
		)
		(duplicate_pad_numbers_are_jumpers no)
		(fp_rect
			(start 0.4318 0.9525)
			(end -0.4318 -0.9525)
			(stroke
				(width 0)
				(type default)
			)
			(fill no)
			(layer "B.CrtYd")
		)
		(fp_rect
			(start 0.4318 0.9525)
			(end -0.4318 -0.9525)
			(stroke
				(width 0)
				(type default)
			)
			(fill no)
			(layer "B.Fab")
		)
		(pad "1" smd custom
			(at 0 -0.4445 180)
			(size 0.1524 0.1524)
			(layers "B.Cu" "B.Mask" "B.Paste")
			(net "P3V3_STBY")
			(options
				(clearance outline)
				(anchor circle)
			)
			(primitives
				(gr_poly
					(pts
						(arc
							(start 0.3048 0.2032)
							(mid 0.275042 0.275042)
							(end 0.2032 0.3048)
						)
						(arc
							(start -0.2032 0.3048)
							(mid -0.275042 0.275042)
							(end -0.3048 0.2032)
						)
						(arc
							(start -0.3048 -0.2032)
							(mid -0.275042 -0.275042)
							(end -0.2032 -0.3048)
						)
						(arc
							(start 0.2032 -0.3048)
							(mid 0.275042 -0.275042)
							(end 0.3048 -0.2032)
						)
					)
					(width 0)
					(fill yes)
				)
			)
		)
		(pad "2" smd custom
			(at 0 0.4445 180)
			(size 0.1524 0.1524)
			(layers "B.Cu" "B.Mask" "B.Paste")
			(net "GND")
			(options
				(clearance outline)
				(anchor circle)
			)
			(primitives
				(gr_poly
					(pts
						(arc
							(start 0.3048 0.2032)
							(mid 0.275042 0.275042)
							(end 0.2032 0.3048)
						)
						(arc
							(start -0.2032 0.3048)
							(mid -0.275042 0.275042)
							(end -0.3048 0.2032)
						)
						(arc
							(start -0.3048 -0.2032)
							(mid -0.275042 -0.275042)
							(end -0.2032 -0.3048)
						)
						(arc
							(start 0.2032 -0.3048)
							(mid 0.275042 -0.275042)
							(end 0.3048 -0.2032)
						)
					)
					(width 0)
					(fill yes)
				)
			)
		)
	)
	(footprint ""
		(layer "B.Cu")
		(at 227.6856 -34.004758 -90)
		(property "Reference" "C566"
			(at 0 0 90)
			(layer "B.SilkS")
			(hide yes)
			(effects
				(font
					(size 1.27 1.27)
				)
				(justify mirror)
			)
		)
		(property "Value" "SCD1U16V1KX-1-GP"
			(at 2.8321 -1.7399 270)
			(unlocked yes)
			(layer "B.Fab")
			(hide yes)
			(effects
				(font
					(size 1.016 1.016)
					(thickness 0.1524)
				)
				(justify mirror)
			)
		)
		(property "Device Type" "C0201H13"
			(at 2.8321 -3.2639 270)
			(unlocked yes)
			(layer "B.Fab")
			(hide yes)
			(effects
				(font
					(size 1.016 1.016)
					(thickness 0.1524)
				)
				(justify mirror)
			)
		)
		(duplicate_pad_numbers_are_jumpers no)
		(fp_rect
			(start 0.2794 0.6477)
			(end -0.2794 -0.6477)
			(stroke
				(width 0)
				(type default)
			)
			(fill no)
			(layer "B.CrtYd")
		)
		(fp_rect
			(start 0.2794 0.6477)
			(end -0.2794 -0.6477)
			(stroke
				(width 0)
				(type default)
			)
			(fill no)
			(layer "B.Fab")
		)
		(pad "1" smd custom
			(at 0 -0.2794 90)
			(size 0.0762 0.0762)
			(layers "B.Cu" "B.Mask" "B.Paste")
			(net "DUT_AVD_PCIE")
			(options
				(clearance outline)
				(anchor circle)
			)
			(primitives
				(gr_poly
					(pts
						(arc
							(start 0.1524 0.127)
							(mid 0.137521 0.162921)
							(end 0.1016 0.1778)
						)
						(arc
							(start -0.1016 0.1778)
							(mid -0.137521 0.162921)
							(end -0.1524 0.127)
						)
						(arc
							(start -0.1524 -0.127)
							(mid -0.137521 -0.162921)
							(end -0.1016 -0.1778)
						)
						(arc
							(start 0.1016 -0.1778)
							(mid 0.137521 -0.162921)
							(end 0.1524 -0.127)
						)
					)
					(width 0)
					(fill yes)
				)
			)
		)
		(pad "2" smd custom
			(at 0 0.2794 90)
			(size 0.0762 0.0762)
			(layers "B.Cu" "B.Mask" "B.Paste")
			(net "GND")
			(options
				(clearance outline)
				(anchor circle)
			)
			(primitives
				(gr_poly
					(pts
						(arc
							(start 0.1524 0.127)
							(mid 0.137521 0.162921)
							(end 0.1016 0.1778)
						)
						(arc
							(start -0.1016 0.1778)
							(mid -0.137521 0.162921)
							(end -0.1524 0.127)
						)
						(arc
							(start -0.1524 -0.127)
							(mid -0.137521 -0.162921)
							(end -0.1016 -0.1778)
						)
						(arc
							(start 0.1016 -0.1778)
							(mid 0.137521 -0.162921)
							(end 0.1524 -0.127)
						)
					)
					(width 0)
					(fill yes)
				)
			)
		)
	)
	(footprint ""
		(layer "B.Cu")
		(at 331.756512 -172.432218 180)
		(property "Reference" "R576"
			(at 0 0 0)
			(layer "B.SilkS")
			(hide yes)
			(effects
				(font
					(size 1.27 1.27)
				)
				(justify mirror)
			)
		)
		(property "Value" "10KR2F-2-GP"
			(at -0.064008 -3.993896 180)
			(unlocked yes)
			(layer "B.Fab")
			(hide yes)
			(effects
				(font
					(size 1.016 1.016)
					(thickness 0.1524)
				)
				(justify mirror)
			)
		)
		(property "Device Type" "R402H16"
			(at -0.064008 -5.517896 180)
			(unlocked yes)
			(layer "B.Fab")
			(hide yes)
			(effects
				(font
					(size 1.016 1.016)
					(thickness 0.1524)
				)
				(justify mirror)
			)
		)
		(duplicate_pad_numbers_are_jumpers no)
		(fp_line
			(start 0.508 -0.9398)
			(end 0.508 0.9398)
			(stroke
				(width 0.1524)
				(type default)
			)
			(layer "B.SilkS")
		)
		(fp_line
			(start -0.508 -0.9398)
			(end 0.508 -0.9398)
			(stroke
				(width 0.1524)
				(type default)
			)
			(layer "B.SilkS")
		)
		(fp_rect
			(start 0.508 0.9398)
			(end -0.508 -0.9398)
			(stroke
				(width 0)
				(type default)
			)
			(fill no)
			(layer "B.CrtYd")
		)
		(fp_rect
			(start 0.508 0.9398)
			(end -0.508 -0.9398)
			(stroke
				(width 0)
				(type default)
			)
			(fill no)
			(layer "B.Fab")
		)
		(pad "1" smd custom
			(at 0 -0.4445)
			(size 0.1397 0.1397)
			(layers "B.Cu" "B.Mask" "B.Paste")
			(net "P3V3_STBY")
			(options
				(clearance outline)
				(anchor circle)
			)
			(primitives
				(gr_poly
					(pts
						(arc
							(start -0.1778 0.2794)
							(mid -0.249642 0.249642)
							(end -0.2794 0.1778)
						)
						(arc
							(start -0.2794 -0.1778)
							(mid -0.249642 -0.249642)
							(end -0.1778 -0.2794)
						)
						(arc
							(start 0.1778 -0.2794)
							(mid 0.249642 -0.249642)
							(end 0.2794 -0.1778)
						)
						(arc
							(start 0.2794 0.1778)
							(mid 0.249642 0.249642)
							(end 0.1778 0.2794)
						)
					)
					(width 0)
					(fill yes)
				)
			)
		)
		(pad "2" smd custom
			(at 0 0.4445)
			(size 0.1397 0.1397)
			(layers "B.Cu" "B.Mask" "B.Paste")
			(net "IOEXP4_AD2")
			(options
				(clearance outline)
				(anchor circle)
			)
			(primitives
				(gr_poly
					(pts
						(arc
							(start -0.1778 0.2794)
							(mid -0.249642 0.249642)
							(end -0.2794 0.1778)
						)
						(arc
							(start -0.2794 -0.1778)
							(mid -0.249642 -0.249642)
							(end -0.1778 -0.2794)
						)
						(arc
							(start 0.1778 -0.2794)
							(mid 0.249642 -0.249642)
							(end 0.2794 -0.1778)
						)
						(arc
							(start 0.2794 0.1778)
							(mid 0.249642 0.249642)
							(end 0.1778 0.2794)
						)
					)
					(width 0)
					(fill yes)
				)
			)
		)
	)
	(footprint ""
		(layer "B.Cu")
		(at 229.5906 -28.575 90)
		(property "Reference" "R27"
			(at 0 0 90)
			(layer "B.SilkS")
			(hide yes)
			(effects
				(font
					(size 1.27 1.27)
				)
				(justify mirror)
			)
		)
		(property "Value" "0R2J-2-GP"
			(at -0.064008 -3.993896 90)
			(unlocked yes)
			(layer "B.Fab")
			(hide yes)
			(effects
				(font
					(size 1.016 1.016)
					(thickness 0.1524)
				)
				(justify mirror)
			)
		)
		(property "Device Type" "R402H16"
			(at -0.064008 -5.517896 90)
			(unlocked yes)
			(layer "B.Fab")
			(hide yes)
			(effects
				(font
					(size 1.016 1.016)
					(thickness 0.1524)
				)
				(justify mirror)
			)
		)
		(duplicate_pad_numbers_are_jumpers no)
		(fp_line
			(start 0.508 -0.9398)
			(end 0.508 0.9398)
			(stroke
				(width 0.1524)
				(type default)
			)
			(layer "B.SilkS")
		)
		(fp_line
			(start -0.508 -0.9398)
			(end 0.508 -0.9398)
			(stroke
				(width 0.1524)
				(type default)
			)
			(layer "B.SilkS")
		)
		(fp_rect
			(start 0.508 0.9398)
			(end -0.508 -0.9398)
			(stroke
				(width 0)
				(type default)
			)
			(fill no)
			(layer "B.CrtYd")
		)
		(fp_rect
			(start 0.508 0.9398)
			(end -0.508 -0.9398)
			(stroke
				(width 0)
				(type default)
			)
			(fill no)
			(layer "B.Fab")
		)
		(pad "1" smd custom
			(at 0 -0.4445 270)
			(size 0.1397 0.1397)
			(layers "B.Cu" "B.Mask" "B.Paste")
			(net "VSS_571")
			(options
				(clearance outline)
				(anchor circle)
			)
			(primitives
				(gr_poly
					(pts
						(arc
							(start -0.1778 0.2794)
							(mid -0.249642 0.249642)
							(end -0.2794 0.1778)
						)
						(arc
							(start -0.2794 -0.1778)
							(mid -0.249642 -0.249642)
							(end -0.1778 -0.2794)
						)
						(arc
							(start 0.1778 -0.2794)
							(mid 0.249642 -0.249642)
							(end 0.2794 -0.1778)
						)
						(arc
							(start 0.2794 0.1778)
							(mid 0.249642 0.249642)
							(end 0.1778 0.2794)
						)
					)
					(width 0)
					(fill yes)
				)
			)
		)
		(pad "2" smd custom
			(at 0 0.4445 270)
			(size 0.1397 0.1397)
			(layers "B.Cu" "B.Mask" "B.Paste")
			(net "GND")
			(options
				(clearance outline)
				(anchor circle)
			)
			(primitives
				(gr_poly
					(pts
						(arc
							(start -0.1778 0.2794)
							(mid -0.249642 0.249642)
							(end -0.2794 0.1778)
						)
						(arc
							(start -0.2794 -0.1778)
							(mid -0.249642 -0.249642)
							(end -0.1778 -0.2794)
						)
						(arc
							(start 0.1778 -0.2794)
							(mid 0.249642 -0.249642)
							(end 0.2794 -0.1778)
						)
						(arc
							(start 0.2794 0.1778)
							(mid 0.249642 0.249642)
							(end 0.1778 0.2794)
						)
					)
					(width 0)
					(fill yes)
				)
			)
		)
	)
	(footprint ""
		(layer "B.Cu")
		(at 251.600208 -26.1112 180)
		(property "Reference" "R776"
			(at 0 0 0)
			(layer "B.SilkS")
			(hide yes)
			(effects
				(font
					(size 1.27 1.27)
				)
				(justify mirror)
			)
		)
		(property "Value" "3K3R2F-2-GP"
			(at -0.064008 -3.993896 180)
			(unlocked yes)
			(layer "B.Fab")
			(hide yes)
			(effects
				(font
					(size 1.016 1.016)
					(thickness 0.1524)
				)
				(justify mirror)
			)
		)
		(property "Device Type" "R402H16"
			(at -0.064008 -5.517896 180)
			(unlocked yes)
			(layer "B.Fab")
			(hide yes)
			(effects
				(font
					(size 1.016 1.016)
					(thickness 0.1524)
				)
				(justify mirror)
			)
		)
		(duplicate_pad_numbers_are_jumpers no)
		(fp_line
			(start 0.508 -0.9398)
			(end 0.508 0.9398)
			(stroke
				(width 0.1524)
				(type default)
			)
			(layer "B.SilkS")
		)
		(fp_line
			(start -0.508 -0.9398)
			(end 0.508 -0.9398)
			(stroke
				(width 0.1524)
				(type default)
			)
			(layer "B.SilkS")
		)
		(fp_rect
			(start 0.508 0.9398)
			(end -0.508 -0.9398)
			(stroke
				(width 0)
				(type default)
			)
			(fill no)
			(layer "B.CrtYd")
		)
		(fp_rect
			(start 0.508 0.9398)
			(end -0.508 -0.9398)
			(stroke
				(width 0)
				(type default)
			)
			(fill no)
			(layer "B.Fab")
		)
		(pad "1" smd custom
			(at 0 -0.4445)
			(size 0.1397 0.1397)
			(layers "B.Cu" "B.Mask" "B.Paste")
			(net "P3V3_GPIO")
			(options
				(clearance outline)
				(anchor circle)
			)
			(primitives
				(gr_poly
					(pts
						(arc
							(start -0.1778 0.2794)
							(mid -0.249642 0.249642)
							(end -0.2794 0.1778)
						)
						(arc
							(start -0.2794 -0.1778)
							(mid -0.249642 -0.249642)
							(end -0.1778 -0.2794)
						)
						(arc
							(start 0.1778 -0.2794)
							(mid 0.249642 -0.249642)
							(end 0.2794 -0.1778)
						)
						(arc
							(start 0.2794 0.1778)
							(mid 0.249642 0.249642)
							(end 0.1778 0.2794)
						)
					)
					(width 0)
					(fill yes)
				)
			)
		)
		(pad "2" smd custom
			(at 0 0.4445)
			(size 0.1397 0.1397)
			(layers "B.Cu" "B.Mask" "B.Paste")
			(net "TWI_SCL2")
			(options
				(clearance outline)
				(anchor circle)
			)
			(primitives
				(gr_poly
					(pts
						(arc
							(start -0.1778 0.2794)
							(mid -0.249642 0.249642)
							(end -0.2794 0.1778)
						)
						(arc
							(start -0.2794 -0.1778)
							(mid -0.249642 -0.249642)
							(end -0.1778 -0.2794)
						)
						(arc
							(start 0.1778 -0.2794)
							(mid 0.249642 -0.249642)
							(end 0.2794 -0.1778)
						)
						(arc
							(start 0.2794 0.1778)
							(mid 0.249642 0.249642)
							(end 0.1778 0.2794)
						)
					)
					(width 0)
					(fill yes)
				)
			)
		)
	)
	(footprint ""
		(layer "B.Cu")
		(at 18.5166 -185.7502)
		(property "Reference" "C372"
			(at 0 0 0)
			(layer "B.SilkS")
			(hide yes)
			(effects
				(font
					(size 1.27 1.27)
				)
				(justify mirror)
			)
		)
		(property "Value" "SCD015U25V2KX-GP"
			(at -1.1811 -2.7051 0)
			(unlocked yes)
			(layer "B.Fab")
			(hide yes)
			(effects
				(font
					(size 1.016 1.016)
					(thickness 0.1524)
				)
				(justify mirror)
			)
		)
		(property "Device Type" "C402H22"
			(at -1.1811 -4.2291 0)
			(unlocked yes)
			(layer "B.Fab")
			(hide yes)
			(effects
				(font
					(size 1.016 1.016)
					(thickness 0.1524)
				)
				(justify mirror)
			)
		)
		(duplicate_pad_numbers_are_jumpers no)
		(fp_rect
			(start 0.4318 0.9525)
			(end -0.4318 -0.9525)
			(stroke
				(width 0)
				(type default)
			)
			(fill no)
			(layer "B.CrtYd")
		)
		(fp_rect
			(start 0.4318 0.9525)
			(end -0.4318 -0.9525)
			(stroke
				(width 0)
				(type default)
			)
			(fill no)
			(layer "B.Fab")
		)
		(pad "1" smd custom
			(at 0 -0.4445 180)
			(size 0.1524 0.1524)
			(layers "B.Cu" "B.Mask" "B.Paste")
			(net "MB0_CM_SENSE_P")
			(options
				(clearance outline)
				(anchor circle)
			)
			(primitives
				(gr_poly
					(pts
						(arc
							(start 0.3048 0.2032)
							(mid 0.275042 0.275042)
							(end 0.2032 0.3048)
						)
						(arc
							(start -0.2032 0.3048)
							(mid -0.275042 0.275042)
							(end -0.3048 0.2032)
						)
						(arc
							(start -0.3048 -0.2032)
							(mid -0.275042 -0.275042)
							(end -0.2032 -0.3048)
						)
						(arc
							(start 0.2032 -0.3048)
							(mid 0.275042 -0.275042)
							(end 0.3048 -0.2032)
						)
					)
					(width 0)
					(fill yes)
				)
			)
		)
		(pad "2" smd custom
			(at 0 0.4445 180)
			(size 0.1524 0.1524)
			(layers "B.Cu" "B.Mask" "B.Paste")
			(net "MB0_CM_SENSE_N")
			(options
				(clearance outline)
				(anchor circle)
			)
			(primitives
				(gr_poly
					(pts
						(arc
							(start 0.3048 0.2032)
							(mid 0.275042 0.275042)
							(end 0.2032 0.3048)
						)
						(arc
							(start -0.2032 0.3048)
							(mid -0.275042 0.275042)
							(end -0.3048 0.2032)
						)
						(arc
							(start -0.3048 -0.2032)
							(mid -0.275042 -0.275042)
							(end -0.2032 -0.3048)
						)
						(arc
							(start 0.2032 -0.3048)
							(mid 0.275042 -0.275042)
							(end 0.3048 -0.2032)
						)
					)
					(width 0)
					(fill yes)
				)
			)
		)
	)
	(footprint ""
		(layer "B.Cu")
		(at 53.975508 -120.807226 -90)
		(property "Reference" "R247"
			(at 0 0 90)
			(layer "B.SilkS")
			(hide yes)
			(effects
				(font
					(size 1.27 1.27)
				)
				(justify mirror)
			)
		)
		(property "Value" "0R2J-2-GP"
			(at -0.064008 -3.993896 270)
			(unlocked yes)
			(layer "B.Fab")
			(hide yes)
			(effects
				(font
					(size 1.016 1.016)
					(thickness 0.1524)
				)
				(justify mirror)
			)
		)
		(property "Device Type" "R402H16"
			(at -0.064008 -5.517896 270)
			(unlocked yes)
			(layer "B.Fab")
			(hide yes)
			(effects
				(font
					(size 1.016 1.016)
					(thickness 0.1524)
				)
				(justify mirror)
			)
		)
		(duplicate_pad_numbers_are_jumpers no)
		(fp_line
			(start -0.508 -0.9398)
			(end 0.508 -0.9398)
			(stroke
				(width 0.1524)
				(type default)
			)
			(layer "B.SilkS")
		)
		(fp_line
			(start 0.508 -0.9398)
			(end 0.508 0.9398)
			(stroke
				(width 0.1524)
				(type default)
			)
			(layer "B.SilkS")
		)
		(fp_rect
			(start 0.508 0.9398)
			(end -0.508 -0.9398)
			(stroke
				(width 0)
				(type default)
			)
			(fill no)
			(layer "B.CrtYd")
		)
		(fp_rect
			(start 0.508 0.9398)
			(end -0.508 -0.9398)
			(stroke
				(width 0)
				(type default)
			)
			(fill no)
			(layer "B.Fab")
		)
		(pad "1" smd custom
			(at 0 -0.4445 90)
			(size 0.1397 0.1397)
			(layers "B.Cu" "B.Mask" "B.Paste")
			(net "BMC_I2C5_D_PEB_DEVICE_SDA")
			(options
				(clearance outline)
				(anchor circle)
			)
			(primitives
				(gr_poly
					(pts
						(arc
							(start -0.1778 0.2794)
							(mid -0.249642 0.249642)
							(end -0.2794 0.1778)
						)
						(arc
							(start -0.2794 -0.1778)
							(mid -0.249642 -0.249642)
							(end -0.1778 -0.2794)
						)
						(arc
							(start 0.1778 -0.2794)
							(mid 0.249642 -0.249642)
							(end 0.2794 -0.1778)
						)
						(arc
							(start 0.2794 0.1778)
							(mid 0.249642 0.249642)
							(end 0.1778 0.2794)
						)
					)
					(width 0)
					(fill yes)
				)
			)
		)
		(pad "2" smd custom
			(at 0 0.4445 90)
			(size 0.1397 0.1397)
			(layers "B.Cu" "B.Mask" "B.Paste")
			(net "BMC0_SMB5_DAT")
			(options
				(clearance outline)
				(anchor circle)
			)
			(primitives
				(gr_poly
					(pts
						(arc
							(start -0.1778 0.2794)
							(mid -0.249642 0.249642)
							(end -0.2794 0.1778)
						)
						(arc
							(start -0.2794 -0.1778)
							(mid -0.249642 -0.249642)
							(end -0.1778 -0.2794)
						)
						(arc
							(start 0.1778 -0.2794)
							(mid 0.249642 -0.249642)
							(end 0.2794 -0.1778)
						)
						(arc
							(start 0.2794 0.1778)
							(mid 0.249642 0.249642)
							(end 0.1778 0.2794)
						)
					)
					(width 0)
					(fill yes)
				)
			)
		)
	)
	(footprint ""
		(layer "B.Cu")
		(at 335.820512 -172.432218)
		(property "Reference" "R4155"
			(at 0 0 0)
			(layer "B.SilkS")
			(hide yes)
			(effects
				(font
					(size 1.27 1.27)
				)
				(justify mirror)
			)
		)
		(property "Value" "4K7R2F-GP"
			(at -0.064008 -3.993896 0)
			(unlocked yes)
			(layer "B.Fab")
			(hide yes)
			(effects
				(font
					(size 1.016 1.016)
					(thickness 0.1524)
				)
				(justify mirror)
			)
		)
		(property "Device Type" "R402H16"
			(at -0.064008 -5.517896 0)
			(unlocked yes)
			(layer "B.Fab")
			(hide yes)
			(effects
				(font
					(size 1.016 1.016)
					(thickness 0.1524)
				)
				(justify mirror)
			)
		)
		(duplicate_pad_numbers_are_jumpers no)
		(fp_line
			(start -0.508 -0.9398)
			(end 0.508 -0.9398)
			(stroke
				(width 0.1524)
				(type default)
			)
			(layer "B.SilkS")
		)
		(fp_line
			(start 0.508 -0.9398)
			(end 0.508 0.9398)
			(stroke
				(width 0.1524)
				(type default)
			)
			(layer "B.SilkS")
		)
		(fp_rect
			(start 0.508 0.9398)
			(end -0.508 -0.9398)
			(stroke
				(width 0)
				(type default)
			)
			(fill no)
			(layer "B.CrtYd")
		)
		(fp_rect
			(start 0.508 0.9398)
			(end -0.508 -0.9398)
			(stroke
				(width 0)
				(type default)
			)
			(fill no)
			(layer "B.Fab")
		)
		(pad "1" smd custom
			(at 0 -0.4445 180)
			(size 0.1397 0.1397)
			(layers "B.Cu" "B.Mask" "B.Paste")
			(net "SSD_PERST#4")
			(options
				(clearance outline)
				(anchor circle)
			)
			(primitives
				(gr_poly
					(pts
						(arc
							(start -0.1778 0.2794)
							(mid -0.249642 0.249642)
							(end -0.2794 0.1778)
						)
						(arc
							(start -0.2794 -0.1778)
							(mid -0.249642 -0.249642)
							(end -0.1778 -0.2794)
						)
						(arc
							(start 0.1778 -0.2794)
							(mid 0.249642 -0.249642)
							(end 0.2794 -0.1778)
						)
						(arc
							(start 0.2794 0.1778)
							(mid 0.249642 0.249642)
							(end 0.1778 0.2794)
						)
					)
					(width 0)
					(fill yes)
				)
			)
		)
		(pad "2" smd custom
			(at 0 0.4445 180)
			(size 0.1397 0.1397)
			(layers "B.Cu" "B.Mask" "B.Paste")
			(net "P3V3_STBY")
			(options
				(clearance outline)
				(anchor circle)
			)
			(primitives
				(gr_poly
					(pts
						(arc
							(start -0.1778 0.2794)
							(mid -0.249642 0.249642)
							(end -0.2794 0.1778)
						)
						(arc
							(start -0.2794 -0.1778)
							(mid -0.249642 -0.249642)
							(end -0.1778 -0.2794)
						)
						(arc
							(start 0.1778 -0.2794)
							(mid 0.249642 -0.249642)
							(end 0.2794 -0.1778)
						)
						(arc
							(start 0.2794 0.1778)
							(mid 0.249642 0.249642)
							(end 0.1778 0.2794)
						)
					)
					(width 0)
					(fill yes)
				)
			)
		)
	)
	(footprint ""
		(layer "B.Cu")
		(at 133.268212 -199.753474)
		(property "Reference" "R3209"
			(at 0 0 0)
			(layer "B.SilkS")
			(hide yes)
			(effects
				(font
					(size 1.27 1.27)
				)
				(justify mirror)
			)
		)
		(property "Value" "0R2J-2-GP"
			(at -0.064008 -3.993896 0)
			(unlocked yes)
			(layer "B.Fab")
			(hide yes)
			(effects
				(font
					(size 1.016 1.016)
					(thickness 0.1524)
				)
				(justify mirror)
			)
		)
		(property "Device Type" "R402H16"
			(at -0.064008 -5.517896 0)
			(unlocked yes)
			(layer "B.Fab")
			(hide yes)
			(effects
				(font
					(size 1.016 1.016)
					(thickness 0.1524)
				)
				(justify mirror)
			)
		)
		(duplicate_pad_numbers_are_jumpers no)
		(fp_line
			(start -0.508 -0.9398)
			(end 0.508 -0.9398)
			(stroke
				(width 0.1524)
				(type default)
			)
			(layer "B.SilkS")
		)
		(fp_line
			(start 0.508 -0.9398)
			(end 0.508 0.9398)
			(stroke
				(width 0.1524)
				(type default)
			)
			(layer "B.SilkS")
		)
		(fp_rect
			(start 0.508 0.9398)
			(end -0.508 -0.9398)
			(stroke
				(width 0)
				(type default)
			)
			(fill no)
			(layer "B.CrtYd")
		)
		(fp_rect
			(start 0.508 0.9398)
			(end -0.508 -0.9398)
			(stroke
				(width 0)
				(type default)
			)
			(fill no)
			(layer "B.Fab")
		)
		(pad "1" smd custom
			(at 0 -0.4445 180)
			(size 0.1397 0.1397)
			(layers "B.Cu" "B.Mask" "B.Paste")
			(net "SSD_PERST_Y2")
			(options
				(clearance outline)
				(anchor circle)
			)
			(primitives
				(gr_poly
					(pts
						(arc
							(start -0.1778 0.2794)
							(mid -0.249642 0.249642)
							(end -0.2794 0.1778)
						)
						(arc
							(start -0.2794 -0.1778)
							(mid -0.249642 -0.249642)
							(end -0.1778 -0.2794)
						)
						(arc
							(start 0.1778 -0.2794)
							(mid 0.249642 -0.249642)
							(end 0.2794 -0.1778)
						)
						(arc
							(start 0.2794 0.1778)
							(mid 0.249642 0.249642)
							(end 0.1778 0.2794)
						)
					)
					(width 0)
					(fill yes)
				)
			)
		)
		(pad "2" smd custom
			(at 0 0.4445 180)
			(size 0.1397 0.1397)
			(layers "B.Cu" "B.Mask" "B.Paste")
			(net "SSD_PERST#2_R")
			(options
				(clearance outline)
				(anchor circle)
			)
			(primitives
				(gr_poly
					(pts
						(arc
							(start -0.1778 0.2794)
							(mid -0.249642 0.249642)
							(end -0.2794 0.1778)
						)
						(arc
							(start -0.2794 -0.1778)
							(mid -0.249642 -0.249642)
							(end -0.1778 -0.2794)
						)
						(arc
							(start 0.1778 -0.2794)
							(mid 0.249642 -0.249642)
							(end 0.2794 -0.1778)
						)
						(arc
							(start 0.2794 0.1778)
							(mid 0.249642 0.249642)
							(end 0.1778 0.2794)
						)
					)
					(width 0)
					(fill yes)
				)
			)
		)
	)
	(footprint ""
		(layer "B.Cu")
		(at 24.13 -123.0884 -90)
		(property "Reference" "R704"
			(at 0 0 90)
			(layer "B.SilkS")
			(hide yes)
			(effects
				(font
					(size 1.27 1.27)
				)
				(justify mirror)
			)
		)
		(property "Value" "0R2J-2-GP"
			(at -0.064008 -3.993896 270)
			(unlocked yes)
			(layer "B.Fab")
			(hide yes)
			(effects
				(font
					(size 1.016 1.016)
					(thickness 0.1524)
				)
				(justify mirror)
			)
		)
		(property "Device Type" "R402H16"
			(at -0.064008 -5.517896 270)
			(unlocked yes)
			(layer "B.Fab")
			(hide yes)
			(effects
				(font
					(size 1.016 1.016)
					(thickness 0.1524)
				)
				(justify mirror)
			)
		)
		(duplicate_pad_numbers_are_jumpers no)
		(fp_line
			(start -0.508 -0.9398)
			(end 0.508 -0.9398)
			(stroke
				(width 0.1524)
				(type default)
			)
			(layer "B.SilkS")
		)
		(fp_line
			(start 0.508 -0.9398)
			(end 0.508 0.9398)
			(stroke
				(width 0.1524)
				(type default)
			)
			(layer "B.SilkS")
		)
		(fp_rect
			(start 0.508 0.9398)
			(end -0.508 -0.9398)
			(stroke
				(width 0)
				(type default)
			)
			(fill no)
			(layer "B.CrtYd")
		)
		(fp_rect
			(start 0.508 0.9398)
			(end -0.508 -0.9398)
			(stroke
				(width 0)
				(type default)
			)
			(fill no)
			(layer "B.Fab")
		)
		(pad "1" smd custom
			(at 0 -0.4445 90)
			(size 0.1397 0.1397)
			(layers "B.Cu" "B.Mask" "B.Paste")
			(net "SPICK_R")
			(options
				(clearance outline)
				(anchor circle)
			)
			(primitives
				(gr_poly
					(pts
						(arc
							(start -0.1778 0.2794)
							(mid -0.249642 0.249642)
							(end -0.2794 0.1778)
						)
						(arc
							(start -0.2794 -0.1778)
							(mid -0.249642 -0.249642)
							(end -0.1778 -0.2794)
						)
						(arc
							(start 0.1778 -0.2794)
							(mid 0.249642 -0.249642)
							(end 0.2794 -0.1778)
						)
						(arc
							(start 0.2794 0.1778)
							(mid 0.249642 0.249642)
							(end 0.1778 0.2794)
						)
					)
					(width 0)
					(fill yes)
				)
			)
		)
		(pad "2" smd custom
			(at 0 0.4445 90)
			(size 0.1397 0.1397)
			(layers "B.Cu" "B.Mask" "B.Paste")
			(net "SPICK")
			(options
				(clearance outline)
				(anchor circle)
			)
			(primitives
				(gr_poly
					(pts
						(arc
							(start -0.1778 0.2794)
							(mid -0.249642 0.249642)
							(end -0.2794 0.1778)
						)
						(arc
							(start -0.2794 -0.1778)
							(mid -0.249642 -0.249642)
							(end -0.1778 -0.2794)
						)
						(arc
							(start 0.1778 -0.2794)
							(mid 0.249642 -0.249642)
							(end 0.2794 -0.1778)
						)
						(arc
							(start 0.2794 0.1778)
							(mid 0.249642 0.249642)
							(end 0.1778 0.2794)
						)
					)
					(width 0)
					(fill yes)
				)
			)
		)
	)
	(footprint ""
		(layer "B.Cu")
		(at 51.5366 -127.7112 90)
		(property "Reference" "R469"
			(at 0 0 90)
			(layer "B.SilkS")
			(hide yes)
			(effects
				(font
					(size 1.27 1.27)
				)
				(justify mirror)
			)
		)
		(property "Value" "0R2J-2-GP"
			(at -0.064008 -3.993896 90)
			(unlocked yes)
			(layer "B.Fab")
			(hide yes)
			(effects
				(font
					(size 1.016 1.016)
					(thickness 0.1524)
				)
				(justify mirror)
			)
		)
		(property "Device Type" "R402H16"
			(at -0.064008 -5.517896 90)
			(unlocked yes)
			(layer "B.Fab")
			(hide yes)
			(effects
				(font
					(size 1.016 1.016)
					(thickness 0.1524)
				)
				(justify mirror)
			)
		)
		(duplicate_pad_numbers_are_jumpers no)
		(fp_line
			(start 0.508 -0.9398)
			(end 0.508 0.9398)
			(stroke
				(width 0.1524)
				(type default)
			)
			(layer "B.SilkS")
		)
		(fp_line
			(start -0.508 -0.9398)
			(end 0.508 -0.9398)
			(stroke
				(width 0.1524)
				(type default)
			)
			(layer "B.SilkS")
		)
		(fp_rect
			(start 0.508 0.9398)
			(end -0.508 -0.9398)
			(stroke
				(width 0)
				(type default)
			)
			(fill no)
			(layer "B.CrtYd")
		)
		(fp_rect
			(start 0.508 0.9398)
			(end -0.508 -0.9398)
			(stroke
				(width 0)
				(type default)
			)
			(fill no)
			(layer "B.Fab")
		)
		(pad "1" smd custom
			(at 0 -0.4445 270)
			(size 0.1397 0.1397)
			(layers "B.Cu" "B.Mask" "B.Paste")
			(net "BMC0_SMB14_SDA")
			(options
				(clearance outline)
				(anchor circle)
			)
			(primitives
				(gr_poly
					(pts
						(arc
							(start -0.1778 0.2794)
							(mid -0.249642 0.249642)
							(end -0.2794 0.1778)
						)
						(arc
							(start -0.2794 -0.1778)
							(mid -0.249642 -0.249642)
							(end -0.1778 -0.2794)
						)
						(arc
							(start 0.1778 -0.2794)
							(mid 0.249642 -0.249642)
							(end 0.2794 -0.1778)
						)
						(arc
							(start 0.2794 0.1778)
							(mid 0.249642 0.249642)
							(end 0.1778 0.2794)
						)
					)
					(width 0)
					(fill yes)
				)
			)
		)
		(pad "2" smd custom
			(at 0 0.4445 270)
			(size 0.1397 0.1397)
			(layers "B.Cu" "B.Mask" "B.Paste")
			(net "BMC_I2C14_MINI8_SDA_S")
			(options
				(clearance outline)
				(anchor circle)
			)
			(primitives
				(gr_poly
					(pts
						(arc
							(start -0.1778 0.2794)
							(mid -0.249642 0.249642)
							(end -0.2794 0.1778)
						)
						(arc
							(start -0.2794 -0.1778)
							(mid -0.249642 -0.249642)
							(end -0.1778 -0.2794)
						)
						(arc
							(start 0.1778 -0.2794)
							(mid 0.249642 -0.249642)
							(end 0.2794 -0.1778)
						)
						(arc
							(start 0.2794 0.1778)
							(mid 0.249642 0.249642)
							(end 0.1778 0.2794)
						)
					)
					(width 0)
					(fill yes)
				)
			)
		)
	)
	(footprint ""
		(layer "B.Cu")
		(at 237.1598 -47.032672 90)
		(property "Reference" "C39"
			(at 0 0 90)
			(layer "B.SilkS")
			(hide yes)
			(effects
				(font
					(size 1.27 1.27)
				)
				(justify mirror)
			)
		)
		(property "Value" "SCD1U16V1KX-1-GP"
			(at 2.8321 -1.7399 90)
			(unlocked yes)
			(layer "B.Fab")
			(hide yes)
			(effects
				(font
					(size 1.016 1.016)
					(thickness 0.1524)
				)
				(justify mirror)
			)
		)
		(property "Device Type" "C0201H13"
			(at 2.8321 -3.2639 90)
			(unlocked yes)
			(layer "B.Fab")
			(hide yes)
			(effects
				(font
					(size 1.016 1.016)
					(thickness 0.1524)
				)
				(justify mirror)
			)
		)
		(duplicate_pad_numbers_are_jumpers no)
		(fp_rect
			(start 0.2794 0.6477)
			(end -0.2794 -0.6477)
			(stroke
				(width 0)
				(type default)
			)
			(fill no)
			(layer "B.CrtYd")
		)
		(fp_rect
			(start 0.2794 0.6477)
			(end -0.2794 -0.6477)
			(stroke
				(width 0)
				(type default)
			)
			(fill no)
			(layer "B.Fab")
		)
		(pad "1" smd custom
			(at 0 -0.2794 270)
			(size 0.0762 0.0762)
			(layers "B.Cu" "B.Mask" "B.Paste")
			(net "DUT_VDD")
			(options
				(clearance outline)
				(anchor circle)
			)
			(primitives
				(gr_poly
					(pts
						(arc
							(start 0.1524 0.127)
							(mid 0.137521 0.162921)
							(end 0.1016 0.1778)
						)
						(arc
							(start -0.1016 0.1778)
							(mid -0.137521 0.162921)
							(end -0.1524 0.127)
						)
						(arc
							(start -0.1524 -0.127)
							(mid -0.137521 -0.162921)
							(end -0.1016 -0.1778)
						)
						(arc
							(start 0.1016 -0.1778)
							(mid 0.137521 -0.162921)
							(end 0.1524 -0.127)
						)
					)
					(width 0)
					(fill yes)
				)
			)
		)
		(pad "2" smd custom
			(at 0 0.2794 270)
			(size 0.0762 0.0762)
			(layers "B.Cu" "B.Mask" "B.Paste")
			(net "GND")
			(options
				(clearance outline)
				(anchor circle)
			)
			(primitives
				(gr_poly
					(pts
						(arc
							(start 0.1524 0.127)
							(mid 0.137521 0.162921)
							(end 0.1016 0.1778)
						)
						(arc
							(start -0.1016 0.1778)
							(mid -0.137521 0.162921)
							(end -0.1524 0.127)
						)
						(arc
							(start -0.1524 -0.127)
							(mid -0.137521 -0.162921)
							(end -0.1016 -0.1778)
						)
						(arc
							(start 0.1016 -0.1778)
							(mid 0.137521 -0.162921)
							(end 0.1524 -0.127)
						)
					)
					(width 0)
					(fill yes)
				)
			)
		)
	)
	(footprint ""
		(layer "B.Cu")
		(at 14.6558 -126.365 180)
		(property "Reference" "R522"
			(at 0 0 0)
			(layer "B.SilkS")
			(hide yes)
			(effects
				(font
					(size 1.27 1.27)
				)
				(justify mirror)
			)
		)
		(property "Value" "4K7R2F-GP"
			(at -0.064008 -3.993896 180)
			(unlocked yes)
			(layer "B.Fab")
			(hide yes)
			(effects
				(font
					(size 1.016 1.016)
					(thickness 0.1524)
				)
				(justify mirror)
			)
		)
		(property "Device Type" "R402H16"
			(at -0.064008 -5.517896 180)
			(unlocked yes)
			(layer "B.Fab")
			(hide yes)
			(effects
				(font
					(size 1.016 1.016)
					(thickness 0.1524)
				)
				(justify mirror)
			)
		)
		(duplicate_pad_numbers_are_jumpers no)
		(fp_line
			(start 0.508 -0.9398)
			(end 0.508 0.9398)
			(stroke
				(width 0.1524)
				(type default)
			)
			(layer "B.SilkS")
		)
		(fp_line
			(start -0.508 -0.9398)
			(end 0.508 -0.9398)
			(stroke
				(width 0.1524)
				(type default)
			)
			(layer "B.SilkS")
		)
		(fp_rect
			(start 0.508 0.9398)
			(end -0.508 -0.9398)
			(stroke
				(width 0)
				(type default)
			)
			(fill no)
			(layer "B.CrtYd")
		)
		(fp_rect
			(start 0.508 0.9398)
			(end -0.508 -0.9398)
			(stroke
				(width 0)
				(type default)
			)
			(fill no)
			(layer "B.Fab")
		)
		(pad "1" smd custom
			(at 0 -0.4445)
			(size 0.1397 0.1397)
			(layers "B.Cu" "B.Mask" "B.Paste")
			(net "BMC_I2C2_MINI2_SDA_S")
			(options
				(clearance outline)
				(anchor circle)
			)
			(primitives
				(gr_poly
					(pts
						(arc
							(start -0.1778 0.2794)
							(mid -0.249642 0.249642)
							(end -0.2794 0.1778)
						)
						(arc
							(start -0.2794 -0.1778)
							(mid -0.249642 -0.249642)
							(end -0.1778 -0.2794)
						)
						(arc
							(start 0.1778 -0.2794)
							(mid 0.249642 -0.249642)
							(end 0.2794 -0.1778)
						)
						(arc
							(start 0.2794 0.1778)
							(mid 0.249642 0.249642)
							(end 0.1778 0.2794)
						)
					)
					(width 0)
					(fill yes)
				)
			)
		)
		(pad "2" smd custom
			(at 0 0.4445)
			(size 0.1397 0.1397)
			(layers "B.Cu" "B.Mask" "B.Paste")
			(net "P3V3_STBY")
			(options
				(clearance outline)
				(anchor circle)
			)
			(primitives
				(gr_poly
					(pts
						(arc
							(start -0.1778 0.2794)
							(mid -0.249642 0.249642)
							(end -0.2794 0.1778)
						)
						(arc
							(start -0.2794 -0.1778)
							(mid -0.249642 -0.249642)
							(end -0.1778 -0.2794)
						)
						(arc
							(start 0.1778 -0.2794)
							(mid 0.249642 -0.249642)
							(end 0.2794 -0.1778)
						)
						(arc
							(start 0.2794 0.1778)
							(mid 0.249642 0.249642)
							(end 0.1778 0.2794)
						)
					)
					(width 0)
					(fill yes)
				)
			)
		)
	)
	(footprint ""
		(layer "B.Cu")
		(at 186.7154 -71.628 180)
		(property "Reference" "C540"
			(at 0 0 0)
			(layer "B.SilkS")
			(hide yes)
			(effects
				(font
					(size 1.27 1.27)
				)
				(justify mirror)
			)
		)
		(property "Value" "SC4D7U16V5KX-1-GP"
			(at 0.0762 -6.1214 180)
			(unlocked yes)
			(layer "B.Fab")
			(hide yes)
			(effects
				(font
					(size 1.016 1.016)
					(thickness 0.1524)
				)
				(justify mirror)
			)
		)
		(property "Device Type" "C805H56"
			(at 0.0762 -8.1534 180)
			(unlocked yes)
			(layer "B.Fab")
			(hide yes)
			(effects
				(font
					(size 1.016 1.016)
					(thickness 0.1524)
				)
				(justify mirror)
			)
		)
		(duplicate_pad_numbers_are_jumpers no)
		(fp_line
			(start -0.635 0)
			(end 0.635 0)
			(stroke
				(width 0.508)
				(type default)
			)
			(layer "B.SilkS")
		)
		(fp_rect
			(start 0.9652 1.778)
			(end -0.9652 -1.778)
			(stroke
				(width 0)
				(type default)
			)
			(fill no)
			(layer "B.CrtYd")
		)
		(fp_poly
			(pts
				(xy 0.9652 -1.778) (xy -0.9652 -1.778) (xy -0.9652 1.778) (xy 0.9652 1.778)
			)
			(stroke
				(width 0)
				(type default)
			)
			(fill no)
			(layer "B.Fab")
		)
		(pad "1" smd rect
			(at 0 -0.9652)
			(size 1.397 1.143)
			(layers "B.Cu" "B.Mask" "B.Paste")
			(net "DUT_AVD_PCIE")
		)
		(pad "2" smd rect
			(at 0 0.9652)
			(size 1.397 1.143)
			(layers "B.Cu" "B.Mask" "B.Paste")
			(net "GND")
		)
	)
	(footprint ""
		(layer "B.Cu")
		(at 242.130072 -41.012872 -90)
		(property "Reference" "C498"
			(at 0 0 90)
			(layer "B.SilkS")
			(hide yes)
			(effects
				(font
					(size 1.27 1.27)
				)
				(justify mirror)
			)
		)
		(property "Value" "SCD1U16V1KX-1-GP"
			(at 2.8321 -1.7399 270)
			(unlocked yes)
			(layer "B.Fab")
			(hide yes)
			(effects
				(font
					(size 1.016 1.016)
					(thickness 0.1524)
				)
				(justify mirror)
			)
		)
		(property "Device Type" "C0201H13"
			(at 2.8321 -3.2639 270)
			(unlocked yes)
			(layer "B.Fab")
			(hide yes)
			(effects
				(font
					(size 1.016 1.016)
					(thickness 0.1524)
				)
				(justify mirror)
			)
		)
		(duplicate_pad_numbers_are_jumpers no)
		(fp_rect
			(start 0.2794 0.6477)
			(end -0.2794 -0.6477)
			(stroke
				(width 0)
				(type default)
			)
			(fill no)
			(layer "B.CrtYd")
		)
		(fp_rect
			(start 0.2794 0.6477)
			(end -0.2794 -0.6477)
			(stroke
				(width 0)
				(type default)
			)
			(fill no)
			(layer "B.Fab")
		)
		(pad "1" smd custom
			(at 0 -0.2794 90)
			(size 0.0762 0.0762)
			(layers "B.Cu" "B.Mask" "B.Paste")
			(net "DUT_AVD_PCIE_Q")
			(options
				(clearance outline)
				(anchor circle)
			)
			(primitives
				(gr_poly
					(pts
						(arc
							(start 0.1524 0.127)
							(mid 0.137521 0.162921)
							(end 0.1016 0.1778)
						)
						(arc
							(start -0.1016 0.1778)
							(mid -0.137521 0.162921)
							(end -0.1524 0.127)
						)
						(arc
							(start -0.1524 -0.127)
							(mid -0.137521 -0.162921)
							(end -0.1016 -0.1778)
						)
						(arc
							(start 0.1016 -0.1778)
							(mid 0.137521 -0.162921)
							(end 0.1524 -0.127)
						)
					)
					(width 0)
					(fill yes)
				)
			)
		)
		(pad "2" smd custom
			(at 0 0.2794 90)
			(size 0.0762 0.0762)
			(layers "B.Cu" "B.Mask" "B.Paste")
			(net "GND")
			(options
				(clearance outline)
				(anchor circle)
			)
			(primitives
				(gr_poly
					(pts
						(arc
							(start 0.1524 0.127)
							(mid 0.137521 0.162921)
							(end 0.1016 0.1778)
						)
						(arc
							(start -0.1016 0.1778)
							(mid -0.137521 0.162921)
							(end -0.1524 0.127)
						)
						(arc
							(start -0.1524 -0.127)
							(mid -0.137521 -0.162921)
							(end -0.1016 -0.1778)
						)
						(arc
							(start 0.1016 -0.1778)
							(mid 0.137521 -0.162921)
							(end 0.1524 -0.127)
						)
					)
					(width 0)
					(fill yes)
				)
			)
		)
	)
	(footprint ""
		(layer "B.Cu")
		(at 235.1024 -47.032672 -90)
		(property "Reference" "C40"
			(at 0 0 90)
			(layer "B.SilkS")
			(hide yes)
			(effects
				(font
					(size 1.27 1.27)
				)
				(justify mirror)
			)
		)
		(property "Value" "SCD1U16V1KX-1-GP"
			(at 2.8321 -1.7399 270)
			(unlocked yes)
			(layer "B.Fab")
			(hide yes)
			(effects
				(font
					(size 1.016 1.016)
					(thickness 0.1524)
				)
				(justify mirror)
			)
		)
		(property "Device Type" "C0201H13"
			(at 2.8321 -3.2639 270)
			(unlocked yes)
			(layer "B.Fab")
			(hide yes)
			(effects
				(font
					(size 1.016 1.016)
					(thickness 0.1524)
				)
				(justify mirror)
			)
		)
		(duplicate_pad_numbers_are_jumpers no)
		(fp_rect
			(start 0.2794 0.6477)
			(end -0.2794 -0.6477)
			(stroke
				(width 0)
				(type default)
			)
			(fill no)
			(layer "B.CrtYd")
		)
		(fp_rect
			(start 0.2794 0.6477)
			(end -0.2794 -0.6477)
			(stroke
				(width 0)
				(type default)
			)
			(fill no)
			(layer "B.Fab")
		)
		(pad "1" smd custom
			(at 0 -0.2794 90)
			(size 0.0762 0.0762)
			(layers "B.Cu" "B.Mask" "B.Paste")
			(net "DUT_VDD")
			(options
				(clearance outline)
				(anchor circle)
			)
			(primitives
				(gr_poly
					(pts
						(arc
							(start 0.1524 0.127)
							(mid 0.137521 0.162921)
							(end 0.1016 0.1778)
						)
						(arc
							(start -0.1016 0.1778)
							(mid -0.137521 0.162921)
							(end -0.1524 0.127)
						)
						(arc
							(start -0.1524 -0.127)
							(mid -0.137521 -0.162921)
							(end -0.1016 -0.1778)
						)
						(arc
							(start 0.1016 -0.1778)
							(mid 0.137521 -0.162921)
							(end 0.1524 -0.127)
						)
					)
					(width 0)
					(fill yes)
				)
			)
		)
		(pad "2" smd custom
			(at 0 0.2794 90)
			(size 0.0762 0.0762)
			(layers "B.Cu" "B.Mask" "B.Paste")
			(net "GND")
			(options
				(clearance outline)
				(anchor circle)
			)
			(primitives
				(gr_poly
					(pts
						(arc
							(start 0.1524 0.127)
							(mid 0.137521 0.162921)
							(end 0.1016 0.1778)
						)
						(arc
							(start -0.1016 0.1778)
							(mid -0.137521 0.162921)
							(end -0.1524 0.127)
						)
						(arc
							(start -0.1524 -0.127)
							(mid -0.137521 -0.162921)
							(end -0.1016 -0.1778)
						)
						(arc
							(start 0.1016 -0.1778)
							(mid 0.137521 -0.162921)
							(end 0.1524 -0.127)
						)
					)
					(width 0)
					(fill yes)
				)
			)
		)
	)
	(footprint ""
		(layer "B.Cu")
		(at 150.460202 -56.542432)
		(property "Reference" "PR169"
			(at 0 0 0)
			(layer "B.SilkS")
			(hide yes)
			(effects
				(font
					(size 1.27 1.27)
				)
				(justify mirror)
			)
		)
		(property "Value" "187KR2F-GP"
			(at -0.064008 -3.993896 0)
			(unlocked yes)
			(layer "B.Fab")
			(hide yes)
			(effects
				(font
					(size 1.016 1.016)
					(thickness 0.1524)
				)
				(justify mirror)
			)
		)
		(property "Device Type" "R402H16"
			(at -0.064008 -5.517896 0)
			(unlocked yes)
			(layer "B.Fab")
			(hide yes)
			(effects
				(font
					(size 1.016 1.016)
					(thickness 0.1524)
				)
				(justify mirror)
			)
		)
		(duplicate_pad_numbers_are_jumpers no)
		(fp_line
			(start -0.508 -0.9398)
			(end 0.508 -0.9398)
			(stroke
				(width 0.1524)
				(type default)
			)
			(layer "B.SilkS")
		)
		(fp_line
			(start 0.508 -0.9398)
			(end 0.508 0.9398)
			(stroke
				(width 0.1524)
				(type default)
			)
			(layer "B.SilkS")
		)
		(fp_rect
			(start 0.508 0.9398)
			(end -0.508 -0.9398)
			(stroke
				(width 0)
				(type default)
			)
			(fill no)
			(layer "B.CrtYd")
		)
		(fp_rect
			(start 0.508 0.9398)
			(end -0.508 -0.9398)
			(stroke
				(width 0)
				(type default)
			)
			(fill no)
			(layer "B.Fab")
		)
		(pad "1" smd custom
			(at 0 -0.4445 180)
			(size 0.1397 0.1397)
			(layers "B.Cu" "B.Mask" "B.Paste")
			(net "P0V9_RF")
			(options
				(clearance outline)
				(anchor circle)
			)
			(primitives
				(gr_poly
					(pts
						(arc
							(start -0.1778 0.2794)
							(mid -0.249642 0.249642)
							(end -0.2794 0.1778)
						)
						(arc
							(start -0.2794 -0.1778)
							(mid -0.249642 -0.249642)
							(end -0.1778 -0.2794)
						)
						(arc
							(start 0.1778 -0.2794)
							(mid 0.249642 -0.249642)
							(end 0.2794 -0.1778)
						)
						(arc
							(start 0.2794 0.1778)
							(mid 0.249642 0.249642)
							(end 0.1778 0.2794)
						)
					)
					(width 0)
					(fill yes)
				)
			)
		)
		(pad "2" smd custom
			(at 0 0.4445 180)
			(size 0.1397 0.1397)
			(layers "B.Cu" "B.Mask" "B.Paste")
			(net "AGND_P0V9")
			(options
				(clearance outline)
				(anchor circle)
			)
			(primitives
				(gr_poly
					(pts
						(arc
							(start -0.1778 0.2794)
							(mid -0.249642 0.249642)
							(end -0.2794 0.1778)
						)
						(arc
							(start -0.2794 -0.1778)
							(mid -0.249642 -0.249642)
							(end -0.1778 -0.2794)
						)
						(arc
							(start 0.1778 -0.2794)
							(mid 0.249642 -0.249642)
							(end 0.2794 -0.1778)
						)
						(arc
							(start 0.2794 0.1778)
							(mid 0.249642 0.249642)
							(end 0.1778 0.2794)
						)
					)
					(width 0)
					(fill yes)
				)
			)
		)
	)
	(footprint ""
		(layer "B.Cu")
		(at 349.640906 -42.98569 90)
		(property "Reference" "R7906"
			(at 0 0 90)
			(layer "B.SilkS")
			(hide yes)
			(effects
				(font
					(size 1.27 1.27)
				)
				(justify mirror)
			)
		)
		(property "Value" "0R2J-2-GP"
			(at -0.064008 -3.993896 90)
			(unlocked yes)
			(layer "B.Fab")
			(hide yes)
			(effects
				(font
					(size 1.016 1.016)
					(thickness 0.1524)
				)
				(justify mirror)
			)
		)
		(property "Device Type" "R402H16"
			(at -0.064008 -5.517896 90)
			(unlocked yes)
			(layer "B.Fab")
			(hide yes)
			(effects
				(font
					(size 1.016 1.016)
					(thickness 0.1524)
				)
				(justify mirror)
			)
		)
		(duplicate_pad_numbers_are_jumpers no)
		(fp_line
			(start 0.508 -0.9398)
			(end 0.508 0.9398)
			(stroke
				(width 0.1524)
				(type default)
			)
			(layer "B.SilkS")
		)
		(fp_line
			(start -0.508 -0.9398)
			(end 0.508 -0.9398)
			(stroke
				(width 0.1524)
				(type default)
			)
			(layer "B.SilkS")
		)
		(fp_rect
			(start 0.508 0.9398)
			(end -0.508 -0.9398)
			(stroke
				(width 0)
				(type default)
			)
			(fill no)
			(layer "B.CrtYd")
		)
		(fp_rect
			(start 0.508 0.9398)
			(end -0.508 -0.9398)
			(stroke
				(width 0)
				(type default)
			)
			(fill no)
			(layer "B.Fab")
		)
		(pad "1" smd custom
			(at 0 -0.4445 270)
			(size 0.1397 0.1397)
			(layers "B.Cu" "B.Mask" "B.Paste")
			(net "SLIDE_SW_PMC_RST#")
			(options
				(clearance outline)
				(anchor circle)
			)
			(primitives
				(gr_poly
					(pts
						(arc
							(start -0.1778 0.2794)
							(mid -0.249642 0.249642)
							(end -0.2794 0.1778)
						)
						(arc
							(start -0.2794 -0.1778)
							(mid -0.249642 -0.249642)
							(end -0.1778 -0.2794)
						)
						(arc
							(start 0.1778 -0.2794)
							(mid 0.249642 -0.249642)
							(end 0.2794 -0.1778)
						)
						(arc
							(start 0.2794 0.1778)
							(mid 0.249642 0.249642)
							(end 0.1778 0.2794)
						)
					)
					(width 0)
					(fill yes)
				)
			)
		)
		(pad "2" smd custom
			(at 0 0.4445 270)
			(size 0.1397 0.1397)
			(layers "B.Cu" "B.Mask" "B.Paste")
			(net "PM8536_PG2_R")
			(options
				(clearance outline)
				(anchor circle)
			)
			(primitives
				(gr_poly
					(pts
						(arc
							(start -0.1778 0.2794)
							(mid -0.249642 0.249642)
							(end -0.2794 0.1778)
						)
						(arc
							(start -0.2794 -0.1778)
							(mid -0.249642 -0.249642)
							(end -0.1778 -0.2794)
						)
						(arc
							(start 0.1778 -0.2794)
							(mid 0.249642 -0.249642)
							(end 0.2794 -0.1778)
						)
						(arc
							(start 0.2794 0.1778)
							(mid 0.249642 0.249642)
							(end 0.1778 0.2794)
						)
					)
					(width 0)
					(fill yes)
				)
			)
		)
	)
	(footprint ""
		(layer "B.Cu")
		(at 314.276232 -37.732462 180)
		(property "Reference" "C278"
			(at 0 0 0)
			(layer "B.SilkS")
			(hide yes)
			(effects
				(font
					(size 1.27 1.27)
				)
				(justify mirror)
			)
		)
		(property "Value" "SCD1U10V2KX-5GP"
			(at -1.1811 -2.7051 180)
			(unlocked yes)
			(layer "B.Fab")
			(hide yes)
			(effects
				(font
					(size 1.016 1.016)
					(thickness 0.1524)
				)
				(justify mirror)
			)
		)
		(property "Device Type" "C402H22"
			(at -1.1811 -4.2291 180)
			(unlocked yes)
			(layer "B.Fab")
			(hide yes)
			(effects
				(font
					(size 1.016 1.016)
					(thickness 0.1524)
				)
				(justify mirror)
			)
		)
		(duplicate_pad_numbers_are_jumpers no)
		(fp_rect
			(start 0.4318 0.9525)
			(end -0.4318 -0.9525)
			(stroke
				(width 0)
				(type default)
			)
			(fill no)
			(layer "B.CrtYd")
		)
		(fp_rect
			(start 0.4318 0.9525)
			(end -0.4318 -0.9525)
			(stroke
				(width 0)
				(type default)
			)
			(fill no)
			(layer "B.Fab")
		)
		(pad "1" smd custom
			(at 0 -0.4445)
			(size 0.1524 0.1524)
			(layers "B.Cu" "B.Mask" "B.Paste")
			(net "GND")
			(options
				(clearance outline)
				(anchor circle)
			)
			(primitives
				(gr_poly
					(pts
						(arc
							(start 0.3048 0.2032)
							(mid 0.275042 0.275042)
							(end 0.2032 0.3048)
						)
						(arc
							(start -0.2032 0.3048)
							(mid -0.275042 0.275042)
							(end -0.3048 0.2032)
						)
						(arc
							(start -0.3048 -0.2032)
							(mid -0.275042 -0.275042)
							(end -0.2032 -0.3048)
						)
						(arc
							(start 0.2032 -0.3048)
							(mid 0.275042 -0.275042)
							(end 0.3048 -0.2032)
						)
					)
					(width 0)
					(fill yes)
				)
			)
		)
		(pad "2" smd custom
			(at 0 0.4445)
			(size 0.1524 0.1524)
			(layers "B.Cu" "B.Mask" "B.Paste")
			(net "P3V3_STBY")
			(options
				(clearance outline)
				(anchor circle)
			)
			(primitives
				(gr_poly
					(pts
						(arc
							(start 0.3048 0.2032)
							(mid 0.275042 0.275042)
							(end 0.2032 0.3048)
						)
						(arc
							(start -0.2032 0.3048)
							(mid -0.275042 0.275042)
							(end -0.3048 0.2032)
						)
						(arc
							(start -0.3048 -0.2032)
							(mid -0.275042 -0.275042)
							(end -0.2032 -0.3048)
						)
						(arc
							(start 0.2032 -0.3048)
							(mid 0.275042 -0.275042)
							(end 0.3048 -0.2032)
						)
					)
					(width 0)
					(fill yes)
				)
			)
		)
	)
	(footprint ""
		(layer "B.Cu")
		(at 42.4942 -187.4012 180)
		(property "Reference" "R869"
			(at 0 0 0)
			(layer "B.SilkS")
			(hide yes)
			(effects
				(font
					(size 1.27 1.27)
				)
				(justify mirror)
			)
		)
		(property "Value" "0R2J-2-GP"
			(at -0.064008 -3.993896 180)
			(unlocked yes)
			(layer "B.Fab")
			(hide yes)
			(effects
				(font
					(size 1.016 1.016)
					(thickness 0.1524)
				)
				(justify mirror)
			)
		)
		(property "Device Type" "R402H16"
			(at -0.064008 -5.517896 180)
			(unlocked yes)
			(layer "B.Fab")
			(hide yes)
			(effects
				(font
					(size 1.016 1.016)
					(thickness 0.1524)
				)
				(justify mirror)
			)
		)
		(duplicate_pad_numbers_are_jumpers no)
		(fp_line
			(start 0.508 -0.9398)
			(end 0.508 0.9398)
			(stroke
				(width 0.1524)
				(type default)
			)
			(layer "B.SilkS")
		)
		(fp_line
			(start -0.508 -0.9398)
			(end 0.508 -0.9398)
			(stroke
				(width 0.1524)
				(type default)
			)
			(layer "B.SilkS")
		)
		(fp_rect
			(start 0.508 0.9398)
			(end -0.508 -0.9398)
			(stroke
				(width 0)
				(type default)
			)
			(fill no)
			(layer "B.CrtYd")
		)
		(fp_rect
			(start 0.508 0.9398)
			(end -0.508 -0.9398)
			(stroke
				(width 0)
				(type default)
			)
			(fill no)
			(layer "B.Fab")
		)
		(pad "1" smd custom
			(at 0 -0.4445)
			(size 0.1397 0.1397)
			(layers "B.Cu" "B.Mask" "B.Paste")
			(net "BMC_I2C9_CLKBUF2_SDA")
			(options
				(clearance outline)
				(anchor circle)
			)
			(primitives
				(gr_poly
					(pts
						(arc
							(start -0.1778 0.2794)
							(mid -0.249642 0.249642)
							(end -0.2794 0.1778)
						)
						(arc
							(start -0.2794 -0.1778)
							(mid -0.249642 -0.249642)
							(end -0.1778 -0.2794)
						)
						(arc
							(start 0.1778 -0.2794)
							(mid 0.249642 -0.249642)
							(end 0.2794 -0.1778)
						)
						(arc
							(start 0.2794 0.1778)
							(mid 0.249642 0.249642)
							(end 0.1778 0.2794)
						)
					)
					(width 0)
					(fill yes)
				)
			)
		)
		(pad "2" smd custom
			(at 0 0.4445)
			(size 0.1397 0.1397)
			(layers "B.Cu" "B.Mask" "B.Paste")
			(net "BUF_I2C9_CLKBUF2_SDA")
			(options
				(clearance outline)
				(anchor circle)
			)
			(primitives
				(gr_poly
					(pts
						(arc
							(start -0.1778 0.2794)
							(mid -0.249642 0.249642)
							(end -0.2794 0.1778)
						)
						(arc
							(start -0.2794 -0.1778)
							(mid -0.249642 -0.249642)
							(end -0.1778 -0.2794)
						)
						(arc
							(start 0.1778 -0.2794)
							(mid 0.249642 -0.249642)
							(end 0.2794 -0.1778)
						)
						(arc
							(start 0.2794 0.1778)
							(mid 0.249642 0.249642)
							(end 0.1778 0.2794)
						)
					)
					(width 0)
					(fill yes)
				)
			)
		)
	)
	(footprint ""
		(layer "B.Cu")
		(at 271.018 -6.223 90)
		(property "Reference" "R2965"
			(at 0 0 90)
			(layer "B.SilkS")
			(hide yes)
			(effects
				(font
					(size 1.27 1.27)
				)
				(justify mirror)
			)
		)
		(property "Value" "0R2J-2-GP"
			(at -0.064008 -3.993896 90)
			(unlocked yes)
			(layer "B.Fab")
			(hide yes)
			(effects
				(font
					(size 1.016 1.016)
					(thickness 0.1524)
				)
				(justify mirror)
			)
		)
		(property "Device Type" "R402H16"
			(at -0.064008 -5.517896 90)
			(unlocked yes)
			(layer "B.Fab")
			(hide yes)
			(effects
				(font
					(size 1.016 1.016)
					(thickness 0.1524)
				)
				(justify mirror)
			)
		)
		(duplicate_pad_numbers_are_jumpers no)
		(fp_line
			(start 0.508 -0.9398)
			(end 0.508 0.9398)
			(stroke
				(width 0.1524)
				(type default)
			)
			(layer "B.SilkS")
		)
		(fp_line
			(start -0.508 -0.9398)
			(end 0.508 -0.9398)
			(stroke
				(width 0.1524)
				(type default)
			)
			(layer "B.SilkS")
		)
		(fp_rect
			(start 0.508 0.9398)
			(end -0.508 -0.9398)
			(stroke
				(width 0)
				(type default)
			)
			(fill no)
			(layer "B.CrtYd")
		)
		(fp_rect
			(start 0.508 0.9398)
			(end -0.508 -0.9398)
			(stroke
				(width 0)
				(type default)
			)
			(fill no)
			(layer "B.Fab")
		)
		(pad "1" smd custom
			(at 0 -0.4445 270)
			(size 0.1397 0.1397)
			(layers "B.Cu" "B.Mask" "B.Paste")
			(net "PCIE_REFCLK_H1_P")
			(options
				(clearance outline)
				(anchor circle)
			)
			(primitives
				(gr_poly
					(pts
						(arc
							(start -0.1778 0.2794)
							(mid -0.249642 0.249642)
							(end -0.2794 0.1778)
						)
						(arc
							(start -0.2794 -0.1778)
							(mid -0.249642 -0.249642)
							(end -0.1778 -0.2794)
						)
						(arc
							(start 0.1778 -0.2794)
							(mid 0.249642 -0.249642)
							(end 0.2794 -0.1778)
						)
						(arc
							(start 0.2794 0.1778)
							(mid 0.249642 0.249642)
							(end 0.1778 0.2794)
						)
					)
					(width 0)
					(fill yes)
				)
			)
		)
		(pad "2" smd custom
			(at 0 0.4445 270)
			(size 0.1397 0.1397)
			(layers "B.Cu" "B.Mask" "B.Paste")
			(net "PCIE_REFCLK_H1_P_R")
			(options
				(clearance outline)
				(anchor circle)
			)
			(primitives
				(gr_poly
					(pts
						(arc
							(start -0.1778 0.2794)
							(mid -0.249642 0.249642)
							(end -0.2794 0.1778)
						)
						(arc
							(start -0.2794 -0.1778)
							(mid -0.249642 -0.249642)
							(end -0.1778 -0.2794)
						)
						(arc
							(start 0.1778 -0.2794)
							(mid 0.249642 -0.249642)
							(end 0.2794 -0.1778)
						)
						(arc
							(start 0.2794 0.1778)
							(mid 0.249642 0.249642)
							(end 0.1778 0.2794)
						)
					)
					(width 0)
					(fill yes)
				)
			)
		)
	)
	(footprint ""
		(layer "B.Cu")
		(at 245.1481 -40.9956 90)
		(property "Reference" "C484"
			(at 0 0 90)
			(layer "B.SilkS")
			(hide yes)
			(effects
				(font
					(size 1.27 1.27)
				)
				(justify mirror)
			)
		)
		(property "Value" "SCD1U16V1KX-1-GP"
			(at 2.8321 -1.7399 90)
			(unlocked yes)
			(layer "B.Fab")
			(hide yes)
			(effects
				(font
					(size 1.016 1.016)
					(thickness 0.1524)
				)
				(justify mirror)
			)
		)
		(property "Device Type" "C0201H13"
			(at 2.8321 -3.2639 90)
			(unlocked yes)
			(layer "B.Fab")
			(hide yes)
			(effects
				(font
					(size 1.016 1.016)
					(thickness 0.1524)
				)
				(justify mirror)
			)
		)
		(duplicate_pad_numbers_are_jumpers no)
		(fp_rect
			(start 0.2794 0.6477)
			(end -0.2794 -0.6477)
			(stroke
				(width 0)
				(type default)
			)
			(fill no)
			(layer "B.CrtYd")
		)
		(fp_rect
			(start 0.2794 0.6477)
			(end -0.2794 -0.6477)
			(stroke
				(width 0)
				(type default)
			)
			(fill no)
			(layer "B.Fab")
		)
		(pad "1" smd custom
			(at 0 -0.2794 270)
			(size 0.0762 0.0762)
			(layers "B.Cu" "B.Mask" "B.Paste")
			(net "DUT_VDDO")
			(options
				(clearance outline)
				(anchor circle)
			)
			(primitives
				(gr_poly
					(pts
						(arc
							(start 0.1524 0.127)
							(mid 0.137521 0.162921)
							(end 0.1016 0.1778)
						)
						(arc
							(start -0.1016 0.1778)
							(mid -0.137521 0.162921)
							(end -0.1524 0.127)
						)
						(arc
							(start -0.1524 -0.127)
							(mid -0.137521 -0.162921)
							(end -0.1016 -0.1778)
						)
						(arc
							(start 0.1016 -0.1778)
							(mid 0.137521 -0.162921)
							(end 0.1524 -0.127)
						)
					)
					(width 0)
					(fill yes)
				)
			)
		)
		(pad "2" smd custom
			(at 0 0.2794 270)
			(size 0.0762 0.0762)
			(layers "B.Cu" "B.Mask" "B.Paste")
			(net "GND")
			(options
				(clearance outline)
				(anchor circle)
			)
			(primitives
				(gr_poly
					(pts
						(arc
							(start 0.1524 0.127)
							(mid 0.137521 0.162921)
							(end 0.1016 0.1778)
						)
						(arc
							(start -0.1016 0.1778)
							(mid -0.137521 0.162921)
							(end -0.1524 0.127)
						)
						(arc
							(start -0.1524 -0.127)
							(mid -0.137521 -0.162921)
							(end -0.1016 -0.1778)
						)
						(arc
							(start 0.1016 -0.1778)
							(mid 0.137521 -0.162921)
							(end 0.1524 -0.127)
						)
					)
					(width 0)
					(fill yes)
				)
			)
		)
	)
	(footprint ""
		(layer "B.Cu")
		(at 24.13 -122.0216 -90)
		(property "Reference" "R221"
			(at 0 0 90)
			(layer "B.SilkS")
			(hide yes)
			(effects
				(font
					(size 1.27 1.27)
				)
				(justify mirror)
			)
		)
		(property "Value" "4K7R2F-GP"
			(at -0.064008 -3.993896 270)
			(unlocked yes)
			(layer "B.Fab")
			(hide yes)
			(effects
				(font
					(size 1.016 1.016)
					(thickness 0.1524)
				)
				(justify mirror)
			)
		)
		(property "Device Type" "R402H16"
			(at -0.064008 -5.517896 270)
			(unlocked yes)
			(layer "B.Fab")
			(hide yes)
			(effects
				(font
					(size 1.016 1.016)
					(thickness 0.1524)
				)
				(justify mirror)
			)
		)
		(duplicate_pad_numbers_are_jumpers no)
		(fp_line
			(start -0.508 -0.9398)
			(end 0.508 -0.9398)
			(stroke
				(width 0.1524)
				(type default)
			)
			(layer "B.SilkS")
		)
		(fp_line
			(start 0.508 -0.9398)
			(end 0.508 0.9398)
			(stroke
				(width 0.1524)
				(type default)
			)
			(layer "B.SilkS")
		)
		(fp_rect
			(start 0.508 0.9398)
			(end -0.508 -0.9398)
			(stroke
				(width 0)
				(type default)
			)
			(fill no)
			(layer "B.CrtYd")
		)
		(fp_rect
			(start 0.508 0.9398)
			(end -0.508 -0.9398)
			(stroke
				(width 0)
				(type default)
			)
			(fill no)
			(layer "B.Fab")
		)
		(pad "1" smd custom
			(at 0 -0.4445 90)
			(size 0.1397 0.1397)
			(layers "B.Cu" "B.Mask" "B.Paste")
			(net "FCB_HW_REVISION")
			(options
				(clearance outline)
				(anchor circle)
			)
			(primitives
				(gr_poly
					(pts
						(arc
							(start -0.1778 0.2794)
							(mid -0.249642 0.249642)
							(end -0.2794 0.1778)
						)
						(arc
							(start -0.2794 -0.1778)
							(mid -0.249642 -0.249642)
							(end -0.1778 -0.2794)
						)
						(arc
							(start 0.1778 -0.2794)
							(mid 0.249642 -0.249642)
							(end 0.2794 -0.1778)
						)
						(arc
							(start 0.2794 0.1778)
							(mid 0.249642 0.249642)
							(end 0.1778 0.2794)
						)
					)
					(width 0)
					(fill yes)
				)
			)
		)
		(pad "2" smd custom
			(at 0 0.4445 90)
			(size 0.1397 0.1397)
			(layers "B.Cu" "B.Mask" "B.Paste")
			(net "P3V3_STBY")
			(options
				(clearance outline)
				(anchor circle)
			)
			(primitives
				(gr_poly
					(pts
						(arc
							(start -0.1778 0.2794)
							(mid -0.249642 0.249642)
							(end -0.2794 0.1778)
						)
						(arc
							(start -0.2794 -0.1778)
							(mid -0.249642 -0.249642)
							(end -0.1778 -0.2794)
						)
						(arc
							(start 0.1778 -0.2794)
							(mid 0.249642 -0.249642)
							(end 0.2794 -0.1778)
						)
						(arc
							(start 0.2794 0.1778)
							(mid 0.249642 0.249642)
							(end 0.1778 0.2794)
						)
					)
					(width 0)
					(fill yes)
				)
			)
		)
	)
	(footprint ""
		(layer "B.Cu")
		(at 26.797 -73.533)
		(property "Reference" "PR9008"
			(at 0 0 0)
			(layer "B.SilkS")
			(hide yes)
			(effects
				(font
					(size 1.27 1.27)
				)
				(justify mirror)
			)
		)
		(property "Value" "0R2J-2-GP"
			(at -0.064008 -3.993896 0)
			(unlocked yes)
			(layer "B.Fab")
			(hide yes)
			(effects
				(font
					(size 1.016 1.016)
					(thickness 0.1524)
				)
				(justify mirror)
			)
		)
		(property "Device Type" "R402H16"
			(at -0.064008 -5.517896 0)
			(unlocked yes)
			(layer "B.Fab")
			(hide yes)
			(effects
				(font
					(size 1.016 1.016)
					(thickness 0.1524)
				)
				(justify mirror)
			)
		)
		(duplicate_pad_numbers_are_jumpers no)
		(fp_line
			(start -0.508 -0.9398)
			(end 0.508 -0.9398)
			(stroke
				(width 0.1524)
				(type default)
			)
			(layer "B.SilkS")
		)
		(fp_line
			(start 0.508 -0.9398)
			(end 0.508 0.9398)
			(stroke
				(width 0.1524)
				(type default)
			)
			(layer "B.SilkS")
		)
		(fp_rect
			(start 0.508 0.9398)
			(end -0.508 -0.9398)
			(stroke
				(width 0)
				(type default)
			)
			(fill no)
			(layer "B.CrtYd")
		)
		(fp_rect
			(start 0.508 0.9398)
			(end -0.508 -0.9398)
			(stroke
				(width 0)
				(type default)
			)
			(fill no)
			(layer "B.Fab")
		)
		(pad "1" smd custom
			(at 0 -0.4445 180)
			(size 0.1397 0.1397)
			(layers "B.Cu" "B.Mask" "B.Paste")
			(net "MB0_P12V_PWRGOOD")
			(options
				(clearance outline)
				(anchor circle)
			)
			(primitives
				(gr_poly
					(pts
						(arc
							(start -0.1778 0.2794)
							(mid -0.249642 0.249642)
							(end -0.2794 0.1778)
						)
						(arc
							(start -0.2794 -0.1778)
							(mid -0.249642 -0.249642)
							(end -0.1778 -0.2794)
						)
						(arc
							(start 0.1778 -0.2794)
							(mid 0.249642 -0.249642)
							(end 0.2794 -0.1778)
						)
						(arc
							(start 0.2794 0.1778)
							(mid 0.249642 0.249642)
							(end 0.1778 0.2794)
						)
					)
					(width 0)
					(fill yes)
				)
			)
		)
		(pad "2" smd custom
			(at 0 0.4445 180)
			(size 0.1397 0.1397)
			(layers "B.Cu" "B.Mask" "B.Paste")
			(net "P5V_STBY_EN")
			(options
				(clearance outline)
				(anchor circle)
			)
			(primitives
				(gr_poly
					(pts
						(arc
							(start -0.1778 0.2794)
							(mid -0.249642 0.249642)
							(end -0.2794 0.1778)
						)
						(arc
							(start -0.2794 -0.1778)
							(mid -0.249642 -0.249642)
							(end -0.1778 -0.2794)
						)
						(arc
							(start 0.1778 -0.2794)
							(mid 0.249642 -0.249642)
							(end 0.2794 -0.1778)
						)
						(arc
							(start 0.2794 0.1778)
							(mid 0.249642 0.249642)
							(end 0.1778 0.2794)
						)
					)
					(width 0)
					(fill yes)
				)
			)
		)
	)
	(footprint ""
		(layer "B.Cu")
		(at 13.6144 -126.365 180)
		(property "Reference" "R524"
			(at 0 0 0)
			(layer "B.SilkS")
			(hide yes)
			(effects
				(font
					(size 1.27 1.27)
				)
				(justify mirror)
			)
		)
		(property "Value" "4K7R2F-GP"
			(at -0.064008 -3.993896 180)
			(unlocked yes)
			(layer "B.Fab")
			(hide yes)
			(effects
				(font
					(size 1.016 1.016)
					(thickness 0.1524)
				)
				(justify mirror)
			)
		)
		(property "Device Type" "R402H16"
			(at -0.064008 -5.517896 180)
			(unlocked yes)
			(layer "B.Fab")
			(hide yes)
			(effects
				(font
					(size 1.016 1.016)
					(thickness 0.1524)
				)
				(justify mirror)
			)
		)
		(duplicate_pad_numbers_are_jumpers no)
		(fp_line
			(start 0.508 -0.9398)
			(end 0.508 0.9398)
			(stroke
				(width 0.1524)
				(type default)
			)
			(layer "B.SilkS")
		)
		(fp_line
			(start -0.508 -0.9398)
			(end 0.508 -0.9398)
			(stroke
				(width 0.1524)
				(type default)
			)
			(layer "B.SilkS")
		)
		(fp_rect
			(start 0.508 0.9398)
			(end -0.508 -0.9398)
			(stroke
				(width 0)
				(type default)
			)
			(fill no)
			(layer "B.CrtYd")
		)
		(fp_rect
			(start 0.508 0.9398)
			(end -0.508 -0.9398)
			(stroke
				(width 0)
				(type default)
			)
			(fill no)
			(layer "B.Fab")
		)
		(pad "1" smd custom
			(at 0 -0.4445)
			(size 0.1397 0.1397)
			(layers "B.Cu" "B.Mask" "B.Paste")
			(net "BMC_I2C2_MINI2_SCL_S")
			(options
				(clearance outline)
				(anchor circle)
			)
			(primitives
				(gr_poly
					(pts
						(arc
							(start -0.1778 0.2794)
							(mid -0.249642 0.249642)
							(end -0.2794 0.1778)
						)
						(arc
							(start -0.2794 -0.1778)
							(mid -0.249642 -0.249642)
							(end -0.1778 -0.2794)
						)
						(arc
							(start 0.1778 -0.2794)
							(mid 0.249642 -0.249642)
							(end 0.2794 -0.1778)
						)
						(arc
							(start 0.2794 0.1778)
							(mid 0.249642 0.249642)
							(end 0.1778 0.2794)
						)
					)
					(width 0)
					(fill yes)
				)
			)
		)
		(pad "2" smd custom
			(at 0 0.4445)
			(size 0.1397 0.1397)
			(layers "B.Cu" "B.Mask" "B.Paste")
			(net "P3V3_STBY")
			(options
				(clearance outline)
				(anchor circle)
			)
			(primitives
				(gr_poly
					(pts
						(arc
							(start -0.1778 0.2794)
							(mid -0.249642 0.249642)
							(end -0.2794 0.1778)
						)
						(arc
							(start -0.2794 -0.1778)
							(mid -0.249642 -0.249642)
							(end -0.1778 -0.2794)
						)
						(arc
							(start 0.1778 -0.2794)
							(mid 0.249642 -0.249642)
							(end 0.2794 -0.1778)
						)
						(arc
							(start 0.2794 0.1778)
							(mid 0.249642 0.249642)
							(end 0.1778 0.2794)
						)
					)
					(width 0)
					(fill yes)
				)
			)
		)
	)
	(footprint ""
		(layer "B.Cu")
		(at 259.176266 -6.92658 90)
		(property "Reference" "U15"
			(at 0 0 90)
			(layer "B.SilkS")
			(hide yes)
			(effects
				(font
					(size 1.27 1.27)
				)
				(justify mirror)
			)
		)
		(property "Value" "TMP421AIDCNRG4-GP"
			(at 5.08 -8.5852 90)
			(unlocked yes)
			(layer "B.Fab")
			(hide yes)
			(effects
				(font
					(size 1.016 1.016)
					(thickness 0.1524)
				)
				(justify mirror)
			)
		)
		(property "Device Type" "SOT23-8PH58"
			(at 5.08 -10.1092 90)
			(unlocked yes)
			(layer "B.Fab")
			(hide yes)
			(effects
				(font
					(size 1.016 1.016)
					(thickness 0.1524)
				)
				(justify mirror)
			)
		)
		(duplicate_pad_numbers_are_jumpers no)
		(fp_line
			(start 1.8796 -0.5588)
			(end -1.8796 -0.5588)
			(stroke
				(width 0.1524)
				(type default)
			)
			(layer "B.SilkS")
		)
		(fp_line
			(start -1.8796 -0.5588)
			(end -1.8796 0.5588)
			(stroke
				(width 0.1524)
				(type default)
			)
			(layer "B.SilkS")
		)
		(fp_line
			(start 1.8796 -0.254)
			(end 1.6256 0)
			(stroke
				(width 0.1524)
				(type default)
			)
			(layer "B.SilkS")
		)
		(fp_line
			(start 1.6256 0)
			(end 1.8796 0.254)
			(stroke
				(width 0.1524)
				(type default)
			)
			(layer "B.SilkS")
		)
		(fp_line
			(start 1.8796 0.5588)
			(end 1.8796 -0.5588)
			(stroke
				(width 0.1524)
				(type default)
			)
			(layer "B.SilkS")
		)
		(fp_line
			(start 1.7018 0.5588)
			(end 1.7018 2.1082)
			(stroke
				(width 0.508)
				(type default)
			)
			(layer "B.SilkS")
		)
		(fp_line
			(start -1.8796 0.5588)
			(end 1.8796 0.5588)
			(stroke
				(width 0.1524)
				(type default)
			)
			(layer "B.SilkS")
		)
		(fp_poly
			(pts
				(xy 1.15316 0.5588) (xy -1.8796 0.5588) (xy -1.8796 -0.5588) (xy 1.15316 -0.5588)
			)
			(stroke
				(width 0)
				(type default)
			)
			(fill yes)
			(layer "B.SilkS")
		)
		(fp_rect
			(start 1.9558 2.3622)
			(end -1.9558 -2.3622)
			(stroke
				(width 0)
				(type default)
			)
			(fill no)
			(layer "B.CrtYd")
		)
		(fp_poly
			(pts
				(xy 1.9558 -2.3622) (xy -1.9558 -2.3622) (xy -1.9558 2.3622) (xy 1.9558 2.3622)
			)
			(stroke
				(width 0)
				(type default)
			)
			(fill no)
			(layer "B.Fab")
		)
		(pad "1" smd rect
			(at 0.97536 1.3462 270)
			(size 0.3556 1.016)
			(layers "B.Cu" "B.Mask" "B.Paste")
			(net "TEMP_SENSOR_DXP")
		)
		(pad "2" smd rect
			(at 0.32512 1.3462 270)
			(size 0.3556 1.016)
			(layers "B.Cu" "B.Mask" "B.Paste")
			(net "TEMP_SENSOR_DXN")
		)
		(pad "3" smd rect
			(at -0.32512 1.3462 270)
			(size 0.3556 1.016)
			(layers "B.Cu" "B.Mask" "B.Paste")
			(net "TEMP_1_A1")
		)
		(pad "4" smd rect
			(at -0.97409 1.3462 270)
			(size 0.3556 1.016)
			(layers "B.Cu" "B.Mask" "B.Paste")
			(net "TEMP_1_A0")
		)
		(pad "5" smd rect
			(at -0.97409 -1.3462 270)
			(size 0.3556 1.016)
			(layers "B.Cu" "B.Mask" "B.Paste")
			(net "GND")
		)
		(pad "6" smd rect
			(at -0.32512 -1.3462 270)
			(size 0.3556 1.016)
			(layers "B.Cu" "B.Mask" "B.Paste")
			(net "TEMP_1_SDA")
		)
		(pad "7" smd rect
			(at 0.32512 -1.3462 270)
			(size 0.3556 1.016)
			(layers "B.Cu" "B.Mask" "B.Paste")
			(net "TEMP_1_SCL")
		)
		(pad "8" smd rect
			(at 0.97536 -1.3462 270)
			(size 0.3556 1.016)
			(layers "B.Cu" "B.Mask" "B.Paste")
			(net "P3V3_STBY")
		)
	)
	(footprint ""
		(layer "B.Cu")
		(at 178.0794 -66.167)
		(property "Reference" "PG23"
			(at 0 0 0)
			(layer "B.SilkS")
			(hide yes)
			(effects
				(font
					(size 1.27 1.27)
				)
				(justify mirror)
			)
		)
		(property "Value" "GAP-CLOSE-PWR-3-GP"
			(at -0.0254 -6.5786 0)
			(unlocked yes)
			(layer "B.Fab")
			(hide yes)
			(effects
				(font
					(size 1.016 1.016)
					(thickness 0.1524)
				)
				(justify mirror)
			)
		)
		(property "Device Type" "GAP-CLOSE-PWR-3"
			(at -0.0254 -8.255 0)
			(unlocked yes)
			(layer "B.Fab")
			(hide yes)
			(effects
				(font
					(size 1.016 1.016)
					(thickness 0.1524)
				)
				(justify mirror)
			)
		)
		(duplicate_pad_numbers_are_jumpers no)
		(fp_rect
			(start 0.7112 0.4572)
			(end -0.7112 -0.4572)
			(stroke
				(width 0)
				(type default)
			)
			(fill no)
			(layer "B.CrtYd")
		)
		(fp_poly
			(pts
				(xy 0.7112 -0.4572) (xy -0.7112 -0.4572) (xy -0.7112 0.4572) (xy 0.7112 0.4572)
			)
			(stroke
				(width 0)
				(type default)
			)
			(fill no)
			(layer "B.Fab")
		)
		(pad "1" smd rect
			(at 0.3048 0 180)
			(size 0.6604 0.762)
			(layers "B.Cu" "B.Mask" "B.Paste")
			(net "DUT_AVD_PCIE")
		)
		(pad "2" smd rect
			(at -0.3048 0 180)
			(size 0.6604 0.762)
			(layers "B.Cu" "B.Mask" "B.Paste")
			(net "P0V9")
		)
	)
	(footprint ""
		(layer "B.Cu")
		(at 232.6005 -34.0106 180)
		(property "Reference" "TP198"
			(at 0 0 0)
			(layer "B.SilkS")
			(hide yes)
			(effects
				(font
					(size 1.27 1.27)
				)
				(justify mirror)
			)
		)
		(property "Value" "TPAD28-2-GP"
			(at 0.0127 -1.6637 180)
			(unlocked yes)
			(layer "B.Fab")
			(hide yes)
			(effects
				(font
					(size 1.016 1.016)
					(thickness 0.1524)
				)
				(justify mirror)
			)
		)
		(property "Device Type" "TPAD28"
			(at 0.0127 -3.1877 180)
			(unlocked yes)
			(layer "B.Fab")
			(hide yes)
			(effects
				(font
					(size 1.016 1.016)
					(thickness 0.1524)
				)
				(justify mirror)
			)
		)
		(duplicate_pad_numbers_are_jumpers no)
		(fp_poly
			(pts
				(arc
					(start -0.3556 0)
					(mid 0.3556 0)
					(end -0.3556 0)
				)
			)
			(stroke
				(width 0)
				(type default)
			)
			(fill no)
			(layer "B.CrtYd")
		)
		(fp_poly
			(pts
				(arc
					(start -0.6096 0)
					(mid 0.6096 0)
					(end -0.6096 0)
				)
			)
			(stroke
				(width 0)
				(type default)
			)
			(fill no)
			(layer "B.Fab")
		)
		(pad "1" smd circle
			(at 0 0)
			(size 0.7112 0.7112)
			(layers "B.Cu" "B.Mask" "B.Paste")
			(net "RMII_TXD_0")
		)
	)
	(footprint ""
		(layer "B.Cu")
		(at 124.37872 -33.47847 180)
		(property "Reference" "C129"
			(at 0 0 0)
			(layer "B.SilkS")
			(hide yes)
			(effects
				(font
					(size 1.27 1.27)
				)
				(justify mirror)
			)
		)
		(property "Value" "SCD1U10V2KX-5GP"
			(at -1.1811 -2.7051 180)
			(unlocked yes)
			(layer "B.Fab")
			(hide yes)
			(effects
				(font
					(size 1.016 1.016)
					(thickness 0.1524)
				)
				(justify mirror)
			)
		)
		(property "Device Type" "C402H22"
			(at -1.1811 -4.2291 180)
			(unlocked yes)
			(layer "B.Fab")
			(hide yes)
			(effects
				(font
					(size 1.016 1.016)
					(thickness 0.1524)
				)
				(justify mirror)
			)
		)
		(duplicate_pad_numbers_are_jumpers no)
		(fp_rect
			(start 0.4318 0.9525)
			(end -0.4318 -0.9525)
			(stroke
				(width 0)
				(type default)
			)
			(fill no)
			(layer "B.CrtYd")
		)
		(fp_rect
			(start 0.4318 0.9525)
			(end -0.4318 -0.9525)
			(stroke
				(width 0)
				(type default)
			)
			(fill no)
			(layer "B.Fab")
		)
		(pad "1" smd custom
			(at 0 -0.4445)
			(size 0.1524 0.1524)
			(layers "B.Cu" "B.Mask" "B.Paste")
			(net "GND")
			(options
				(clearance outline)
				(anchor circle)
			)
			(primitives
				(gr_poly
					(pts
						(arc
							(start 0.3048 0.2032)
							(mid 0.275042 0.275042)
							(end 0.2032 0.3048)
						)
						(arc
							(start -0.2032 0.3048)
							(mid -0.275042 0.275042)
							(end -0.3048 0.2032)
						)
						(arc
							(start -0.3048 -0.2032)
							(mid -0.275042 -0.275042)
							(end -0.2032 -0.3048)
						)
						(arc
							(start 0.2032 -0.3048)
							(mid 0.275042 -0.275042)
							(end 0.3048 -0.2032)
						)
					)
					(width 0)
					(fill yes)
				)
			)
		)
		(pad "2" smd custom
			(at 0 0.4445)
			(size 0.1524 0.1524)
			(layers "B.Cu" "B.Mask" "B.Paste")
			(net "P3V3_STBY")
			(options
				(clearance outline)
				(anchor circle)
			)
			(primitives
				(gr_poly
					(pts
						(arc
							(start 0.3048 0.2032)
							(mid 0.275042 0.275042)
							(end 0.2032 0.3048)
						)
						(arc
							(start -0.2032 0.3048)
							(mid -0.275042 0.275042)
							(end -0.3048 0.2032)
						)
						(arc
							(start -0.3048 -0.2032)
							(mid -0.275042 -0.275042)
							(end -0.2032 -0.3048)
						)
						(arc
							(start 0.2032 -0.3048)
							(mid 0.275042 -0.275042)
							(end 0.3048 -0.2032)
						)
					)
					(width 0)
					(fill yes)
				)
			)
		)
	)
	(footprint ""
		(layer "B.Cu")
		(at 52.343304 -51.5874)
		(property "Reference" "R649"
			(at 0 0 0)
			(layer "B.SilkS")
			(hide yes)
			(effects
				(font
					(size 1.27 1.27)
				)
				(justify mirror)
			)
		)
		(property "Value" "0R2J-2-GP"
			(at -0.064008 -3.993896 0)
			(unlocked yes)
			(layer "B.Fab")
			(hide yes)
			(effects
				(font
					(size 1.016 1.016)
					(thickness 0.1524)
				)
				(justify mirror)
			)
		)
		(property "Device Type" "R402H16"
			(at -0.064008 -5.517896 0)
			(unlocked yes)
			(layer "B.Fab")
			(hide yes)
			(effects
				(font
					(size 1.016 1.016)
					(thickness 0.1524)
				)
				(justify mirror)
			)
		)
		(duplicate_pad_numbers_are_jumpers no)
		(fp_line
			(start -0.508 -0.9398)
			(end 0.508 -0.9398)
			(stroke
				(width 0.1524)
				(type default)
			)
			(layer "B.SilkS")
		)
		(fp_line
			(start 0.508 -0.9398)
			(end 0.508 0.9398)
			(stroke
				(width 0.1524)
				(type default)
			)
			(layer "B.SilkS")
		)
		(fp_rect
			(start 0.508 0.9398)
			(end -0.508 -0.9398)
			(stroke
				(width 0)
				(type default)
			)
			(fill no)
			(layer "B.CrtYd")
		)
		(fp_rect
			(start 0.508 0.9398)
			(end -0.508 -0.9398)
			(stroke
				(width 0)
				(type default)
			)
			(fill no)
			(layer "B.Fab")
		)
		(pad "1" smd custom
			(at 0 -0.4445 180)
			(size 0.1397 0.1397)
			(layers "B.Cu" "B.Mask" "B.Paste")
			(net "USB_P2_DN")
			(options
				(clearance outline)
				(anchor circle)
			)
			(primitives
				(gr_poly
					(pts
						(arc
							(start -0.1778 0.2794)
							(mid -0.249642 0.249642)
							(end -0.2794 0.1778)
						)
						(arc
							(start -0.2794 -0.1778)
							(mid -0.249642 -0.249642)
							(end -0.1778 -0.2794)
						)
						(arc
							(start 0.1778 -0.2794)
							(mid 0.249642 -0.249642)
							(end 0.2794 -0.1778)
						)
						(arc
							(start 0.2794 0.1778)
							(mid 0.249642 0.249642)
							(end 0.1778 0.2794)
						)
					)
					(width 0)
					(fill yes)
				)
			)
		)
		(pad "2" smd custom
			(at 0 0.4445 180)
			(size 0.1397 0.1397)
			(layers "B.Cu" "B.Mask" "B.Paste")
			(net "USB_DN_R")
			(options
				(clearance outline)
				(anchor circle)
			)
			(primitives
				(gr_poly
					(pts
						(arc
							(start -0.1778 0.2794)
							(mid -0.249642 0.249642)
							(end -0.2794 0.1778)
						)
						(arc
							(start -0.2794 -0.1778)
							(mid -0.249642 -0.249642)
							(end -0.1778 -0.2794)
						)
						(arc
							(start 0.1778 -0.2794)
							(mid 0.249642 -0.249642)
							(end 0.2794 -0.1778)
						)
						(arc
							(start 0.2794 0.1778)
							(mid 0.249642 0.249642)
							(end 0.1778 0.2794)
						)
					)
					(width 0)
					(fill yes)
				)
			)
		)
	)
	(footprint ""
		(layer "B.Cu")
		(at 227.6856 -37.9984 -90)
		(property "Reference" "C570"
			(at 0 0 90)
			(layer "B.SilkS")
			(hide yes)
			(effects
				(font
					(size 1.27 1.27)
				)
				(justify mirror)
			)
		)
		(property "Value" "SCD1U16V1KX-1-GP"
			(at 2.8321 -1.7399 270)
			(unlocked yes)
			(layer "B.Fab")
			(hide yes)
			(effects
				(font
					(size 1.016 1.016)
					(thickness 0.1524)
				)
				(justify mirror)
			)
		)
		(property "Device Type" "C0201H13"
			(at 2.8321 -3.2639 270)
			(unlocked yes)
			(layer "B.Fab")
			(hide yes)
			(effects
				(font
					(size 1.016 1.016)
					(thickness 0.1524)
				)
				(justify mirror)
			)
		)
		(duplicate_pad_numbers_are_jumpers no)
		(fp_rect
			(start 0.2794 0.6477)
			(end -0.2794 -0.6477)
			(stroke
				(width 0)
				(type default)
			)
			(fill no)
			(layer "B.CrtYd")
		)
		(fp_rect
			(start 0.2794 0.6477)
			(end -0.2794 -0.6477)
			(stroke
				(width 0)
				(type default)
			)
			(fill no)
			(layer "B.Fab")
		)
		(pad "1" smd custom
			(at 0 -0.2794 90)
			(size 0.0762 0.0762)
			(layers "B.Cu" "B.Mask" "B.Paste")
			(net "DUT_AVD_PCIE")
			(options
				(clearance outline)
				(anchor circle)
			)
			(primitives
				(gr_poly
					(pts
						(arc
							(start 0.1524 0.127)
							(mid 0.137521 0.162921)
							(end 0.1016 0.1778)
						)
						(arc
							(start -0.1016 0.1778)
							(mid -0.137521 0.162921)
							(end -0.1524 0.127)
						)
						(arc
							(start -0.1524 -0.127)
							(mid -0.137521 -0.162921)
							(end -0.1016 -0.1778)
						)
						(arc
							(start 0.1016 -0.1778)
							(mid 0.137521 -0.162921)
							(end 0.1524 -0.127)
						)
					)
					(width 0)
					(fill yes)
				)
			)
		)
		(pad "2" smd custom
			(at 0 0.2794 90)
			(size 0.0762 0.0762)
			(layers "B.Cu" "B.Mask" "B.Paste")
			(net "GND")
			(options
				(clearance outline)
				(anchor circle)
			)
			(primitives
				(gr_poly
					(pts
						(arc
							(start 0.1524 0.127)
							(mid 0.137521 0.162921)
							(end 0.1016 0.1778)
						)
						(arc
							(start -0.1016 0.1778)
							(mid -0.137521 0.162921)
							(end -0.1524 0.127)
						)
						(arc
							(start -0.1524 -0.127)
							(mid -0.137521 -0.162921)
							(end -0.1016 -0.1778)
						)
						(arc
							(start 0.1016 -0.1778)
							(mid 0.137521 -0.162921)
							(end 0.1524 -0.127)
						)
					)
					(width 0)
					(fill yes)
				)
			)
		)
	)
	(footprint ""
		(layer "B.Cu")
		(at 228.6254 -49.001172 90)
		(property "Reference" "C493"
			(at 0 0 90)
			(layer "B.SilkS")
			(hide yes)
			(effects
				(font
					(size 1.27 1.27)
				)
				(justify mirror)
			)
		)
		(property "Value" "SCD1U16V1KX-1-GP"
			(at 2.8321 -1.7399 90)
			(unlocked yes)
			(layer "B.Fab")
			(hide yes)
			(effects
				(font
					(size 1.016 1.016)
					(thickness 0.1524)
				)
				(justify mirror)
			)
		)
		(property "Device Type" "C0201H13"
			(at 2.8321 -3.2639 90)
			(unlocked yes)
			(layer "B.Fab")
			(hide yes)
			(effects
				(font
					(size 1.016 1.016)
					(thickness 0.1524)
				)
				(justify mirror)
			)
		)
		(duplicate_pad_numbers_are_jumpers no)
		(fp_rect
			(start 0.2794 0.6477)
			(end -0.2794 -0.6477)
			(stroke
				(width 0)
				(type default)
			)
			(fill no)
			(layer "B.CrtYd")
		)
		(fp_rect
			(start 0.2794 0.6477)
			(end -0.2794 -0.6477)
			(stroke
				(width 0)
				(type default)
			)
			(fill no)
			(layer "B.Fab")
		)
		(pad "1" smd custom
			(at 0 -0.2794 270)
			(size 0.0762 0.0762)
			(layers "B.Cu" "B.Mask" "B.Paste")
			(net "DUT_AVD_PCIE")
			(options
				(clearance outline)
				(anchor circle)
			)
			(primitives
				(gr_poly
					(pts
						(arc
							(start 0.1524 0.127)
							(mid 0.137521 0.162921)
							(end 0.1016 0.1778)
						)
						(arc
							(start -0.1016 0.1778)
							(mid -0.137521 0.162921)
							(end -0.1524 0.127)
						)
						(arc
							(start -0.1524 -0.127)
							(mid -0.137521 -0.162921)
							(end -0.1016 -0.1778)
						)
						(arc
							(start 0.1016 -0.1778)
							(mid 0.137521 -0.162921)
							(end 0.1524 -0.127)
						)
					)
					(width 0)
					(fill yes)
				)
			)
		)
		(pad "2" smd custom
			(at 0 0.2794 270)
			(size 0.0762 0.0762)
			(layers "B.Cu" "B.Mask" "B.Paste")
			(net "GND")
			(options
				(clearance outline)
				(anchor circle)
			)
			(primitives
				(gr_poly
					(pts
						(arc
							(start 0.1524 0.127)
							(mid 0.137521 0.162921)
							(end 0.1016 0.1778)
						)
						(arc
							(start -0.1016 0.1778)
							(mid -0.137521 0.162921)
							(end -0.1524 0.127)
						)
						(arc
							(start -0.1524 -0.127)
							(mid -0.137521 -0.162921)
							(end -0.1016 -0.1778)
						)
						(arc
							(start 0.1016 -0.1778)
							(mid 0.137521 -0.162921)
							(end 0.1524 -0.127)
						)
					)
					(width 0)
					(fill yes)
				)
			)
		)
	)
	(footprint ""
		(layer "B.Cu")
		(at 231.394 -23.241 180)
		(property "Reference" "R790"
			(at 0 0 0)
			(layer "B.SilkS")
			(hide yes)
			(effects
				(font
					(size 1.27 1.27)
				)
				(justify mirror)
			)
		)
		(property "Value" "4K7R2F-GP"
			(at -0.064008 -3.993896 180)
			(unlocked yes)
			(layer "B.Fab")
			(hide yes)
			(effects
				(font
					(size 1.016 1.016)
					(thickness 0.1524)
				)
				(justify mirror)
			)
		)
		(property "Device Type" "R402H16"
			(at -0.064008 -5.517896 180)
			(unlocked yes)
			(layer "B.Fab")
			(hide yes)
			(effects
				(font
					(size 1.016 1.016)
					(thickness 0.1524)
				)
				(justify mirror)
			)
		)
		(duplicate_pad_numbers_are_jumpers no)
		(fp_line
			(start 0.508 -0.9398)
			(end 0.508 0.9398)
			(stroke
				(width 0.1524)
				(type default)
			)
			(layer "B.SilkS")
		)
		(fp_line
			(start -0.508 -0.9398)
			(end 0.508 -0.9398)
			(stroke
				(width 0.1524)
				(type default)
			)
			(layer "B.SilkS")
		)
		(fp_rect
			(start 0.508 0.9398)
			(end -0.508 -0.9398)
			(stroke
				(width 0)
				(type default)
			)
			(fill no)
			(layer "B.CrtYd")
		)
		(fp_rect
			(start 0.508 0.9398)
			(end -0.508 -0.9398)
			(stroke
				(width 0)
				(type default)
			)
			(fill no)
			(layer "B.Fab")
		)
		(pad "1" smd custom
			(at 0 -0.4445)
			(size 0.1397 0.1397)
			(layers "B.Cu" "B.Mask" "B.Paste")
			(net "BOOTSTRAP10")
			(options
				(clearance outline)
				(anchor circle)
			)
			(primitives
				(gr_poly
					(pts
						(arc
							(start -0.1778 0.2794)
							(mid -0.249642 0.249642)
							(end -0.2794 0.1778)
						)
						(arc
							(start -0.2794 -0.1778)
							(mid -0.249642 -0.249642)
							(end -0.1778 -0.2794)
						)
						(arc
							(start 0.1778 -0.2794)
							(mid 0.249642 -0.249642)
							(end 0.2794 -0.1778)
						)
						(arc
							(start 0.2794 0.1778)
							(mid 0.249642 0.249642)
							(end 0.1778 0.2794)
						)
					)
					(width 0)
					(fill yes)
				)
			)
		)
		(pad "2" smd custom
			(at 0 0.4445)
			(size 0.1397 0.1397)
			(layers "B.Cu" "B.Mask" "B.Paste")
			(net "BOOTSTRAP_R_10")
			(options
				(clearance outline)
				(anchor circle)
			)
			(primitives
				(gr_poly
					(pts
						(arc
							(start -0.1778 0.2794)
							(mid -0.249642 0.249642)
							(end -0.2794 0.1778)
						)
						(arc
							(start -0.2794 -0.1778)
							(mid -0.249642 -0.249642)
							(end -0.1778 -0.2794)
						)
						(arc
							(start 0.1778 -0.2794)
							(mid 0.249642 -0.249642)
							(end 0.2794 -0.1778)
						)
						(arc
							(start 0.2794 0.1778)
							(mid 0.249642 0.249642)
							(end 0.1778 0.2794)
						)
					)
					(width 0)
					(fill yes)
				)
			)
		)
	)
	(footprint ""
		(layer "B.Cu")
		(at 243.59997 -34.99993 -90)
		(property "Reference" "TP262"
			(at 0 0 90)
			(layer "B.SilkS")
			(hide yes)
			(effects
				(font
					(size 1.27 1.27)
				)
				(justify mirror)
			)
		)
		(property "Value" "TPAD28-2-GP"
			(at 0.0127 -1.6637 270)
			(unlocked yes)
			(layer "B.Fab")
			(hide yes)
			(effects
				(font
					(size 1.016 1.016)
					(thickness 0.1524)
				)
				(justify mirror)
			)
		)
		(property "Device Type" "TPAD28"
			(at 0.0127 -3.1877 270)
			(unlocked yes)
			(layer "B.Fab")
			(hide yes)
			(effects
				(font
					(size 1.016 1.016)
					(thickness 0.1524)
				)
				(justify mirror)
			)
		)
		(duplicate_pad_numbers_are_jumpers no)
		(fp_poly
			(pts
				(arc
					(start 0 -0.3556)
					(mid 0 0.3556)
					(end 0 -0.3556)
				)
			)
			(stroke
				(width 0)
				(type default)
			)
			(fill no)
			(layer "B.CrtYd")
		)
		(fp_poly
			(pts
				(arc
					(start 0 -0.6096)
					(mid 0 0.6096)
					(end 0 -0.6096)
				)
			)
			(stroke
				(width 0)
				(type default)
			)
			(fill no)
			(layer "B.Fab")
		)
		(pad "1" smd circle
			(at 0 0 90)
			(size 0.7112 0.7112)
			(layers "B.Cu" "B.Mask" "B.Paste")
			(net "LBI_DATA_4")
		)
	)
	(footprint ""
		(layer "B.Cu")
		(at 237.617 -59.99734 -90)
		(property "Reference" "C526"
			(at 0 0 90)
			(layer "B.SilkS")
			(hide yes)
			(effects
				(font
					(size 1.27 1.27)
				)
				(justify mirror)
			)
		)
		(property "Value" "SCD1U16V1KX-1-GP"
			(at 2.8321 -1.7399 270)
			(unlocked yes)
			(layer "B.Fab")
			(hide yes)
			(effects
				(font
					(size 1.016 1.016)
					(thickness 0.1524)
				)
				(justify mirror)
			)
		)
		(property "Device Type" "C0201H13"
			(at 2.8321 -3.2639 270)
			(unlocked yes)
			(layer "B.Fab")
			(hide yes)
			(effects
				(font
					(size 1.016 1.016)
					(thickness 0.1524)
				)
				(justify mirror)
			)
		)
		(duplicate_pad_numbers_are_jumpers no)
		(fp_rect
			(start 0.2794 0.6477)
			(end -0.2794 -0.6477)
			(stroke
				(width 0)
				(type default)
			)
			(fill no)
			(layer "B.CrtYd")
		)
		(fp_rect
			(start 0.2794 0.6477)
			(end -0.2794 -0.6477)
			(stroke
				(width 0)
				(type default)
			)
			(fill no)
			(layer "B.Fab")
		)
		(pad "1" smd custom
			(at 0 -0.2794 90)
			(size 0.0762 0.0762)
			(layers "B.Cu" "B.Mask" "B.Paste")
			(net "DUT_AVD_TX")
			(options
				(clearance outline)
				(anchor circle)
			)
			(primitives
				(gr_poly
					(pts
						(arc
							(start 0.1524 0.127)
							(mid 0.137521 0.162921)
							(end 0.1016 0.1778)
						)
						(arc
							(start -0.1016 0.1778)
							(mid -0.137521 0.162921)
							(end -0.1524 0.127)
						)
						(arc
							(start -0.1524 -0.127)
							(mid -0.137521 -0.162921)
							(end -0.1016 -0.1778)
						)
						(arc
							(start 0.1016 -0.1778)
							(mid 0.137521 -0.162921)
							(end 0.1524 -0.127)
						)
					)
					(width 0)
					(fill yes)
				)
			)
		)
		(pad "2" smd custom
			(at 0 0.2794 90)
			(size 0.0762 0.0762)
			(layers "B.Cu" "B.Mask" "B.Paste")
			(net "GND")
			(options
				(clearance outline)
				(anchor circle)
			)
			(primitives
				(gr_poly
					(pts
						(arc
							(start 0.1524 0.127)
							(mid 0.137521 0.162921)
							(end 0.1016 0.1778)
						)
						(arc
							(start -0.1016 0.1778)
							(mid -0.137521 0.162921)
							(end -0.1524 0.127)
						)
						(arc
							(start -0.1524 -0.127)
							(mid -0.137521 -0.162921)
							(end -0.1016 -0.1778)
						)
						(arc
							(start 0.1016 -0.1778)
							(mid 0.137521 -0.162921)
							(end 0.1524 -0.127)
						)
					)
					(width 0)
					(fill yes)
				)
			)
		)
	)
	(footprint ""
		(layer "B.Cu")
		(at 243.59997 -36.999926)
		(property "Reference" "TP210"
			(at 0 0 0)
			(layer "B.SilkS")
			(hide yes)
			(effects
				(font
					(size 1.27 1.27)
				)
				(justify mirror)
			)
		)
		(property "Value" "TPAD28-2-GP"
			(at 0.0127 -1.6637 0)
			(unlocked yes)
			(layer "B.Fab")
			(hide yes)
			(effects
				(font
					(size 1.016 1.016)
					(thickness 0.1524)
				)
				(justify mirror)
			)
		)
		(property "Device Type" "TPAD28"
			(at 0.0127 -3.1877 0)
			(unlocked yes)
			(layer "B.Fab")
			(hide yes)
			(effects
				(font
					(size 1.016 1.016)
					(thickness 0.1524)
				)
				(justify mirror)
			)
		)
		(duplicate_pad_numbers_are_jumpers no)
		(fp_poly
			(pts
				(arc
					(start 0.3556 0)
					(mid -0.3556 0)
					(end 0.3556 0)
				)
			)
			(stroke
				(width 0)
				(type default)
			)
			(fill no)
			(layer "B.CrtYd")
		)
		(fp_poly
			(pts
				(arc
					(start 0.6096 0)
					(mid -0.6096 0)
					(end 0.6096 0)
				)
			)
			(stroke
				(width 0)
				(type default)
			)
			(fill no)
			(layer "B.Fab")
		)
		(pad "1" smd circle
			(at 0 0 180)
			(size 0.7112 0.7112)
			(layers "B.Cu" "B.Mask" "B.Paste")
			(net "LBI_DATA_1")
		)
	)
	(footprint ""
		(layer "B.Cu")
		(at 20.955 -140.843 90)
		(property "Reference" "R299"
			(at 0 0 90)
			(layer "B.SilkS")
			(hide yes)
			(effects
				(font
					(size 1.27 1.27)
				)
				(justify mirror)
			)
		)
		(property "Value" "0R2J-2-GP"
			(at -0.064008 -3.993896 90)
			(unlocked yes)
			(layer "B.Fab")
			(hide yes)
			(effects
				(font
					(size 1.016 1.016)
					(thickness 0.1524)
				)
				(justify mirror)
			)
		)
		(property "Device Type" "R402H16"
			(at -0.064008 -5.517896 90)
			(unlocked yes)
			(layer "B.Fab")
			(hide yes)
			(effects
				(font
					(size 1.016 1.016)
					(thickness 0.1524)
				)
				(justify mirror)
			)
		)
		(duplicate_pad_numbers_are_jumpers no)
		(fp_line
			(start 0.508 -0.9398)
			(end 0.508 0.9398)
			(stroke
				(width 0.1524)
				(type default)
			)
			(layer "B.SilkS")
		)
		(fp_line
			(start -0.508 -0.9398)
			(end 0.508 -0.9398)
			(stroke
				(width 0.1524)
				(type default)
			)
			(layer "B.SilkS")
		)
		(fp_rect
			(start 0.508 0.9398)
			(end -0.508 -0.9398)
			(stroke
				(width 0)
				(type default)
			)
			(fill no)
			(layer "B.CrtYd")
		)
		(fp_rect
			(start 0.508 0.9398)
			(end -0.508 -0.9398)
			(stroke
				(width 0)
				(type default)
			)
			(fill no)
			(layer "B.Fab")
		)
		(pad "1" smd custom
			(at 0 -0.4445 270)
			(size 0.1397 0.1397)
			(layers "B.Cu" "B.Mask" "B.Paste")
			(net "FM_BMC_RESET_N")
			(options
				(clearance outline)
				(anchor circle)
			)
			(primitives
				(gr_poly
					(pts
						(arc
							(start -0.1778 0.2794)
							(mid -0.249642 0.249642)
							(end -0.2794 0.1778)
						)
						(arc
							(start -0.2794 -0.1778)
							(mid -0.249642 -0.249642)
							(end -0.1778 -0.2794)
						)
						(arc
							(start 0.1778 -0.2794)
							(mid 0.249642 -0.249642)
							(end 0.2794 -0.1778)
						)
						(arc
							(start 0.2794 0.1778)
							(mid 0.249642 0.249642)
							(end 0.1778 0.2794)
						)
					)
					(width 0)
					(fill yes)
				)
			)
		)
		(pad "2" smd custom
			(at 0 0.4445 270)
			(size 0.1397 0.1397)
			(layers "B.Cu" "B.Mask" "B.Paste")
			(net "BMC0_SRST_N")
			(options
				(clearance outline)
				(anchor circle)
			)
			(primitives
				(gr_poly
					(pts
						(arc
							(start -0.1778 0.2794)
							(mid -0.249642 0.249642)
							(end -0.2794 0.1778)
						)
						(arc
							(start -0.2794 -0.1778)
							(mid -0.249642 -0.249642)
							(end -0.1778 -0.2794)
						)
						(arc
							(start 0.1778 -0.2794)
							(mid 0.249642 -0.249642)
							(end 0.2794 -0.1778)
						)
						(arc
							(start 0.2794 0.1778)
							(mid 0.249642 0.249642)
							(end 0.1778 0.2794)
						)
					)
					(width 0)
					(fill yes)
				)
			)
		)
	)
	(footprint ""
		(layer "B.Cu")
		(at 127.680212 -205.849474)
		(property "Reference" "R3205"
			(at 0 0 0)
			(layer "B.SilkS")
			(hide yes)
			(effects
				(font
					(size 1.27 1.27)
				)
				(justify mirror)
			)
		)
		(property "Value" "0R2J-2-GP"
			(at -0.064008 -3.993896 0)
			(unlocked yes)
			(layer "B.Fab")
			(hide yes)
			(effects
				(font
					(size 1.016 1.016)
					(thickness 0.1524)
				)
				(justify mirror)
			)
		)
		(property "Device Type" "R402H16"
			(at -0.064008 -5.517896 0)
			(unlocked yes)
			(layer "B.Fab")
			(hide yes)
			(effects
				(font
					(size 1.016 1.016)
					(thickness 0.1524)
				)
				(justify mirror)
			)
		)
		(duplicate_pad_numbers_are_jumpers no)
		(fp_line
			(start -0.508 -0.9398)
			(end 0.508 -0.9398)
			(stroke
				(width 0.1524)
				(type default)
			)
			(layer "B.SilkS")
		)
		(fp_line
			(start 0.508 -0.9398)
			(end 0.508 0.9398)
			(stroke
				(width 0.1524)
				(type default)
			)
			(layer "B.SilkS")
		)
		(fp_rect
			(start 0.508 0.9398)
			(end -0.508 -0.9398)
			(stroke
				(width 0)
				(type default)
			)
			(fill no)
			(layer "B.CrtYd")
		)
		(fp_rect
			(start 0.508 0.9398)
			(end -0.508 -0.9398)
			(stroke
				(width 0)
				(type default)
			)
			(fill no)
			(layer "B.Fab")
		)
		(pad "1" smd custom
			(at 0 -0.4445 180)
			(size 0.1397 0.1397)
			(layers "B.Cu" "B.Mask" "B.Paste")
			(net "BMC_SSD_RST#1")
			(options
				(clearance outline)
				(anchor circle)
			)
			(primitives
				(gr_poly
					(pts
						(arc
							(start -0.1778 0.2794)
							(mid -0.249642 0.249642)
							(end -0.2794 0.1778)
						)
						(arc
							(start -0.2794 -0.1778)
							(mid -0.249642 -0.249642)
							(end -0.1778 -0.2794)
						)
						(arc
							(start 0.1778 -0.2794)
							(mid 0.249642 -0.249642)
							(end 0.2794 -0.1778)
						)
						(arc
							(start 0.2794 0.1778)
							(mid 0.249642 0.249642)
							(end 0.1778 0.2794)
						)
					)
					(width 0)
					(fill yes)
				)
			)
		)
		(pad "2" smd custom
			(at 0 0.4445 180)
			(size 0.1397 0.1397)
			(layers "B.Cu" "B.Mask" "B.Paste")
			(net "BMC_SSD_RST#0_A1")
			(options
				(clearance outline)
				(anchor circle)
			)
			(primitives
				(gr_poly
					(pts
						(arc
							(start -0.1778 0.2794)
							(mid -0.249642 0.249642)
							(end -0.2794 0.1778)
						)
						(arc
							(start -0.2794 -0.1778)
							(mid -0.249642 -0.249642)
							(end -0.1778 -0.2794)
						)
						(arc
							(start 0.1778 -0.2794)
							(mid 0.249642 -0.249642)
							(end 0.2794 -0.1778)
						)
						(arc
							(start 0.2794 0.1778)
							(mid 0.249642 0.249642)
							(end 0.1778 0.2794)
						)
					)
					(width 0)
					(fill yes)
				)
			)
		)
	)
	(footprint ""
		(layer "B.Cu")
		(at 74.594212 -192.641474)
		(property "Reference" "R3201"
			(at 0 0 0)
			(layer "B.SilkS")
			(hide yes)
			(effects
				(font
					(size 1.27 1.27)
				)
				(justify mirror)
			)
		)
		(property "Value" "0R2J-2-GP"
			(at -0.064008 -3.993896 0)
			(unlocked yes)
			(layer "B.Fab")
			(hide yes)
			(effects
				(font
					(size 1.016 1.016)
					(thickness 0.1524)
				)
				(justify mirror)
			)
		)
		(property "Device Type" "R402H16"
			(at -0.064008 -5.517896 0)
			(unlocked yes)
			(layer "B.Fab")
			(hide yes)
			(effects
				(font
					(size 1.016 1.016)
					(thickness 0.1524)
				)
				(justify mirror)
			)
		)
		(duplicate_pad_numbers_are_jumpers no)
		(fp_line
			(start -0.508 -0.9398)
			(end 0.508 -0.9398)
			(stroke
				(width 0.1524)
				(type default)
			)
			(layer "B.SilkS")
		)
		(fp_line
			(start 0.508 -0.9398)
			(end 0.508 0.9398)
			(stroke
				(width 0.1524)
				(type default)
			)
			(layer "B.SilkS")
		)
		(fp_rect
			(start 0.508 0.9398)
			(end -0.508 -0.9398)
			(stroke
				(width 0)
				(type default)
			)
			(fill no)
			(layer "B.CrtYd")
		)
		(fp_rect
			(start 0.508 0.9398)
			(end -0.508 -0.9398)
			(stroke
				(width 0)
				(type default)
			)
			(fill no)
			(layer "B.Fab")
		)
		(pad "1" smd custom
			(at 0 -0.4445 180)
			(size 0.1397 0.1397)
			(layers "B.Cu" "B.Mask" "B.Paste")
			(net "SSD_PERST#0")
			(options
				(clearance outline)
				(anchor circle)
			)
			(primitives
				(gr_poly
					(pts
						(arc
							(start -0.1778 0.2794)
							(mid -0.249642 0.249642)
							(end -0.2794 0.1778)
						)
						(arc
							(start -0.2794 -0.1778)
							(mid -0.249642 -0.249642)
							(end -0.1778 -0.2794)
						)
						(arc
							(start 0.1778 -0.2794)
							(mid 0.249642 -0.249642)
							(end 0.2794 -0.1778)
						)
						(arc
							(start 0.2794 0.1778)
							(mid 0.249642 0.249642)
							(end 0.1778 0.2794)
						)
					)
					(width 0)
					(fill yes)
				)
			)
		)
		(pad "2" smd custom
			(at 0 0.4445 180)
			(size 0.1397 0.1397)
			(layers "B.Cu" "B.Mask" "B.Paste")
			(net "SSD_PERST#0_B0")
			(options
				(clearance outline)
				(anchor circle)
			)
			(primitives
				(gr_poly
					(pts
						(arc
							(start -0.1778 0.2794)
							(mid -0.249642 0.249642)
							(end -0.2794 0.1778)
						)
						(arc
							(start -0.2794 -0.1778)
							(mid -0.249642 -0.249642)
							(end -0.1778 -0.2794)
						)
						(arc
							(start 0.1778 -0.2794)
							(mid 0.249642 -0.249642)
							(end 0.2794 -0.1778)
						)
						(arc
							(start 0.2794 0.1778)
							(mid 0.249642 0.249642)
							(end 0.1778 0.2794)
						)
					)
					(width 0)
					(fill yes)
				)
			)
		)
	)
	(footprint ""
		(layer "B.Cu")
		(at 234.595416 -60.1472)
		(property "Reference" "C541"
			(at 0 0 0)
			(layer "B.SilkS")
			(hide yes)
			(effects
				(font
					(size 1.27 1.27)
				)
				(justify mirror)
			)
		)
		(property "Value" "SCD1U16V1KX-1-GP"
			(at 2.8321 -1.7399 0)
			(unlocked yes)
			(layer "B.Fab")
			(hide yes)
			(effects
				(font
					(size 1.016 1.016)
					(thickness 0.1524)
				)
				(justify mirror)
			)
		)
		(property "Device Type" "C0201H13"
			(at 2.8321 -3.2639 0)
			(unlocked yes)
			(layer "B.Fab")
			(hide yes)
			(effects
				(font
					(size 1.016 1.016)
					(thickness 0.1524)
				)
				(justify mirror)
			)
		)
		(duplicate_pad_numbers_are_jumpers no)
		(fp_rect
			(start 0.2794 0.6477)
			(end -0.2794 -0.6477)
			(stroke
				(width 0)
				(type default)
			)
			(fill no)
			(layer "B.CrtYd")
		)
		(fp_rect
			(start 0.2794 0.6477)
			(end -0.2794 -0.6477)
			(stroke
				(width 0)
				(type default)
			)
			(fill no)
			(layer "B.Fab")
		)
		(pad "1" smd custom
			(at 0 -0.2794 180)
			(size 0.0762 0.0762)
			(layers "B.Cu" "B.Mask" "B.Paste")
			(net "DUT_AVD_PCIE")
			(options
				(clearance outline)
				(anchor circle)
			)
			(primitives
				(gr_poly
					(pts
						(arc
							(start 0.1524 0.127)
							(mid 0.137521 0.162921)
							(end 0.1016 0.1778)
						)
						(arc
							(start -0.1016 0.1778)
							(mid -0.137521 0.162921)
							(end -0.1524 0.127)
						)
						(arc
							(start -0.1524 -0.127)
							(mid -0.137521 -0.162921)
							(end -0.1016 -0.1778)
						)
						(arc
							(start 0.1016 -0.1778)
							(mid 0.137521 -0.162921)
							(end 0.1524 -0.127)
						)
					)
					(width 0)
					(fill yes)
				)
			)
		)
		(pad "2" smd custom
			(at 0 0.2794 180)
			(size 0.0762 0.0762)
			(layers "B.Cu" "B.Mask" "B.Paste")
			(net "GND")
			(options
				(clearance outline)
				(anchor circle)
			)
			(primitives
				(gr_poly
					(pts
						(arc
							(start 0.1524 0.127)
							(mid 0.137521 0.162921)
							(end 0.1016 0.1778)
						)
						(arc
							(start -0.1016 0.1778)
							(mid -0.137521 0.162921)
							(end -0.1524 0.127)
						)
						(arc
							(start -0.1524 -0.127)
							(mid -0.137521 -0.162921)
							(end -0.1016 -0.1778)
						)
						(arc
							(start 0.1016 -0.1778)
							(mid 0.137521 -0.162921)
							(end 0.1524 -0.127)
						)
					)
					(width 0)
					(fill yes)
				)
			)
		)
	)
	(footprint ""
		(layer "B.Cu")
		(at 241.6048 -59.99734 90)
		(property "Reference" "C527"
			(at 0 0 90)
			(layer "B.SilkS")
			(hide yes)
			(effects
				(font
					(size 1.27 1.27)
				)
				(justify mirror)
			)
		)
		(property "Value" "SCD1U16V1KX-1-GP"
			(at 2.8321 -1.7399 90)
			(unlocked yes)
			(layer "B.Fab")
			(hide yes)
			(effects
				(font
					(size 1.016 1.016)
					(thickness 0.1524)
				)
				(justify mirror)
			)
		)
		(property "Device Type" "C0201H13"
			(at 2.8321 -3.2639 90)
			(unlocked yes)
			(layer "B.Fab")
			(hide yes)
			(effects
				(font
					(size 1.016 1.016)
					(thickness 0.1524)
				)
				(justify mirror)
			)
		)
		(duplicate_pad_numbers_are_jumpers no)
		(fp_rect
			(start 0.2794 0.6477)
			(end -0.2794 -0.6477)
			(stroke
				(width 0)
				(type default)
			)
			(fill no)
			(layer "B.CrtYd")
		)
		(fp_rect
			(start 0.2794 0.6477)
			(end -0.2794 -0.6477)
			(stroke
				(width 0)
				(type default)
			)
			(fill no)
			(layer "B.Fab")
		)
		(pad "1" smd custom
			(at 0 -0.2794 270)
			(size 0.0762 0.0762)
			(layers "B.Cu" "B.Mask" "B.Paste")
			(net "DUT_AVD_TX")
			(options
				(clearance outline)
				(anchor circle)
			)
			(primitives
				(gr_poly
					(pts
						(arc
							(start 0.1524 0.127)
							(mid 0.137521 0.162921)
							(end 0.1016 0.1778)
						)
						(arc
							(start -0.1016 0.1778)
							(mid -0.137521 0.162921)
							(end -0.1524 0.127)
						)
						(arc
							(start -0.1524 -0.127)
							(mid -0.137521 -0.162921)
							(end -0.1016 -0.1778)
						)
						(arc
							(start 0.1016 -0.1778)
							(mid 0.137521 -0.162921)
							(end 0.1524 -0.127)
						)
					)
					(width 0)
					(fill yes)
				)
			)
		)
		(pad "2" smd custom
			(at 0 0.2794 270)
			(size 0.0762 0.0762)
			(layers "B.Cu" "B.Mask" "B.Paste")
			(net "GND")
			(options
				(clearance outline)
				(anchor circle)
			)
			(primitives
				(gr_poly
					(pts
						(arc
							(start 0.1524 0.127)
							(mid 0.137521 0.162921)
							(end 0.1016 0.1778)
						)
						(arc
							(start -0.1016 0.1778)
							(mid -0.137521 0.162921)
							(end -0.1524 0.127)
						)
						(arc
							(start -0.1524 -0.127)
							(mid -0.137521 -0.162921)
							(end -0.1016 -0.1778)
						)
						(arc
							(start 0.1016 -0.1778)
							(mid 0.137521 -0.162921)
							(end 0.1524 -0.127)
						)
					)
					(width 0)
					(fill yes)
				)
			)
		)
	)
	(footprint ""
		(layer "B.Cu")
		(at 333.4766 -175.7426)
		(property "Reference" "R3215"
			(at 0 0 0)
			(layer "B.SilkS")
			(hide yes)
			(effects
				(font
					(size 1.27 1.27)
				)
				(justify mirror)
			)
		)
		(property "Value" "0R2J-2-GP"
			(at -0.064008 -3.993896 0)
			(unlocked yes)
			(layer "B.Fab")
			(hide yes)
			(effects
				(font
					(size 1.016 1.016)
					(thickness 0.1524)
				)
				(justify mirror)
			)
		)
		(property "Device Type" "R402H16"
			(at -0.064008 -5.517896 0)
			(unlocked yes)
			(layer "B.Fab")
			(hide yes)
			(effects
				(font
					(size 1.016 1.016)
					(thickness 0.1524)
				)
				(justify mirror)
			)
		)
		(duplicate_pad_numbers_are_jumpers no)
		(fp_line
			(start -0.508 -0.9398)
			(end 0.508 -0.9398)
			(stroke
				(width 0.1524)
				(type default)
			)
			(layer "B.SilkS")
		)
		(fp_line
			(start 0.508 -0.9398)
			(end 0.508 0.9398)
			(stroke
				(width 0.1524)
				(type default)
			)
			(layer "B.SilkS")
		)
		(fp_rect
			(start 0.508 0.9398)
			(end -0.508 -0.9398)
			(stroke
				(width 0)
				(type default)
			)
			(fill no)
			(layer "B.CrtYd")
		)
		(fp_rect
			(start 0.508 0.9398)
			(end -0.508 -0.9398)
			(stroke
				(width 0)
				(type default)
			)
			(fill no)
			(layer "B.Fab")
		)
		(pad "1" smd custom
			(at 0 -0.4445 180)
			(size 0.1397 0.1397)
			(layers "B.Cu" "B.Mask" "B.Paste")
			(net "SSD_PERST_Y4")
			(options
				(clearance outline)
				(anchor circle)
			)
			(primitives
				(gr_poly
					(pts
						(arc
							(start -0.1778 0.2794)
							(mid -0.249642 0.249642)
							(end -0.2794 0.1778)
						)
						(arc
							(start -0.2794 -0.1778)
							(mid -0.249642 -0.249642)
							(end -0.1778 -0.2794)
						)
						(arc
							(start 0.1778 -0.2794)
							(mid 0.249642 -0.249642)
							(end 0.2794 -0.1778)
						)
						(arc
							(start 0.2794 0.1778)
							(mid 0.249642 0.249642)
							(end 0.1778 0.2794)
						)
					)
					(width 0)
					(fill yes)
				)
			)
		)
		(pad "2" smd custom
			(at 0 0.4445 180)
			(size 0.1397 0.1397)
			(layers "B.Cu" "B.Mask" "B.Paste")
			(net "SSD_PERST#4_R")
			(options
				(clearance outline)
				(anchor circle)
			)
			(primitives
				(gr_poly
					(pts
						(arc
							(start -0.1778 0.2794)
							(mid -0.249642 0.249642)
							(end -0.2794 0.1778)
						)
						(arc
							(start -0.2794 -0.1778)
							(mid -0.249642 -0.249642)
							(end -0.1778 -0.2794)
						)
						(arc
							(start 0.1778 -0.2794)
							(mid 0.249642 -0.249642)
							(end 0.2794 -0.1778)
						)
						(arc
							(start 0.2794 0.1778)
							(mid 0.249642 0.249642)
							(end 0.1778 0.2794)
						)
					)
					(width 0)
					(fill yes)
				)
			)
		)
	)
	(footprint ""
		(layer "B.Cu")
		(at 239.395 -23.241)
		(property "Reference" "R794"
			(at 0 0 0)
			(layer "B.SilkS")
			(hide yes)
			(effects
				(font
					(size 1.27 1.27)
				)
				(justify mirror)
			)
		)
		(property "Value" "4K7R2F-GP"
			(at -0.064008 -3.993896 0)
			(unlocked yes)
			(layer "B.Fab")
			(hide yes)
			(effects
				(font
					(size 1.016 1.016)
					(thickness 0.1524)
				)
				(justify mirror)
			)
		)
		(property "Device Type" "R402H16"
			(at -0.064008 -5.517896 0)
			(unlocked yes)
			(layer "B.Fab")
			(hide yes)
			(effects
				(font
					(size 1.016 1.016)
					(thickness 0.1524)
				)
				(justify mirror)
			)
		)
		(duplicate_pad_numbers_are_jumpers no)
		(fp_line
			(start -0.508 -0.9398)
			(end 0.508 -0.9398)
			(stroke
				(width 0.1524)
				(type default)
			)
			(layer "B.SilkS")
		)
		(fp_line
			(start 0.508 -0.9398)
			(end 0.508 0.9398)
			(stroke
				(width 0.1524)
				(type default)
			)
			(layer "B.SilkS")
		)
		(fp_rect
			(start 0.508 0.9398)
			(end -0.508 -0.9398)
			(stroke
				(width 0)
				(type default)
			)
			(fill no)
			(layer "B.CrtYd")
		)
		(fp_rect
			(start 0.508 0.9398)
			(end -0.508 -0.9398)
			(stroke
				(width 0)
				(type default)
			)
			(fill no)
			(layer "B.Fab")
		)
		(pad "1" smd custom
			(at 0 -0.4445 180)
			(size 0.1397 0.1397)
			(layers "B.Cu" "B.Mask" "B.Paste")
			(net "GND")
			(options
				(clearance outline)
				(anchor circle)
			)
			(primitives
				(gr_poly
					(pts
						(arc
							(start -0.1778 0.2794)
							(mid -0.249642 0.249642)
							(end -0.2794 0.1778)
						)
						(arc
							(start -0.2794 -0.1778)
							(mid -0.249642 -0.249642)
							(end -0.1778 -0.2794)
						)
						(arc
							(start 0.1778 -0.2794)
							(mid 0.249642 -0.249642)
							(end 0.2794 -0.1778)
						)
						(arc
							(start 0.2794 0.1778)
							(mid 0.249642 0.249642)
							(end 0.1778 0.2794)
						)
					)
					(width 0)
					(fill yes)
				)
			)
		)
		(pad "2" smd custom
			(at 0 0.4445 180)
			(size 0.1397 0.1397)
			(layers "B.Cu" "B.Mask" "B.Paste")
			(net "BOOTSTRAP1")
			(options
				(clearance outline)
				(anchor circle)
			)
			(primitives
				(gr_poly
					(pts
						(arc
							(start -0.1778 0.2794)
							(mid -0.249642 0.249642)
							(end -0.2794 0.1778)
						)
						(arc
							(start -0.2794 -0.1778)
							(mid -0.249642 -0.249642)
							(end -0.1778 -0.2794)
						)
						(arc
							(start 0.1778 -0.2794)
							(mid 0.249642 -0.249642)
							(end 0.2794 -0.1778)
						)
						(arc
							(start 0.2794 0.1778)
							(mid 0.249642 0.249642)
							(end 0.1778 0.2794)
						)
					)
					(width 0)
					(fill yes)
				)
			)
		)
	)
	(footprint ""
		(layer "B.Cu")
		(at 223.393 -23.241 180)
		(property "Reference" "R831"
			(at 0 0 0)
			(layer "B.SilkS")
			(hide yes)
			(effects
				(font
					(size 1.27 1.27)
				)
				(justify mirror)
			)
		)
		(property "Value" "0R2J-2-GP"
			(at -0.064008 -3.993896 180)
			(unlocked yes)
			(layer "B.Fab")
			(hide yes)
			(effects
				(font
					(size 1.016 1.016)
					(thickness 0.1524)
				)
				(justify mirror)
			)
		)
		(property "Device Type" "R402H16"
			(at -0.064008 -5.517896 180)
			(unlocked yes)
			(layer "B.Fab")
			(hide yes)
			(effects
				(font
					(size 1.016 1.016)
					(thickness 0.1524)
				)
				(justify mirror)
			)
		)
		(duplicate_pad_numbers_are_jumpers no)
		(fp_line
			(start 0.508 -0.9398)
			(end 0.508 0.9398)
			(stroke
				(width 0.1524)
				(type default)
			)
			(layer "B.SilkS")
		)
		(fp_line
			(start -0.508 -0.9398)
			(end 0.508 -0.9398)
			(stroke
				(width 0.1524)
				(type default)
			)
			(layer "B.SilkS")
		)
		(fp_rect
			(start 0.508 0.9398)
			(end -0.508 -0.9398)
			(stroke
				(width 0)
				(type default)
			)
			(fill no)
			(layer "B.CrtYd")
		)
		(fp_rect
			(start 0.508 0.9398)
			(end -0.508 -0.9398)
			(stroke
				(width 0)
				(type default)
			)
			(fill no)
			(layer "B.Fab")
		)
		(pad "1" smd custom
			(at 0 -0.4445)
			(size 0.1397 0.1397)
			(layers "B.Cu" "B.Mask" "B.Paste")
			(net "HOST7_RST_N_LS")
			(options
				(clearance outline)
				(anchor circle)
			)
			(primitives
				(gr_poly
					(pts
						(arc
							(start -0.1778 0.2794)
							(mid -0.249642 0.249642)
							(end -0.2794 0.1778)
						)
						(arc
							(start -0.2794 -0.1778)
							(mid -0.249642 -0.249642)
							(end -0.1778 -0.2794)
						)
						(arc
							(start 0.1778 -0.2794)
							(mid 0.249642 -0.249642)
							(end 0.2794 -0.1778)
						)
						(arc
							(start 0.2794 0.1778)
							(mid 0.249642 0.249642)
							(end 0.1778 0.2794)
						)
					)
					(width 0)
					(fill yes)
				)
			)
		)
		(pad "2" smd custom
			(at 0 0.4445)
			(size 0.1397 0.1397)
			(layers "B.Cu" "B.Mask" "B.Paste")
			(net "LBI_ADDR_6_R")
			(options
				(clearance outline)
				(anchor circle)
			)
			(primitives
				(gr_poly
					(pts
						(arc
							(start -0.1778 0.2794)
							(mid -0.249642 0.249642)
							(end -0.2794 0.1778)
						)
						(arc
							(start -0.2794 -0.1778)
							(mid -0.249642 -0.249642)
							(end -0.1778 -0.2794)
						)
						(arc
							(start 0.1778 -0.2794)
							(mid 0.249642 -0.249642)
							(end 0.2794 -0.1778)
						)
						(arc
							(start 0.2794 0.1778)
							(mid 0.249642 0.249642)
							(end 0.1778 0.2794)
						)
					)
					(width 0)
					(fill yes)
				)
			)
		)
	)
	(footprint ""
		(layer "B.Cu")
		(at 70.993 -36.3982 -90)
		(property "Reference" "PR20"
			(at 0 0 90)
			(layer "B.SilkS")
			(hide yes)
			(effects
				(font
					(size 1.27 1.27)
				)
				(justify mirror)
			)
		)
		(property "Value" "0R3J-0-U-GP"
			(at 0.0254 -2.5146 270)
			(unlocked yes)
			(layer "B.Fab")
			(hide yes)
			(effects
				(font
					(size 1.016 1.016)
					(thickness 0.1524)
				)
				(justify mirror)
			)
		)
		(property "Device Type" "R603H22"
			(at 0.0254 -4.0386 270)
			(unlocked yes)
			(layer "B.Fab")
			(hide yes)
			(effects
				(font
					(size 1.016 1.016)
					(thickness 0.1524)
				)
				(justify mirror)
			)
		)
		(duplicate_pad_numbers_are_jumpers no)
		(fp_line
			(start -0.2032 0)
			(end -0.4826 0)
			(stroke
				(width 0.2032)
				(type default)
			)
			(layer "B.SilkS")
		)
		(fp_line
			(start 0.4826 0)
			(end 0.2032 0)
			(stroke
				(width 0.2032)
				(type default)
			)
			(layer "B.SilkS")
		)
		(fp_rect
			(start 0.5842 1.3335)
			(end -0.5842 -1.3335)
			(stroke
				(width 0)
				(type default)
			)
			(fill no)
			(layer "B.CrtYd")
		)
		(fp_rect
			(start 0.5842 1.3335)
			(end -0.5842 -1.3335)
			(stroke
				(width 0)
				(type default)
			)
			(fill no)
			(layer "B.Fab")
		)
		(pad "1" smd custom
			(at 0 -0.762 90)
			(size 0.2159 0.2159)
			(layers "B.Cu" "B.Mask" "B.Paste")
			(net "P3V3_STBY_VBST_RC")
			(options
				(clearance outline)
				(anchor circle)
			)
			(primitives
				(gr_poly
					(pts
						(arc
							(start -0.3302 0.4318)
							(mid -0.402042 0.402042)
							(end -0.4318 0.3302)
						)
						(arc
							(start -0.4318 -0.3302)
							(mid -0.402042 -0.402042)
							(end -0.3302 -0.4318)
						)
						(arc
							(start 0.3302 -0.4318)
							(mid 0.402042 -0.402042)
							(end 0.4318 -0.3302)
						)
						(arc
							(start 0.4318 0.3302)
							(mid 0.402042 0.402042)
							(end 0.3302 0.4318)
						)
					)
					(width 0)
					(fill yes)
				)
			)
		)
		(pad "2" smd custom
			(at 0 0.762 90)
			(size 0.2159 0.2159)
			(layers "B.Cu" "B.Mask" "B.Paste")
			(net "P3V3_STBY_VBST")
			(options
				(clearance outline)
				(anchor circle)
			)
			(primitives
				(gr_poly
					(pts
						(arc
							(start -0.3302 0.4318)
							(mid -0.402042 0.402042)
							(end -0.4318 0.3302)
						)
						(arc
							(start -0.4318 -0.3302)
							(mid -0.402042 -0.402042)
							(end -0.3302 -0.4318)
						)
						(arc
							(start 0.3302 -0.4318)
							(mid 0.402042 -0.402042)
							(end 0.4318 -0.3302)
						)
						(arc
							(start 0.4318 0.3302)
							(mid 0.402042 0.402042)
							(end 0.3302 0.4318)
						)
					)
					(width 0)
					(fill yes)
				)
			)
		)
	)
	(footprint ""
		(layer "B.Cu")
		(at 250.584208 -26.1112 180)
		(property "Reference" "R775"
			(at 0 0 0)
			(layer "B.SilkS")
			(hide yes)
			(effects
				(font
					(size 1.27 1.27)
				)
				(justify mirror)
			)
		)
		(property "Value" "3K3R2F-2-GP"
			(at -0.064008 -3.993896 180)
			(unlocked yes)
			(layer "B.Fab")
			(hide yes)
			(effects
				(font
					(size 1.016 1.016)
					(thickness 0.1524)
				)
				(justify mirror)
			)
		)
		(property "Device Type" "R402H16"
			(at -0.064008 -5.517896 180)
			(unlocked yes)
			(layer "B.Fab")
			(hide yes)
			(effects
				(font
					(size 1.016 1.016)
					(thickness 0.1524)
				)
				(justify mirror)
			)
		)
		(duplicate_pad_numbers_are_jumpers no)
		(fp_line
			(start 0.508 -0.9398)
			(end 0.508 0.9398)
			(stroke
				(width 0.1524)
				(type default)
			)
			(layer "B.SilkS")
		)
		(fp_line
			(start -0.508 -0.9398)
			(end 0.508 -0.9398)
			(stroke
				(width 0.1524)
				(type default)
			)
			(layer "B.SilkS")
		)
		(fp_rect
			(start 0.508 0.9398)
			(end -0.508 -0.9398)
			(stroke
				(width 0)
				(type default)
			)
			(fill no)
			(layer "B.CrtYd")
		)
		(fp_rect
			(start 0.508 0.9398)
			(end -0.508 -0.9398)
			(stroke
				(width 0)
				(type default)
			)
			(fill no)
			(layer "B.Fab")
		)
		(pad "1" smd custom
			(at 0 -0.4445)
			(size 0.1397 0.1397)
			(layers "B.Cu" "B.Mask" "B.Paste")
			(net "P3V3_GPIO")
			(options
				(clearance outline)
				(anchor circle)
			)
			(primitives
				(gr_poly
					(pts
						(arc
							(start -0.1778 0.2794)
							(mid -0.249642 0.249642)
							(end -0.2794 0.1778)
						)
						(arc
							(start -0.2794 -0.1778)
							(mid -0.249642 -0.249642)
							(end -0.1778 -0.2794)
						)
						(arc
							(start 0.1778 -0.2794)
							(mid 0.249642 -0.249642)
							(end 0.2794 -0.1778)
						)
						(arc
							(start 0.2794 0.1778)
							(mid 0.249642 0.249642)
							(end 0.1778 0.2794)
						)
					)
					(width 0)
					(fill yes)
				)
			)
		)
		(pad "2" smd custom
			(at 0 0.4445)
			(size 0.1397 0.1397)
			(layers "B.Cu" "B.Mask" "B.Paste")
			(net "TWI_SDA2")
			(options
				(clearance outline)
				(anchor circle)
			)
			(primitives
				(gr_poly
					(pts
						(arc
							(start -0.1778 0.2794)
							(mid -0.249642 0.249642)
							(end -0.2794 0.1778)
						)
						(arc
							(start -0.2794 -0.1778)
							(mid -0.249642 -0.249642)
							(end -0.1778 -0.2794)
						)
						(arc
							(start 0.1778 -0.2794)
							(mid 0.249642 -0.249642)
							(end 0.2794 -0.1778)
						)
						(arc
							(start 0.2794 0.1778)
							(mid 0.249642 0.249642)
							(end 0.1778 0.2794)
						)
					)
					(width 0)
					(fill yes)
				)
			)
		)
	)
	(footprint ""
		(layer "B.Cu")
		(at 40.64 -201.549 180)
		(property "Reference" "R881"
			(at 0 0 0)
			(layer "B.SilkS")
			(hide yes)
			(effects
				(font
					(size 1.27 1.27)
				)
				(justify mirror)
			)
		)
		(property "Value" "0R2J-2-GP"
			(at -0.064008 -3.993896 180)
			(unlocked yes)
			(layer "B.Fab")
			(hide yes)
			(effects
				(font
					(size 1.016 1.016)
					(thickness 0.1524)
				)
				(justify mirror)
			)
		)
		(property "Device Type" "R402H16"
			(at -0.064008 -5.517896 180)
			(unlocked yes)
			(layer "B.Fab")
			(hide yes)
			(effects
				(font
					(size 1.016 1.016)
					(thickness 0.1524)
				)
				(justify mirror)
			)
		)
		(duplicate_pad_numbers_are_jumpers no)
		(fp_line
			(start 0.508 -0.9398)
			(end 0.508 0.9398)
			(stroke
				(width 0.1524)
				(type default)
			)
			(layer "B.SilkS")
		)
		(fp_line
			(start -0.508 -0.9398)
			(end 0.508 -0.9398)
			(stroke
				(width 0.1524)
				(type default)
			)
			(layer "B.SilkS")
		)
		(fp_rect
			(start 0.508 0.9398)
			(end -0.508 -0.9398)
			(stroke
				(width 0)
				(type default)
			)
			(fill no)
			(layer "B.CrtYd")
		)
		(fp_rect
			(start 0.508 0.9398)
			(end -0.508 -0.9398)
			(stroke
				(width 0)
				(type default)
			)
			(fill no)
			(layer "B.Fab")
		)
		(pad "1" smd custom
			(at 0 -0.4445)
			(size 0.1397 0.1397)
			(layers "B.Cu" "B.Mask" "B.Paste")
			(net "BMC_I2C6_C_FCB_SDA")
			(options
				(clearance outline)
				(anchor circle)
			)
			(primitives
				(gr_poly
					(pts
						(arc
							(start -0.1778 0.2794)
							(mid -0.249642 0.249642)
							(end -0.2794 0.1778)
						)
						(arc
							(start -0.2794 -0.1778)
							(mid -0.249642 -0.249642)
							(end -0.1778 -0.2794)
						)
						(arc
							(start 0.1778 -0.2794)
							(mid 0.249642 -0.249642)
							(end 0.2794 -0.1778)
						)
						(arc
							(start 0.2794 0.1778)
							(mid 0.249642 0.249642)
							(end 0.1778 0.2794)
						)
					)
					(width 0)
					(fill yes)
				)
			)
		)
		(pad "2" smd custom
			(at 0 0.4445)
			(size 0.1397 0.1397)
			(layers "B.Cu" "B.Mask" "B.Paste")
			(net "BUF_I2C6_C_FCB_SDA")
			(options
				(clearance outline)
				(anchor circle)
			)
			(primitives
				(gr_poly
					(pts
						(arc
							(start -0.1778 0.2794)
							(mid -0.249642 0.249642)
							(end -0.2794 0.1778)
						)
						(arc
							(start -0.2794 -0.1778)
							(mid -0.249642 -0.249642)
							(end -0.1778 -0.2794)
						)
						(arc
							(start 0.1778 -0.2794)
							(mid 0.249642 -0.249642)
							(end 0.2794 -0.1778)
						)
						(arc
							(start 0.2794 0.1778)
							(mid 0.249642 0.249642)
							(end 0.1778 0.2794)
						)
					)
					(width 0)
					(fill yes)
				)
			)
		)
	)
	(footprint ""
		(layer "B.Cu")
		(at 17.526 -135.89 90)
		(property "Reference" "R1202"
			(at 0 0 90)
			(layer "B.SilkS")
			(hide yes)
			(effects
				(font
					(size 1.27 1.27)
				)
				(justify mirror)
			)
		)
		(property "Value" "274R2F-GP"
			(at -0.064008 -3.993896 90)
			(unlocked yes)
			(layer "B.Fab")
			(hide yes)
			(effects
				(font
					(size 1.016 1.016)
					(thickness 0.1524)
				)
				(justify mirror)
			)
		)
		(property "Device Type" "R402H16"
			(at -0.064008 -5.517896 90)
			(unlocked yes)
			(layer "B.Fab")
			(hide yes)
			(effects
				(font
					(size 1.016 1.016)
					(thickness 0.1524)
				)
				(justify mirror)
			)
		)
		(duplicate_pad_numbers_are_jumpers no)
		(fp_line
			(start 0.508 -0.9398)
			(end 0.508 0.9398)
			(stroke
				(width 0.1524)
				(type default)
			)
			(layer "B.SilkS")
		)
		(fp_line
			(start -0.508 -0.9398)
			(end 0.508 -0.9398)
			(stroke
				(width 0.1524)
				(type default)
			)
			(layer "B.SilkS")
		)
		(fp_rect
			(start 0.508 0.9398)
			(end -0.508 -0.9398)
			(stroke
				(width 0)
				(type default)
			)
			(fill no)
			(layer "B.CrtYd")
		)
		(fp_rect
			(start 0.508 0.9398)
			(end -0.508 -0.9398)
			(stroke
				(width 0)
				(type default)
			)
			(fill no)
			(layer "B.Fab")
		)
		(pad "1" smd custom
			(at 0 -0.4445 270)
			(size 0.1397 0.1397)
			(layers "B.Cu" "B.Mask" "B.Paste")
			(net "GND")
			(options
				(clearance outline)
				(anchor circle)
			)
			(primitives
				(gr_poly
					(pts
						(arc
							(start -0.1778 0.2794)
							(mid -0.249642 0.249642)
							(end -0.2794 0.1778)
						)
						(arc
							(start -0.2794 -0.1778)
							(mid -0.249642 -0.249642)
							(end -0.1778 -0.2794)
						)
						(arc
							(start 0.1778 -0.2794)
							(mid 0.249642 -0.249642)
							(end 0.2794 -0.1778)
						)
						(arc
							(start 0.2794 0.1778)
							(mid 0.249642 0.249642)
							(end 0.1778 0.2794)
						)
					)
					(width 0)
					(fill yes)
				)
			)
		)
		(pad "2" smd custom
			(at 0 0.4445 270)
			(size 0.1397 0.1397)
			(layers "B.Cu" "B.Mask" "B.Paste")
			(net "BMC_MIOZ")
			(options
				(clearance outline)
				(anchor circle)
			)
			(primitives
				(gr_poly
					(pts
						(arc
							(start -0.1778 0.2794)
							(mid -0.249642 0.249642)
							(end -0.2794 0.1778)
						)
						(arc
							(start -0.2794 -0.1778)
							(mid -0.249642 -0.249642)
							(end -0.1778 -0.2794)
						)
						(arc
							(start 0.1778 -0.2794)
							(mid 0.249642 -0.249642)
							(end 0.2794 -0.1778)
						)
						(arc
							(start 0.2794 0.1778)
							(mid 0.249642 0.249642)
							(end 0.1778 0.2794)
						)
					)
					(width 0)
					(fill yes)
				)
			)
		)
	)
	(footprint ""
		(layer "B.Cu")
		(at 129.2098 -200.3298 -90)
		(property "Reference" "R3206"
			(at 0 0 90)
			(layer "B.SilkS")
			(hide yes)
			(effects
				(font
					(size 1.27 1.27)
				)
				(justify mirror)
			)
		)
		(property "Value" "0R2J-2-GP"
			(at -0.064008 -3.993896 270)
			(unlocked yes)
			(layer "B.Fab")
			(hide yes)
			(effects
				(font
					(size 1.016 1.016)
					(thickness 0.1524)
				)
				(justify mirror)
			)
		)
		(property "Device Type" "R402H16"
			(at -0.064008 -5.517896 270)
			(unlocked yes)
			(layer "B.Fab")
			(hide yes)
			(effects
				(font
					(size 1.016 1.016)
					(thickness 0.1524)
				)
				(justify mirror)
			)
		)
		(duplicate_pad_numbers_are_jumpers no)
		(fp_line
			(start -0.508 -0.9398)
			(end 0.508 -0.9398)
			(stroke
				(width 0.1524)
				(type default)
			)
			(layer "B.SilkS")
		)
		(fp_line
			(start 0.508 -0.9398)
			(end 0.508 0.9398)
			(stroke
				(width 0.1524)
				(type default)
			)
			(layer "B.SilkS")
		)
		(fp_rect
			(start 0.508 0.9398)
			(end -0.508 -0.9398)
			(stroke
				(width 0)
				(type default)
			)
			(fill no)
			(layer "B.CrtYd")
		)
		(fp_rect
			(start 0.508 0.9398)
			(end -0.508 -0.9398)
			(stroke
				(width 0)
				(type default)
			)
			(fill no)
			(layer "B.Fab")
		)
		(pad "1" smd custom
			(at 0 -0.4445 90)
			(size 0.1397 0.1397)
			(layers "B.Cu" "B.Mask" "B.Paste")
			(net "SSD_PERST_Y1")
			(options
				(clearance outline)
				(anchor circle)
			)
			(primitives
				(gr_poly
					(pts
						(arc
							(start -0.1778 0.2794)
							(mid -0.249642 0.249642)
							(end -0.2794 0.1778)
						)
						(arc
							(start -0.2794 -0.1778)
							(mid -0.249642 -0.249642)
							(end -0.1778 -0.2794)
						)
						(arc
							(start 0.1778 -0.2794)
							(mid 0.249642 -0.249642)
							(end 0.2794 -0.1778)
						)
						(arc
							(start 0.2794 0.1778)
							(mid 0.249642 0.249642)
							(end 0.1778 0.2794)
						)
					)
					(width 0)
					(fill yes)
				)
			)
		)
		(pad "2" smd custom
			(at 0 0.4445 90)
			(size 0.1397 0.1397)
			(layers "B.Cu" "B.Mask" "B.Paste")
			(net "SSD_PERST#1_R")
			(options
				(clearance outline)
				(anchor circle)
			)
			(primitives
				(gr_poly
					(pts
						(arc
							(start -0.1778 0.2794)
							(mid -0.249642 0.249642)
							(end -0.2794 0.1778)
						)
						(arc
							(start -0.2794 -0.1778)
							(mid -0.249642 -0.249642)
							(end -0.1778 -0.2794)
						)
						(arc
							(start 0.1778 -0.2794)
							(mid 0.249642 -0.249642)
							(end 0.2794 -0.1778)
						)
						(arc
							(start 0.2794 0.1778)
							(mid 0.249642 0.249642)
							(end 0.1778 0.2794)
						)
					)
					(width 0)
					(fill yes)
				)
			)
		)
	)
	(footprint ""
		(layer "B.Cu")
		(at 231.3432 -35.0012 -90)
		(property "Reference" "C480"
			(at 0 0 90)
			(layer "B.SilkS")
			(hide yes)
			(effects
				(font
					(size 1.27 1.27)
				)
				(justify mirror)
			)
		)
		(property "Value" "SCD1U16V1KX-1-GP"
			(at 2.8321 -1.7399 270)
			(unlocked yes)
			(layer "B.Fab")
			(hide yes)
			(effects
				(font
					(size 1.016 1.016)
					(thickness 0.1524)
				)
				(justify mirror)
			)
		)
		(property "Device Type" "C0201H13"
			(at 2.8321 -3.2639 270)
			(unlocked yes)
			(layer "B.Fab")
			(hide yes)
			(effects
				(font
					(size 1.016 1.016)
					(thickness 0.1524)
				)
				(justify mirror)
			)
		)
		(duplicate_pad_numbers_are_jumpers no)
		(fp_rect
			(start 0.2794 0.6477)
			(end -0.2794 -0.6477)
			(stroke
				(width 0)
				(type default)
			)
			(fill no)
			(layer "B.CrtYd")
		)
		(fp_rect
			(start 0.2794 0.6477)
			(end -0.2794 -0.6477)
			(stroke
				(width 0)
				(type default)
			)
			(fill no)
			(layer "B.Fab")
		)
		(pad "1" smd custom
			(at 0 -0.2794 90)
			(size 0.0762 0.0762)
			(layers "B.Cu" "B.Mask" "B.Paste")
			(net "DUT_VDDO")
			(options
				(clearance outline)
				(anchor circle)
			)
			(primitives
				(gr_poly
					(pts
						(arc
							(start 0.1524 0.127)
							(mid 0.137521 0.162921)
							(end 0.1016 0.1778)
						)
						(arc
							(start -0.1016 0.1778)
							(mid -0.137521 0.162921)
							(end -0.1524 0.127)
						)
						(arc
							(start -0.1524 -0.127)
							(mid -0.137521 -0.162921)
							(end -0.1016 -0.1778)
						)
						(arc
							(start 0.1016 -0.1778)
							(mid 0.137521 -0.162921)
							(end 0.1524 -0.127)
						)
					)
					(width 0)
					(fill yes)
				)
			)
		)
		(pad "2" smd custom
			(at 0 0.2794 90)
			(size 0.0762 0.0762)
			(layers "B.Cu" "B.Mask" "B.Paste")
			(net "GND")
			(options
				(clearance outline)
				(anchor circle)
			)
			(primitives
				(gr_poly
					(pts
						(arc
							(start 0.1524 0.127)
							(mid 0.137521 0.162921)
							(end 0.1016 0.1778)
						)
						(arc
							(start -0.1016 0.1778)
							(mid -0.137521 0.162921)
							(end -0.1524 0.127)
						)
						(arc
							(start -0.1524 -0.127)
							(mid -0.137521 -0.162921)
							(end -0.1016 -0.1778)
						)
						(arc
							(start 0.1016 -0.1778)
							(mid 0.137521 -0.162921)
							(end 0.1524 -0.127)
						)
					)
					(width 0)
					(fill yes)
				)
			)
		)
	)
	(footprint ""
		(layer "B.Cu")
		(at 37.719 -132.969)
		(property "Reference" "C204"
			(at 0 0 0)
			(layer "B.SilkS")
			(hide yes)
			(effects
				(font
					(size 1.27 1.27)
				)
				(justify mirror)
			)
		)
		(property "Value" "SC1U10V2KX-4-GP"
			(at -1.1811 -2.7051 0)
			(unlocked yes)
			(layer "B.Fab")
			(hide yes)
			(effects
				(font
					(size 1.016 1.016)
					(thickness 0.1524)
				)
				(justify mirror)
			)
		)
		(property "Device Type" "C402H22"
			(at -1.1811 -4.2291 0)
			(unlocked yes)
			(layer "B.Fab")
			(hide yes)
			(effects
				(font
					(size 1.016 1.016)
					(thickness 0.1524)
				)
				(justify mirror)
			)
		)
		(duplicate_pad_numbers_are_jumpers no)
		(fp_rect
			(start 0.4318 0.9525)
			(end -0.4318 -0.9525)
			(stroke
				(width 0)
				(type default)
			)
			(fill no)
			(layer "B.CrtYd")
		)
		(fp_rect
			(start 0.4318 0.9525)
			(end -0.4318 -0.9525)
			(stroke
				(width 0)
				(type default)
			)
			(fill no)
			(layer "B.Fab")
		)
		(pad "1" smd custom
			(at 0 -0.4445 180)
			(size 0.1524 0.1524)
			(layers "B.Cu" "B.Mask" "B.Paste")
			(net "P1V26_STBY")
			(options
				(clearance outline)
				(anchor circle)
			)
			(primitives
				(gr_poly
					(pts
						(arc
							(start 0.3048 0.2032)
							(mid 0.275042 0.275042)
							(end 0.2032 0.3048)
						)
						(arc
							(start -0.2032 0.3048)
							(mid -0.275042 0.275042)
							(end -0.3048 0.2032)
						)
						(arc
							(start -0.3048 -0.2032)
							(mid -0.275042 -0.275042)
							(end -0.2032 -0.3048)
						)
						(arc
							(start 0.2032 -0.3048)
							(mid 0.275042 -0.275042)
							(end 0.3048 -0.2032)
						)
					)
					(width 0)
					(fill yes)
				)
			)
		)
		(pad "2" smd custom
			(at 0 0.4445 180)
			(size 0.1524 0.1524)
			(layers "B.Cu" "B.Mask" "B.Paste")
			(net "GND")
			(options
				(clearance outline)
				(anchor circle)
			)
			(primitives
				(gr_poly
					(pts
						(arc
							(start 0.3048 0.2032)
							(mid 0.275042 0.275042)
							(end 0.2032 0.3048)
						)
						(arc
							(start -0.2032 0.3048)
							(mid -0.275042 0.275042)
							(end -0.3048 0.2032)
						)
						(arc
							(start -0.3048 -0.2032)
							(mid -0.275042 -0.275042)
							(end -0.2032 -0.3048)
						)
						(arc
							(start 0.2032 -0.3048)
							(mid 0.275042 -0.275042)
							(end 0.3048 -0.2032)
						)
					)
					(width 0)
					(fill yes)
				)
			)
		)
	)
	(footprint ""
		(layer "B.Cu")
		(at 20.400518 -124.481844 90)
		(property "Reference" "R240"
			(at 0 0 90)
			(layer "B.SilkS")
			(hide yes)
			(effects
				(font
					(size 1.27 1.27)
				)
				(justify mirror)
			)
		)
		(property "Value" "0R2J-2-GP"
			(at -0.064008 -3.993896 90)
			(unlocked yes)
			(layer "B.Fab")
			(hide yes)
			(effects
				(font
					(size 1.016 1.016)
					(thickness 0.1524)
				)
				(justify mirror)
			)
		)
		(property "Device Type" "R402H16"
			(at -0.064008 -5.517896 90)
			(unlocked yes)
			(layer "B.Fab")
			(hide yes)
			(effects
				(font
					(size 1.016 1.016)
					(thickness 0.1524)
				)
				(justify mirror)
			)
		)
		(duplicate_pad_numbers_are_jumpers no)
		(fp_line
			(start 0.508 -0.9398)
			(end 0.508 0.9398)
			(stroke
				(width 0.1524)
				(type default)
			)
			(layer "B.SilkS")
		)
		(fp_line
			(start -0.508 -0.9398)
			(end 0.508 -0.9398)
			(stroke
				(width 0.1524)
				(type default)
			)
			(layer "B.SilkS")
		)
		(fp_rect
			(start 0.508 0.9398)
			(end -0.508 -0.9398)
			(stroke
				(width 0)
				(type default)
			)
			(fill no)
			(layer "B.CrtYd")
		)
		(fp_rect
			(start 0.508 0.9398)
			(end -0.508 -0.9398)
			(stroke
				(width 0)
				(type default)
			)
			(fill no)
			(layer "B.Fab")
		)
		(pad "1" smd custom
			(at 0 -0.4445 270)
			(size 0.1397 0.1397)
			(layers "B.Cu" "B.Mask" "B.Paste")
			(net "BMC_I2C2_MINI2_SCL_S")
			(options
				(clearance outline)
				(anchor circle)
			)
			(primitives
				(gr_poly
					(pts
						(arc
							(start -0.1778 0.2794)
							(mid -0.249642 0.249642)
							(end -0.2794 0.1778)
						)
						(arc
							(start -0.2794 -0.1778)
							(mid -0.249642 -0.249642)
							(end -0.1778 -0.2794)
						)
						(arc
							(start 0.1778 -0.2794)
							(mid 0.249642 -0.249642)
							(end 0.2794 -0.1778)
						)
						(arc
							(start 0.2794 0.1778)
							(mid 0.249642 0.249642)
							(end 0.1778 0.2794)
						)
					)
					(width 0)
					(fill yes)
				)
			)
		)
		(pad "2" smd custom
			(at 0 0.4445 270)
			(size 0.1397 0.1397)
			(layers "B.Cu" "B.Mask" "B.Paste")
			(net "BMC0_SMB2_CLK")
			(options
				(clearance outline)
				(anchor circle)
			)
			(primitives
				(gr_poly
					(pts
						(arc
							(start -0.1778 0.2794)
							(mid -0.249642 0.249642)
							(end -0.2794 0.1778)
						)
						(arc
							(start -0.2794 -0.1778)
							(mid -0.249642 -0.249642)
							(end -0.1778 -0.2794)
						)
						(arc
							(start 0.1778 -0.2794)
							(mid 0.249642 -0.249642)
							(end 0.2794 -0.1778)
						)
						(arc
							(start 0.2794 0.1778)
							(mid 0.249642 0.249642)
							(end 0.1778 0.2794)
						)
					)
					(width 0)
					(fill yes)
				)
			)
		)
	)
	(footprint ""
		(layer "B.Cu")
		(at 336.9818 -207.6196 90)
		(property "Reference" "C4160"
			(at 0 0 90)
			(layer "B.SilkS")
			(hide yes)
			(effects
				(font
					(size 1.27 1.27)
				)
				(justify mirror)
			)
		)
		(property "Value" "SCD1U25V3KX-GP"
			(at 0 -2.8194 90)
			(unlocked yes)
			(layer "B.Fab")
			(hide yes)
			(effects
				(font
					(size 1.016 1.016)
					(thickness 0.1524)
				)
				(justify mirror)
			)
		)
		(property "Device Type" "C603H36"
			(at 0 -4.3434 90)
			(unlocked yes)
			(layer "B.Fab")
			(hide yes)
			(effects
				(font
					(size 1.016 1.016)
					(thickness 0.1524)
				)
				(justify mirror)
			)
		)
		(duplicate_pad_numbers_are_jumpers no)
		(fp_line
			(start -0.508 0)
			(end 0.508 0)
			(stroke
				(width 0.2032)
				(type default)
			)
			(layer "B.SilkS")
		)
		(fp_rect
			(start 0.5842 1.3335)
			(end -0.5842 -1.3335)
			(stroke
				(width 0)
				(type default)
			)
			(fill no)
			(layer "B.CrtYd")
		)
		(fp_rect
			(start 0.5842 1.3335)
			(end -0.5842 -1.3335)
			(stroke
				(width 0)
				(type default)
			)
			(fill no)
			(layer "B.Fab")
		)
		(pad "1" smd custom
			(at 0 -0.762 270)
			(size 0.2159 0.2159)
			(layers "B.Cu" "B.Mask" "B.Paste")
			(net "GND")
			(options
				(clearance outline)
				(anchor circle)
			)
			(primitives
				(gr_poly
					(pts
						(arc
							(start -0.3302 0.4318)
							(mid -0.402042 0.402042)
							(end -0.4318 0.3302)
						)
						(arc
							(start -0.4318 -0.3302)
							(mid -0.402042 -0.402042)
							(end -0.3302 -0.4318)
						)
						(arc
							(start 0.3302 -0.4318)
							(mid 0.402042 -0.402042)
							(end 0.4318 -0.3302)
						)
						(arc
							(start 0.4318 0.3302)
							(mid 0.402042 0.402042)
							(end 0.3302 0.4318)
						)
					)
					(width 0)
					(fill yes)
				)
			)
		)
		(pad "2" smd custom
			(at 0 0.762 270)
			(size 0.2159 0.2159)
			(layers "B.Cu" "B.Mask" "B.Paste")
			(net "SSD_PWREN14_R")
			(options
				(clearance outline)
				(anchor circle)
			)
			(primitives
				(gr_poly
					(pts
						(arc
							(start -0.3302 0.4318)
							(mid -0.402042 0.402042)
							(end -0.4318 0.3302)
						)
						(arc
							(start -0.4318 -0.3302)
							(mid -0.402042 -0.402042)
							(end -0.3302 -0.4318)
						)
						(arc
							(start 0.3302 -0.4318)
							(mid 0.402042 -0.402042)
							(end 0.4318 -0.3302)
						)
						(arc
							(start 0.4318 0.3302)
							(mid 0.402042 0.402042)
							(end 0.3302 0.4318)
						)
					)
					(width 0)
					(fill yes)
				)
			)
		)
	)
	(gr_line
		(start 5.361432 -186.109102)
		(end 5.38353 -186.1312)
		(stroke
			(width 0.060198)
			(type default)
		)
		(layer "F.Cu")
	)
	(gr_line
		(start 5.38353 -186.1312)
		(end 5.6642 -186.1312)
		(stroke
			(width 0.060198)
			(type default)
		)
		(layer "F.Cu")
	)
	(gr_line
		(start 5.4102 -185.0136)
		(end 5.6642 -185.2676)
		(stroke
			(width 0.060198)
			(type default)
		)
		(layer "F.Cu")
	)
	(gr_line
		(start 5.6642 -186.1312)
		(end 5.8166 -186.2836)
		(stroke
			(width 0.060198)
			(type default)
		)
		(layer "F.Cu")
	)
	(gr_line
		(start 5.6642 -185.2676)
		(end 6.3627 -185.2676)
		(stroke
			(width 0.060198)
			(type default)
		)
		(layer "F.Cu")
	)
	(gr_line
		(start 5.8166 -186.2836)
		(end 6.3627 -186.2836)
		(stroke
			(width 0.060198)
			(type default)
		)
		(layer "F.Cu")
	)
	(gr_line
		(start 7.2517 -186.2836)
		(end 7.403084 -186.132216)
		(stroke
			(width 0.060198)
			(type default)
		)
		(layer "F.Cu")
	)
	(gr_line
		(start 7.2517 -185.2676)
		(end 7.403084 -185.418984)
		(stroke
			(width 0.060198)
			(type default)
		)
		(layer "F.Cu")
	)
	(gr_line
		(start 8.016748 -120.094248)
		(end 8.128 -120.2055)
		(stroke
			(width 0.060198)
			(type default)
		)
		(layer "F.Cu")
	)
	(gr_line
		(start 8.016748 -118.15953)
		(end 8.016748 -120.094248)
		(stroke
			(width 0.060198)
			(type default)
		)
		(layer "F.Cu")
	)
	(gr_line
		(start 8.016748 -118.068852)
		(end 8.016748 -118.15953)
		(stroke
			(width 0.060198)
			(type default)
		)
		(layer "F.Cu")
	)
	(gr_line
		(start 8.016748 -118.068852)
		(end 9.017 -117.0686)
		(stroke
			(width 0.060198)
			(type default)
		)
		(layer "F.Cu")
	)
	(gr_line
		(start 8.025892 -79.907892)
		(end 8.0518 -79.9338)
		(stroke
			(width 0.060198)
			(type default)
		)
		(layer "F.Cu")
	)
	(gr_line
		(start 8.025892 -78.961488)
		(end 8.025892 -79.907892)
		(stroke
			(width 0.060198)
			(type default)
		)
		(layer "F.Cu")
	)
	(gr_line
		(start 8.025892 -78.961488)
		(end 8.21055 -78.77683)
		(stroke
			(width 0.060198)
			(type default)
		)
		(layer "F.Cu")
	)
	(gr_line
		(start 8.042148 -77.895196)
		(end 8.21055 -78.063598)
		(stroke
			(width 0.060198)
			(type default)
		)
		(layer "F.Cu")
	)
	(gr_line
		(start 8.042148 -77.028548)
		(end 8.042148 -77.895196)
		(stroke
			(width 0.060198)
			(type default)
		)
		(layer "F.Cu")
	)
	(gr_line
		(start 8.0518 -122.1994)
		(end 8.2296 -122.3772)
		(stroke
			(width 0.060198)
			(type default)
		)
		(layer "F.Cu")
	)
	(gr_line
		(start 8.0518 -121.1707)
		(end 8.0518 -122.1994)
		(stroke
			(width 0.060198)
			(type default)
		)
		(layer "F.Cu")
	)
	(gr_line
		(start 8.0518 -121.1707)
		(end 8.128 -121.0945)
		(stroke
			(width 0.060198)
			(type default)
		)
		(layer "F.Cu")
	)
	(gr_line
		(start 8.128 -121.0945)
		(end 8.65505 -120.56745)
		(stroke
			(width 0.060198)
			(type default)
		)
		(layer "F.Cu")
	)
	(gr_line
		(start 8.128 -120.2055)
		(end 9.14146 -120.2055)
		(stroke
			(width 0.060198)
			(type default)
		)
		(layer "F.Cu")
	)
	(gr_line
		(start 8.229092 -185.488834)
		(end 8.847074 -184.871106)
		(stroke
			(width 0.060198)
			(type default)
		)
		(layer "F.Cu")
	)
	(gr_line
		(start 8.2296 -122.3772)
		(end 8.6106 -122.3772)
		(stroke
			(width 0.060198)
			(type default)
		)
		(layer "F.Cu")
	)
	(gr_line
		(start 8.548624 -185.993024)
		(end 8.7122 -186.1566)
		(stroke
			(width 0.060198)
			(type default)
		)
		(layer "F.Cu")
	)
	(gr_line
		(start 8.6106 -122.3772)
		(end 9.398 -121.5898)
		(stroke
			(width 0.060198)
			(type default)
		)
		(layer "F.Cu")
	)
	(gr_line
		(start 8.6106 -119.2022)
		(end 9.1186 -119.7102)
		(stroke
			(width 0.060198)
			(type default)
		)
		(layer "F.Cu")
	)
	(gr_line
		(start 8.65505 -120.56745)
		(end 9.291574 -120.56745)
		(stroke
			(width 0.060198)
			(type default)
		)
		(layer "F.Cu")
	)
	(gr_line
		(start 8.7122 -186.1566)
		(end 9.065768 -185.803032)
		(stroke
			(width 0.060198)
			(type default)
		)
		(layer "F.Cu")
	)
	(gr_line
		(start 8.847074 -184.871106)
		(end 9.065768 -185.0898)
		(stroke
			(width 0.060198)
			(type default)
		)
		(layer "F.Cu")
	)
	(gr_line
		(start 9.017 -117.0686)
		(end 9.8806 -117.0686)
		(stroke
			(width 0.060198)
			(type default)
		)
		(layer "F.Cu")
	)
	(gr_line
		(start 9.1186 -119.7102)
		(end 9.63676 -119.7102)
		(stroke
			(width 0.060198)
			(type default)
		)
		(layer "F.Cu")
	)
	(gr_line
		(start 9.14146 -120.2055)
		(end 9.63676 -119.7102)
		(stroke
			(width 0.060198)
			(type default)
		)
		(layer "F.Cu")
	)
	(gr_line
		(start 9.291574 -120.56745)
		(end 9.453372 -120.405652)
		(stroke
			(width 0.060198)
			(type default)
		)
		(layer "F.Cu")
	)
	(gr_line
		(start 9.398 -121.5898)
		(end 9.63676 -121.5898)
		(stroke
			(width 0.060198)
			(type default)
		)
		(layer "F.Cu")
	)
	(gr_line
		(start 9.453372 -120.405652)
		(end 11.472926 -120.405652)
		(stroke
			(width 0.060198)
			(type default)
		)
		(layer "F.Cu")
	)
	(gr_line
		(start 9.4996 -52.0446)
		(end 9.826752 -52.371752)
		(stroke
			(width 0.052324)
			(type default)
		)
		(layer "F.Cu")
	)
	(gr_line
		(start 9.4996 -52.0446)
		(end 9.826752 -51.717448)
		(stroke
			(width 0.052324)
			(type default)
		)
		(layer "F.Cu")
	)
	(gr_line
		(start 9.5631 -54.0385)
		(end 9.826752 -54.302152)
		(stroke
			(width 0.052324)
			(type default)
		)
		(layer "F.Cu")
	)
	(gr_line
		(start 9.5631 -53.1495)
		(end 9.826752 -52.885848)
		(stroke
			(width 0.052324)
			(type default)
		)
		(layer "F.Cu")
	)
	(gr_line
		(start 9.6647 -55.048912)
		(end 9.826752 -54.88686)
		(stroke
			(width 0.052324)
			(type default)
		)
		(layer "F.Cu")
	)
	(gr_line
		(start 9.8806 -117.0686)
		(end 10.3378 -117.5258)
		(stroke
			(width 0.060198)
			(type default)
		)
		(layer "F.Cu")
	)
	(gr_line
		(start 10.143744 -184.91454)
		(end 11.2395 -184.91454)
		(stroke
			(width 0.060198)
			(type default)
		)
		(layer "F.Cu")
	)
	(gr_line
		(start 10.315448 -54.88686)
		(end 10.4775 -55.048912)
		(stroke
			(width 0.052324)
			(type default)
		)
		(layer "F.Cu")
	)
	(gr_line
		(start 10.315448 -54.302152)
		(end 10.5791 -54.0385)
		(stroke
			(width 0.052324)
			(type default)
		)
		(layer "F.Cu")
	)
	(gr_line
		(start 10.315448 -52.885848)
		(end 10.5791 -53.1495)
		(stroke
			(width 0.052324)
			(type default)
		)
		(layer "F.Cu")
	)
	(gr_line
		(start 10.315448 -52.371752)
		(end 10.6426 -52.0446)
		(stroke
			(width 0.052324)
			(type default)
		)
		(layer "F.Cu")
	)
	(gr_line
		(start 10.315448 -51.717448)
		(end 10.6426 -52.0446)
		(stroke
			(width 0.052324)
			(type default)
		)
		(layer "F.Cu")
	)
	(gr_line
		(start 10.3378 -117.5258)
		(end 12.1412 -117.5258)
		(stroke
			(width 0.060198)
			(type default)
		)
		(layer "F.Cu")
	)
	(gr_line
		(start 10.35177 -185.41619)
		(end 10.353294 -185.414666)
		(stroke
			(width 0.060198)
			(type default)
		)
		(layer "F.Cu")
	)
	(gr_line
		(start 10.353294 -185.414666)
		(end 11.3157 -185.414666)
		(stroke
			(width 0.060198)
			(type default)
		)
		(layer "F.Cu")
	)
	(gr_line
		(start 10.93724 -119.7102)
		(end 11.6586 -119.7102)
		(stroke
			(width 0.060198)
			(type default)
		)
		(layer "F.Cu")
	)
	(gr_line
		(start 11.356086 -78.69301)
		(end 11.954002 -78.095094)
		(stroke
			(width 0.060198)
			(type default)
		)
		(layer "F.Cu")
	)
	(gr_line
		(start 11.472926 -120.405652)
		(end 11.564874 -120.4976)
		(stroke
			(width 0.060198)
			(type default)
		)
		(layer "F.Cu")
	)
	(gr_line
		(start 11.571986 -47.649892)
		(end 12.216892 -47.649892)
		(stroke
			(width 0.052324)
			(type default)
		)
		(layer "F.Cu")
	)
	(gr_line
		(start 11.6586 -119.7102)
		(end 12.1539 -120.2055)
		(stroke
			(width 0.060198)
			(type default)
		)
		(layer "F.Cu")
	)
	(gr_line
		(start 11.857736 -79.1972)
		(end 12.685776 -79.1972)
		(stroke
			(width 0.060198)
			(type default)
		)
		(layer "F.Cu")
	)
	(gr_line
		(start 11.954002 -78.095094)
		(end 12.723114 -78.095094)
		(stroke
			(width 0.060198)
			(type default)
		)
		(layer "F.Cu")
	)
	(gr_line
		(start 12.124436 -118.392448)
		(end 12.446 -118.714012)
		(stroke
			(width 0.060198)
			(type default)
		)
		(layer "F.Cu")
	)
	(gr_line
		(start 12.124436 -118.311168)
		(end 12.124436 -118.392448)
		(stroke
			(width 0.060198)
			(type default)
		)
		(layer "F.Cu")
	)
	(gr_line
		(start 12.1412 -117.5258)
		(end 12.9032 -118.2878)
		(stroke
			(width 0.060198)
			(type default)
		)
		(layer "F.Cu")
	)
	(gr_line
		(start 12.1539 -120.2055)
		(end 12.446 -120.2055)
		(stroke
			(width 0.060198)
			(type default)
		)
		(layer "F.Cu")
	)
	(gr_line
		(start 12.216892 -47.649892)
		(end 12.341352 -47.774352)
		(stroke
			(width 0.052324)
			(type default)
		)
		(layer "F.Cu")
	)
	(gr_line
		(start 12.446 -121.0945)
		(end 12.621514 -121.270014)
		(stroke
			(width 0.060198)
			(type default)
		)
		(layer "F.Cu")
	)
	(gr_line
		(start 12.446 -121.0945)
		(end 13.081 -120.4595)
		(stroke
			(width 0.060198)
			(type default)
		)
		(layer "F.Cu")
	)
	(gr_line
		(start 12.446 -119.2276)
		(end 12.446 -120.2055)
		(stroke
			(width 0.060198)
			(type default)
		)
		(layer "F.Cu")
	)
	(gr_line
		(start 12.446 -118.714012)
		(end 12.446 -119.2276)
		(stroke
			(width 0.060198)
			(type default)
		)
		(layer "F.Cu")
	)
	(gr_line
		(start 12.59713 -45.109892)
		(end 13.207492 -45.109892)
		(stroke
			(width 0.052324)
			(type default)
		)
		(layer "F.Cu")
	)
	(gr_line
		(start 12.621514 -121.8692)
		(end 12.652248 -121.899934)
		(stroke
			(width 0.060198)
			(type default)
		)
		(layer "F.Cu")
	)
	(gr_line
		(start 12.621514 -121.270014)
		(end 12.621514 -121.8692)
		(stroke
			(width 0.060198)
			(type default)
		)
		(layer "F.Cu")
	)
	(gr_line
		(start 12.685776 -79.1972)
		(end 12.966446 -78.91653)
		(stroke
			(width 0.060198)
			(type default)
		)
		(layer "F.Cu")
	)
	(gr_line
		(start 12.723114 -78.095094)
		(end 12.901676 -77.916532)
		(stroke
			(width 0.060198)
			(type default)
		)
		(layer "F.Cu")
	)
	(gr_line
		(start 12.73556 -125.617986)
		(end 12.767818 -125.650244)
		(stroke
			(width 0.060198)
			(type default)
		)
		(layer "F.Cu")
	)
	(gr_line
		(start 12.767818 -125.793246)
		(end 13.009372 -126.0348)
		(stroke
			(width 0.060198)
			(type default)
		)
		(layer "F.Cu")
	)
	(gr_line
		(start 12.767818 -125.650244)
		(end 12.767818 -125.793246)
		(stroke
			(width 0.060198)
			(type default)
		)
		(layer "F.Cu")
	)
	(gr_line
		(start 12.830048 -47.774352)
		(end 12.954508 -47.649892)
		(stroke
			(width 0.052324)
			(type default)
		)
		(layer "F.Cu")
	)
	(gr_line
		(start 12.901676 -77.916532)
		(end 13.737082 -77.916532)
		(stroke
			(width 0.060198)
			(type default)
		)
		(layer "F.Cu")
	)
	(gr_line
		(start 12.9032 -118.8085)
		(end 13.5128 -119.4181)
		(stroke
			(width 0.060198)
			(type default)
		)
		(layer "F.Cu")
	)
	(gr_line
		(start 12.9032 -118.2878)
		(end 12.9032 -118.8085)
		(stroke
			(width 0.060198)
			(type default)
		)
		(layer "F.Cu")
	)
	(gr_line
		(start 12.954508 -47.649892)
		(end 13.601954 -47.649892)
		(stroke
			(width 0.052324)
			(type default)
		)
		(layer "F.Cu")
	)
	(gr_line
		(start 12.966446 -78.91653)
		(end 13.737082 -78.91653)
		(stroke
			(width 0.060198)
			(type default)
		)
		(layer "F.Cu")
	)
	(gr_line
		(start 13.009372 -126.0348)
		(end 13.44676 -126.0348)
		(stroke
			(width 0.060198)
			(type default)
		)
		(layer "F.Cu")
	)
	(gr_line
		(start 13.081 -120.4595)
		(end 13.5128 -120.4595)
		(stroke
			(width 0.060198)
			(type default)
		)
		(layer "F.Cu")
	)
	(gr_line
		(start 13.207492 -45.109892)
		(end 13.37818 -45.28058)
		(stroke
			(width 0.052324)
			(type default)
		)
		(layer "F.Cu")
	)
	(gr_line
		(start 13.3985 -50.8254)
		(end 13.725652 -51.152552)
		(stroke
			(width 0.052324)
			(type default)
		)
		(layer "F.Cu")
	)
	(gr_line
		(start 13.3985 -50.8254)
		(end 13.725652 -50.498248)
		(stroke
			(width 0.052324)
			(type default)
		)
		(layer "F.Cu")
	)
	(gr_line
		(start 13.462 -52.8193)
		(end 13.725652 -53.082952)
		(stroke
			(width 0.052324)
			(type default)
		)
		(layer "F.Cu")
	)
	(gr_line
		(start 13.462 -51.9303)
		(end 13.725652 -51.666648)
		(stroke
			(width 0.052324)
			(type default)
		)
		(layer "F.Cu")
	)
	(gr_line
		(start 13.5128 -120.4595)
		(end 14.5542 -120.4595)
		(stroke
			(width 0.060198)
			(type default)
		)
		(layer "F.Cu")
	)
	(gr_line
		(start 13.5128 -119.4181)
		(end 14.5542 -119.4181)
		(stroke
			(width 0.060198)
			(type default)
		)
		(layer "F.Cu")
	)
	(gr_line
		(start 13.5636 -53.829712)
		(end 13.725652 -53.66766)
		(stroke
			(width 0.052324)
			(type default)
		)
		(layer "F.Cu")
	)
	(gr_line
		(start 13.866876 -45.28058)
		(end 14.037564 -45.109892)
		(stroke
			(width 0.052324)
			(type default)
		)
		(layer "F.Cu")
	)
	(gr_line
		(start 14.011148 -68.28917)
		(end 14.1732 -68.451222)
		(stroke
			(width 0.052324)
			(type default)
		)
		(layer "F.Cu")
	)
	(gr_line
		(start 14.011148 -67.800474)
		(end 14.1732 -67.638422)
		(stroke
			(width 0.052324)
			(type default)
		)
		(layer "F.Cu")
	)
	(gr_line
		(start 14.037564 -45.109892)
		(end 14.627098 -45.109892)
		(stroke
			(width 0.052324)
			(type default)
		)
		(layer "F.Cu")
	)
	(gr_line
		(start 14.214348 -53.66766)
		(end 14.3764 -53.829712)
		(stroke
			(width 0.052324)
			(type default)
		)
		(layer "F.Cu")
	)
	(gr_line
		(start 14.214348 -53.082952)
		(end 14.478 -52.8193)
		(stroke
			(width 0.052324)
			(type default)
		)
		(layer "F.Cu")
	)
	(gr_line
		(start 14.214348 -51.666648)
		(end 14.478 -51.9303)
		(stroke
			(width 0.052324)
			(type default)
		)
		(layer "F.Cu")
	)
	(gr_line
		(start 14.214348 -51.152552)
		(end 14.5415 -50.8254)
		(stroke
			(width 0.052324)
			(type default)
		)
		(layer "F.Cu")
	)
	(gr_line
		(start 14.214348 -50.498248)
		(end 14.5415 -50.8254)
		(stroke
			(width 0.052324)
			(type default)
		)
		(layer "F.Cu")
	)
	(gr_line
		(start 14.410944 -70.588632)
		(end 14.410944 -71.242682)
		(stroke
			(width 0.052324)
			(type default)
		)
		(layer "F.Cu")
	)
	(gr_line
		(start 14.410944 -70.588632)
		(end 14.426184 -70.573392)
		(stroke
			(width 0.052324)
			(type default)
		)
		(layer "F.Cu")
	)
	(gr_line
		(start 14.5542 -120.4595)
		(end 14.5669 -120.4468)
		(stroke
			(width 0.060198)
			(type default)
		)
		(layer "F.Cu")
	)
	(gr_line
		(start 14.5542 -119.4181)
		(end 14.5669 -119.4054)
		(stroke
			(width 0.060198)
			(type default)
		)
		(layer "F.Cu")
	)
	(gr_line
		(start 14.91107 -70.569836)
		(end 14.91107 -71.242682)
		(stroke
			(width 0.052324)
			(type default)
		)
		(layer "F.Cu")
	)
	(gr_line
		(start 15.4559 -120.4468)
		(end 15.619984 -120.282716)
		(stroke
			(width 0.060198)
			(type default)
		)
		(layer "F.Cu")
	)
	(gr_line
		(start 15.4559 -119.4054)
		(end 15.619984 -119.569484)
		(stroke
			(width 0.060198)
			(type default)
		)
		(layer "F.Cu")
	)
	(gr_line
		(start 15.4686 -125.9586)
		(end 16.09598 -126.58598)
		(stroke
			(width 0.060198)
			(type default)
		)
		(layer "F.Cu")
	)
	(gr_line
		(start 15.4686 -125.760988)
		(end 15.4686 -125.9586)
		(stroke
			(width 0.060198)
			(type default)
		)
		(layer "F.Cu")
	)
	(gr_line
		(start 15.490698 -124.262642)
		(end 15.878556 -124.6505)
		(stroke
			(width 0.060198)
			(type default)
		)
		(layer "F.Cu")
	)
	(gr_line
		(start 15.7988 -73.217024)
		(end 15.960852 -73.054972)
		(stroke
			(width 0.052324)
			(type default)
		)
		(layer "F.Cu")
	)
	(gr_line
		(start 15.8496 -87.0458)
		(end 16.190976 -86.704424)
		(stroke
			(width 0.068326)
			(type default)
		)
		(layer "F.Cu")
	)
	(gr_line
		(start 15.878556 -124.6505)
		(end 16.256 -124.6505)
		(stroke
			(width 0.060198)
			(type default)
		)
		(layer "F.Cu")
	)
	(gr_line
		(start 15.911068 -70.575932)
		(end 15.911068 -71.242682)
		(stroke
			(width 0.052324)
			(type default)
		)
		(layer "F.Cu")
	)
	(gr_line
		(start 16.007842 -119.76735)
		(end 16.12011 -119.879618)
		(stroke
			(width 0.060198)
			(type default)
		)
		(layer "F.Cu")
	)
	(gr_line
		(start 16.017748 -66.874898)
		(end 16.1798 -67.03695)
		(stroke
			(width 0.052324)
			(type default)
		)
		(layer "F.Cu")
	)
	(gr_line
		(start 16.017748 -66.386202)
		(end 16.1798 -66.22415)
		(stroke
			(width 0.052324)
			(type default)
		)
		(layer "F.Cu")
	)
	(gr_line
		(start 16.09598 -126.546356)
		(end 16.09598 -126.58598)
		(stroke
			(width 0.060198)
			(type default)
		)
		(layer "F.Cu")
	)
	(gr_line
		(start 16.09598 -126.546356)
		(end 16.256 -126.386336)
		(stroke
			(width 0.060198)
			(type default)
		)
		(layer "F.Cu")
	)
	(gr_line
		(start 16.256 -125.5395)
		(end 16.256 -126.386336)
		(stroke
			(width 0.060198)
			(type default)
		)
		(layer "F.Cu")
	)
	(gr_line
		(start 16.396208 -120.155716)
		(end 16.468344 -120.227852)
		(stroke
			(width 0.060198)
			(type default)
		)
		(layer "F.Cu")
	)
	(gr_line
		(start 16.398748 -70.576948)
		(end 16.41094 -70.58914)
		(stroke
			(width 0.052324)
			(type default)
		)
		(layer "F.Cu")
	)
	(gr_line
		(start 16.41094 -70.58914)
		(end 16.41094 -71.242682)
		(stroke
			(width 0.052324)
			(type default)
		)
		(layer "F.Cu")
	)
	(gr_line
		(start 16.449548 -73.054972)
		(end 16.6116 -73.217024)
		(stroke
			(width 0.052324)
			(type default)
		)
		(layer "F.Cu")
	)
	(gr_line
		(start 16.468344 -120.227852)
		(end 16.489426 -120.32742)
		(stroke
			(width 0.060198)
			(type default)
		)
		(layer "F.Cu")
	)
	(gr_line
		(start 16.531336 -120.525032)
		(end 16.53159 -120.526556)
		(stroke
			(width 0.060198)
			(type default)
		)
		(layer "F.Cu")
	)
	(gr_line
		(start 16.625824 -86.704424)
		(end 16.9672 -87.0458)
		(stroke
			(width 0.068326)
			(type default)
		)
		(layer "F.Cu")
	)
	(gr_line
		(start 16.657066 -45.109892)
		(end 17.271492 -45.109892)
		(stroke
			(width 0.052324)
			(type default)
		)
		(layer "F.Cu")
	)
	(gr_line
		(start 16.911066 -71.907908)
		(end 16.920972 -71.917814)
		(stroke
			(width 0.052324)
			(type default)
		)
		(layer "F.Cu")
	)
	(gr_line
		(start 16.911066 -71.242682)
		(end 16.911066 -71.907908)
		(stroke
			(width 0.052324)
			(type default)
		)
		(layer "F.Cu")
	)
	(gr_line
		(start 17.116552 -118.452392)
		(end 17.121124 -118.475252)
		(stroke
			(width 0.068326)
			(type default)
		)
		(layer "F.Cu")
	)
	(gr_line
		(start 17.116552 -118.452392)
		(end 17.121378 -118.429278)
		(stroke
			(width 0.068326)
			(type default)
		)
		(layer "F.Cu")
	)
	(gr_line
		(start 17.214596 -118.955058)
		(end 17.341596 -119.608854)
		(stroke
			(width 0.068326)
			(type default)
		)
		(layer "F.Cu")
	)
	(gr_line
		(start 17.271492 -45.109892)
		(end 17.440148 -45.278548)
		(stroke
			(width 0.052324)
			(type default)
		)
		(layer "F.Cu")
	)
	(gr_line
		(start 17.409414 -71.917814)
		(end 17.410938 -71.91629)
		(stroke
			(width 0.052324)
			(type default)
		)
		(layer "F.Cu")
	)
	(gr_line
		(start 17.410938 -80.748886)
		(end 17.440656 -80.778604)
		(stroke
			(width 0.068326)
			(type default)
		)
		(layer "F.Cu")
	)
	(gr_line
		(start 17.410938 -80.090518)
		(end 17.410938 -80.748886)
		(stroke
			(width 0.068326)
			(type default)
		)
		(layer "F.Cu")
	)
	(gr_line
		(start 17.410938 -71.242682)
		(end 17.410938 -71.91629)
		(stroke
			(width 0.052324)
			(type default)
		)
		(layer "F.Cu")
	)
	(gr_line
		(start 17.435322 -120.090438)
		(end 17.562322 -120.744488)
		(stroke
			(width 0.068326)
			(type default)
		)
		(layer "F.Cu")
	)
	(gr_line
		(start 17.444466 -116.909088)
		(end 17.583912 -116.25326)
		(stroke
			(width 0.068326)
			(type default)
		)
		(layer "F.Cu")
	)
	(gr_line
		(start 17.508728 -118.859554)
		(end 17.703038 -118.990618)
		(stroke
			(width 0.068326)
			(type default)
		)
		(layer "F.Cu")
	)
	(gr_line
		(start 17.65046 -119.587264)
		(end 17.78127 -119.392954)
		(stroke
			(width 0.068326)
			(type default)
		)
		(layer "F.Cu")
	)
	(gr_line
		(start 17.68221 -47.649892)
		(end 18.236692 -47.649892)
		(stroke
			(width 0.052324)
			(type default)
		)
		(layer "F.Cu")
	)
	(gr_line
		(start 17.68475 -115.779042)
		(end 17.824196 -115.123214)
		(stroke
			(width 0.068326)
			(type default)
		)
		(layer "F.Cu")
	)
	(gr_line
		(start 17.703038 -118.990618)
		(end 17.78127 -119.392954)
		(stroke
			(width 0.068326)
			(type default)
		)
		(layer "F.Cu")
	)
	(gr_line
		(start 17.729454 -119.994426)
		(end 17.923764 -120.12549)
		(stroke
			(width 0.068326)
			(type default)
		)
		(layer "F.Cu")
	)
	(gr_line
		(start 17.737836 -117.00764)
		(end 17.934432 -116.880132)
		(stroke
			(width 0.068326)
			(type default)
		)
		(layer "F.Cu")
	)
	(gr_line
		(start 17.799558 -121.964704)
		(end 17.80413 -121.988072)
		(stroke
			(width 0.068326)
			(type default)
		)
		(layer "F.Cu")
	)
	(gr_line
		(start 17.80413 -121.988072)
		(end 17.817592 -122.008138)
		(stroke
			(width 0.068326)
			(type default)
		)
		(layer "F.Cu")
	)
	(gr_line
		(start 17.870932 -120.722136)
		(end 18.001996 -120.527826)
		(stroke
			(width 0.068326)
			(type default)
		)
		(layer "F.Cu")
	)
	(gr_line
		(start 17.875504 -80.778604)
		(end 17.911064 -80.743044)
		(stroke
			(width 0.068326)
			(type default)
		)
		(layer "F.Cu")
	)
	(gr_line
		(start 17.892014 -116.28247)
		(end 18.019776 -116.479066)
		(stroke
			(width 0.068326)
			(type default)
		)
		(layer "F.Cu")
	)
	(gr_line
		(start 17.911064 -80.090518)
		(end 17.911064 -80.743044)
		(stroke
			(width 0.068326)
			(type default)
		)
		(layer "F.Cu")
	)
	(gr_line
		(start 17.923764 -120.12549)
		(end 18.001996 -120.527826)
		(stroke
			(width 0.068326)
			(type default)
		)
		(layer "F.Cu")
	)
	(gr_line
		(start 17.925796 -114.645694)
		(end 17.92986 -114.626644)
		(stroke
			(width 0.068326)
			(type default)
		)
		(layer "F.Cu")
	)
	(gr_line
		(start 17.928844 -45.278548)
		(end 18.0975 -45.109892)
		(stroke
			(width 0.052324)
			(type default)
		)
		(layer "F.Cu")
	)
	(gr_line
		(start 17.929606 -114.626644)
		(end 17.92986 -114.626644)
		(stroke
			(width 0.068326)
			(type default)
		)
		(layer "F.Cu")
	)
	(gr_line
		(start 17.929606 -114.626644)
		(end 17.92986 -114.626136)
		(stroke
			(width 0.068326)
			(type default)
		)
		(layer "F.Cu")
	)
	(gr_line
		(start 17.92986 -114.626136)
		(end 17.941798 -114.608356)
		(stroke
			(width 0.068326)
			(type default)
		)
		(layer "F.Cu")
	)
	(gr_line
		(start 17.934432 -116.880132)
		(end 18.019776 -116.479066)
		(stroke
			(width 0.068326)
			(type default)
		)
		(layer "F.Cu")
	)
	(gr_line
		(start 17.978374 -115.876832)
		(end 18.17497 -115.74907)
		(stroke
			(width 0.068326)
			(type default)
		)
		(layer "F.Cu")
	)
	(gr_line
		(start 18.0975 -45.109892)
		(end 18.687034 -45.109892)
		(stroke
			(width 0.052324)
			(type default)
		)
		(layer "F.Cu")
	)
	(gr_line
		(start 18.132552 -115.151662)
		(end 18.26006 -115.348004)
		(stroke
			(width 0.068326)
			(type default)
		)
		(layer "F.Cu")
	)
	(gr_line
		(start 18.17497 -115.74907)
		(end 18.26006 -115.348004)
		(stroke
			(width 0.068326)
			(type default)
		)
		(layer "F.Cu")
	)
	(gr_line
		(start 18.236692 -47.649892)
		(end 18.43532 -47.84852)
		(stroke
			(width 0.052324)
			(type default)
		)
		(layer "F.Cu")
	)
	(gr_line
		(start 18.31594 -114.052858)
		(end 18.69059 -113.496598)
		(stroke
			(width 0.068326)
			(type default)
		)
		(layer "F.Cu")
	)
	(gr_line
		(start 18.410936 -80.800194)
		(end 18.477992 -80.86725)
		(stroke
			(width 0.068326)
			(type default)
		)
		(layer "F.Cu")
	)
	(gr_line
		(start 18.410936 -80.090518)
		(end 18.410936 -80.800194)
		(stroke
			(width 0.068326)
			(type default)
		)
		(layer "F.Cu")
	)
	(gr_line
		(start 18.410936 -71.888096)
		(end 18.418302 -71.895462)
		(stroke
			(width 0.052324)
			(type default)
		)
		(layer "F.Cu")
	)
	(gr_line
		(start 18.410936 -71.242682)
		(end 18.410936 -71.888096)
		(stroke
			(width 0.052324)
			(type default)
		)
		(layer "F.Cu")
	)
	(gr_line
		(start 18.551398 -114.253772)
		(end 18.781522 -114.20856)
		(stroke
			(width 0.068326)
			(type default)
		)
		(layer "F.Cu")
	)
	(gr_line
		(start 18.57375 -73.210674)
		(end 18.735802 -73.048622)
		(stroke
			(width 0.052324)
			(type default)
		)
		(layer "F.Cu")
	)
	(gr_line
		(start 18.6944 -58.239406)
		(end 19.008852 -57.924954)
		(stroke
			(width 0.052324)
			(type default)
		)
		(layer "F.Cu")
	)
	(gr_line
		(start 18.6944 -52.0192)
		(end 19.021552 -52.346352)
		(stroke
			(width 0.052324)
			(type default)
		)
		(layer "F.Cu")
	)
	(gr_line
		(start 18.6944 -52.0192)
		(end 19.021552 -51.692048)
		(stroke
			(width 0.052324)
			(type default)
		)
		(layer "F.Cu")
	)
	(gr_line
		(start 18.7452 -56.9849)
		(end 19.008852 -57.248552)
		(stroke
			(width 0.052324)
			(type default)
		)
		(layer "F.Cu")
	)
	(gr_line
		(start 18.7452 -56.0959)
		(end 19.008852 -55.832248)
		(stroke
			(width 0.052324)
			(type default)
		)
		(layer "F.Cu")
	)
	(gr_line
		(start 18.7452 -53.1749)
		(end 19.008852 -52.911248)
		(stroke
			(width 0.052324)
			(type default)
		)
		(layer "F.Cu")
	)
	(gr_line
		(start 18.781522 -114.20856)
		(end 19.01063 -113.868708)
		(stroke
			(width 0.068326)
			(type default)
		)
		(layer "F.Cu")
	)
	(gr_line
		(start 18.8468 -54.998112)
		(end 19.008852 -55.160164)
		(stroke
			(width 0.052324)
			(type default)
		)
		(layer "F.Cu")
	)
	(gr_line
		(start 18.852134 -81.90738)
		(end 19.04111 -81.718404)
		(stroke
			(width 0.068326)
			(type default)
		)
		(layer "F.Cu")
	)
	(gr_line
		(start 18.906998 -71.895462)
		(end 18.911062 -71.891398)
		(stroke
			(width 0.052324)
			(type default)
		)
		(layer "F.Cu")
	)
	(gr_line
		(start 18.911062 -80.090518)
		(end 18.911062 -80.865726)
		(stroke
			(width 0.068326)
			(type default)
		)
		(layer "F.Cu")
	)
	(gr_line
		(start 18.911062 -71.242682)
		(end 18.911062 -71.891398)
		(stroke
			(width 0.052324)
			(type default)
		)
		(layer "F.Cu")
	)
	(gr_line
		(start 18.924016 -47.84852)
		(end 19.122644 -47.649892)
		(stroke
			(width 0.052324)
			(type default)
		)
		(layer "F.Cu")
	)
	(gr_line
		(start 18.961862 -113.093754)
		(end 19.33702 -112.536732)
		(stroke
			(width 0.068326)
			(type default)
		)
		(layer "F.Cu")
	)
	(gr_line
		(start 18.965672 -113.638584)
		(end 19.01063 -113.868708)
		(stroke
			(width 0.068326)
			(type default)
		)
		(layer "F.Cu")
	)
	(gr_line
		(start 19.051524 -123.8377)
		(end 19.064224 -123.856496)
		(stroke
			(width 0.068326)
			(type default)
		)
		(layer "F.Cu")
	)
	(gr_line
		(start 19.064224 -123.856496)
		(end 19.083528 -123.869196)
		(stroke
			(width 0.068326)
			(type default)
		)
		(layer "F.Cu")
	)
	(gr_line
		(start 19.122644 -47.649892)
		(end 19.712178 -47.649892)
		(stroke
			(width 0.052324)
			(type default)
		)
		(layer "F.Cu")
	)
	(gr_line
		(start 19.19732 -113.294414)
		(end 19.427444 -113.24971)
		(stroke
			(width 0.068326)
			(type default)
		)
		(layer "F.Cu")
	)
	(gr_line
		(start 19.224498 -73.048622)
		(end 19.38655 -73.210674)
		(stroke
			(width 0.052324)
			(type default)
		)
		(layer "F.Cu")
	)
	(gr_line
		(start 19.427444 -113.24971)
		(end 19.656552 -112.909858)
		(stroke
			(width 0.068326)
			(type default)
		)
		(layer "F.Cu")
	)
	(gr_line
		(start 19.475958 -81.718404)
		(end 19.664934 -81.90738)
		(stroke
			(width 0.068326)
			(type default)
		)
		(layer "F.Cu")
	)
	(gr_line
		(start 19.49196 -124.136404)
		(end 20.05076 -124.502164)
		(stroke
			(width 0.068326)
			(type default)
		)
		(layer "F.Cu")
	)
	(gr_line
		(start 19.497548 -57.924954)
		(end 19.812 -58.239406)
		(stroke
			(width 0.052324)
			(type default)
		)
		(layer "F.Cu")
	)
	(gr_line
		(start 19.497548 -57.248552)
		(end 19.7612 -56.9849)
		(stroke
			(width 0.052324)
			(type default)
		)
		(layer "F.Cu")
	)
	(gr_line
		(start 19.497548 -55.832248)
		(end 19.7612 -56.0959)
		(stroke
			(width 0.052324)
			(type default)
		)
		(layer "F.Cu")
	)
	(gr_line
		(start 19.497548 -55.160164)
		(end 19.6596 -54.998112)
		(stroke
			(width 0.052324)
			(type default)
		)
		(layer "F.Cu")
	)
	(gr_line
		(start 19.497548 -52.911248)
		(end 19.7612 -53.1749)
		(stroke
			(width 0.052324)
			(type default)
		)
		(layer "F.Cu")
	)
	(gr_line
		(start 19.509994 -51.691794)
		(end 19.8374 -52.0192)
		(stroke
			(width 0.052324)
			(type default)
		)
		(layer "F.Cu")
	)
	(gr_line
		(start 19.510248 -52.346352)
		(end 19.8374 -52.0192)
		(stroke
			(width 0.052324)
			(type default)
		)
		(layer "F.Cu")
	)
	(gr_line
		(start 19.608546 -112.134142)
		(end 19.982434 -111.578644)
		(stroke
			(width 0.068326)
			(type default)
		)
		(layer "F.Cu")
	)
	(gr_line
		(start 19.611594 -112.679734)
		(end 19.656552 -112.909858)
		(stroke
			(width 0.068326)
			(type default)
		)
		(layer "F.Cu")
	)
	(gr_line
		(start 19.62912 -123.858782)
		(end 19.858482 -123.810776)
		(stroke
			(width 0.068326)
			(type default)
		)
		(layer "F.Cu")
	)
	(gr_line
		(start 19.843242 -112.335564)
		(end 20.073366 -112.290606)
		(stroke
			(width 0.068326)
			(type default)
		)
		(layer "F.Cu")
	)
	(gr_line
		(start 19.858482 -123.810776)
		(end 20.201382 -124.035312)
		(stroke
			(width 0.068326)
			(type default)
		)
		(layer "F.Cu")
	)
	(gr_line
		(start 19.91106 -80.869282)
		(end 19.943572 -80.901794)
		(stroke
			(width 0.068326)
			(type default)
		)
		(layer "F.Cu")
	)
	(gr_line
		(start 19.91106 -80.090518)
		(end 19.91106 -80.869282)
		(stroke
			(width 0.068326)
			(type default)
		)
		(layer "F.Cu")
	)
	(gr_line
		(start 20.073366 -112.290606)
		(end 20.302474 -111.950754)
		(stroke
			(width 0.068326)
			(type default)
		)
		(layer "F.Cu")
	)
	(gr_line
		(start 20.201382 -124.035312)
		(end 20.249388 -124.264928)
		(stroke
			(width 0.068326)
			(type default)
		)
		(layer "F.Cu")
	)
	(gr_line
		(start 20.254214 -111.175038)
		(end 20.627848 -110.620556)
		(stroke
			(width 0.068326)
			(type default)
		)
		(layer "F.Cu")
	)
	(gr_line
		(start 20.257516 -111.72063)
		(end 20.302474 -111.950754)
		(stroke
			(width 0.068326)
			(type default)
		)
		(layer "F.Cu")
	)
	(gr_line
		(start 20.37842 -80.901794)
		(end 20.410932 -80.869282)
		(stroke
			(width 0.068326)
			(type default)
		)
		(layer "F.Cu")
	)
	(gr_arc
		(start 20.3962 -87.4268)
		(mid 20.577857 -87.244)
		(end 20.644358 -86.995)
		(stroke
			(width 0.068326)
			(type default)
		)
		(layer "F.Cu")
	)
	(gr_line
		(start 20.410932 -80.090518)
		(end 20.410932 -80.869282)
		(stroke
			(width 0.068326)
			(type default)
		)
		(layer "F.Cu")
	)
	(gr_line
		(start 20.474686 -124.779532)
		(end 21.033232 -125.144784)
		(stroke
			(width 0.068326)
			(type default)
		)
		(layer "F.Cu")
	)
	(gr_line
		(start 20.489164 -111.37646)
		(end 20.719288 -111.331502)
		(stroke
			(width 0.068326)
			(type default)
		)
		(layer "F.Cu")
	)
	(gr_line
		(start 20.612608 -124.502418)
		(end 20.84197 -124.454666)
		(stroke
			(width 0.068326)
			(type default)
		)
		(layer "F.Cu")
	)
	(gr_line
		(start 20.6502 -84.2645)
		(end 20.864576 -84.478876)
		(stroke
			(width 0.068326)
			(type default)
		)
		(layer "F.Cu")
	)
	(gr_line
		(start 20.6502 -83.3755)
		(end 20.864576 -83.161124)
		(stroke
			(width 0.068326)
			(type default)
		)
		(layer "F.Cu")
	)
	(gr_line
		(start 20.719288 -111.331502)
		(end 20.948396 -110.99165)
		(stroke
			(width 0.068326)
			(type default)
		)
		(layer "F.Cu")
	)
	(gr_line
		(start 20.84197 -124.454666)
		(end 21.185124 -124.679202)
		(stroke
			(width 0.068326)
			(type default)
		)
		(layer "F.Cu")
	)
	(gr_line
		(start 20.903438 -110.76178)
		(end 20.948396 -110.99165)
		(stroke
			(width 0.068326)
			(type default)
		)
		(layer "F.Cu")
	)
	(gr_arc
		(start 20.949158 -86.995)
		(mid 21.019132 -87.246969)
		(end 21.209 -87.4268)
		(stroke
			(width 0.068326)
			(type default)
		)
		(layer "F.Cu")
	)
	(gr_arc
		(start 21.069808 -112.951768)
		(mid 21.049823 -112.968804)
		(end 21.033486 -112.98936)
		(stroke
			(width 0.068326)
			(type default)
		)
		(layer "F.Cu")
	)
	(gr_line
		(start 21.185124 -124.679202)
		(end 21.232876 -124.908564)
		(stroke
			(width 0.068326)
			(type default)
		)
		(layer "F.Cu")
	)
	(gr_line
		(start 21.299424 -84.478876)
		(end 21.5138 -84.2645)
		(stroke
			(width 0.068326)
			(type default)
		)
		(layer "F.Cu")
	)
	(gr_line
		(start 21.299424 -83.161124)
		(end 21.5138 -83.3755)
		(stroke
			(width 0.068326)
			(type default)
		)
		(layer "F.Cu")
	)
	(gr_line
		(start 21.444204 -109.804708)
		(end 22.001988 -109.430312)
		(stroke
			(width 0.068326)
			(type default)
		)
		(layer "F.Cu")
	)
	(gr_line
		(start 21.586444 -110.079282)
		(end 21.816822 -110.124494)
		(stroke
			(width 0.068326)
			(type default)
		)
		(layer "F.Cu")
	)
	(gr_line
		(start 21.816822 -110.124494)
		(end 22.157182 -109.896148)
		(stroke
			(width 0.068326)
			(type default)
		)
		(layer "F.Cu")
	)
	(gr_line
		(start 22.057614 -124.10694)
		(end 22.28469 -124.334016)
		(stroke
			(width 0.068326)
			(type default)
		)
		(layer "F.Cu")
	)
	(gr_line
		(start 22.057614 -123.672092)
		(end 22.28469 -123.445016)
		(stroke
			(width 0.068326)
			(type default)
		)
		(layer "F.Cu")
	)
	(gr_line
		(start 22.157182 -109.896148)
		(end 22.202648 -109.666024)
		(stroke
			(width 0.068326)
			(type default)
		)
		(layer "F.Cu")
	)
	(gr_line
		(start 22.19706 -125.906784)
		(end 22.24024 -125.934978)
		(stroke
			(width 0.068326)
			(type default)
		)
		(layer "F.Cu")
	)
	(gr_line
		(start 22.282404 -112.105186)
		(end 22.28977 -112.100868)
		(stroke
			(width 0.068326)
			(type default)
		)
		(layer "F.Cu")
	)
	(gr_line
		(start 22.3901 -50.6476)
		(end 22.717252 -50.974752)
		(stroke
			(width 0.052324)
			(type default)
		)
		(layer "F.Cu")
	)
	(gr_line
		(start 22.3901 -50.6476)
		(end 22.717252 -50.320448)
		(stroke
			(width 0.052324)
			(type default)
		)
		(layer "F.Cu")
	)
	(gr_line
		(start 22.417786 -56.688736)
		(end 22.732238 -56.374284)
		(stroke
			(width 0.052324)
			(type default)
		)
		(layer "F.Cu")
	)
	(gr_line
		(start 22.43836 -112.36706)
		(end 22.441154 -112.365282)
		(stroke
			(width 0.068326)
			(type default)
		)
		(layer "F.Cu")
	)
	(gr_line
		(start 22.4536 -55.5625)
		(end 22.717252 -55.826152)
		(stroke
			(width 0.052324)
			(type default)
		)
		(layer "F.Cu")
	)
	(gr_line
		(start 22.4536 -54.6735)
		(end 22.717252 -54.409848)
		(stroke
			(width 0.052324)
			(type default)
		)
		(layer "F.Cu")
	)
	(gr_line
		(start 22.4536 -51.7779)
		(end 22.717252 -51.514248)
		(stroke
			(width 0.052324)
			(type default)
		)
		(layer "F.Cu")
	)
	(gr_arc
		(start 22.5044 -114.41303)
		(mid 22.560543 -114.41026)
		(end 22.61616 -114.402108)
		(stroke
			(width 0.068326)
			(type default)
		)
		(layer "F.Cu")
	)
	(gr_line
		(start 22.5552 -53.556154)
		(end 22.717252 -53.718206)
		(stroke
			(width 0.052324)
			(type default)
		)
		(layer "F.Cu")
	)
	(gr_line
		(start 22.61616 -114.402108)
		(end 22.639274 -114.398806)
		(stroke
			(width 0.068326)
			(type default)
		)
		(layer "F.Cu")
	)
	(gr_arc
		(start 22.639274 -114.398806)
		(mid 22.661989 -114.393616)
		(end 22.68347 -114.384582)
		(stroke
			(width 0.068326)
			(type default)
		)
		(layer "F.Cu")
	)
	(gr_line
		(start 22.68347 -114.384582)
		(end 22.771862 -114.337338)
		(stroke
			(width 0.068326)
			(type default)
		)
		(layer "F.Cu")
	)
	(gr_arc
		(start 22.692868 -114.739928)
		(mid 22.638204 -114.723386)
		(end 22.581362 -114.71783)
		(stroke
			(width 0.068326)
			(type default)
		)
		(layer "F.Cu")
	)
	(gr_line
		(start 22.692868 -114.739928)
		(end 22.75078 -114.764058)
		(stroke
			(width 0.068326)
			(type default)
		)
		(layer "F.Cu")
	)
	(gr_line
		(start 22.743668 -125.627638)
		(end 22.909276 -125.46203)
		(stroke
			(width 0.068326)
			(type default)
		)
		(layer "F.Cu")
	)
	(gr_arc
		(start 22.771862 -114.337338)
		(mid 22.875837 -114.271632)
		(end 22.968966 -114.191288)
		(stroke
			(width 0.068326)
			(type default)
		)
		(layer "F.Cu")
	)
	(gr_line
		(start 22.909276 -125.46203)
		(end 23.319232 -125.46203)
		(stroke
			(width 0.068326)
			(type default)
		)
		(layer "F.Cu")
	)
	(gr_arc
		(start 22.94763 -114.89563)
		(mid 22.855674 -114.820167)
		(end 22.75078 -114.764058)
		(stroke
			(width 0.068326)
			(type default)
		)
		(layer "F.Cu")
	)
	(gr_line
		(start 22.94763 -114.89563)
		(end 23.1648 -115.1128)
		(stroke
			(width 0.068326)
			(type default)
		)
		(layer "F.Cu")
	)
	(gr_line
		(start 22.95017 -127.418846)
		(end 22.963632 -127.418846)
		(stroke
			(width 0.060198)
			(type default)
		)
		(layer "F.Cu")
	)
	(gr_line
		(start 22.968966 -114.191288)
		(end 23.1648 -113.9952)
		(stroke
			(width 0.068326)
			(type default)
		)
		(layer "F.Cu")
	)
	(gr_line
		(start 23.048468 -125.934978)
		(end 23.18004 -125.934978)
		(stroke
			(width 0.068326)
			(type default)
		)
		(layer "F.Cu")
	)
	(gr_line
		(start 23.17369 -124.334016)
		(end 23.45055 -124.334016)
		(stroke
			(width 0.068326)
			(type default)
		)
		(layer "F.Cu")
	)
	(gr_line
		(start 23.17369 -123.445016)
		(end 23.75535 -124.026676)
		(stroke
			(width 0.068326)
			(type default)
		)
		(layer "F.Cu")
	)
	(gr_line
		(start 23.205948 -55.826152)
		(end 23.4696 -55.5625)
		(stroke
			(width 0.052324)
			(type default)
		)
		(layer "F.Cu")
	)
	(gr_line
		(start 23.205948 -54.409848)
		(end 23.4696 -54.6735)
		(stroke
			(width 0.052324)
			(type default)
		)
		(layer "F.Cu")
	)
	(gr_line
		(start 23.205948 -53.718206)
		(end 23.368 -53.556154)
		(stroke
			(width 0.052324)
			(type default)
		)
		(layer "F.Cu")
	)
	(gr_line
		(start 23.205948 -51.514248)
		(end 23.4696 -51.7779)
		(stroke
			(width 0.052324)
			(type default)
		)
		(layer "F.Cu")
	)
	(gr_line
		(start 23.205948 -50.974752)
		(end 23.5331 -50.6476)
		(stroke
			(width 0.052324)
			(type default)
		)
		(layer "F.Cu")
	)
	(gr_line
		(start 23.205948 -50.320448)
		(end 23.5331 -50.6476)
		(stroke
			(width 0.052324)
			(type default)
		)
		(layer "F.Cu")
	)
	(gr_line
		(start 23.220934 -56.374284)
		(end 23.535386 -56.688736)
		(stroke
			(width 0.052324)
			(type default)
		)
		(layer "F.Cu")
	)
	(gr_line
		(start 23.319232 -125.46203)
		(end 23.48484 -125.627638)
		(stroke
			(width 0.068326)
			(type default)
		)
		(layer "F.Cu")
	)
	(gr_line
		(start 23.45182 -127.197358)
		(end 23.465282 -127.197358)
		(stroke
			(width 0.060198)
			(type default)
		)
		(layer "F.Cu")
	)
	(gr_arc
		(start 23.672292 -111.810292)
		(mid 24.118675 -111.698019)
		(end 24.473154 -111.4044)
		(stroke
			(width 0.068326)
			(type default)
		)
		(layer "F.Cu")
	)
	(gr_line
		(start 24.052022 -109.053122)
		(end 24.394922 -109.396022)
		(stroke
			(width 0.068326)
			(type default)
		)
		(layer "F.Cu")
	)
	(gr_line
		(start 24.053292 -108.743242)
		(end 24.395176 -108.401612)
		(stroke
			(width 0.068326)
			(type default)
		)
		(layer "F.Cu")
	)
	(gr_line
		(start 24.170386 -124.026676)
		(end 24.355298 -123.841764)
		(stroke
			(width 0.068326)
			(type default)
		)
		(layer "F.Cu")
	)
	(gr_line
		(start 24.355298 -123.841764)
		(end 24.765254 -123.841764)
		(stroke
			(width 0.068326)
			(type default)
		)
		(layer "F.Cu")
	)
	(gr_line
		(start 24.394922 -109.396022)
		(end 24.67483 -109.116114)
		(stroke
			(width 0.068326)
			(type default)
		)
		(layer "F.Cu")
	)
	(gr_line
		(start 24.395176 -108.401612)
		(end 24.395684 -108.40212)
		(stroke
			(width 0.068326)
			(type default)
		)
		(layer "F.Cu")
	)
	(gr_line
		(start 24.395684 -108.40212)
		(end 24.67483 -108.681266)
		(stroke
			(width 0.068326)
			(type default)
		)
		(layer "F.Cu")
	)
	(gr_arc
		(start 24.473154 -112.522)
		(mid 24.107573 -112.2227)
		(end 23.6474 -112.1156)
		(stroke
			(width 0.068326)
			(type default)
		)
		(layer "F.Cu")
	)
	(gr_line
		(start 24.475186 -124.334016)
		(end 24.645366 -124.334016)
		(stroke
			(width 0.068326)
			(type default)
		)
		(layer "F.Cu")
	)
	(gr_line
		(start 24.540464 -126.000002)
		(end 24.60244 -126.061978)
		(stroke
			(width 0.068326)
			(type default)
		)
		(layer "F.Cu")
	)
	(gr_line
		(start 24.540464 -125.565154)
		(end 24.60244 -125.503178)
		(stroke
			(width 0.068326)
			(type default)
		)
		(layer "F.Cu")
	)
	(gr_line
		(start 24.60244 -126.061978)
		(end 24.736298 -125.92812)
		(stroke
			(width 0.0508)
			(type default)
		)
		(layer "F.Cu")
	)
	(gr_line
		(start 24.60244 -125.503178)
		(end 24.736298 -125.637036)
		(stroke
			(width 0.0508)
			(type default)
		)
		(layer "F.Cu")
	)
	(gr_line
		(start 24.738076 -125.926342)
		(end 24.78024 -125.884178)
		(stroke
			(width 0.0508)
			(type default)
		)
		(layer "F.Cu")
	)
	(gr_line
		(start 24.738076 -125.638814)
		(end 24.78024 -125.680978)
		(stroke
			(width 0.0508)
			(type default)
		)
		(layer "F.Cu")
	)
	(gr_line
		(start 24.75992 -67.67068)
		(end 24.8539 -67.76466)
		(stroke
			(width 0.060198)
			(type default)
		)
		(layer "F.Cu")
	)
	(gr_line
		(start 24.765254 -123.841764)
		(end 24.950166 -124.026676)
		(stroke
			(width 0.068326)
			(type default)
		)
		(layer "F.Cu")
	)
	(gr_line
		(start 24.8539 -67.76466)
		(end 24.8539 -69.088)
		(stroke
			(width 0.060198)
			(type default)
		)
		(layer "F.Cu")
	)
	(gr_line
		(start 24.997918 -122.1994)
		(end 25.015444 -122.206258)
		(stroke
			(width 0.068326)
			(type default)
		)
		(layer "F.Cu")
	)
	(gr_line
		(start 25.140158 -109.113574)
		(end 25.419304 -109.39272)
		(stroke
			(width 0.068326)
			(type default)
		)
		(layer "F.Cu")
	)
	(gr_line
		(start 25.140158 -108.678726)
		(end 25.420066 -108.398818)
		(stroke
			(width 0.068326)
			(type default)
		)
		(layer "F.Cu")
	)
	(gr_line
		(start 25.365202 -124.026676)
		(end 25.550114 -123.841764)
		(stroke
			(width 0.068326)
			(type default)
		)
		(layer "F.Cu")
	)
	(gr_line
		(start 25.419304 -109.39272)
		(end 25.699212 -109.112812)
		(stroke
			(width 0.068326)
			(type default)
		)
		(layer "F.Cu")
	)
	(gr_line
		(start 25.420066 -108.398818)
		(end 25.699212 -108.677964)
		(stroke
			(width 0.068326)
			(type default)
		)
		(layer "F.Cu")
	)
	(gr_line
		(start 25.550114 -123.841764)
		(end 25.96007 -123.841764)
		(stroke
			(width 0.068326)
			(type default)
		)
		(layer "F.Cu")
	)
	(gr_line
		(start 25.670002 -124.334016)
		(end 25.840182 -124.334016)
		(stroke
			(width 0.068326)
			(type default)
		)
		(layer "F.Cu")
	)
	(gr_line
		(start 25.7429 -69.088)
		(end 26.0477 -69.3928)
		(stroke
			(width 0.060198)
			(type default)
		)
		(layer "F.Cu")
	)
	(gr_line
		(start 25.863804 -125.437138)
		(end 25.962864 -125.338078)
		(stroke
			(width 0.0508)
			(type default)
		)
		(layer "F.Cu")
	)
	(gr_line
		(start 25.96007 -123.841764)
		(end 26.144982 -124.026676)
		(stroke
			(width 0.068326)
			(type default)
		)
		(layer "F.Cu")
	)
	(gr_line
		(start 25.962864 -125.338078)
		(end 26.267664 -125.338078)
		(stroke
			(width 0.0508)
			(type default)
		)
		(layer "F.Cu")
	)
	(gr_line
		(start 26.0477 -69.3928)
		(end 27.1272 -69.3928)
		(stroke
			(width 0.060198)
			(type default)
		)
		(layer "F.Cu")
	)
	(gr_line
		(start 26.067004 -125.642878)
		(end 26.163524 -125.642878)
		(stroke
			(width 0.0508)
			(type default)
		)
		(layer "F.Cu")
	)
	(gr_line
		(start 26.0731 -186.0042)
		(end 26.1366 -185.9407)
		(stroke
			(width 0.060198)
			(type default)
		)
		(layer "F.Cu")
	)
	(gr_line
		(start 26.0731 -184.8612)
		(end 26.1366 -184.9247)
		(stroke
			(width 0.060198)
			(type default)
		)
		(layer "F.Cu")
	)
	(gr_line
		(start 26.12898 -143.69796)
		(end 26.470356 -143.356584)
		(stroke
			(width 0.068326)
			(type default)
		)
		(layer "F.Cu")
	)
	(gr_line
		(start 26.12898 -142.58036)
		(end 26.470356 -142.921736)
		(stroke
			(width 0.068326)
			(type default)
		)
		(layer "F.Cu")
	)
	(gr_line
		(start 26.1366 -185.9407)
		(end 27.1526 -185.9407)
		(stroke
			(width 0.060198)
			(type default)
		)
		(layer "F.Cu")
	)
	(gr_line
		(start 26.1366 -184.9247)
		(end 27.1526 -184.9247)
		(stroke
			(width 0.060198)
			(type default)
		)
		(layer "F.Cu")
	)
	(gr_line
		(start 26.227532 -109.109764)
		(end 26.444448 -109.32668)
		(stroke
			(width 0.068326)
			(type default)
		)
		(layer "F.Cu")
	)
	(gr_line
		(start 26.227532 -108.674916)
		(end 26.443432 -108.459016)
		(stroke
			(width 0.068326)
			(type default)
		)
		(layer "F.Cu")
	)
	(gr_line
		(start 26.267664 -125.338078)
		(end 26.366724 -125.437138)
		(stroke
			(width 0.0508)
			(type default)
		)
		(layer "F.Cu")
	)
	(gr_line
		(start 26.9367 -58.4454)
		(end 27.555952 -59.064652)
		(stroke
			(width 0.060198)
			(type default)
		)
		(layer "F.Cu")
	)
	(gr_line
		(start 26.950924 -143.346424)
		(end 27.2415 -143.637)
		(stroke
			(width 0.068326)
			(type default)
		)
		(layer "F.Cu")
	)
	(gr_line
		(start 26.950924 -142.911576)
		(end 27.2415 -142.621)
		(stroke
			(width 0.068326)
			(type default)
		)
		(layer "F.Cu")
	)
	(gr_line
		(start 27.1272 -69.3928)
		(end 27.2542 -69.2658)
		(stroke
			(width 0.060198)
			(type default)
		)
		(layer "F.Cu")
	)
	(gr_line
		(start 27.1526 -185.9407)
		(end 27.2161 -186.0042)
		(stroke
			(width 0.060198)
			(type default)
		)
		(layer "F.Cu")
	)
	(gr_line
		(start 27.1526 -184.9247)
		(end 27.2161 -184.8612)
		(stroke
			(width 0.060198)
			(type default)
		)
		(layer "F.Cu")
	)
	(gr_line
		(start 27.2161 -186.0042)
		(end 28.2956 -186.0042)
		(stroke
			(width 0.060198)
			(type default)
		)
		(layer "F.Cu")
	)
	(gr_line
		(start 27.2161 -184.8612)
		(end 28.2956 -184.8612)
		(stroke
			(width 0.060198)
			(type default)
		)
		(layer "F.Cu")
	)
	(gr_line
		(start 27.2542 -69.2658)
		(end 27.800808 -68.719192)
		(stroke
			(width 0.060198)
			(type default)
		)
		(layer "F.Cu")
	)
	(gr_line
		(start 27.320748 -124.932948)
		(end 27.409902 -125.022102)
		(stroke
			(width 0.068326)
			(type default)
		)
		(layer "F.Cu")
	)
	(gr_line
		(start 27.322272 -124.499878)
		(end 27.624278 -124.499878)
		(stroke
			(width 0.068326)
			(type default)
		)
		(layer "F.Cu")
	)
	(gr_line
		(start 27.332432 -108.459016)
		(end 27.549348 -108.675932)
		(stroke
			(width 0.068326)
			(type default)
		)
		(layer "F.Cu")
	)
	(gr_line
		(start 27.333448 -109.32668)
		(end 27.549348 -109.11078)
		(stroke
			(width 0.068326)
			(type default)
		)
		(layer "F.Cu")
	)
	(gr_line
		(start 27.555952 -59.064652)
		(end 28.750768 -59.064652)
		(stroke
			(width 0.060198)
			(type default)
		)
		(layer "F.Cu")
	)
	(gr_line
		(start 27.624278 -124.499878)
		(end 27.842972 -124.718572)
		(stroke
			(width 0.068326)
			(type default)
		)
		(layer "F.Cu")
	)
	(gr_line
		(start 27.642058 -67.064128)
		(end 27.800808 -67.222878)
		(stroke
			(width 0.060198)
			(type default)
		)
		(layer "F.Cu")
	)
	(gr_line
		(start 27.642058 -65.294764)
		(end 27.642058 -67.064128)
		(stroke
			(width 0.060198)
			(type default)
		)
		(layer "F.Cu")
	)
	(gr_line
		(start 27.800808 -67.222878)
		(end 27.800808 -68.719192)
		(stroke
			(width 0.060198)
			(type default)
		)
		(layer "F.Cu")
	)
	(gr_line
		(start 27.8257 -58.4454)
		(end 29.303726 -58.4454)
		(stroke
			(width 0.060198)
			(type default)
		)
		(layer "F.Cu")
	)
	(gr_line
		(start 27.842972 -124.718572)
		(end 27.842972 -125.020578)
		(stroke
			(width 0.068326)
			(type default)
		)
		(layer "F.Cu")
	)
	(gr_line
		(start 28.043124 -105.935018)
		(end 28.14955 -106.041444)
		(stroke
			(width 0.068326)
			(type default)
		)
		(layer "F.Cu")
	)
	(gr_arc
		(start 28.1305 -142.621)
		(mid 28.258937 -142.874545)
		(end 28.5242 -142.9766)
		(stroke
			(width 0.068326)
			(type default)
		)
		(layer "F.Cu")
	)
	(gr_line
		(start 28.134564 -125.746764)
		(end 28.223972 -125.836172)
		(stroke
			(width 0.068326)
			(type default)
		)
		(layer "F.Cu")
	)
	(gr_line
		(start 28.136088 -125.313694)
		(end 28.438094 -125.313694)
		(stroke
			(width 0.068326)
			(type default)
		)
		(layer "F.Cu")
	)
	(gr_arc
		(start 28.14955 -106.44886)
		(mid 28.233929 -106.245152)
		(end 28.14955 -106.041444)
		(stroke
			(width 0.068326)
			(type default)
		)
		(layer "F.Cu")
	)
	(gr_line
		(start 28.2956 -186.0042)
		(end 28.510484 -185.789316)
		(stroke
			(width 0.060198)
			(type default)
		)
		(layer "F.Cu")
	)
	(gr_line
		(start 28.2956 -184.8612)
		(end 28.510484 -185.076084)
		(stroke
			(width 0.060198)
			(type default)
		)
		(layer "F.Cu")
	)
	(gr_arc
		(start 28.334716 -127.041148)
		(mid 28.344456 -127.050736)
		(end 28.354782 -127.05969)
		(stroke
			(width 0.0508)
			(type default)
		)
		(layer "F.Cu")
	)
	(gr_line
		(start 28.438094 -125.313694)
		(end 28.657042 -125.532642)
		(stroke
			(width 0.068326)
			(type default)
		)
		(layer "F.Cu")
	)
	(gr_arc
		(start 28.5242 -143.2814)
		(mid 28.258943 -143.383461)
		(end 28.1305 -143.637)
		(stroke
			(width 0.068326)
			(type default)
		)
		(layer "F.Cu")
	)
	(gr_line
		(start 28.657042 -125.532642)
		(end 28.657042 -125.834648)
		(stroke
			(width 0.068326)
			(type default)
		)
		(layer "F.Cu")
	)
	(gr_line
		(start 28.750768 -59.064652)
		(end 29.142182 -59.456066)
		(stroke
			(width 0.060198)
			(type default)
		)
		(layer "F.Cu")
	)
	(gr_arc
		(start 28.772612 -106.664506)
		(mid 28.568904 -106.580127)
		(end 28.365196 -106.664506)
		(stroke
			(width 0.068326)
			(type default)
		)
		(layer "F.Cu")
	)
	(gr_line
		(start 28.772612 -106.664506)
		(end 28.833572 -106.725466)
		(stroke
			(width 0.068326)
			(type default)
		)
		(layer "F.Cu")
	)
	(gr_line
		(start 29.096462 -129.68478)
		(end 30.03042 -129.68478)
		(stroke
			(width 0.060198)
			(type default)
		)
		(layer "F.Cu")
	)
	(gr_line
		(start 29.142182 -59.456066)
		(end 29.142182 -60.704984)
		(stroke
			(width 0.060198)
			(type default)
		)
		(layer "F.Cu")
	)
	(gr_line
		(start 29.246068 -142.965424)
		(end 29.250132 -142.96136)
		(stroke
			(width 0.068326)
			(type default)
		)
		(layer "F.Cu")
	)
	(gr_line
		(start 29.303726 -58.4454)
		(end 30.4292 -59.570874)
		(stroke
			(width 0.060198)
			(type default)
		)
		(layer "F.Cu")
	)
	(gr_line
		(start 29.304488 -129.18313)
		(end 29.406596 -129.285238)
		(stroke
			(width 0.060198)
			(type default)
		)
		(layer "F.Cu")
	)
	(gr_line
		(start 29.314902 -125.453902)
		(end 29.41447 -125.55347)
		(stroke
			(width 0.068326)
			(type default)
		)
		(layer "F.Cu")
	)
	(gr_arc
		(start 29.315664 -127.046736)
		(mid 29.478151 -127.022112)
		(end 29.626052 -126.95047)
		(stroke
			(width 0.0508)
			(type default)
		)
		(layer "F.Cu")
	)
	(gr_line
		(start 29.406596 -129.285238)
		(end 29.704538 -129.285238)
		(stroke
			(width 0.060198)
			(type default)
		)
		(layer "F.Cu")
	)
	(gr_arc
		(start 29.41447 -125.55347)
		(mid 29.530437 -125.630897)
		(end 29.6672 -125.658118)
		(stroke
			(width 0.068326)
			(type default)
		)
		(layer "F.Cu")
	)
	(gr_arc
		(start 29.50464 -125.212094)
		(mid 29.589309 -125.265738)
		(end 29.687774 -125.284484)
		(stroke
			(width 0.068326)
			(type default)
		)
		(layer "F.Cu")
	)
	(gr_line
		(start 29.521404 -127.249936)
		(end 29.623766 -127.249936)
		(stroke
			(width 0.0508)
			(type default)
		)
		(layer "F.Cu")
	)
	(gr_arc
		(start 29.539946 -126.153164)
		(mid 29.629163 -126.135384)
		(end 29.704792 -126.084838)
		(stroke
			(width 0.068326)
			(type default)
		)
		(layer "F.Cu")
	)
	(gr_arc
		(start 29.623766 -127.249936)
		(mid 29.722503 -127.245959)
		(end 29.820616 -127.234188)
		(stroke
			(width 0.0508)
			(type default)
		)
		(layer "F.Cu")
	)
	(gr_arc
		(start 29.626052 -126.95047)
		(mid 29.666404 -126.920007)
		(end 29.703776 -126.885954)
		(stroke
			(width 0.0508)
			(type default)
		)
		(layer "F.Cu")
	)
	(gr_line
		(start 29.6672 -125.658118)
		(end 29.74848 -125.658118)
		(stroke
			(width 0.068326)
			(type default)
		)
		(layer "F.Cu")
	)
	(gr_arc
		(start 29.687774 -125.284484)
		(mid 29.69628 -125.284854)
		(end 29.704792 -125.284992)
		(stroke
			(width 0.068326)
			(type default)
		)
		(layer "F.Cu")
	)
	(gr_line
		(start 29.703776 -126.885954)
		(end 29.704792 -126.884938)
		(stroke
			(width 0.0508)
			(type default)
		)
		(layer "F.Cu")
	)
	(gr_line
		(start 29.704538 -129.285238)
		(end 29.704792 -129.284984)
		(stroke
			(width 0.060198)
			(type default)
		)
		(layer "F.Cu")
	)
	(gr_arc
		(start 29.7434 -126.457964)
		(mid 30.167403 -126.359674)
		(end 30.504892 -126.084838)
		(stroke
			(width 0.068326)
			(type default)
		)
		(layer "F.Cu")
	)
	(gr_arc
		(start 29.74848 -125.658118)
		(mid 29.822031 -125.650876)
		(end 29.892752 -125.629416)
		(stroke
			(width 0.068326)
			(type default)
		)
		(layer "F.Cu")
	)
	(gr_arc
		(start 29.820616 -127.234188)
		(mid 30.19035 -127.113637)
		(end 30.504892 -126.884938)
		(stroke
			(width 0.0508)
			(type default)
		)
		(layer "F.Cu")
	)
	(gr_line
		(start 29.85135 -140.08354)
		(end 29.85135 -140.300456)
		(stroke
			(width 0.068326)
			(type default)
		)
		(layer "F.Cu")
	)
	(gr_line
		(start 29.85135 -140.08354)
		(end 30.141418 -139.793726)
		(stroke
			(width 0.068326)
			(type default)
		)
		(layer "F.Cu")
	)
	(gr_line
		(start 29.892752 -125.629416)
		(end 30.019752 -125.576838)
		(stroke
			(width 0.068326)
			(type default)
		)
		(layer "F.Cu")
	)
	(gr_arc
		(start 30.019752 -125.576838)
		(mid 30.143573 -125.518253)
		(end 30.261052 -125.447806)
		(stroke
			(width 0.068326)
			(type default)
		)
		(layer "F.Cu")
	)
	(gr_line
		(start 30.03042 -129.68478)
		(end 30.430216 -129.284984)
		(stroke
			(width 0.060198)
			(type default)
		)
		(layer "F.Cu")
	)
	(gr_line
		(start 30.141418 -139.793726)
		(end 30.35808 -139.793726)
		(stroke
			(width 0.068326)
			(type default)
		)
		(layer "F.Cu")
	)
	(gr_line
		(start 30.261052 -125.447806)
		(end 30.504892 -125.284992)
		(stroke
			(width 0.068326)
			(type default)
		)
		(layer "F.Cu")
	)
	(gr_line
		(start 30.28442 -140.30198)
		(end 30.359604 -140.226796)
		(stroke
			(width 0.068326)
			(type default)
		)
		(layer "F.Cu")
	)
	(gr_line
		(start 30.305756 -185.687462)
		(end 30.63748 -186.019186)
		(stroke
			(width 0.060198)
			(type default)
		)
		(layer "F.Cu")
	)
	(gr_line
		(start 30.305756 -184.974484)
		(end 30.63748 -184.64276)
		(stroke
			(width 0.060198)
			(type default)
		)
		(layer "F.Cu")
	)
	(gr_line
		(start 30.430216 -129.284984)
		(end 30.504892 -129.284984)
		(stroke
			(width 0.060198)
			(type default)
		)
		(layer "F.Cu")
	)
	(gr_line
		(start 30.504892 -138.884914)
		(end 30.833314 -138.884914)
		(stroke
			(width 0.068326)
			(type default)
		)
		(layer "F.Cu")
	)
	(gr_line
		(start 30.63748 -186.019186)
		(end 30.63748 -187.4393)
		(stroke
			(width 0.060198)
			(type default)
		)
		(layer "F.Cu")
	)
	(gr_line
		(start 30.63748 -183.2991)
		(end 30.63748 -184.64276)
		(stroke
			(width 0.060198)
			(type default)
		)
		(layer "F.Cu")
	)
	(gr_line
		(start 30.833314 -138.884914)
		(end 30.9118 -138.9634)
		(stroke
			(width 0.068326)
			(type default)
		)
		(layer "F.Cu")
	)
	(gr_line
		(start 31.28772 -186.053476)
		(end 31.28772 -187.4393)
		(stroke
			(width 0.060198)
			(type default)
		)
		(layer "F.Cu")
	)
	(gr_line
		(start 31.28772 -186.053476)
		(end 31.590234 -185.750962)
		(stroke
			(width 0.060198)
			(type default)
		)
		(layer "F.Cu")
	)
	(gr_line
		(start 31.28772 -184.735216)
		(end 31.590234 -185.03773)
		(stroke
			(width 0.060198)
			(type default)
		)
		(layer "F.Cu")
	)
	(gr_line
		(start 31.28772 -183.2991)
		(end 31.28772 -184.735216)
		(stroke
			(width 0.060198)
			(type default)
		)
		(layer "F.Cu")
	)
	(gr_arc
		(start 31.304738 -138.884914)
		(mid 31.239379 -138.99223)
		(end 31.2166 -139.1158)
		(stroke
			(width 0.068326)
			(type default)
		)
		(layer "F.Cu")
	)
	(gr_line
		(start 31.704788 -128.084834)
		(end 32.104838 -128.484884)
		(stroke
			(width 0.060198)
			(type default)
		)
		(layer "F.Cu")
	)
	(gr_line
		(start 32.1183 -99.6442)
		(end 32.4358 -99.6442)
		(stroke
			(width 0.060198)
			(type default)
		)
		(layer "F.Cu")
	)
	(gr_line
		(start 32.4358 -99.6442)
		(end 33.09112 -98.98888)
		(stroke
			(width 0.060198)
			(type default)
		)
		(layer "F.Cu")
	)
	(gr_line
		(start 32.505142 -128.085088)
		(end 32.904938 -128.484884)
		(stroke
			(width 0.060198)
			(type default)
		)
		(layer "F.Cu")
	)
	(gr_line
		(start 32.942276 -96.328738)
		(end 34.098738 -96.328738)
		(stroke
			(width 0.060198)
			(type default)
		)
		(layer "F.Cu")
	)
	(gr_line
		(start 32.942276 -95.79737)
		(end 32.942276 -96.328738)
		(stroke
			(width 0.060198)
			(type default)
		)
		(layer "F.Cu")
	)
	(gr_line
		(start 32.942276 -95.79737)
		(end 33.722056 -95.01759)
		(stroke
			(width 0.060198)
			(type default)
		)
		(layer "F.Cu")
	)
	(gr_line
		(start 33.09112 -98.98888)
		(end 33.278064 -98.801936)
		(stroke
			(width 0.060198)
			(type default)
		)
		(layer "F.Cu")
	)
	(gr_line
		(start 33.278064 -98.801936)
		(end 34.544 -98.801936)
		(stroke
			(width 0.060198)
			(type default)
		)
		(layer "F.Cu")
	)
	(gr_line
		(start 33.414716 -185.789316)
		(end 33.6296 -186.0042)
		(stroke
			(width 0.060198)
			(type default)
		)
		(layer "F.Cu")
	)
	(gr_line
		(start 33.414716 -185.076084)
		(end 33.6296 -184.8612)
		(stroke
			(width 0.060198)
			(type default)
		)
		(layer "F.Cu")
	)
	(gr_line
		(start 33.6296 -186.0042)
		(end 34.8361 -186.0042)
		(stroke
			(width 0.060198)
			(type default)
		)
		(layer "F.Cu")
	)
	(gr_line
		(start 33.6296 -184.8612)
		(end 34.8361 -184.8612)
		(stroke
			(width 0.060198)
			(type default)
		)
		(layer "F.Cu")
	)
	(gr_line
		(start 33.722056 -94.99219)
		(end 33.722056 -95.01759)
		(stroke
			(width 0.060198)
			(type default)
		)
		(layer "F.Cu")
	)
	(gr_line
		(start 34.098738 -96.328738)
		(end 34.544 -96.774)
		(stroke
			(width 0.060198)
			(type default)
		)
		(layer "F.Cu")
	)
	(gr_line
		(start 34.544 -96.774)
		(end 34.544 -97.302066)
		(stroke
			(width 0.060198)
			(type default)
		)
		(layer "F.Cu")
	)
	(gr_line
		(start 34.56813 -152.379934)
		(end 34.967926 -152.77973)
		(stroke
			(width 0.068326)
			(type default)
		)
		(layer "F.Cu")
	)
	(gr_line
		(start 35.367976 -152.917906)
		(end 35.48507 -153.035)
		(stroke
			(width 0.068326)
			(type default)
		)
		(layer "F.Cu")
	)
	(gr_line
		(start 35.367976 -152.379934)
		(end 35.367976 -152.917906)
		(stroke
			(width 0.068326)
			(type default)
		)
		(layer "F.Cu")
	)
	(gr_line
		(start 35.48507 -153.035)
		(end 35.650678 -153.035)
		(stroke
			(width 0.068326)
			(type default)
		)
		(layer "F.Cu")
	)
	(gr_line
		(start 35.650678 -153.035)
		(end 35.767772 -152.917906)
		(stroke
			(width 0.068326)
			(type default)
		)
		(layer "F.Cu")
	)
	(gr_line
		(start 35.767772 -152.77973)
		(end 35.767772 -152.917906)
		(stroke
			(width 0.068326)
			(type default)
		)
		(layer "F.Cu")
	)
	(gr_line
		(start 36.599876 -38.999922)
		(end 37.304726 -39.704772)
		(stroke
			(width 0.068326)
			(type default)
		)
		(layer "F.Cu")
	)
	(gr_line
		(start 36.967922 -155.579826)
		(end 37.367718 -155.18003)
		(stroke
			(width 0.068326)
			(type default)
		)
		(layer "F.Cu")
	)
	(gr_line
		(start 37.07511 -95.123)
		(end 37.07511 -96.5327)
		(stroke
			(width 0.060198)
			(type default)
		)
		(layer "F.Cu")
	)
	(gr_line
		(start 37.07511 -94.17939)
		(end 37.07511 -95.123)
		(stroke
			(width 0.060198)
			(type default)
		)
		(layer "F.Cu")
	)
	(gr_line
		(start 37.07511 -94.17939)
		(end 37.084 -94.1705)
		(stroke
			(width 0.060198)
			(type default)
		)
		(layer "F.Cu")
	)
	(gr_arc
		(start 37.3634 -39.846504)
		(mid 37.348145 -39.769812)
		(end 37.304726 -39.704772)
		(stroke
			(width 0.068326)
			(type default)
		)
		(layer "F.Cu")
	)
	(gr_line
		(start 37.452554 -140.166344)
		(end 37.603684 -140.015214)
		(stroke
			(width 0.068326)
			(type default)
		)
		(layer "F.Cu")
	)
	(gr_line
		(start 37.452554 -139.582144)
		(end 37.60216 -139.582144)
		(stroke
			(width 0.068326)
			(type default)
		)
		(layer "F.Cu")
	)
	(gr_line
		(start 37.6682 -39.364158)
		(end 37.6682 -39.539164)
		(stroke
			(width 0.068326)
			(type default)
		)
		(layer "F.Cu")
	)
	(gr_line
		(start 37.704776 -138.884914)
		(end 37.770562 -138.9507)
		(stroke
			(width 0.068326)
			(type default)
		)
		(layer "F.Cu")
	)
	(gr_line
		(start 37.704776 -138.084814)
		(end 38.077902 -138.45794)
		(stroke
			(width 0.068326)
			(type default)
		)
		(layer "F.Cu")
	)
	(gr_line
		(start 37.768022 -155.1178)
		(end 37.768022 -155.579826)
		(stroke
			(width 0.068326)
			(type default)
		)
		(layer "F.Cu")
	)
	(gr_line
		(start 37.768022 -155.1178)
		(end 37.895022 -154.9908)
		(stroke
			(width 0.068326)
			(type default)
		)
		(layer "F.Cu")
	)
	(gr_arc
		(start 37.77488 -39.106602)
		(mid 37.695923 -39.22477)
		(end 37.6682 -39.364158)
		(stroke
			(width 0.068326)
			(type default)
		)
		(layer "F.Cu")
	)
	(gr_line
		(start 37.77488 -39.106602)
		(end 37.815012 -39.06647)
		(stroke
			(width 0.068326)
			(type default)
		)
		(layer "F.Cu")
	)
	(gr_line
		(start 37.895022 -154.9908)
		(end 38.041072 -154.9908)
		(stroke
			(width 0.068326)
			(type default)
		)
		(layer "F.Cu")
	)
	(gr_arc
		(start 37.975794 -38.999922)
		(mid 37.888784 -39.017211)
		(end 37.815012 -39.06647)
		(stroke
			(width 0.068326)
			(type default)
		)
		(layer "F.Cu")
	)
	(gr_line
		(start 37.975794 -38.999922)
		(end 38.599872 -38.999922)
		(stroke
			(width 0.068326)
			(type default)
		)
		(layer "F.Cu")
	)
	(gr_line
		(start 38.041072 -154.9908)
		(end 38.168072 -155.1178)
		(stroke
			(width 0.068326)
			(type default)
		)
		(layer "F.Cu")
	)
	(gr_line
		(start 38.077902 -138.45794)
		(end 38.077902 -138.6459)
		(stroke
			(width 0.068326)
			(type default)
		)
		(layer "F.Cu")
	)
	(gr_line
		(start 38.1 -98.302064)
		(end 39.976298 -98.302064)
		(stroke
			(width 0.060198)
			(type default)
		)
		(layer "F.Cu")
	)
	(gr_line
		(start 38.168072 -155.1178)
		(end 38.168072 -155.179776)
		(stroke
			(width 0.068326)
			(type default)
		)
		(layer "F.Cu")
	)
	(gr_line
		(start 38.404546 -46.948598)
		(end 38.46195 -47.006002)
		(stroke
			(width 0.068326)
			(type default)
		)
		(layer "F.Cu")
	)
	(gr_line
		(start 38.404546 -45.138594)
		(end 38.404546 -46.948598)
		(stroke
			(width 0.068326)
			(type default)
		)
		(layer "F.Cu")
	)
	(gr_line
		(start 38.404546 -45.138594)
		(end 38.46195 -45.08119)
		(stroke
			(width 0.068326)
			(type default)
		)
		(layer "F.Cu")
	)
	(gr_line
		(start 38.605206 -141.513052)
		(end 38.756336 -141.361922)
		(stroke
			(width 0.068326)
			(type default)
		)
		(layer "F.Cu")
	)
	(gr_line
		(start 38.605206 -140.928852)
		(end 38.754812 -140.928852)
		(stroke
			(width 0.068326)
			(type default)
		)
		(layer "F.Cu")
	)
	(gr_line
		(start 38.89502 -46.007274)
		(end 38.89502 -47.004478)
		(stroke
			(width 0.068326)
			(type default)
		)
		(layer "F.Cu")
	)
	(gr_line
		(start 38.89502 -45.082714)
		(end 38.89502 -46.007274)
		(stroke
			(width 0.068326)
			(type default)
		)
		(layer "F.Cu")
	)
	(gr_line
		(start 38.89502 -43.314874)
		(end 38.89502 -43.8404)
		(stroke
			(width 0.068326)
			(type default)
		)
		(layer "F.Cu")
	)
	(gr_line
		(start 38.89502 -42.80916)
		(end 38.89502 -43.314874)
		(stroke
			(width 0.068326)
			(type default)
		)
		(layer "F.Cu")
	)
	(gr_line
		(start 38.9001 -224.199958)
		(end 38.9001 -225.54438)
		(stroke
			(width 0.060198)
			(type default)
		)
		(layer "F.Cu")
	)
	(gr_line
		(start 38.9001 -224.199958)
		(end 38.943788 -224.15627)
		(stroke
			(width 0.060198)
			(type default)
		)
		(layer "F.Cu")
	)
	(gr_line
		(start 39.0779 -201.87412)
		(end 40.191436 -201.87412)
		(stroke
			(width 0.060198)
			(type default)
		)
		(layer "F.Cu")
	)
	(gr_line
		(start 39.0779 -201.22388)
		(end 40.410638 -201.22388)
		(stroke
			(width 0.060198)
			(type default)
		)
		(layer "F.Cu")
	)
	(gr_line
		(start 39.20236 -44.1452)
		(end 39.41826 -43.9293)
		(stroke
			(width 0.068326)
			(type default)
		)
		(layer "F.Cu")
	)
	(gr_line
		(start 39.20236 -42.50436)
		(end 39.41826 -42.72026)
		(stroke
			(width 0.068326)
			(type default)
		)
		(layer "F.Cu")
	)
	(gr_line
		(start 39.304722 -138.884914)
		(end 39.370508 -138.9507)
		(stroke
			(width 0.068326)
			(type default)
		)
		(layer "F.Cu")
	)
	(gr_line
		(start 39.304722 -138.357102)
		(end 39.677848 -138.730228)
		(stroke
			(width 0.068326)
			(type default)
		)
		(layer "F.Cu")
	)
	(gr_line
		(start 39.304722 -138.084814)
		(end 39.304722 -138.357102)
		(stroke
			(width 0.068326)
			(type default)
		)
		(layer "F.Cu")
	)
	(gr_line
		(start 39.41826 -42.72026)
		(end 39.41826 -43.9293)
		(stroke
			(width 0.068326)
			(type default)
		)
		(layer "F.Cu")
	)
	(gr_line
		(start 39.656766 -224.15627)
		(end 39.7002 -224.199704)
		(stroke
			(width 0.060198)
			(type default)
		)
		(layer "F.Cu")
	)
	(gr_line
		(start 39.7002 -224.199704)
		(end 39.7002 -225.54438)
		(stroke
			(width 0.060198)
			(type default)
		)
		(layer "F.Cu")
	)
	(gr_line
		(start 39.9669 -96.583246)
		(end 40.691816 -97.308162)
		(stroke
			(width 0.060198)
			(type default)
		)
		(layer "F.Cu")
	)
	(gr_line
		(start 39.9669 -96.3168)
		(end 39.9669 -96.583246)
		(stroke
			(width 0.060198)
			(type default)
		)
		(layer "F.Cu")
	)
	(gr_line
		(start 39.976298 -98.302064)
		(end 40.691816 -97.586546)
		(stroke
			(width 0.060198)
			(type default)
		)
		(layer "F.Cu")
	)
	(gr_line
		(start 40.168068 -152.379934)
		(end 40.567864 -152.77973)
		(stroke
			(width 0.068326)
			(type default)
		)
		(layer "F.Cu")
	)
	(gr_line
		(start 40.191436 -201.87412)
		(end 40.903652 -202.586844)
		(stroke
			(width 0.060198)
			(type default)
		)
		(layer "F.Cu")
	)
	(gr_line
		(start 40.410638 -201.22388)
		(end 40.83177 -200.802748)
		(stroke
			(width 0.060198)
			(type default)
		)
		(layer "F.Cu")
	)
	(gr_line
		(start 40.64 -206.4385)
		(end 40.7035 -206.375)
		(stroke
			(width 0.060198)
			(type default)
		)
		(layer "F.Cu")
	)
	(gr_line
		(start 40.64 -205.2955)
		(end 40.7035 -205.359)
		(stroke
			(width 0.060198)
			(type default)
		)
		(layer "F.Cu")
	)
	(gr_line
		(start 40.64 -204.216)
		(end 40.64 -205.2955)
		(stroke
			(width 0.060198)
			(type default)
		)
		(layer "F.Cu")
	)
	(gr_line
		(start 40.64 -204.216)
		(end 40.854884 -204.001116)
		(stroke
			(width 0.060198)
			(type default)
		)
		(layer "F.Cu")
	)
	(gr_line
		(start 40.64 -198.882)
		(end 40.854884 -199.096884)
		(stroke
			(width 0.060198)
			(type default)
		)
		(layer "F.Cu")
	)
	(gr_line
		(start 40.64 -197.6755)
		(end 40.64 -198.882)
		(stroke
			(width 0.060198)
			(type default)
		)
		(layer "F.Cu")
	)
	(gr_line
		(start 40.691816 -97.308162)
		(end 40.691816 -97.586546)
		(stroke
			(width 0.060198)
			(type default)
		)
		(layer "F.Cu")
	)
	(gr_line
		(start 40.7035 -205.359)
		(end 40.7035 -206.375)
		(stroke
			(width 0.060198)
			(type default)
		)
		(layer "F.Cu")
	)
	(gr_line
		(start 40.7416 -208.28)
		(end 40.816784 -208.355184)
		(stroke
			(width 0.060198)
			(type default)
		)
		(layer "F.Cu")
	)
	(gr_line
		(start 40.904922 -138.884914)
		(end 40.978328 -138.95832)
		(stroke
			(width 0.068326)
			(type default)
		)
		(layer "F.Cu")
	)
	(gr_line
		(start 40.904922 -138.084814)
		(end 41.331642 -138.511534)
		(stroke
			(width 0.068326)
			(type default)
		)
		(layer "F.Cu")
	)
	(gr_line
		(start 40.9067 -187.87872)
		(end 42.272712 -187.87872)
		(stroke
			(width 0.060198)
			(type default)
		)
		(layer "F.Cu")
	)
	(gr_line
		(start 40.9067 -187.22848)
		(end 42.15892 -187.22848)
		(stroke
			(width 0.060198)
			(type default)
		)
		(layer "F.Cu")
	)
	(gr_line
		(start 40.96512 -141.8336)
		(end 40.97782 -141.8336)
		(stroke
			(width 0.068326)
			(type default)
		)
		(layer "F.Cu")
	)
	(gr_line
		(start 40.96512 -141.2494)
		(end 41.11625 -141.40053)
		(stroke
			(width 0.068326)
			(type default)
		)
		(layer "F.Cu")
	)
	(gr_line
		(start 40.967914 -152.908)
		(end 41.094914 -153.035)
		(stroke
			(width 0.068326)
			(type default)
		)
		(layer "F.Cu")
	)
	(gr_line
		(start 40.967914 -152.379934)
		(end 40.967914 -152.908)
		(stroke
			(width 0.068326)
			(type default)
		)
		(layer "F.Cu")
	)
	(gr_line
		(start 40.98036 -141.8336)
		(end 41.118028 -141.8336)
		(stroke
			(width 0.068326)
			(type default)
		)
		(layer "F.Cu")
	)
	(gr_line
		(start 41.094914 -153.035)
		(end 41.24071 -153.035)
		(stroke
			(width 0.068326)
			(type default)
		)
		(layer "F.Cu")
	)
	(gr_line
		(start 41.24071 -153.035)
		(end 41.36771 -152.908)
		(stroke
			(width 0.068326)
			(type default)
		)
		(layer "F.Cu")
	)
	(gr_line
		(start 41.28516 -141.56944)
		(end 41.422828 -141.56944)
		(stroke
			(width 0.068326)
			(type default)
		)
		(layer "F.Cu")
	)
	(gr_line
		(start 41.300146 -224.199958)
		(end 41.300146 -225.54438)
		(stroke
			(width 0.060198)
			(type default)
		)
		(layer "F.Cu")
	)
	(gr_line
		(start 41.300146 -224.199958)
		(end 41.34358 -224.156524)
		(stroke
			(width 0.060198)
			(type default)
		)
		(layer "F.Cu")
	)
	(gr_line
		(start 41.331642 -138.511534)
		(end 41.331642 -138.699494)
		(stroke
			(width 0.068326)
			(type default)
		)
		(layer "F.Cu")
	)
	(gr_line
		(start 41.36771 -152.77973)
		(end 41.36771 -152.908)
		(stroke
			(width 0.068326)
			(type default)
		)
		(layer "F.Cu")
	)
	(gr_line
		(start 41.409366 -202.616562)
		(end 42.151808 -201.87412)
		(stroke
			(width 0.060198)
			(type default)
		)
		(layer "F.Cu")
	)
	(gr_line
		(start 41.530016 -208.355184)
		(end 41.6052 -208.28)
		(stroke
			(width 0.060198)
			(type default)
		)
		(layer "F.Cu")
	)
	(gr_line
		(start 41.544748 -200.802748)
		(end 41.96588 -201.22388)
		(stroke
			(width 0.060198)
			(type default)
		)
		(layer "F.Cu")
	)
	(gr_line
		(start 41.568116 -204.001116)
		(end 41.783 -204.216)
		(stroke
			(width 0.060198)
			(type default)
		)
		(layer "F.Cu")
	)
	(gr_line
		(start 41.568116 -199.096884)
		(end 41.783 -198.882)
		(stroke
			(width 0.060198)
			(type default)
		)
		(layer "F.Cu")
	)
	(gr_line
		(start 41.663112 -47.000668)
		(end 41.928288 -47.265844)
		(stroke
			(width 0.068326)
			(type default)
		)
		(layer "F.Cu")
	)
	(gr_line
		(start 41.663112 -46.56582)
		(end 41.928288 -46.300644)
		(stroke
			(width 0.068326)
			(type default)
		)
		(layer "F.Cu")
	)
	(gr_line
		(start 41.7195 -206.375)
		(end 41.783 -206.4385)
		(stroke
			(width 0.060198)
			(type default)
		)
		(layer "F.Cu")
	)
	(gr_line
		(start 41.7195 -205.359)
		(end 41.7195 -206.375)
		(stroke
			(width 0.060198)
			(type default)
		)
		(layer "F.Cu")
	)
	(gr_line
		(start 41.7195 -205.359)
		(end 41.783 -205.2955)
		(stroke
			(width 0.060198)
			(type default)
		)
		(layer "F.Cu")
	)
	(gr_line
		(start 41.783 -204.216)
		(end 41.783 -205.2955)
		(stroke
			(width 0.060198)
			(type default)
		)
		(layer "F.Cu")
	)
	(gr_line
		(start 41.783 -197.6755)
		(end 41.783 -198.882)
		(stroke
			(width 0.060198)
			(type default)
		)
		(layer "F.Cu")
	)
	(gr_line
		(start 41.928288 -47.265844)
		(end 42.540936 -47.265844)
		(stroke
			(width 0.068326)
			(type default)
		)
		(layer "F.Cu")
	)
	(gr_line
		(start 41.928288 -46.300644)
		(end 42.540936 -46.300644)
		(stroke
			(width 0.068326)
			(type default)
		)
		(layer "F.Cu")
	)
	(gr_line
		(start 41.96588 -201.22388)
		(end 43.2181 -201.22388)
		(stroke
			(width 0.060198)
			(type default)
		)
		(layer "F.Cu")
	)
	(gr_line
		(start 42.056558 -224.156524)
		(end 42.099992 -224.199958)
		(stroke
			(width 0.060198)
			(type default)
		)
		(layer "F.Cu")
	)
	(gr_line
		(start 42.099992 -224.199958)
		(end 42.099992 -225.54438)
		(stroke
			(width 0.060198)
			(type default)
		)
		(layer "F.Cu")
	)
	(gr_line
		(start 42.151808 -201.87412)
		(end 43.2181 -201.87412)
		(stroke
			(width 0.060198)
			(type default)
		)
		(layer "F.Cu")
	)
	(gr_line
		(start 42.15892 -187.22848)
		(end 42.620184 -186.767216)
		(stroke
			(width 0.060198)
			(type default)
		)
		(layer "F.Cu")
	)
	(gr_line
		(start 42.272712 -187.87872)
		(end 42.647108 -188.253116)
		(stroke
			(width 0.060198)
			(type default)
		)
		(layer "F.Cu")
	)
	(gr_line
		(start 42.4688 -192.4431)
		(end 42.5323 -192.3796)
		(stroke
			(width 0.060198)
			(type default)
		)
		(layer "F.Cu")
	)
	(gr_line
		(start 42.4688 -191.3001)
		(end 42.5323 -191.3636)
		(stroke
			(width 0.060198)
			(type default)
		)
		(layer "F.Cu")
	)
	(gr_line
		(start 42.4688 -190.2206)
		(end 42.4688 -191.3001)
		(stroke
			(width 0.060198)
			(type default)
		)
		(layer "F.Cu")
	)
	(gr_line
		(start 42.4688 -190.2206)
		(end 42.683684 -190.005716)
		(stroke
			(width 0.060198)
			(type default)
		)
		(layer "F.Cu")
	)
	(gr_line
		(start 42.4688 -184.8866)
		(end 42.683684 -185.101484)
		(stroke
			(width 0.060198)
			(type default)
		)
		(layer "F.Cu")
	)
	(gr_line
		(start 42.4688 -183.6801)
		(end 42.4688 -184.8866)
		(stroke
			(width 0.060198)
			(type default)
		)
		(layer "F.Cu")
	)
	(gr_line
		(start 42.5323 -191.3636)
		(end 42.5323 -192.3796)
		(stroke
			(width 0.060198)
			(type default)
		)
		(layer "F.Cu")
	)
	(gr_line
		(start 42.5704 -194.2846)
		(end 42.645584 -194.359784)
		(stroke
			(width 0.060198)
			(type default)
		)
		(layer "F.Cu")
	)
	(gr_line
		(start 42.5958 -75.408028)
		(end 42.793666 -75.210162)
		(stroke
			(width 0.060198)
			(type default)
		)
		(layer "F.Cu")
	)
	(gr_line
		(start 42.5958 -74.299318)
		(end 42.793666 -74.497184)
		(stroke
			(width 0.060198)
			(type default)
		)
		(layer "F.Cu")
	)
	(gr_line
		(start 43.304714 -126.884938)
		(end 43.70451 -126.485142)
		(stroke
			(width 0.060198)
			(type default)
		)
		(layer "F.Cu")
	)
	(gr_line
		(start 43.304714 -126.084838)
		(end 43.70451 -125.685042)
		(stroke
			(width 0.060198)
			(type default)
		)
		(layer "F.Cu")
	)
	(gr_line
		(start 43.304714 -125.284992)
		(end 43.70451 -124.885196)
		(stroke
			(width 0.060198)
			(type default)
		)
		(layer "F.Cu")
	)
	(gr_line
		(start 43.304714 -123.684792)
		(end 43.70451 -123.284996)
		(stroke
			(width 0.060198)
			(type default)
		)
		(layer "F.Cu")
	)
	(gr_line
		(start 43.333416 -186.767216)
		(end 43.79468 -187.22848)
		(stroke
			(width 0.060198)
			(type default)
		)
		(layer "F.Cu")
	)
	(gr_line
		(start 43.358816 -194.359784)
		(end 43.434 -194.2846)
		(stroke
			(width 0.060198)
			(type default)
		)
		(layer "F.Cu")
	)
	(gr_line
		(start 43.360086 -188.253116)
		(end 43.734482 -187.87872)
		(stroke
			(width 0.060198)
			(type default)
		)
		(layer "F.Cu")
	)
	(gr_line
		(start 43.396916 -190.005716)
		(end 43.6118 -190.2206)
		(stroke
			(width 0.060198)
			(type default)
		)
		(layer "F.Cu")
	)
	(gr_line
		(start 43.396916 -185.101484)
		(end 43.6118 -184.8866)
		(stroke
			(width 0.060198)
			(type default)
		)
		(layer "F.Cu")
	)
	(gr_line
		(start 43.5483 -192.3796)
		(end 43.6118 -192.4431)
		(stroke
			(width 0.060198)
			(type default)
		)
		(layer "F.Cu")
	)
	(gr_line
		(start 43.5483 -191.3636)
		(end 43.5483 -192.3796)
		(stroke
			(width 0.060198)
			(type default)
		)
		(layer "F.Cu")
	)
	(gr_line
		(start 43.5483 -191.3636)
		(end 43.6118 -191.3001)
		(stroke
			(width 0.060198)
			(type default)
		)
		(layer "F.Cu")
	)
	(gr_line
		(start 43.6118 -190.2206)
		(end 43.6118 -191.3001)
		(stroke
			(width 0.060198)
			(type default)
		)
		(layer "F.Cu")
	)
	(gr_line
		(start 43.6118 -183.6801)
		(end 43.6118 -184.8866)
		(stroke
			(width 0.060198)
			(type default)
		)
		(layer "F.Cu")
	)
	(gr_line
		(start 43.700192 -224.199958)
		(end 43.700192 -225.54438)
		(stroke
			(width 0.060198)
			(type default)
		)
		(layer "F.Cu")
	)
	(gr_line
		(start 43.700192 -224.199958)
		(end 43.743626 -224.156524)
		(stroke
			(width 0.060198)
			(type default)
		)
		(layer "F.Cu")
	)
	(gr_line
		(start 43.705018 -122.48515)
		(end 44.104814 -122.884946)
		(stroke
			(width 0.060198)
			(type default)
		)
		(layer "F.Cu")
	)
	(gr_line
		(start 43.734482 -187.87872)
		(end 45.0469 -187.87872)
		(stroke
			(width 0.060198)
			(type default)
		)
		(layer "F.Cu")
	)
	(gr_line
		(start 43.79468 -187.22848)
		(end 45.0469 -187.22848)
		(stroke
			(width 0.060198)
			(type default)
		)
		(layer "F.Cu")
	)
	(gr_line
		(start 44.069 -220.3704)
		(end 44.144184 -220.295216)
		(stroke
			(width 0.060198)
			(type default)
		)
		(layer "F.Cu")
	)
	(gr_line
		(start 44.104814 -129.284984)
		(end 44.50461 -128.885188)
		(stroke
			(width 0.068326)
			(type default)
		)
		(layer "F.Cu")
	)
	(gr_line
		(start 44.104814 -127.684784)
		(end 44.50461 -127.284988)
		(stroke
			(width 0.060198)
			(type default)
		)
		(layer "F.Cu")
	)
	(gr_line
		(start 44.104814 -126.084838)
		(end 44.50461 -125.685042)
		(stroke
			(width 0.060198)
			(type default)
		)
		(layer "F.Cu")
	)
	(gr_line
		(start 44.104814 -124.484892)
		(end 44.504864 -124.084842)
		(stroke
			(width 0.060198)
			(type default)
		)
		(layer "F.Cu")
	)
	(gr_line
		(start 44.104814 -123.684792)
		(end 44.50461 -123.284996)
		(stroke
			(width 0.060198)
			(type default)
		)
		(layer "F.Cu")
	)
	(gr_line
		(start 44.217336 -47.265844)
		(end 44.829984 -47.265844)
		(stroke
			(width 0.068326)
			(type default)
		)
		(layer "F.Cu")
	)
	(gr_line
		(start 44.217336 -46.300644)
		(end 44.829984 -46.300644)
		(stroke
			(width 0.068326)
			(type default)
		)
		(layer "F.Cu")
	)
	(gr_line
		(start 44.456604 -224.156524)
		(end 44.500038 -224.199958)
		(stroke
			(width 0.060198)
			(type default)
		)
		(layer "F.Cu")
	)
	(gr_line
		(start 44.500038 -224.199958)
		(end 44.500038 -225.54438)
		(stroke
			(width 0.060198)
			(type default)
		)
		(layer "F.Cu")
	)
	(gr_line
		(start 44.505118 -122.48515)
		(end 44.904914 -122.884946)
		(stroke
			(width 0.060198)
			(type default)
		)
		(layer "F.Cu")
	)
	(gr_line
		(start 44.829984 -47.265844)
		(end 45.09516 -47.000668)
		(stroke
			(width 0.068326)
			(type default)
		)
		(layer "F.Cu")
	)
	(gr_line
		(start 44.829984 -46.300644)
		(end 45.09516 -46.56582)
		(stroke
			(width 0.068326)
			(type default)
		)
		(layer "F.Cu")
	)
	(gr_line
		(start 44.857416 -220.295216)
		(end 44.9326 -220.3704)
		(stroke
			(width 0.060198)
			(type default)
		)
		(layer "F.Cu")
	)
	(gr_line
		(start 44.904914 -129.284984)
		(end 45.30471 -128.885188)
		(stroke
			(width 0.068326)
			(type default)
		)
		(layer "F.Cu")
	)
	(gr_line
		(start 44.904914 -127.684784)
		(end 45.30471 -127.284988)
		(stroke
			(width 0.060198)
			(type default)
		)
		(layer "F.Cu")
	)
	(gr_line
		(start 44.904914 -126.084838)
		(end 45.30471 -125.685042)
		(stroke
			(width 0.060198)
			(type default)
		)
		(layer "F.Cu")
	)
	(gr_line
		(start 44.904914 -125.284992)
		(end 45.30471 -124.885196)
		(stroke
			(width 0.060198)
			(type default)
		)
		(layer "F.Cu")
	)
	(gr_line
		(start 44.904914 -124.484892)
		(end 45.30471 -124.085096)
		(stroke
			(width 0.060198)
			(type default)
		)
		(layer "F.Cu")
	)
	(gr_line
		(start 44.904914 -123.684792)
		(end 45.30471 -123.284996)
		(stroke
			(width 0.060198)
			(type default)
		)
		(layer "F.Cu")
	)
	(gr_line
		(start 45.70476 -128.484884)
		(end 45.977048 -128.484884)
		(stroke
			(width 0.068326)
			(type default)
		)
		(layer "F.Cu")
	)
	(gr_line
		(start 45.70476 -125.284992)
		(end 46.13021 -124.859542)
		(stroke
			(width 0.060198)
			(type default)
		)
		(layer "F.Cu")
	)
	(gr_line
		(start 45.70476 -124.484892)
		(end 46.104556 -124.085096)
		(stroke
			(width 0.060198)
			(type default)
		)
		(layer "F.Cu")
	)
	(gr_line
		(start 45.70476 -123.684792)
		(end 46.104556 -123.284996)
		(stroke
			(width 0.060198)
			(type default)
		)
		(layer "F.Cu")
	)
	(gr_line
		(start 45.70476 -122.884946)
		(end 45.814488 -122.884946)
		(stroke
			(width 0.060198)
			(type default)
		)
		(layer "F.Cu")
	)
	(gr_line
		(start 45.70476 -122.084846)
		(end 46.104556 -121.68505)
		(stroke
			(width 0.060198)
			(type default)
		)
		(layer "F.Cu")
	)
	(gr_line
		(start 45.814488 -122.884946)
		(end 46.204886 -122.494548)
		(stroke
			(width 0.060198)
			(type default)
		)
		(layer "F.Cu")
	)
	(gr_line
		(start 45.977048 -128.484884)
		(end 46.350174 -128.85801)
		(stroke
			(width 0.068326)
			(type default)
		)
		(layer "F.Cu")
	)
	(gr_line
		(start 46.099984 -224.386394)
		(end 46.099984 -225.54438)
		(stroke
			(width 0.068326)
			(type default)
		)
		(layer "F.Cu")
	)
	(gr_line
		(start 46.13021 -124.859542)
		(end 46.169834 -124.859542)
		(stroke
			(width 0.060198)
			(type default)
		)
		(layer "F.Cu")
	)
	(gr_arc
		(start 46.137068 -224.296732)
		(mid 46.109615 -224.337878)
		(end 46.099984 -224.386394)
		(stroke
			(width 0.068326)
			(type default)
		)
		(layer "F.Cu")
	)
	(gr_line
		(start 46.137068 -224.296732)
		(end 46.31055 -224.12325)
		(stroke
			(width 0.068326)
			(type default)
		)
		(layer "F.Cu")
	)
	(gr_line
		(start 46.169834 -124.859542)
		(end 46.170342 -124.86005)
		(stroke
			(width 0.060198)
			(type default)
		)
		(layer "F.Cu")
	)
	(gr_line
		(start 46.170342 -124.86005)
		(end 46.24578 -124.86005)
		(stroke
			(width 0.060198)
			(type default)
		)
		(layer "F.Cu")
	)
	(gr_line
		(start 46.204886 -122.494548)
		(end 46.666658 -122.494548)
		(stroke
			(width 0.060198)
			(type default)
		)
		(layer "F.Cu")
	)
	(gr_line
		(start 46.24832 -124.86005)
		(end 46.721014 -124.86005)
		(stroke
			(width 0.060198)
			(type default)
		)
		(layer "F.Cu")
	)
	(gr_arc
		(start 46.31055 -224.12325)
		(mid 46.337983 -224.082099)
		(end 46.347634 -224.033588)
		(stroke
			(width 0.068326)
			(type default)
		)
		(layer "F.Cu")
	)
	(gr_line
		(start 46.50486 -128.484884)
		(end 46.570646 -128.55067)
		(stroke
			(width 0.068326)
			(type default)
		)
		(layer "F.Cu")
	)
	(gr_line
		(start 46.50486 -123.684792)
		(end 46.904656 -124.084588)
		(stroke
			(width 0.060198)
			(type default)
		)
		(layer "F.Cu")
	)
	(gr_line
		(start 46.50486 -122.884946)
		(end 46.904402 -123.284488)
		(stroke
			(width 0.060198)
			(type default)
		)
		(layer "F.Cu")
	)
	(gr_line
		(start 46.518068 -124.4981)
		(end 46.610016 -124.590048)
		(stroke
			(width 0.060198)
			(type default)
		)
		(layer "F.Cu")
	)
	(gr_line
		(start 46.610016 -124.590048)
		(end 47.335186 -124.590048)
		(stroke
			(width 0.060198)
			(type default)
		)
		(layer "F.Cu")
	)
	(gr_arc
		(start 46.652434 -224.018856)
		(mid 46.662081 -224.067366)
		(end 46.689518 -224.108518)
		(stroke
			(width 0.068326)
			(type default)
		)
		(layer "F.Cu")
	)
	(gr_line
		(start 46.666658 -122.494548)
		(end 46.758606 -122.586496)
		(stroke
			(width 0.060198)
			(type default)
		)
		(layer "F.Cu")
	)
	(gr_line
		(start 46.689518 -224.108518)
		(end 46.863 -224.282)
		(stroke
			(width 0.068326)
			(type default)
		)
		(layer "F.Cu")
	)
	(gr_line
		(start 46.721014 -124.86005)
		(end 46.721522 -124.860558)
		(stroke
			(width 0.060198)
			(type default)
		)
		(layer "F.Cu")
	)
	(gr_line
		(start 46.721522 -124.860558)
		(end 47.324772 -124.860558)
		(stroke
			(width 0.060198)
			(type default)
		)
		(layer "F.Cu")
	)
	(gr_line
		(start 46.758606 -122.586496)
		(end 46.790864 -122.586496)
		(stroke
			(width 0.060198)
			(type default)
		)
		(layer "F.Cu")
	)
	(gr_arc
		(start 46.900084 -224.371662)
		(mid 46.890451 -224.323144)
		(end 46.863 -224.282)
		(stroke
			(width 0.068326)
			(type default)
		)
		(layer "F.Cu")
	)
	(gr_line
		(start 46.900084 -224.371662)
		(end 46.900084 -225.54438)
		(stroke
			(width 0.068326)
			(type default)
		)
		(layer "F.Cu")
	)
	(gr_line
		(start 46.904402 -123.284488)
		(end 46.904656 -123.284488)
		(stroke
			(width 0.060198)
			(type default)
		)
		(layer "F.Cu")
	)
	(gr_line
		(start 46.985682 -128.55067)
		(end 47.14875 -128.387602)
		(stroke
			(width 0.068326)
			(type default)
		)
		(layer "F.Cu")
	)
	(gr_line
		(start 47.14875 -128.387602)
		(end 47.558706 -128.387602)
		(stroke
			(width 0.068326)
			(type default)
		)
		(layer "F.Cu")
	)
	(gr_line
		(start 47.290482 -128.85801)
		(end 47.416974 -128.85801)
		(stroke
			(width 0.068326)
			(type default)
		)
		(layer "F.Cu")
	)
	(gr_line
		(start 47.324772 -124.860558)
		(end 47.325788 -124.859542)
		(stroke
			(width 0.060198)
			(type default)
		)
		(layer "F.Cu")
	)
	(gr_line
		(start 47.325788 -124.859542)
		(end 47.697136 -124.859542)
		(stroke
			(width 0.060198)
			(type default)
		)
		(layer "F.Cu")
	)
	(gr_line
		(start 47.335186 -124.590048)
		(end 47.451518 -124.473716)
		(stroke
			(width 0.060198)
			(type default)
		)
		(layer "F.Cu")
	)
	(gr_line
		(start 47.453296 -124.471938)
		(end 47.51324 -124.411994)
		(stroke
			(width 0.060198)
			(type default)
		)
		(layer "F.Cu")
	)
	(gr_line
		(start 47.51324 -124.411994)
		(end 47.597568 -124.411994)
		(stroke
			(width 0.060198)
			(type default)
		)
		(layer "F.Cu")
	)
	(gr_line
		(start 47.558706 -128.387602)
		(end 47.721774 -128.55067)
		(stroke
			(width 0.068326)
			(type default)
		)
		(layer "F.Cu")
	)
	(gr_line
		(start 47.650908 -46.71314)
		(end 47.803816 -46.866048)
		(stroke
			(width 0.068326)
			(type default)
		)
		(layer "F.Cu")
	)
	(gr_line
		(start 47.699676 -124.859542)
		(end 47.85868 -124.859542)
		(stroke
			(width 0.060198)
			(type default)
		)
		(layer "F.Cu")
	)
	(gr_line
		(start 47.803816 -46.866048)
		(end 48.213772 -46.866048)
		(stroke
			(width 0.068326)
			(type default)
		)
		(layer "F.Cu")
	)
	(gr_line
		(start 47.85868 -124.859542)
		(end 47.859696 -124.859542)
		(stroke
			(width 0.060198)
			(type default)
		)
		(layer "F.Cu")
	)
	(gr_line
		(start 47.955708 -46.4058)
		(end 48.06188 -46.4058)
		(stroke
			(width 0.068326)
			(type default)
		)
		(layer "F.Cu")
	)
	(gr_line
		(start 48.13681 -128.55067)
		(end 48.299878 -128.387602)
		(stroke
			(width 0.068326)
			(type default)
		)
		(layer "F.Cu")
	)
	(gr_line
		(start 48.213772 -46.866048)
		(end 48.36668 -46.71314)
		(stroke
			(width 0.068326)
			(type default)
		)
		(layer "F.Cu")
	)
	(gr_line
		(start 48.299878 -128.387602)
		(end 48.709834 -128.387602)
		(stroke
			(width 0.068326)
			(type default)
		)
		(layer "F.Cu")
	)
	(gr_line
		(start 48.39208 -211.975954)
		(end 48.673766 -211.694268)
		(stroke
			(width 0.068326)
			(type default)
		)
		(layer "F.Cu")
	)
	(gr_line
		(start 48.44161 -128.85801)
		(end 48.568102 -128.85801)
		(stroke
			(width 0.068326)
			(type default)
		)
		(layer "F.Cu")
	)
	(gr_line
		(start 48.49368 -210.896454)
		(end 48.647096 -211.050124)
		(stroke
			(width 0.068326)
			(type default)
		)
		(layer "F.Cu")
	)
	(gr_line
		(start 48.50003 -224.828608)
		(end 48.50003 -225.54438)
		(stroke
			(width 0.068326)
			(type default)
		)
		(layer "F.Cu")
	)
	(gr_line
		(start 48.50003 -224.828608)
		(end 48.500284 -224.828354)
		(stroke
			(width 0.068326)
			(type default)
		)
		(layer "F.Cu")
	)
	(gr_arc
		(start 48.668432 -224.32264)
		(mid 48.543404 -224.561883)
		(end 48.500284 -224.828354)
		(stroke
			(width 0.068326)
			(type default)
		)
		(layer "F.Cu")
	)
	(gr_arc
		(start 48.668432 -224.32264)
		(mid 48.727066 -224.234888)
		(end 48.74768 -224.131378)
		(stroke
			(width 0.068326)
			(type default)
		)
		(layer "F.Cu")
	)
	(gr_arc
		(start 48.673766 -211.694268)
		(mid 48.723757 -211.619452)
		(end 48.74133 -211.5312)
		(stroke
			(width 0.068326)
			(type default)
		)
		(layer "F.Cu")
	)
	(gr_line
		(start 48.709834 -128.387602)
		(end 48.872902 -128.55067)
		(stroke
			(width 0.068326)
			(type default)
		)
		(layer "F.Cu")
	)
	(gr_arc
		(start 48.74133 -211.2772)
		(mid 48.716789 -211.154294)
		(end 48.647096 -211.050124)
		(stroke
			(width 0.068326)
			(type default)
		)
		(layer "F.Cu")
	)
	(gr_arc
		(start 48.74768 -213.723474)
		(mid 48.655261 -213.25885)
		(end 48.39208 -212.864954)
		(stroke
			(width 0.068326)
			(type default)
		)
		(layer "F.Cu")
	)
	(gr_line
		(start 48.781716 -46.71314)
		(end 48.934624 -46.866048)
		(stroke
			(width 0.068326)
			(type default)
		)
		(layer "F.Cu")
	)
	(gr_line
		(start 48.934624 -46.866048)
		(end 49.34458 -46.866048)
		(stroke
			(width 0.068326)
			(type default)
		)
		(layer "F.Cu")
	)
	(gr_arc
		(start 49.04613 -211.5312)
		(mid 49.061413 -211.607654)
		(end 49.104804 -211.672424)
		(stroke
			(width 0.068326)
			(type default)
		)
		(layer "F.Cu")
	)
	(gr_arc
		(start 49.052734 -224.133664)
		(mid 49.072906 -224.234825)
		(end 49.130204 -224.320608)
		(stroke
			(width 0.068326)
			(type default)
		)
		(layer "F.Cu")
	)
	(gr_line
		(start 49.086516 -46.4058)
		(end 49.192688 -46.4058)
		(stroke
			(width 0.068326)
			(type default)
		)
		(layer "F.Cu")
	)
	(gr_line
		(start 49.104804 -211.672424)
		(end 49.40808 -211.975954)
		(stroke
			(width 0.068326)
			(type default)
		)
		(layer "F.Cu")
	)
	(gr_line
		(start 49.1109 -195.90512)
		(end 50.546 -195.90512)
		(stroke
			(width 0.060198)
			(type default)
		)
		(layer "F.Cu")
	)
	(gr_line
		(start 49.1109 -195.25488)
		(end 50.36312 -195.25488)
		(stroke
			(width 0.060198)
			(type default)
		)
		(layer "F.Cu")
	)
	(gr_line
		(start 49.1109 -181.80812)
		(end 50.23612 -181.80812)
		(stroke
			(width 0.060198)
			(type default)
		)
		(layer "F.Cu")
	)
	(gr_line
		(start 49.1109 -181.15788)
		(end 50.36312 -181.15788)
		(stroke
			(width 0.060198)
			(type default)
		)
		(layer "F.Cu")
	)
	(gr_arc
		(start 49.139856 -211.063078)
		(mid 49.070501 -211.166919)
		(end 49.04613 -211.289392)
		(stroke
			(width 0.068326)
			(type default)
		)
		(layer "F.Cu")
	)
	(gr_line
		(start 49.139856 -211.063078)
		(end 49.30648 -210.896454)
		(stroke
			(width 0.068326)
			(type default)
		)
		(layer "F.Cu")
	)
	(gr_line
		(start 49.287938 -128.55067)
		(end 49.451006 -128.387602)
		(stroke
			(width 0.068326)
			(type default)
		)
		(layer "F.Cu")
	)
	(gr_arc
		(start 49.30013 -224.828354)
		(mid 49.256493 -224.560646)
		(end 49.130204 -224.320608)
		(stroke
			(width 0.068326)
			(type default)
		)
		(layer "F.Cu")
	)
	(gr_line
		(start 49.30013 -224.828354)
		(end 49.30013 -225.54438)
		(stroke
			(width 0.068326)
			(type default)
		)
		(layer "F.Cu")
	)
	(gr_line
		(start 49.34458 -46.866048)
		(end 49.497488 -46.71314)
		(stroke
			(width 0.068326)
			(type default)
		)
		(layer "F.Cu")
	)
	(gr_arc
		(start 49.40808 -212.864954)
		(mid 49.145088 -213.258484)
		(end 49.052734 -213.722712)
		(stroke
			(width 0.068326)
			(type default)
		)
		(layer "F.Cu")
	)
	(gr_line
		(start 49.451006 -128.387602)
		(end 49.860962 -128.387602)
		(stroke
			(width 0.068326)
			(type default)
		)
		(layer "F.Cu")
	)
	(gr_line
		(start 49.592738 -128.85801)
		(end 49.71923 -128.85801)
		(stroke
			(width 0.068326)
			(type default)
		)
		(layer "F.Cu")
	)
	(gr_line
		(start 49.860962 -128.387602)
		(end 50.02403 -128.55067)
		(stroke
			(width 0.068326)
			(type default)
		)
		(layer "F.Cu")
	)
	(gr_line
		(start 49.912524 -46.71314)
		(end 50.065432 -46.866048)
		(stroke
			(width 0.068326)
			(type default)
		)
		(layer "F.Cu")
	)
	(gr_line
		(start 50.065432 -46.866048)
		(end 50.475388 -46.866048)
		(stroke
			(width 0.068326)
			(type default)
		)
		(layer "F.Cu")
	)
	(gr_line
		(start 50.217324 -46.4058)
		(end 50.323496 -46.4058)
		(stroke
			(width 0.068326)
			(type default)
		)
		(layer "F.Cu")
	)
	(gr_line
		(start 50.23612 -181.80812)
		(end 50.887884 -182.459884)
		(stroke
			(width 0.060198)
			(type default)
		)
		(layer "F.Cu")
	)
	(gr_line
		(start 50.36312 -195.25488)
		(end 50.824384 -194.793616)
		(stroke
			(width 0.060198)
			(type default)
		)
		(layer "F.Cu")
	)
	(gr_line
		(start 50.36312 -181.15788)
		(end 50.824384 -180.696616)
		(stroke
			(width 0.060198)
			(type default)
		)
		(layer "F.Cu")
	)
	(gr_line
		(start 50.475388 -46.866048)
		(end 50.628296 -46.71314)
		(stroke
			(width 0.068326)
			(type default)
		)
		(layer "F.Cu")
	)
	(gr_line
		(start 50.546 -195.90512)
		(end 50.884836 -196.243956)
		(stroke
			(width 0.060198)
			(type default)
		)
		(layer "F.Cu")
	)
	(gr_line
		(start 50.673 -200.4695)
		(end 50.7365 -200.406)
		(stroke
			(width 0.060198)
			(type default)
		)
		(layer "F.Cu")
	)
	(gr_line
		(start 50.673 -199.3265)
		(end 50.7365 -199.39)
		(stroke
			(width 0.060198)
			(type default)
		)
		(layer "F.Cu")
	)
	(gr_line
		(start 50.673 -198.247)
		(end 50.673 -199.3265)
		(stroke
			(width 0.060198)
			(type default)
		)
		(layer "F.Cu")
	)
	(gr_line
		(start 50.673 -198.247)
		(end 50.986182 -197.933564)
		(stroke
			(width 0.060198)
			(type default)
		)
		(layer "F.Cu")
	)
	(gr_line
		(start 50.673 -192.913)
		(end 50.887884 -193.127884)
		(stroke
			(width 0.060198)
			(type default)
		)
		(layer "F.Cu")
	)
	(gr_line
		(start 50.673 -191.7065)
		(end 50.673 -192.913)
		(stroke
			(width 0.060198)
			(type default)
		)
		(layer "F.Cu")
	)
	(gr_line
		(start 50.673 -186.3725)
		(end 50.7365 -186.309)
		(stroke
			(width 0.060198)
			(type default)
		)
		(layer "F.Cu")
	)
	(gr_line
		(start 50.673 -185.2295)
		(end 50.7365 -185.293)
		(stroke
			(width 0.060198)
			(type default)
		)
		(layer "F.Cu")
	)
	(gr_line
		(start 50.673 -184.15)
		(end 50.673 -185.2295)
		(stroke
			(width 0.060198)
			(type default)
		)
		(layer "F.Cu")
	)
	(gr_line
		(start 50.673 -184.15)
		(end 50.887884 -183.935116)
		(stroke
			(width 0.060198)
			(type default)
		)
		(layer "F.Cu")
	)
	(gr_line
		(start 50.673 -178.816)
		(end 50.887884 -179.030884)
		(stroke
			(width 0.060198)
			(type default)
		)
		(layer "F.Cu")
	)
	(gr_line
		(start 50.673 -177.6095)
		(end 50.673 -178.816)
		(stroke
			(width 0.060198)
			(type default)
		)
		(layer "F.Cu")
	)
	(gr_line
		(start 50.7365 -199.39)
		(end 50.7365 -200.406)
		(stroke
			(width 0.060198)
			(type default)
		)
		(layer "F.Cu")
	)
	(gr_line
		(start 50.7365 -185.293)
		(end 50.7365 -186.309)
		(stroke
			(width 0.060198)
			(type default)
		)
		(layer "F.Cu")
	)
	(gr_line
		(start 50.7746 -202.311)
		(end 50.84445 -202.38085)
		(stroke
			(width 0.060198)
			(type default)
		)
		(layer "F.Cu")
	)
	(gr_line
		(start 50.7746 -188.214)
		(end 50.849784 -188.289184)
		(stroke
			(width 0.060198)
			(type default)
		)
		(layer "F.Cu")
	)
	(gr_line
		(start 51.043332 -46.71314)
		(end 51.19624 -46.866048)
		(stroke
			(width 0.068326)
			(type default)
		)
		(layer "F.Cu")
	)
	(gr_line
		(start 51.19624 -46.866048)
		(end 51.606196 -46.866048)
		(stroke
			(width 0.068326)
			(type default)
		)
		(layer "F.Cu")
	)
	(gr_line
		(start 51.348132 -46.4058)
		(end 51.454304 -46.4058)
		(stroke
			(width 0.068326)
			(type default)
		)
		(layer "F.Cu")
	)
	(gr_line
		(start 51.477418 -202.471782)
		(end 51.6382 -202.311)
		(stroke
			(width 0.060198)
			(type default)
		)
		(layer "F.Cu")
	)
	(gr_line
		(start 51.492658 -197.923658)
		(end 51.816 -198.247)
		(stroke
			(width 0.060198)
			(type default)
		)
		(layer "F.Cu")
	)
	(gr_line
		(start 51.537616 -194.793616)
		(end 51.99888 -195.25488)
		(stroke
			(width 0.060198)
			(type default)
		)
		(layer "F.Cu")
	)
	(gr_line
		(start 51.537616 -180.696616)
		(end 51.99888 -181.15788)
		(stroke
			(width 0.060198)
			(type default)
		)
		(layer "F.Cu")
	)
	(gr_line
		(start 51.563016 -188.289184)
		(end 51.6382 -188.214)
		(stroke
			(width 0.060198)
			(type default)
		)
		(layer "F.Cu")
	)
	(gr_line
		(start 51.591972 -211.975954)
		(end 51.873658 -211.694268)
		(stroke
			(width 0.068326)
			(type default)
		)
		(layer "F.Cu")
	)
	(gr_line
		(start 51.597814 -196.243956)
		(end 51.93665 -195.90512)
		(stroke
			(width 0.060198)
			(type default)
		)
		(layer "F.Cu")
	)
	(gr_line
		(start 51.600862 -182.459884)
		(end 52.252626 -181.80812)
		(stroke
			(width 0.060198)
			(type default)
		)
		(layer "F.Cu")
	)
	(gr_line
		(start 51.601116 -193.127884)
		(end 51.816 -192.913)
		(stroke
			(width 0.060198)
			(type default)
		)
		(layer "F.Cu")
	)
	(gr_line
		(start 51.601116 -183.935116)
		(end 51.816 -184.15)
		(stroke
			(width 0.060198)
			(type default)
		)
		(layer "F.Cu")
	)
	(gr_line
		(start 51.601116 -179.030884)
		(end 51.816 -178.816)
		(stroke
			(width 0.060198)
			(type default)
		)
		(layer "F.Cu")
	)
	(gr_line
		(start 51.606196 -46.866048)
		(end 51.759104 -46.71314)
		(stroke
			(width 0.068326)
			(type default)
		)
		(layer "F.Cu")
	)
	(gr_line
		(start 51.693572 -210.896454)
		(end 51.829208 -211.03209)
		(stroke
			(width 0.068326)
			(type default)
		)
		(layer "F.Cu")
	)
	(gr_line
		(start 51.700176 -224.828354)
		(end 51.700176 -225.54438)
		(stroke
			(width 0.068326)
			(type default)
		)
		(layer "F.Cu")
	)
	(gr_line
		(start 51.7525 -200.406)
		(end 51.816 -200.4695)
		(stroke
			(width 0.060198)
			(type default)
		)
		(layer "F.Cu")
	)
	(gr_line
		(start 51.7525 -199.39)
		(end 51.7525 -200.406)
		(stroke
			(width 0.060198)
			(type default)
		)
		(layer "F.Cu")
	)
	(gr_line
		(start 51.7525 -199.39)
		(end 51.816 -199.3265)
		(stroke
			(width 0.060198)
			(type default)
		)
		(layer "F.Cu")
	)
	(gr_line
		(start 51.7525 -186.309)
		(end 51.816 -186.3725)
		(stroke
			(width 0.060198)
			(type default)
		)
		(layer "F.Cu")
	)
	(gr_line
		(start 51.7525 -185.293)
		(end 51.7525 -186.309)
		(stroke
			(width 0.060198)
			(type default)
		)
		(layer "F.Cu")
	)
	(gr_line
		(start 51.7525 -185.293)
		(end 51.816 -185.2295)
		(stroke
			(width 0.060198)
			(type default)
		)
		(layer "F.Cu")
	)
	(gr_line
		(start 51.816 -198.247)
		(end 51.816 -199.3265)
		(stroke
			(width 0.060198)
			(type default)
		)
		(layer "F.Cu")
	)
	(gr_line
		(start 51.816 -191.7065)
		(end 51.816 -192.913)
		(stroke
			(width 0.060198)
			(type default)
		)
		(layer "F.Cu")
	)
	(gr_line
		(start 51.816 -184.15)
		(end 51.816 -185.2295)
		(stroke
			(width 0.060198)
			(type default)
		)
		(layer "F.Cu")
	)
	(gr_line
		(start 51.816 -177.6095)
		(end 51.816 -178.816)
		(stroke
			(width 0.060198)
			(type default)
		)
		(layer "F.Cu")
	)
	(gr_arc
		(start 51.868324 -224.32264)
		(mid 51.743297 -224.561883)
		(end 51.700176 -224.828354)
		(stroke
			(width 0.068326)
			(type default)
		)
		(layer "F.Cu")
	)
	(gr_arc
		(start 51.868324 -224.32264)
		(mid 51.926958 -224.234888)
		(end 51.947572 -224.131378)
		(stroke
			(width 0.068326)
			(type default)
		)
		(layer "F.Cu")
	)
	(gr_arc
		(start 51.873658 -211.694268)
		(mid 51.923649 -211.619452)
		(end 51.941222 -211.5312)
		(stroke
			(width 0.068326)
			(type default)
		)
		(layer "F.Cu")
	)
	(gr_line
		(start 51.93665 -195.90512)
		(end 53.2511 -195.90512)
		(stroke
			(width 0.060198)
			(type default)
		)
		(layer "F.Cu")
	)
	(gr_arc
		(start 51.941222 -211.3026)
		(mid 51.912104 -211.156214)
		(end 51.829208 -211.03209)
		(stroke
			(width 0.068326)
			(type default)
		)
		(layer "F.Cu")
	)
	(gr_arc
		(start 51.947572 -213.723474)
		(mid 51.855153 -213.25885)
		(end 51.591972 -212.864954)
		(stroke
			(width 0.068326)
			(type default)
		)
		(layer "F.Cu")
	)
	(gr_line
		(start 51.99888 -195.25488)
		(end 53.2511 -195.25488)
		(stroke
			(width 0.060198)
			(type default)
		)
		(layer "F.Cu")
	)
	(gr_line
		(start 51.99888 -181.15788)
		(end 53.2511 -181.15788)
		(stroke
			(width 0.060198)
			(type default)
		)
		(layer "F.Cu")
	)
	(gr_line
		(start 52.222654 -108.952792)
		(end 52.816252 -109.54639)
		(stroke
			(width 0.060198)
			(type default)
		)
		(layer "F.Cu")
	)
	(gr_line
		(start 52.222654 -108.257848)
		(end 52.222654 -108.952792)
		(stroke
			(width 0.060198)
			(type default)
		)
		(layer "F.Cu")
	)
	(gr_line
		(start 52.222654 -108.257848)
		(end 52.225194 -108.255308)
		(stroke
			(width 0.060198)
			(type default)
		)
		(layer "F.Cu")
	)
	(gr_line
		(start 52.225194 -108.004102)
		(end 52.225194 -108.255308)
		(stroke
			(width 0.060198)
			(type default)
		)
		(layer "F.Cu")
	)
	(gr_line
		(start 52.225194 -108.004102)
		(end 52.345844 -107.883452)
		(stroke
			(width 0.060198)
			(type default)
		)
		(layer "F.Cu")
	)
	(gr_arc
		(start 52.246022 -211.5312)
		(mid 52.261305 -211.607654)
		(end 52.304696 -211.672424)
		(stroke
			(width 0.068326)
			(type default)
		)
		(layer "F.Cu")
	)
	(gr_arc
		(start 52.252626 -224.133664)
		(mid 52.272797 -224.234825)
		(end 52.330096 -224.320608)
		(stroke
			(width 0.068326)
			(type default)
		)
		(layer "F.Cu")
	)
	(gr_line
		(start 52.252626 -181.80812)
		(end 53.2511 -181.80812)
		(stroke
			(width 0.060198)
			(type default)
		)
		(layer "F.Cu")
	)
	(gr_line
		(start 52.304696 -211.672424)
		(end 52.607972 -211.975954)
		(stroke
			(width 0.068326)
			(type default)
		)
		(layer "F.Cu")
	)
	(gr_line
		(start 52.345844 -107.883452)
		(end 53.106574 -107.883452)
		(stroke
			(width 0.060198)
			(type default)
		)
		(layer "F.Cu")
	)
	(gr_arc
		(start 52.356766 -211.046314)
		(mid 52.274869 -211.168784)
		(end 52.246022 -211.313268)
		(stroke
			(width 0.068326)
			(type default)
		)
		(layer "F.Cu")
	)
	(gr_line
		(start 52.356766 -211.046314)
		(end 52.506372 -210.896454)
		(stroke
			(width 0.068326)
			(type default)
		)
		(layer "F.Cu")
	)
	(gr_line
		(start 52.399438 -47.876968)
		(end 52.635404 -47.641002)
		(stroke
			(width 0.068326)
			(type default)
		)
		(layer "F.Cu")
	)
	(gr_arc
		(start 52.500022 -224.828354)
		(mid 52.456385 -224.560646)
		(end 52.330096 -224.320608)
		(stroke
			(width 0.068326)
			(type default)
		)
		(layer "F.Cu")
	)
	(gr_line
		(start 52.500022 -224.828354)
		(end 52.500022 -225.54438)
		(stroke
			(width 0.068326)
			(type default)
		)
		(layer "F.Cu")
	)
	(gr_line
		(start 52.603654 -128.21666)
		(end 52.803044 -128.01727)
		(stroke
			(width 0.068326)
			(type default)
		)
		(layer "F.Cu")
	)
	(gr_arc
		(start 52.607972 -212.864954)
		(mid 52.344982 -213.258485)
		(end 52.252626 -213.722712)
		(stroke
			(width 0.068326)
			(type default)
		)
		(layer "F.Cu")
	)
	(gr_line
		(start 52.803044 -127.635254)
		(end 52.803044 -128.01727)
		(stroke
			(width 0.068326)
			(type default)
		)
		(layer "F.Cu")
	)
	(gr_line
		(start 52.803044 -127.635254)
		(end 52.930298 -127.508)
		(stroke
			(width 0.068326)
			(type default)
		)
		(layer "F.Cu")
	)
	(gr_line
		(start 52.816252 -111.668052)
		(end 53.286152 -112.137952)
		(stroke
			(width 0.060198)
			(type default)
		)
		(layer "F.Cu")
	)
	(gr_line
		(start 52.816252 -110.84687)
		(end 52.816252 -111.668052)
		(stroke
			(width 0.060198)
			(type default)
		)
		(layer "F.Cu")
	)
	(gr_line
		(start 52.908454 -128.524)
		(end 53.2765 -128.524)
		(stroke
			(width 0.068326)
			(type default)
		)
		(layer "F.Cu")
	)
	(gr_line
		(start 52.930298 -127.508)
		(end 53.2765 -127.508)
		(stroke
			(width 0.068326)
			(type default)
		)
		(layer "F.Cu")
	)
	(gr_line
		(start 53.069998 -47.641002)
		(end 53.305964 -47.876968)
		(stroke
			(width 0.068326)
			(type default)
		)
		(layer "F.Cu")
	)
	(gr_line
		(start 53.106574 -107.883452)
		(end 53.336952 -108.11383)
		(stroke
			(width 0.060198)
			(type default)
		)
		(layer "F.Cu")
	)
	(gr_line
		(start 53.125116 -118.974616)
		(end 53.2765 -119.126)
		(stroke
			(width 0.060198)
			(type default)
		)
		(layer "F.Cu")
	)
	(gr_line
		(start 53.125116 -118.261384)
		(end 53.2765 -118.11)
		(stroke
			(width 0.060198)
			(type default)
		)
		(layer "F.Cu")
	)
	(gr_line
		(start 53.1876 -114.3127)
		(end 53.2003 -114.3)
		(stroke
			(width 0.060198)
			(type default)
		)
		(layer "F.Cu")
	)
	(gr_line
		(start 53.2003 -113.284)
		(end 53.2003 -114.3)
		(stroke
			(width 0.060198)
			(type default)
		)
		(layer "F.Cu")
	)
	(gr_line
		(start 53.2003 -112.339882)
		(end 53.2003 -113.284)
		(stroke
			(width 0.060198)
			(type default)
		)
		(layer "F.Cu")
	)
	(gr_line
		(start 53.2003 -112.339882)
		(end 53.286152 -112.25403)
		(stroke
			(width 0.060198)
			(type default)
		)
		(layer "F.Cu")
	)
	(gr_line
		(start 53.286152 -112.137952)
		(end 53.286152 -112.25403)
		(stroke
			(width 0.060198)
			(type default)
		)
		(layer "F.Cu")
	)
	(gr_line
		(start 53.336952 -108.11383)
		(end 53.381148 -108.158026)
		(stroke
			(width 0.060198)
			(type default)
		)
		(layer "F.Cu")
	)
	(gr_line
		(start 53.381148 -109.057948)
		(end 53.673502 -109.350302)
		(stroke
			(width 0.060198)
			(type default)
		)
		(layer "F.Cu")
	)
	(gr_line
		(start 53.381148 -108.158026)
		(end 53.381148 -109.057948)
		(stroke
			(width 0.060198)
			(type default)
		)
		(layer "F.Cu")
	)
	(gr_line
		(start 53.673502 -111.258604)
		(end 53.848 -111.433102)
		(stroke
			(width 0.060198)
			(type default)
		)
		(layer "F.Cu")
	)
	(gr_line
		(start 53.673502 -109.350302)
		(end 53.673502 -111.258604)
		(stroke
			(width 0.060198)
			(type default)
		)
		(layer "F.Cu")
	)
	(gr_line
		(start 54.064916 -115.365784)
		(end 54.229 -115.2017)
		(stroke
			(width 0.060198)
			(type default)
		)
		(layer "F.Cu")
	)
	(gr_line
		(start 54.1655 -128.524)
		(end 54.456076 -128.233424)
		(stroke
			(width 0.068326)
			(type default)
		)
		(layer "F.Cu")
	)
	(gr_line
		(start 54.1655 -127.508)
		(end 54.456076 -127.798576)
		(stroke
			(width 0.068326)
			(type default)
		)
		(layer "F.Cu")
	)
	(gr_line
		(start 54.175152 -112.25403)
		(end 55.233062 -112.25403)
		(stroke
			(width 0.060198)
			(type default)
		)
		(layer "F.Cu")
	)
	(gr_line
		(start 54.175152 -111.966248)
		(end 54.175152 -112.25403)
		(stroke
			(width 0.060198)
			(type default)
		)
		(layer "F.Cu")
	)
	(gr_line
		(start 54.175152 -111.966248)
		(end 54.695852 -111.445548)
		(stroke
			(width 0.060198)
			(type default)
		)
		(layer "F.Cu")
	)
	(gr_line
		(start 54.2163 -113.284)
		(end 54.229 -113.2967)
		(stroke
			(width 0.060198)
			(type default)
		)
		(layer "F.Cu")
	)
	(gr_line
		(start 54.2163 -113.1951)
		(end 54.2163 -113.284)
		(stroke
			(width 0.060198)
			(type default)
		)
		(layer "F.Cu")
	)
	(gr_line
		(start 54.2163 -113.1951)
		(end 54.683152 -112.728248)
		(stroke
			(width 0.060198)
			(type default)
		)
		(layer "F.Cu")
	)
	(gr_line
		(start 54.225952 -108.561886)
		(end 54.695852 -109.031786)
		(stroke
			(width 0.060198)
			(type default)
		)
		(layer "F.Cu")
	)
	(gr_line
		(start 54.225952 -108.11383)
		(end 54.225952 -108.561886)
		(stroke
			(width 0.060198)
			(type default)
		)
		(layer "F.Cu")
	)
	(gr_line
		(start 54.225952 -108.11383)
		(end 54.447948 -107.891834)
		(stroke
			(width 0.060198)
			(type default)
		)
		(layer "F.Cu")
	)
	(gr_line
		(start 54.229 -113.2967)
		(end 54.229 -114.3127)
		(stroke
			(width 0.060198)
			(type default)
		)
		(layer "F.Cu")
	)
	(gr_line
		(start 54.447948 -107.891834)
		(end 55.371492 -107.891834)
		(stroke
			(width 0.060198)
			(type default)
		)
		(layer "F.Cu")
	)
	(gr_line
		(start 54.683152 -112.728248)
		(end 55.047134 -112.728248)
		(stroke
			(width 0.060198)
			(type default)
		)
		(layer "F.Cu")
	)
	(gr_line
		(start 54.695852 -110.84687)
		(end 54.695852 -111.445548)
		(stroke
			(width 0.060198)
			(type default)
		)
		(layer "F.Cu")
	)
	(gr_line
		(start 54.695852 -109.031786)
		(end 54.695852 -109.54639)
		(stroke
			(width 0.060198)
			(type default)
		)
		(layer "F.Cu")
	)
	(gr_line
		(start 54.792118 -211.975954)
		(end 55.073804 -211.694268)
		(stroke
			(width 0.068326)
			(type default)
		)
		(layer "F.Cu")
	)
	(gr_line
		(start 54.893718 -210.896454)
		(end 55.043324 -211.04606)
		(stroke
			(width 0.068326)
			(type default)
		)
		(layer "F.Cu")
	)
	(gr_line
		(start 54.900068 -224.828608)
		(end 54.900068 -225.54438)
		(stroke
			(width 0.068326)
			(type default)
		)
		(layer "F.Cu")
	)
	(gr_line
		(start 54.900068 -224.828608)
		(end 54.900322 -224.828354)
		(stroke
			(width 0.068326)
			(type default)
		)
		(layer "F.Cu")
	)
	(gr_line
		(start 54.935628 -117.675152)
		(end 55.370476 -118.11)
		(stroke
			(width 0.060198)
			(type default)
		)
		(layer "F.Cu")
	)
	(gr_line
		(start 54.966616 -119.316754)
		(end 55.15737 -119.126)
		(stroke
			(width 0.060198)
			(type default)
		)
		(layer "F.Cu")
	)
	(gr_line
		(start 55.047134 -112.728248)
		(end 55.051706 -112.73282)
		(stroke
			(width 0.060198)
			(type default)
		)
		(layer "F.Cu")
	)
	(gr_line
		(start 55.051706 -112.73282)
		(end 55.438294 -112.73282)
		(stroke
			(width 0.060198)
			(type default)
		)
		(layer "F.Cu")
	)
	(gr_arc
		(start 55.06847 -224.32264)
		(mid 54.943451 -224.561885)
		(end 54.900322 -224.828354)
		(stroke
			(width 0.068326)
			(type default)
		)
		(layer "F.Cu")
	)
	(gr_arc
		(start 55.06847 -224.32264)
		(mid 55.127104 -224.234888)
		(end 55.147718 -224.131378)
		(stroke
			(width 0.068326)
			(type default)
		)
		(layer "F.Cu")
	)
	(gr_arc
		(start 55.073804 -211.694268)
		(mid 55.123795 -211.619452)
		(end 55.141368 -211.5312)
		(stroke
			(width 0.068326)
			(type default)
		)
		(layer "F.Cu")
	)
	(gr_arc
		(start 55.141368 -211.282788)
		(mid 55.115885 -211.154676)
		(end 55.043324 -211.04606)
		(stroke
			(width 0.068326)
			(type default)
		)
		(layer "F.Cu")
	)
	(gr_arc
		(start 55.147718 -213.723474)
		(mid 55.055299 -213.25885)
		(end 54.792118 -212.864954)
		(stroke
			(width 0.068326)
			(type default)
		)
		(layer "F.Cu")
	)
	(gr_line
		(start 55.15737 -119.126)
		(end 55.8165 -119.126)
		(stroke
			(width 0.060198)
			(type default)
		)
		(layer "F.Cu")
	)
	(gr_line
		(start 55.233062 -112.25403)
		(end 55.245 -112.265968)
		(stroke
			(width 0.060198)
			(type default)
		)
		(layer "F.Cu")
	)
	(gr_line
		(start 55.370476 -118.11)
		(end 55.8165 -118.11)
		(stroke
			(width 0.060198)
			(type default)
		)
		(layer "F.Cu")
	)
	(gr_line
		(start 55.371492 -107.891834)
		(end 57.037986 -109.558328)
		(stroke
			(width 0.060198)
			(type default)
		)
		(layer "F.Cu")
	)
	(gr_line
		(start 55.438294 -112.73282)
		(end 55.442866 -112.728248)
		(stroke
			(width 0.060198)
			(type default)
		)
		(layer "F.Cu")
	)
	(gr_line
		(start 55.442866 -112.728248)
		(end 55.814976 -112.728248)
		(stroke
			(width 0.060198)
			(type default)
		)
		(layer "F.Cu")
	)
	(gr_arc
		(start 55.446168 -211.5312)
		(mid 55.461448 -211.607657)
		(end 55.504842 -211.672424)
		(stroke
			(width 0.068326)
			(type default)
		)
		(layer "F.Cu")
	)
	(gr_arc
		(start 55.452772 -224.133664)
		(mid 55.47294 -224.234828)
		(end 55.530242 -224.320608)
		(stroke
			(width 0.068326)
			(type default)
		)
		(layer "F.Cu")
	)
	(gr_line
		(start 55.504842 -211.672424)
		(end 55.808118 -211.975954)
		(stroke
			(width 0.068326)
			(type default)
		)
		(layer "F.Cu")
	)
	(gr_arc
		(start 55.535322 -211.067904)
		(mid 55.469386 -211.166486)
		(end 55.446168 -211.282788)
		(stroke
			(width 0.068326)
			(type default)
		)
		(layer "F.Cu")
	)
	(gr_line
		(start 55.535322 -211.067904)
		(end 55.706518 -210.896454)
		(stroke
			(width 0.068326)
			(type default)
		)
		(layer "F.Cu")
	)
	(gr_arc
		(start 55.700168 -224.828354)
		(mid 55.656531 -224.560646)
		(end 55.530242 -224.320608)
		(stroke
			(width 0.068326)
			(type default)
		)
		(layer "F.Cu")
	)
	(gr_line
		(start 55.700168 -224.828354)
		(end 55.700168 -225.54438)
		(stroke
			(width 0.068326)
			(type default)
		)
		(layer "F.Cu")
	)
	(gr_arc
		(start 55.808118 -212.864954)
		(mid 55.545118 -213.258482)
		(end 55.452772 -213.722712)
		(stroke
			(width 0.068326)
			(type default)
		)
		(layer "F.Cu")
	)
	(gr_line
		(start 55.814976 -112.728248)
		(end 55.954676 -112.867948)
		(stroke
			(width 0.060198)
			(type default)
		)
		(layer "F.Cu")
	)
	(gr_line
		(start 55.954676 -112.867948)
		(end 56.384444 -112.867948)
		(stroke
			(width 0.060198)
			(type default)
		)
		(layer "F.Cu")
	)
	(gr_line
		(start 56.15686 -149.66188)
		(end 57.01792 -149.66188)
		(stroke
			(width 0.060198)
			(type default)
		)
		(layer "F.Cu")
	)
	(gr_line
		(start 56.15686 -149.01164)
		(end 57.06364 -149.01164)
		(stroke
			(width 0.060198)
			(type default)
		)
		(layer "F.Cu")
	)
	(gr_arc
		(start 56.25084 -85.22081)
		(mid 56.359459 -85.483034)
		(end 56.62168 -85.59165)
		(stroke
			(width 0.068326)
			(type default)
		)
		(layer "F.Cu")
	)
	(gr_line
		(start 56.25084 -85.21065)
		(end 56.25084 -85.22081)
		(stroke
			(width 0.068326)
			(type default)
		)
		(layer "F.Cu")
	)
	(gr_line
		(start 56.384444 -112.867948)
		(end 56.6547 -112.597692)
		(stroke
			(width 0.060198)
			(type default)
		)
		(layer "F.Cu")
	)
	(gr_line
		(start 56.477916 -26.163524)
		(end 57.073292 -26.7589)
		(stroke
			(width 0.060198)
			(type default)
		)
		(layer "F.Cu")
	)
	(gr_line
		(start 56.6547 -112.580674)
		(end 56.6547 -112.597692)
		(stroke
			(width 0.060198)
			(type default)
		)
		(layer "F.Cu")
	)
	(gr_line
		(start 56.6547 -112.580674)
		(end 57.037986 -112.197388)
		(stroke
			(width 0.060198)
			(type default)
		)
		(layer "F.Cu")
	)
	(gr_arc
		(start 56.68264 -85.89645)
		(mid 56.377303 -86.02291)
		(end 56.25084 -86.32825)
		(stroke
			(width 0.068326)
			(type default)
		)
		(layer "F.Cu")
	)
	(gr_line
		(start 57.037986 -109.558328)
		(end 57.037986 -112.197388)
		(stroke
			(width 0.060198)
			(type default)
		)
		(layer "F.Cu")
	)
	(gr_line
		(start 57.073292 -26.7589)
		(end 57.3786 -26.7589)
		(stroke
			(width 0.060198)
			(type default)
		)
		(layer "F.Cu")
	)
	(gr_line
		(start 57.30113 -120.77573)
		(end 57.303162 -119.405908)
		(stroke
			(width 0.060198)
			(type default)
		)
		(layer "F.Cu")
	)
	(gr_line
		(start 57.30113 -120.77573)
		(end 57.565798 -121.040398)
		(stroke
			(width 0.060198)
			(type default)
		)
		(layer "F.Cu")
	)
	(gr_line
		(start 57.565798 -121.040398)
		(end 57.8358 -121.040398)
		(stroke
			(width 0.060198)
			(type default)
		)
		(layer "F.Cu")
	)
	(gr_line
		(start 57.6072 -119.081296)
		(end 57.6072 -119.10187)
		(stroke
			(width 0.060198)
			(type default)
		)
		(layer "F.Cu")
	)
	(gr_line
		(start 57.811924 -25.055068)
		(end 57.825386 -25.041606)
		(stroke
			(width 0.060198)
			(type default)
		)
		(layer "F.Cu")
	)
	(gr_line
		(start 57.825386 -25.041606)
		(end 59.871102 -25.041606)
		(stroke
			(width 0.060198)
			(type default)
		)
		(layer "F.Cu")
	)
	(gr_line
		(start 57.8358 -119.60606)
		(end 57.8358 -119.9388)
		(stroke
			(width 0.060198)
			(type default)
		)
		(layer "F.Cu")
	)
	(gr_line
		(start 57.8358 -119.582946)
		(end 57.8358 -119.60352)
		(stroke
			(width 0.060198)
			(type default)
		)
		(layer "F.Cu")
	)
	(gr_line
		(start 57.953402 -19.961606)
		(end 59.871102 -19.961606)
		(stroke
			(width 0.052324)
			(type default)
		)
		(layer "F.Cu")
	)
	(gr_line
		(start 57.953402 -17.421606)
		(end 59.871102 -17.421606)
		(stroke
			(width 0.052324)
			(type default)
		)
		(layer "F.Cu")
	)
	(gr_line
		(start 57.99201 -211.975954)
		(end 58.273696 -211.694268)
		(stroke
			(width 0.068326)
			(type default)
		)
		(layer "F.Cu")
	)
	(gr_line
		(start 58.0517 -196.2658)
		(end 58.117994 -196.332094)
		(stroke
			(width 0.068326)
			(type default)
		)
		(layer "F.Cu")
	)
	(gr_line
		(start 58.09361 -210.896454)
		(end 58.243978 -211.047076)
		(stroke
			(width 0.068326)
			(type default)
		)
		(layer "F.Cu")
	)
	(gr_line
		(start 58.09996 -224.828608)
		(end 58.09996 -225.54438)
		(stroke
			(width 0.068326)
			(type default)
		)
		(layer "F.Cu")
	)
	(gr_line
		(start 58.09996 -224.828608)
		(end 58.100214 -224.828354)
		(stroke
			(width 0.068326)
			(type default)
		)
		(layer "F.Cu")
	)
	(gr_arc
		(start 58.268362 -224.32264)
		(mid 58.143344 -224.561885)
		(end 58.100214 -224.828354)
		(stroke
			(width 0.068326)
			(type default)
		)
		(layer "F.Cu")
	)
	(gr_arc
		(start 58.268362 -224.32264)
		(mid 58.326996 -224.234888)
		(end 58.34761 -224.131378)
		(stroke
			(width 0.068326)
			(type default)
		)
		(layer "F.Cu")
	)
	(gr_arc
		(start 58.273696 -211.694268)
		(mid 58.323687 -211.619452)
		(end 58.34126 -211.5312)
		(stroke
			(width 0.068326)
			(type default)
		)
		(layer "F.Cu")
	)
	(gr_arc
		(start 58.293 -196.75475)
		(mid 58.247521 -196.52602)
		(end 58.117994 -196.332094)
		(stroke
			(width 0.068326)
			(type default)
		)
		(layer "F.Cu")
	)
	(gr_line
		(start 58.332116 -149.708616)
		(end 58.4835 -149.86)
		(stroke
			(width 0.060198)
			(type default)
		)
		(layer "F.Cu")
	)
	(gr_line
		(start 58.332116 -148.995384)
		(end 58.4835 -148.844)
		(stroke
			(width 0.060198)
			(type default)
		)
		(layer "F.Cu")
	)
	(gr_arc
		(start 58.34126 -211.281518)
		(mid 58.315926 -211.154626)
		(end 58.243978 -211.047076)
		(stroke
			(width 0.068326)
			(type default)
		)
		(layer "F.Cu")
	)
	(gr_arc
		(start 58.34761 -213.723474)
		(mid 58.255191 -213.25885)
		(end 57.99201 -212.864954)
		(stroke
			(width 0.068326)
			(type default)
		)
		(layer "F.Cu")
	)
	(gr_arc
		(start 58.64606 -211.5312)
		(mid 58.661345 -211.607652)
		(end 58.704734 -211.672424)
		(stroke
			(width 0.068326)
			(type default)
		)
		(layer "F.Cu")
	)
	(gr_arc
		(start 58.652664 -224.133664)
		(mid 58.672832 -224.234829)
		(end 58.730134 -224.320608)
		(stroke
			(width 0.068326)
			(type default)
		)
		(layer "F.Cu")
	)
	(gr_line
		(start 58.704734 -211.672424)
		(end 59.00801 -211.975954)
		(stroke
			(width 0.068326)
			(type default)
		)
		(layer "F.Cu")
	)
	(gr_arc
		(start 58.74004 -211.062824)
		(mid 58.670486 -211.166884)
		(end 58.64606 -211.289646)
		(stroke
			(width 0.068326)
			(type default)
		)
		(layer "F.Cu")
	)
	(gr_line
		(start 58.74004 -211.062824)
		(end 58.90641 -210.896454)
		(stroke
			(width 0.068326)
			(type default)
		)
		(layer "F.Cu")
	)
	(gr_arc
		(start 58.8645 -196.2658)
		(mid 58.667106 -196.561219)
		(end 58.5978 -196.90969)
		(stroke
			(width 0.068326)
			(type default)
		)
		(layer "F.Cu")
	)
	(gr_arc
		(start 58.90006 -224.828354)
		(mid 58.856423 -224.560646)
		(end 58.730134 -224.320608)
		(stroke
			(width 0.068326)
			(type default)
		)
		(layer "F.Cu")
	)
	(gr_line
		(start 58.90006 -224.828354)
		(end 58.90006 -225.54438)
		(stroke
			(width 0.068326)
			(type default)
		)
		(layer "F.Cu")
	)
	(gr_arc
		(start 59.00801 -212.864954)
		(mid 58.745012 -213.258483)
		(end 58.652664 -213.722712)
		(stroke
			(width 0.068326)
			(type default)
		)
		(layer "F.Cu")
	)
	(gr_line
		(start 62.5602 -122.428)
		(end 62.635384 -122.352816)
		(stroke
			(width 0.060198)
			(type default)
		)
		(layer "F.Cu")
	)
	(gr_line
		(start 62.5602 -121.5644)
		(end 62.635384 -121.639584)
		(stroke
			(width 0.060198)
			(type default)
		)
		(layer "F.Cu")
	)
	(gr_line
		(start 62.966854 -108.138214)
		(end 63.5508 -108.72216)
		(stroke
			(width 0.060198)
			(type default)
		)
		(layer "F.Cu")
	)
	(gr_line
		(start 62.966854 -107.286806)
		(end 62.966854 -108.138214)
		(stroke
			(width 0.060198)
			(type default)
		)
		(layer "F.Cu")
	)
	(gr_line
		(start 62.966854 -107.286806)
		(end 63.16726 -107.0864)
		(stroke
			(width 0.060198)
			(type default)
		)
		(layer "F.Cu")
	)
	(gr_line
		(start 63.16726 -107.0864)
		(end 63.9318 -107.0864)
		(stroke
			(width 0.060198)
			(type default)
		)
		(layer "F.Cu")
	)
	(gr_line
		(start 63.332868 -110.240572)
		(end 63.332868 -111.522256)
		(stroke
			(width 0.060198)
			(type default)
		)
		(layer "F.Cu")
	)
	(gr_line
		(start 63.332868 -110.240572)
		(end 63.5508 -110.02264)
		(stroke
			(width 0.060198)
			(type default)
		)
		(layer "F.Cu")
	)
	(gr_line
		(start 63.545974 -25.041606)
		(end 65.225422 -25.041606)
		(stroke
			(width 0.060198)
			(type default)
		)
		(layer "F.Cu")
	)
	(gr_line
		(start 63.545974 -19.961606)
		(end 65.463674 -19.961606)
		(stroke
			(width 0.052324)
			(type default)
		)
		(layer "F.Cu")
	)
	(gr_line
		(start 63.545974 -17.421606)
		(end 65.470786 -17.421606)
		(stroke
			(width 0.052324)
			(type default)
		)
		(layer "F.Cu")
	)
	(gr_line
		(start 63.5508 -110.02264)
		(end 64.17564 -110.02264)
		(stroke
			(width 0.060198)
			(type default)
		)
		(layer "F.Cu")
	)
	(gr_line
		(start 63.591948 -211.975954)
		(end 63.873634 -211.694268)
		(stroke
			(width 0.068326)
			(type default)
		)
		(layer "F.Cu")
	)
	(gr_line
		(start 63.693548 -210.896454)
		(end 63.813182 -211.016088)
		(stroke
			(width 0.068326)
			(type default)
		)
		(layer "F.Cu")
	)
	(gr_line
		(start 63.700152 -224.828354)
		(end 63.700152 -225.54438)
		(stroke
			(width 0.068326)
			(type default)
		)
		(layer "F.Cu")
	)
	(gr_arc
		(start 63.8683 -224.32264)
		(mid 63.743277 -224.561884)
		(end 63.700152 -224.828354)
		(stroke
			(width 0.068326)
			(type default)
		)
		(layer "F.Cu")
	)
	(gr_arc
		(start 63.8683 -224.32264)
		(mid 63.926934 -224.234888)
		(end 63.947548 -224.131378)
		(stroke
			(width 0.068326)
			(type default)
		)
		(layer "F.Cu")
	)
	(gr_arc
		(start 63.873634 -211.694268)
		(mid 63.923625 -211.619452)
		(end 63.941198 -211.5312)
		(stroke
			(width 0.068326)
			(type default)
		)
		(layer "F.Cu")
	)
	(gr_line
		(start 63.9318 -108.0008)
		(end 64.66205 -108.73105)
		(stroke
			(width 0.060198)
			(type default)
		)
		(layer "F.Cu")
	)
	(gr_arc
		(start 63.941198 -211.325206)
		(mid 63.907923 -211.157922)
		(end 63.813182 -211.016088)
		(stroke
			(width 0.068326)
			(type default)
		)
		(layer "F.Cu")
	)
	(gr_arc
		(start 63.947548 -213.723474)
		(mid 63.855129 -213.25885)
		(end 63.591948 -212.864954)
		(stroke
			(width 0.068326)
			(type default)
		)
		(layer "F.Cu")
	)
	(gr_line
		(start 64.17564 -110.02264)
		(end 64.3001 -110.1471)
		(stroke
			(width 0.060198)
			(type default)
		)
		(layer "F.Cu")
	)
	(gr_arc
		(start 64.245998 -211.5312)
		(mid 64.261279 -211.607656)
		(end 64.304672 -211.672424)
		(stroke
			(width 0.068326)
			(type default)
		)
		(layer "F.Cu")
	)
	(gr_arc
		(start 64.252602 -224.133664)
		(mid 64.272772 -224.234827)
		(end 64.330072 -224.320608)
		(stroke
			(width 0.068326)
			(type default)
		)
		(layer "F.Cu")
	)
	(gr_line
		(start 64.3001 -112.522)
		(end 64.3763 -112.5982)
		(stroke
			(width 0.060198)
			(type default)
		)
		(layer "F.Cu")
	)
	(gr_line
		(start 64.3001 -111.4044)
		(end 64.3001 -112.522)
		(stroke
			(width 0.060198)
			(type default)
		)
		(layer "F.Cu")
	)
	(gr_line
		(start 64.3001 -110.1471)
		(end 64.3001 -111.4044)
		(stroke
			(width 0.060198)
			(type default)
		)
		(layer "F.Cu")
	)
	(gr_line
		(start 64.304672 -211.672424)
		(end 64.607948 -211.975954)
		(stroke
			(width 0.068326)
			(type default)
		)
		(layer "F.Cu")
	)
	(gr_line
		(start 64.338708 -115.996466)
		(end 64.514476 -115.820698)
		(stroke
			(width 0.060198)
			(type default)
		)
		(layer "F.Cu")
	)
	(gr_line
		(start 64.3636 -114.5413)
		(end 64.53251 -114.71021)
		(stroke
			(width 0.060198)
			(type default)
		)
		(layer "F.Cu")
	)
	(gr_line
		(start 64.3636 -113.6523)
		(end 64.3763 -113.6396)
		(stroke
			(width 0.060198)
			(type default)
		)
		(layer "F.Cu")
	)
	(gr_arc
		(start 64.365124 -211.037678)
		(mid 64.276948 -211.169589)
		(end 64.245998 -211.325206)
		(stroke
			(width 0.068326)
			(type default)
		)
		(layer "F.Cu")
	)
	(gr_line
		(start 64.365124 -211.037678)
		(end 64.506348 -210.896454)
		(stroke
			(width 0.068326)
			(type default)
		)
		(layer "F.Cu")
	)
	(gr_line
		(start 64.3763 -112.5982)
		(end 64.3763 -113.6396)
		(stroke
			(width 0.060198)
			(type default)
		)
		(layer "F.Cu")
	)
	(gr_arc
		(start 64.499998 -224.828354)
		(mid 64.456361 -224.560646)
		(end 64.330072 -224.320608)
		(stroke
			(width 0.068326)
			(type default)
		)
		(layer "F.Cu")
	)
	(gr_line
		(start 64.499998 -224.828354)
		(end 64.499998 -225.54438)
		(stroke
			(width 0.068326)
			(type default)
		)
		(layer "F.Cu")
	)
	(gr_arc
		(start 64.607948 -212.864954)
		(mid 64.344963 -213.258486)
		(end 64.252602 -213.722712)
		(stroke
			(width 0.068326)
			(type default)
		)
		(layer "F.Cu")
	)
	(gr_line
		(start 64.66205 -110.91545)
		(end 65.151 -111.4044)
		(stroke
			(width 0.060198)
			(type default)
		)
		(layer "F.Cu")
	)
	(gr_line
		(start 64.66205 -108.73105)
		(end 64.66205 -110.91545)
		(stroke
			(width 0.060198)
			(type default)
		)
		(layer "F.Cu")
	)
	(gr_line
		(start 64.72047 -121.280428)
		(end 65.148968 -121.708926)
		(stroke
			(width 0.060198)
			(type default)
		)
		(layer "F.Cu")
	)
	(gr_line
		(start 64.72047 -120.567196)
		(end 65.044066 -120.2436)
		(stroke
			(width 0.060198)
			(type default)
		)
		(layer "F.Cu")
	)
	(gr_line
		(start 65.044066 -120.2436)
		(end 65.278 -120.2436)
		(stroke
			(width 0.060198)
			(type default)
		)
		(layer "F.Cu")
	)
	(gr_line
		(start 65.148968 -121.708926)
		(end 66.057272 -121.708926)
		(stroke
			(width 0.060198)
			(type default)
		)
		(layer "F.Cu")
	)
	(gr_line
		(start 65.151 -111.4044)
		(end 65.1891 -111.4044)
		(stroke
			(width 0.060198)
			(type default)
		)
		(layer "F.Cu")
	)
	(gr_line
		(start 65.1891 -111.4044)
		(end 65.4304 -111.1631)
		(stroke
			(width 0.060198)
			(type default)
		)
		(layer "F.Cu")
	)
	(gr_line
		(start 65.225422 -25.041606)
		(end 65.539366 -24.727662)
		(stroke
			(width 0.060198)
			(type default)
		)
		(layer "F.Cu")
	)
	(gr_line
		(start 65.227454 -115.820698)
		(end 65.403222 -115.996466)
		(stroke
			(width 0.060198)
			(type default)
		)
		(layer "F.Cu")
	)
	(gr_line
		(start 65.245742 -114.71021)
		(end 65.405 -114.550952)
		(stroke
			(width 0.060198)
			(type default)
		)
		(layer "F.Cu")
	)
	(gr_line
		(start 65.278 -120.2436)
		(end 66.1035 -120.2436)
		(stroke
			(width 0.060198)
			(type default)
		)
		(layer "F.Cu")
	)
	(gr_line
		(start 65.330578 -127.679196)
		(end 65.519554 -127.868172)
		(stroke
			(width 0.068326)
			(type default)
		)
		(layer "F.Cu")
	)
	(gr_line
		(start 65.3923 -112.5982)
		(end 65.405 -112.6109)
		(stroke
			(width 0.060198)
			(type default)
		)
		(layer "F.Cu")
	)
	(gr_line
		(start 65.3923 -112.5982)
		(end 66.004694 -111.985552)
		(stroke
			(width 0.060198)
			(type default)
		)
		(layer "F.Cu")
	)
	(gr_line
		(start 65.405 -112.6109)
		(end 65.405 -113.661952)
		(stroke
			(width 0.060198)
			(type default)
		)
		(layer "F.Cu")
	)
	(gr_line
		(start 65.4304 -110.02264)
		(end 65.4304 -111.1631)
		(stroke
			(width 0.060198)
			(type default)
		)
		(layer "F.Cu")
	)
	(gr_line
		(start 65.4304 -108.72216)
		(end 67.668648 -108.72216)
		(stroke
			(width 0.060198)
			(type default)
		)
		(layer "F.Cu")
	)
	(gr_line
		(start 65.4304 -107.7595)
		(end 65.4304 -108.72216)
		(stroke
			(width 0.060198)
			(type default)
		)
		(layer "F.Cu")
	)
	(gr_line
		(start 65.4304 -107.7595)
		(end 65.8749 -107.315)
		(stroke
			(width 0.060198)
			(type default)
		)
		(layer "F.Cu")
	)
	(gr_line
		(start 65.8749 -107.315)
		(end 66.3448 -107.315)
		(stroke
			(width 0.060198)
			(type default)
		)
		(layer "F.Cu")
	)
	(gr_line
		(start 65.91173 -127.910844)
		(end 66.143378 -127.679196)
		(stroke
			(width 0.068326)
			(type default)
		)
		(layer "F.Cu")
	)
	(gr_line
		(start 66.004694 -111.985552)
		(end 67.006978 -111.985552)
		(stroke
			(width 0.060198)
			(type default)
		)
		(layer "F.Cu")
	)
	(gr_line
		(start 66.057272 -121.708926)
		(end 66.8782 -122.529854)
		(stroke
			(width 0.060198)
			(type default)
		)
		(layer "F.Cu")
	)
	(gr_line
		(start 66.1035 -120.2436)
		(end 66.1924 -120.1547)
		(stroke
			(width 0.060198)
			(type default)
		)
		(layer "F.Cu")
	)
	(gr_line
		(start 66.1924 -120.1547)
		(end 66.3067 -120.0404)
		(stroke
			(width 0.060198)
			(type default)
		)
		(layer "F.Cu")
	)
	(gr_line
		(start 66.3067 -120.0404)
		(end 67.70116 -120.0404)
		(stroke
			(width 0.060198)
			(type default)
		)
		(layer "F.Cu")
	)
	(gr_line
		(start 66.3448 -107.315)
		(end 67.0814 -108.0516)
		(stroke
			(width 0.060198)
			(type default)
		)
		(layer "F.Cu")
	)
	(gr_line
		(start 66.3448 -26.7589)
		(end 67.263518 -26.7589)
		(stroke
			(width 0.060198)
			(type default)
		)
		(layer "F.Cu")
	)
	(gr_line
		(start 66.792094 -211.975954)
		(end 67.07378 -211.694268)
		(stroke
			(width 0.068326)
			(type default)
		)
		(layer "F.Cu")
	)
	(gr_line
		(start 66.8782 -123.5202)
		(end 68.08216 -124.72416)
		(stroke
			(width 0.060198)
			(type default)
		)
		(layer "F.Cu")
	)
	(gr_line
		(start 66.8782 -122.529854)
		(end 66.8782 -123.5202)
		(stroke
			(width 0.060198)
			(type default)
		)
		(layer "F.Cu")
	)
	(gr_line
		(start 66.893694 -210.896454)
		(end 67.031616 -211.034376)
		(stroke
			(width 0.068326)
			(type default)
		)
		(layer "F.Cu")
	)
	(gr_line
		(start 66.900044 -224.828608)
		(end 66.900044 -225.54438)
		(stroke
			(width 0.068326)
			(type default)
		)
		(layer "F.Cu")
	)
	(gr_line
		(start 66.900044 -224.828608)
		(end 66.900298 -224.828354)
		(stroke
			(width 0.068326)
			(type default)
		)
		(layer "F.Cu")
	)
	(gr_line
		(start 66.925952 -150.66391)
		(end 68.41109 -150.66391)
		(stroke
			(width 0.060198)
			(type default)
		)
		(layer "F.Cu")
	)
	(gr_line
		(start 66.925952 -149.39391)
		(end 68.11391 -149.39391)
		(stroke
			(width 0.060198)
			(type default)
		)
		(layer "F.Cu")
	)
	(gr_line
		(start 66.9798 -120.848882)
		(end 67.70116 -121.570242)
		(stroke
			(width 0.060198)
			(type default)
		)
		(layer "F.Cu")
	)
	(gr_line
		(start 66.9798 -120.5484)
		(end 66.9798 -120.848882)
		(stroke
			(width 0.060198)
			(type default)
		)
		(layer "F.Cu")
	)
	(gr_line
		(start 67.006978 -111.985552)
		(end 68.324476 -110.668054)
		(stroke
			(width 0.060198)
			(type default)
		)
		(layer "F.Cu")
	)
	(gr_arc
		(start 67.068446 -224.32264)
		(mid 66.943431 -224.561886)
		(end 66.900298 -224.828354)
		(stroke
			(width 0.068326)
			(type default)
		)
		(layer "F.Cu")
	)
	(gr_arc
		(start 67.068446 -224.32264)
		(mid 67.12708 -224.234888)
		(end 67.147694 -224.131378)
		(stroke
			(width 0.068326)
			(type default)
		)
		(layer "F.Cu")
	)
	(gr_arc
		(start 67.07378 -211.694268)
		(mid 67.123771 -211.619452)
		(end 67.141344 -211.5312)
		(stroke
			(width 0.068326)
			(type default)
		)
		(layer "F.Cu")
	)
	(gr_arc
		(start 67.147694 -213.723474)
		(mid 67.055275 -213.25885)
		(end 66.792094 -212.864954)
		(stroke
			(width 0.068326)
			(type default)
		)
		(layer "F.Cu")
	)
	(gr_arc
		(start 67.446144 -211.5312)
		(mid 67.461428 -211.607653)
		(end 67.504818 -211.672424)
		(stroke
			(width 0.068326)
			(type default)
		)
		(layer "F.Cu")
	)
	(gr_arc
		(start 67.452748 -224.133664)
		(mid 67.472915 -224.23483)
		(end 67.530218 -224.320608)
		(stroke
			(width 0.068326)
			(type default)
		)
		(layer "F.Cu")
	)
	(gr_line
		(start 67.504818 -211.672424)
		(end 67.808094 -211.975954)
		(stroke
			(width 0.068326)
			(type default)
		)
		(layer "F.Cu")
	)
	(gr_arc
		(start 67.545204 -211.057998)
		(mid 67.471959 -211.167535)
		(end 67.446144 -211.296758)
		(stroke
			(width 0.068326)
			(type default)
		)
		(layer "F.Cu")
	)
	(gr_line
		(start 67.545204 -211.057998)
		(end 67.706494 -210.896454)
		(stroke
			(width 0.068326)
			(type default)
		)
		(layer "F.Cu")
	)
	(gr_line
		(start 67.668648 -108.72216)
		(end 68.324476 -109.377988)
		(stroke
			(width 0.060198)
			(type default)
		)
		(layer "F.Cu")
	)
	(gr_arc
		(start 67.700144 -224.828354)
		(mid 67.656507 -224.560646)
		(end 67.530218 -224.320608)
		(stroke
			(width 0.068326)
			(type default)
		)
		(layer "F.Cu")
	)
	(gr_line
		(start 67.700144 -224.828354)
		(end 67.700144 -225.54438)
		(stroke
			(width 0.068326)
			(type default)
		)
		(layer "F.Cu")
	)
	(gr_line
		(start 67.70116 -121.570242)
		(end 67.70116 -121.92)
		(stroke
			(width 0.060198)
			(type default)
		)
		(layer "F.Cu")
	)
	(gr_arc
		(start 67.808094 -212.864954)
		(mid 67.545099 -213.258484)
		(end 67.452748 -213.722712)
		(stroke
			(width 0.068326)
			(type default)
		)
		(layer "F.Cu")
	)
	(gr_line
		(start 68.08216 -124.72416)
		(end 69.699378 -124.72416)
		(stroke
			(width 0.060198)
			(type default)
		)
		(layer "F.Cu")
	)
	(gr_line
		(start 68.11391 -149.39391)
		(end 68.326 -149.606)
		(stroke
			(width 0.060198)
			(type default)
		)
		(layer "F.Cu")
	)
	(gr_line
		(start 68.324476 -109.377988)
		(end 68.324476 -110.668054)
		(stroke
			(width 0.060198)
			(type default)
		)
		(layer "F.Cu")
	)
	(gr_line
		(start 69.00164 -121.92)
		(end 69.49694 -121.4247)
		(stroke
			(width 0.060198)
			(type default)
		)
		(layer "F.Cu")
	)
	(gr_line
		(start 69.49694 -121.4247)
		(end 70.6374 -121.4247)
		(stroke
			(width 0.060198)
			(type default)
		)
		(layer "F.Cu")
	)
	(gr_line
		(start 69.540882 -120.9294)
		(end 69.934582 -120.5357)
		(stroke
			(width 0.060198)
			(type default)
		)
		(layer "F.Cu")
	)
	(gr_line
		(start 69.699124 -196.125592)
		(end 69.850508 -196.276976)
		(stroke
			(width 0.060198)
			(type default)
		)
		(layer "F.Cu")
	)
	(gr_line
		(start 69.699124 -193.929)
		(end 69.699124 -195.236592)
		(stroke
			(width 0.060198)
			(type default)
		)
		(layer "F.Cu")
	)
	(gr_line
		(start 69.699124 -193.929)
		(end 70.080124 -193.548)
		(stroke
			(width 0.060198)
			(type default)
		)
		(layer "F.Cu")
	)
	(gr_line
		(start 69.699378 -124.72416)
		(end 70.634352 -123.789186)
		(stroke
			(width 0.060198)
			(type default)
		)
		(layer "F.Cu")
	)
	(gr_line
		(start 69.934582 -120.5357)
		(end 70.6374 -120.5357)
		(stroke
			(width 0.060198)
			(type default)
		)
		(layer "F.Cu")
	)
	(gr_line
		(start 69.991986 -211.975954)
		(end 70.273672 -211.694268)
		(stroke
			(width 0.068326)
			(type default)
		)
		(layer "F.Cu")
	)
	(gr_line
		(start 70.080124 -193.548)
		(end 70.866 -193.548)
		(stroke
			(width 0.060198)
			(type default)
		)
		(layer "F.Cu")
	)
	(gr_line
		(start 70.093586 -210.896454)
		(end 70.23227 -211.035392)
		(stroke
			(width 0.068326)
			(type default)
		)
		(layer "F.Cu")
	)
	(gr_line
		(start 70.10019 -224.828354)
		(end 70.10019 -225.54438)
		(stroke
			(width 0.068326)
			(type default)
		)
		(layer "F.Cu")
	)
	(gr_arc
		(start 70.268338 -224.32264)
		(mid 70.143309 -224.561883)
		(end 70.10019 -224.828354)
		(stroke
			(width 0.068326)
			(type default)
		)
		(layer "F.Cu")
	)
	(gr_arc
		(start 70.268338 -224.32264)
		(mid 70.326972 -224.234888)
		(end 70.347586 -224.131378)
		(stroke
			(width 0.068326)
			(type default)
		)
		(layer "F.Cu")
	)
	(gr_arc
		(start 70.273672 -211.694268)
		(mid 70.323663 -211.619452)
		(end 70.341236 -211.5312)
		(stroke
			(width 0.068326)
			(type default)
		)
		(layer "F.Cu")
	)
	(gr_arc
		(start 70.341236 -211.298028)
		(mid 70.312867 -211.155876)
		(end 70.23227 -211.035392)
		(stroke
			(width 0.068326)
			(type default)
		)
		(layer "F.Cu")
	)
	(gr_arc
		(start 70.347586 -213.723474)
		(mid 70.255167 -213.25885)
		(end 69.991986 -212.864954)
		(stroke
			(width 0.068326)
			(type default)
		)
		(layer "F.Cu")
	)
	(gr_line
		(start 70.56374 -196.276976)
		(end 70.715124 -196.125592)
		(stroke
			(width 0.060198)
			(type default)
		)
		(layer "F.Cu")
	)
	(gr_line
		(start 70.634352 -122.431048)
		(end 70.634352 -123.789186)
		(stroke
			(width 0.060198)
			(type default)
		)
		(layer "F.Cu")
	)
	(gr_line
		(start 70.634352 -122.431048)
		(end 70.6374 -122.428)
		(stroke
			(width 0.060198)
			(type default)
		)
		(layer "F.Cu")
	)
	(gr_line
		(start 70.6374 -121.4247)
		(end 70.6374 -122.428)
		(stroke
			(width 0.060198)
			(type default)
		)
		(layer "F.Cu")
	)
	(gr_arc
		(start 70.646036 -211.5312)
		(mid 70.66132 -211.607653)
		(end 70.70471 -211.672424)
		(stroke
			(width 0.068326)
			(type default)
		)
		(layer "F.Cu")
	)
	(gr_arc
		(start 70.65264 -224.133664)
		(mid 70.672806 -224.23483)
		(end 70.73011 -224.320608)
		(stroke
			(width 0.068326)
			(type default)
		)
		(layer "F.Cu")
	)
	(gr_line
		(start 70.70471 -211.672424)
		(end 71.007986 -211.975954)
		(stroke
			(width 0.068326)
			(type default)
		)
		(layer "F.Cu")
	)
	(gr_line
		(start 70.715124 -194.460876)
		(end 70.715124 -195.236592)
		(stroke
			(width 0.060198)
			(type default)
		)
		(layer "F.Cu")
	)
	(gr_line
		(start 70.715124 -194.460876)
		(end 70.993 -194.183)
		(stroke
			(width 0.060198)
			(type default)
		)
		(layer "F.Cu")
	)
	(gr_arc
		(start 70.757034 -211.045806)
		(mid 70.674876 -211.16875)
		(end 70.646036 -211.313776)
		(stroke
			(width 0.068326)
			(type default)
		)
		(layer "F.Cu")
	)
	(gr_line
		(start 70.757034 -211.045806)
		(end 70.906386 -210.896454)
		(stroke
			(width 0.068326)
			(type default)
		)
		(layer "F.Cu")
	)
	(gr_line
		(start 70.866 -193.548)
		(end 71.017384 -193.396616)
		(stroke
			(width 0.060198)
			(type default)
		)
		(layer "F.Cu")
	)
	(gr_arc
		(start 70.900036 -224.828354)
		(mid 70.856399 -224.560646)
		(end 70.73011 -224.320608)
		(stroke
			(width 0.068326)
			(type default)
		)
		(layer "F.Cu")
	)
	(gr_line
		(start 70.900036 -224.828354)
		(end 70.900036 -225.54438)
		(stroke
			(width 0.068326)
			(type default)
		)
		(layer "F.Cu")
	)
	(gr_line
		(start 70.993 -194.183)
		(end 71.628 -193.548)
		(stroke
			(width 0.060198)
			(type default)
		)
		(layer "F.Cu")
	)
	(gr_arc
		(start 71.007986 -212.864954)
		(mid 70.744993 -213.258484)
		(end 70.65264 -213.722712)
		(stroke
			(width 0.068326)
			(type default)
		)
		(layer "F.Cu")
	)
	(gr_line
		(start 71.019162 -193.394838)
		(end 71.218044 -193.195956)
		(stroke
			(width 0.060198)
			(type default)
		)
		(layer "F.Cu")
	)
	(gr_line
		(start 71.218044 -192.79235)
		(end 71.218044 -193.195956)
		(stroke
			(width 0.060198)
			(type default)
		)
		(layer "F.Cu")
	)
	(gr_line
		(start 71.218044 -192.404492)
		(end 71.218044 -192.78981)
		(stroke
			(width 0.060198)
			(type default)
		)
		(layer "F.Cu")
	)
	(gr_line
		(start 71.628 -193.294)
		(end 71.628 -193.548)
		(stroke
			(width 0.060198)
			(type default)
		)
		(layer "F.Cu")
	)
	(gr_line
		(start 71.628 -193.294)
		(end 71.719694 -193.202306)
		(stroke
			(width 0.060198)
			(type default)
		)
		(layer "F.Cu")
	)
	(gr_line
		(start 71.82866 -193.09334)
		(end 71.868284 -193.053716)
		(stroke
			(width 0.060198)
			(type default)
		)
		(layer "F.Cu")
	)
	(gr_line
		(start 71.868284 -192.404492)
		(end 71.868284 -193.053716)
		(stroke
			(width 0.060198)
			(type default)
		)
		(layer "F.Cu")
	)
	(gr_line
		(start 79.591916 -211.975954)
		(end 79.873602 -211.694268)
		(stroke
			(width 0.068326)
			(type default)
		)
		(layer "F.Cu")
	)
	(gr_line
		(start 79.693516 -210.896454)
		(end 79.864966 -211.067904)
		(stroke
			(width 0.068326)
			(type default)
		)
		(layer "F.Cu")
	)
	(gr_line
		(start 79.70012 -224.828354)
		(end 79.70012 -225.54438)
		(stroke
			(width 0.068326)
			(type default)
		)
		(layer "F.Cu")
	)
	(gr_arc
		(start 79.868268 -224.32264)
		(mid 79.743249 -224.561885)
		(end 79.70012 -224.828354)
		(stroke
			(width 0.068326)
			(type default)
		)
		(layer "F.Cu")
	)
	(gr_arc
		(start 79.868268 -224.32264)
		(mid 79.926902 -224.234888)
		(end 79.947516 -224.131378)
		(stroke
			(width 0.068326)
			(type default)
		)
		(layer "F.Cu")
	)
	(gr_arc
		(start 79.873602 -211.694268)
		(mid 79.923593 -211.619452)
		(end 79.941166 -211.5312)
		(stroke
			(width 0.068326)
			(type default)
		)
		(layer "F.Cu")
	)
	(gr_arc
		(start 79.941166 -211.2518)
		(mid 79.921367 -211.152266)
		(end 79.864966 -211.067904)
		(stroke
			(width 0.068326)
			(type default)
		)
		(layer "F.Cu")
	)
	(gr_arc
		(start 79.947516 -213.723474)
		(mid 79.855097 -213.25885)
		(end 79.591916 -212.864954)
		(stroke
			(width 0.068326)
			(type default)
		)
		(layer "F.Cu")
	)
	(gr_arc
		(start 80.245966 -211.5312)
		(mid 80.261251 -211.607652)
		(end 80.30464 -211.672424)
		(stroke
			(width 0.068326)
			(type default)
		)
		(layer "F.Cu")
	)
	(gr_arc
		(start 80.25257 -224.133664)
		(mid 80.272738 -224.234828)
		(end 80.33004 -224.320608)
		(stroke
			(width 0.068326)
			(type default)
		)
		(layer "F.Cu")
	)
	(gr_line
		(start 80.30464 -211.672424)
		(end 80.607916 -211.975954)
		(stroke
			(width 0.068326)
			(type default)
		)
		(layer "F.Cu")
	)
	(gr_arc
		(start 80.321404 -211.081366)
		(mid 80.265563 -211.16492)
		(end 80.245966 -211.263484)
		(stroke
			(width 0.068326)
			(type default)
		)
		(layer "F.Cu")
	)
	(gr_line
		(start 80.321404 -211.081366)
		(end 80.506316 -210.896454)
		(stroke
			(width 0.068326)
			(type default)
		)
		(layer "F.Cu")
	)
	(gr_arc
		(start 80.499966 -224.828354)
		(mid 80.456329 -224.560646)
		(end 80.33004 -224.320608)
		(stroke
			(width 0.068326)
			(type default)
		)
		(layer "F.Cu")
	)
	(gr_line
		(start 80.499966 -224.828354)
		(end 80.499966 -225.54438)
		(stroke
			(width 0.068326)
			(type default)
		)
		(layer "F.Cu")
	)
	(gr_arc
		(start 80.607916 -212.864954)
		(mid 80.344917 -213.258482)
		(end 80.25257 -213.722712)
		(stroke
			(width 0.068326)
			(type default)
		)
		(layer "F.Cu")
	)
	(gr_line
		(start 82.792062 -211.975954)
		(end 83.073748 -211.694268)
		(stroke
			(width 0.068326)
			(type default)
		)
		(layer "F.Cu")
	)
	(gr_line
		(start 82.893662 -210.896454)
		(end 83.029298 -211.03209)
		(stroke
			(width 0.068326)
			(type default)
		)
		(layer "F.Cu")
	)
	(gr_line
		(start 82.900012 -224.828608)
		(end 82.900012 -225.54438)
		(stroke
			(width 0.068326)
			(type default)
		)
		(layer "F.Cu")
	)
	(gr_line
		(start 82.900012 -224.828608)
		(end 82.900266 -224.828354)
		(stroke
			(width 0.068326)
			(type default)
		)
		(layer "F.Cu")
	)
	(gr_arc
		(start 83.068414 -224.32264)
		(mid 82.943389 -224.561884)
		(end 82.900266 -224.828354)
		(stroke
			(width 0.068326)
			(type default)
		)
		(layer "F.Cu")
	)
	(gr_arc
		(start 83.068414 -224.32264)
		(mid 83.127048 -224.234888)
		(end 83.147662 -224.131378)
		(stroke
			(width 0.068326)
			(type default)
		)
		(layer "F.Cu")
	)
	(gr_arc
		(start 83.073748 -211.694268)
		(mid 83.123739 -211.619452)
		(end 83.141312 -211.5312)
		(stroke
			(width 0.068326)
			(type default)
		)
		(layer "F.Cu")
	)
	(gr_arc
		(start 83.141312 -211.3026)
		(mid 83.112194 -211.156214)
		(end 83.029298 -211.03209)
		(stroke
			(width 0.068326)
			(type default)
		)
		(layer "F.Cu")
	)
	(gr_arc
		(start 83.147662 -213.723474)
		(mid 83.055243 -213.25885)
		(end 82.792062 -212.864954)
		(stroke
			(width 0.068326)
			(type default)
		)
		(layer "F.Cu")
	)
	(gr_arc
		(start 83.446112 -211.5312)
		(mid 83.461394 -211.607655)
		(end 83.504786 -211.672424)
		(stroke
			(width 0.068326)
			(type default)
		)
		(layer "F.Cu")
	)
	(gr_arc
		(start 83.452716 -224.133664)
		(mid 83.472887 -224.234826)
		(end 83.530186 -224.320608)
		(stroke
			(width 0.068326)
			(type default)
		)
		(layer "F.Cu")
	)
	(gr_line
		(start 83.504786 -211.672424)
		(end 83.808062 -211.975954)
		(stroke
			(width 0.068326)
			(type default)
		)
		(layer "F.Cu")
	)
	(gr_arc
		(start 83.556856 -211.045806)
		(mid 83.474853 -211.168645)
		(end 83.446112 -211.313522)
		(stroke
			(width 0.068326)
			(type default)
		)
		(layer "F.Cu")
	)
	(gr_line
		(start 83.556856 -211.045806)
		(end 83.706462 -210.896454)
		(stroke
			(width 0.068326)
			(type default)
		)
		(layer "F.Cu")
	)
	(gr_arc
		(start 83.700112 -224.828354)
		(mid 83.656475 -224.560646)
		(end 83.530186 -224.320608)
		(stroke
			(width 0.068326)
			(type default)
		)
		(layer "F.Cu")
	)
	(gr_line
		(start 83.700112 -224.828354)
		(end 83.700112 -225.54438)
		(stroke
			(width 0.068326)
			(type default)
		)
		(layer "F.Cu")
	)
	(gr_arc
		(start 83.808062 -212.864954)
		(mid 83.545074 -213.258485)
		(end 83.452716 -213.722712)
		(stroke
			(width 0.068326)
			(type default)
		)
		(layer "F.Cu")
	)
	(gr_line
		(start 85.991954 -211.975954)
		(end 86.27364 -211.694268)
		(stroke
			(width 0.068326)
			(type default)
		)
		(layer "F.Cu")
	)
	(gr_line
		(start 86.093554 -210.896454)
		(end 86.22919 -211.03209)
		(stroke
			(width 0.068326)
			(type default)
		)
		(layer "F.Cu")
	)
	(gr_line
		(start 86.100158 -224.828354)
		(end 86.100158 -225.54438)
		(stroke
			(width 0.068326)
			(type default)
		)
		(layer "F.Cu")
	)
	(gr_arc
		(start 86.268306 -224.32264)
		(mid 86.143282 -224.561884)
		(end 86.100158 -224.828354)
		(stroke
			(width 0.068326)
			(type default)
		)
		(layer "F.Cu")
	)
	(gr_arc
		(start 86.268306 -224.32264)
		(mid 86.32694 -224.234888)
		(end 86.347554 -224.131378)
		(stroke
			(width 0.068326)
			(type default)
		)
		(layer "F.Cu")
	)
	(gr_arc
		(start 86.27364 -211.694268)
		(mid 86.323631 -211.619452)
		(end 86.341204 -211.5312)
		(stroke
			(width 0.068326)
			(type default)
		)
		(layer "F.Cu")
	)
	(gr_arc
		(start 86.341204 -211.3026)
		(mid 86.312086 -211.156214)
		(end 86.22919 -211.03209)
		(stroke
			(width 0.068326)
			(type default)
		)
		(layer "F.Cu")
	)
	(gr_arc
		(start 86.347554 -213.723474)
		(mid 86.255135 -213.25885)
		(end 85.991954 -212.864954)
		(stroke
			(width 0.068326)
			(type default)
		)
		(layer "F.Cu")
	)
	(gr_arc
		(start 86.646004 -211.5312)
		(mid 86.661286 -211.607655)
		(end 86.704678 -211.672424)
		(stroke
			(width 0.068326)
			(type default)
		)
		(layer "F.Cu")
	)
	(gr_arc
		(start 86.652608 -224.133664)
		(mid 86.672778 -224.234826)
		(end 86.730078 -224.320608)
		(stroke
			(width 0.068326)
			(type default)
		)
		(layer "F.Cu")
	)
	(gr_line
		(start 86.704678 -211.672424)
		(end 87.007954 -211.975954)
		(stroke
			(width 0.068326)
			(type default)
		)
		(layer "F.Cu")
	)
	(gr_arc
		(start 86.756748 -211.045806)
		(mid 86.674747 -211.168645)
		(end 86.646004 -211.313522)
		(stroke
			(width 0.068326)
			(type default)
		)
		(layer "F.Cu")
	)
	(gr_line
		(start 86.756748 -211.045806)
		(end 86.906354 -210.896454)
		(stroke
			(width 0.068326)
			(type default)
		)
		(layer "F.Cu")
	)
	(gr_arc
		(start 86.900004 -224.828354)
		(mid 86.856367 -224.560646)
		(end 86.730078 -224.320608)
		(stroke
			(width 0.068326)
			(type default)
		)
		(layer "F.Cu")
	)
	(gr_line
		(start 86.900004 -224.828354)
		(end 86.900004 -225.54438)
		(stroke
			(width 0.068326)
			(type default)
		)
		(layer "F.Cu")
	)
	(gr_arc
		(start 87.007954 -212.864954)
		(mid 86.744968 -213.258486)
		(end 86.652608 -213.722712)
		(stroke
			(width 0.068326)
			(type default)
		)
		(layer "F.Cu")
	)
	(gr_line
		(start 89.1921 -211.975954)
		(end 89.473786 -211.694268)
		(stroke
			(width 0.068326)
			(type default)
		)
		(layer "F.Cu")
	)
	(gr_line
		(start 89.2937 -210.896454)
		(end 89.40673 -211.009738)
		(stroke
			(width 0.068326)
			(type default)
		)
		(layer "F.Cu")
	)
	(gr_line
		(start 89.30005 -224.828608)
		(end 89.30005 -225.54438)
		(stroke
			(width 0.068326)
			(type default)
		)
		(layer "F.Cu")
	)
	(gr_line
		(start 89.30005 -224.828608)
		(end 89.300304 -224.828354)
		(stroke
			(width 0.068326)
			(type default)
		)
		(layer "F.Cu")
	)
	(gr_line
		(start 89.36609 -33.470088)
		(end 89.5604 -33.664398)
		(stroke
			(width 0.060198)
			(type default)
		)
		(layer "F.Cu")
	)
	(gr_line
		(start 89.36609 -32.75711)
		(end 89.5604 -32.5628)
		(stroke
			(width 0.060198)
			(type default)
		)
		(layer "F.Cu")
	)
	(gr_arc
		(start 89.468452 -224.32264)
		(mid 89.343436 -224.561885)
		(end 89.300304 -224.828354)
		(stroke
			(width 0.068326)
			(type default)
		)
		(layer "F.Cu")
	)
	(gr_arc
		(start 89.468452 -224.32264)
		(mid 89.527086 -224.234888)
		(end 89.5477 -224.131378)
		(stroke
			(width 0.068326)
			(type default)
		)
		(layer "F.Cu")
	)
	(gr_arc
		(start 89.473786 -211.694268)
		(mid 89.523777 -211.619452)
		(end 89.54135 -211.5312)
		(stroke
			(width 0.068326)
			(type default)
		)
		(layer "F.Cu")
	)
	(gr_arc
		(start 89.54135 -211.33435)
		(mid 89.50631 -211.158663)
		(end 89.40673 -211.009738)
		(stroke
			(width 0.068326)
			(type default)
		)
		(layer "F.Cu")
	)
	(gr_arc
		(start 89.5477 -213.723474)
		(mid 89.455281 -213.25885)
		(end 89.1921 -212.864954)
		(stroke
			(width 0.068326)
			(type default)
		)
		(layer "F.Cu")
	)
	(gr_arc
		(start 89.84615 -211.5312)
		(mid 89.861434 -211.607653)
		(end 89.904824 -211.672424)
		(stroke
			(width 0.068326)
			(type default)
		)
		(layer "F.Cu")
	)
	(gr_arc
		(start 89.852754 -224.133664)
		(mid 89.872921 -224.234829)
		(end 89.930224 -224.320608)
		(stroke
			(width 0.068326)
			(type default)
		)
		(layer "F.Cu")
	)
	(gr_line
		(start 89.904824 -211.672424)
		(end 90.2081 -211.975954)
		(stroke
			(width 0.068326)
			(type default)
		)
		(layer "F.Cu")
	)
	(gr_arc
		(start 89.971626 -211.031074)
		(mid 89.878692 -211.170222)
		(end 89.84615 -211.33435)
		(stroke
			(width 0.068326)
			(type default)
		)
		(layer "F.Cu")
	)
	(gr_line
		(start 89.971626 -211.031074)
		(end 90.1065 -210.896454)
		(stroke
			(width 0.068326)
			(type default)
		)
		(layer "F.Cu")
	)
	(gr_arc
		(start 90.10015 -224.828354)
		(mid 90.056513 -224.560646)
		(end 89.930224 -224.320608)
		(stroke
			(width 0.068326)
			(type default)
		)
		(layer "F.Cu")
	)
	(gr_line
		(start 90.10015 -224.828354)
		(end 90.10015 -225.54438)
		(stroke
			(width 0.068326)
			(type default)
		)
		(layer "F.Cu")
	)
	(gr_arc
		(start 90.2081 -212.864954)
		(mid 89.945104 -213.258483)
		(end 89.852754 -213.722712)
		(stroke
			(width 0.068326)
			(type default)
		)
		(layer "F.Cu")
	)
	(gr_arc
		(start 91.90863 -185.763154)
		(mid 91.954883 -185.693932)
		(end 91.971114 -185.612278)
		(stroke
			(width 0.068326)
			(type default)
		)
		(layer "F.Cu")
	)
	(gr_line
		(start 91.971114 -185.302652)
		(end 91.971114 -185.612278)
		(stroke
			(width 0.068326)
			(type default)
		)
		(layer "F.Cu")
	)
	(gr_line
		(start 92.283788 -190.179198)
		(end 92.288868 -190.207392)
		(stroke
			(width 0.068326)
			(type default)
		)
		(layer "F.Cu")
	)
	(gr_line
		(start 92.288868 -190.207392)
		(end 92.305124 -190.23076)
		(stroke
			(width 0.068326)
			(type default)
		)
		(layer "F.Cu")
	)
	(gr_arc
		(start 92.368878 -185.877454)
		(mid 92.236504 -185.903816)
		(end 92.124276 -185.9788)
		(stroke
			(width 0.068326)
			(type default)
		)
		(layer "F.Cu")
	)
	(gr_line
		(start 92.368878 -185.877454)
		(end 92.545916 -185.877454)
		(stroke
			(width 0.068326)
			(type default)
		)
		(layer "F.Cu")
	)
	(gr_line
		(start 92.391992 -211.975954)
		(end 92.673678 -211.694268)
		(stroke
			(width 0.068326)
			(type default)
		)
		(layer "F.Cu")
	)
	(gr_line
		(start 92.493592 -210.896454)
		(end 92.625164 -211.027772)
		(stroke
			(width 0.068326)
			(type default)
		)
		(layer "F.Cu")
	)
	(gr_line
		(start 92.500196 -224.828354)
		(end 92.500196 -225.54438)
		(stroke
			(width 0.068326)
			(type default)
		)
		(layer "F.Cu")
	)
	(gr_arc
		(start 92.668344 -224.32264)
		(mid 92.543329 -224.561886)
		(end 92.500196 -224.828354)
		(stroke
			(width 0.068326)
			(type default)
		)
		(layer "F.Cu")
	)
	(gr_arc
		(start 92.668344 -224.32264)
		(mid 92.726978 -224.234888)
		(end 92.747592 -224.131378)
		(stroke
			(width 0.068326)
			(type default)
		)
		(layer "F.Cu")
	)
	(gr_arc
		(start 92.673678 -211.694268)
		(mid 92.723669 -211.619452)
		(end 92.741242 -211.5312)
		(stroke
			(width 0.068326)
			(type default)
		)
		(layer "F.Cu")
	)
	(gr_arc
		(start 92.741242 -211.308442)
		(mid 92.711124 -211.156559)
		(end 92.625164 -211.027772)
		(stroke
			(width 0.068326)
			(type default)
		)
		(layer "F.Cu")
	)
	(gr_arc
		(start 92.747592 -213.723474)
		(mid 92.655173 -213.25885)
		(end 92.391992 -212.864954)
		(stroke
			(width 0.068326)
			(type default)
		)
		(layer "F.Cu")
	)
	(gr_arc
		(start 93.046042 -211.5312)
		(mid 93.061326 -211.607653)
		(end 93.104716 -211.672424)
		(stroke
			(width 0.068326)
			(type default)
		)
		(layer "F.Cu")
	)
	(gr_arc
		(start 93.052646 -224.133664)
		(mid 93.072813 -224.23483)
		(end 93.130116 -224.320608)
		(stroke
			(width 0.068326)
			(type default)
		)
		(layer "F.Cu")
	)
	(gr_line
		(start 93.104716 -211.672424)
		(end 93.407992 -211.975954)
		(stroke
			(width 0.068326)
			(type default)
		)
		(layer "F.Cu")
	)
	(gr_arc
		(start 93.153484 -211.049362)
		(mid 93.073956 -211.168339)
		(end 93.046042 -211.308696)
		(stroke
			(width 0.068326)
			(type default)
		)
		(layer "F.Cu")
	)
	(gr_line
		(start 93.153484 -211.049362)
		(end 93.306392 -210.896454)
		(stroke
			(width 0.068326)
			(type default)
		)
		(layer "F.Cu")
	)
	(gr_arc
		(start 93.300042 -224.828354)
		(mid 93.256405 -224.560646)
		(end 93.130116 -224.320608)
		(stroke
			(width 0.068326)
			(type default)
		)
		(layer "F.Cu")
	)
	(gr_line
		(start 93.300042 -224.828354)
		(end 93.300042 -225.54438)
		(stroke
			(width 0.068326)
			(type default)
		)
		(layer "F.Cu")
	)
	(gr_arc
		(start 93.407992 -212.864954)
		(mid 93.144998 -213.258484)
		(end 93.052646 -213.722712)
		(stroke
			(width 0.068326)
			(type default)
		)
		(layer "F.Cu")
	)
	(gr_line
		(start 95.960184 -195.45046)
		(end 95.969074 -195.46316)
		(stroke
			(width 0.068326)
			(type default)
		)
		(layer "F.Cu")
	)
	(gr_line
		(start 95.969074 -195.46316)
		(end 95.981774 -195.47205)
		(stroke
			(width 0.068326)
			(type default)
		)
		(layer "F.Cu")
	)
	(gr_line
		(start 97.992184 -211.975954)
		(end 98.27387 -211.694268)
		(stroke
			(width 0.068326)
			(type default)
		)
		(layer "F.Cu")
	)
	(gr_line
		(start 98.093784 -210.896454)
		(end 98.2472 -211.050124)
		(stroke
			(width 0.068326)
			(type default)
		)
		(layer "F.Cu")
	)
	(gr_line
		(start 98.100134 -224.828608)
		(end 98.100134 -225.54438)
		(stroke
			(width 0.068326)
			(type default)
		)
		(layer "F.Cu")
	)
	(gr_line
		(start 98.100134 -224.828608)
		(end 98.100388 -224.828354)
		(stroke
			(width 0.068326)
			(type default)
		)
		(layer "F.Cu")
	)
	(gr_arc
		(start 98.268536 -224.32264)
		(mid 98.143507 -224.561883)
		(end 98.100388 -224.828354)
		(stroke
			(width 0.068326)
			(type default)
		)
		(layer "F.Cu")
	)
	(gr_arc
		(start 98.268536 -224.32264)
		(mid 98.32717 -224.234888)
		(end 98.347784 -224.131378)
		(stroke
			(width 0.068326)
			(type default)
		)
		(layer "F.Cu")
	)
	(gr_arc
		(start 98.27387 -211.694268)
		(mid 98.323861 -211.619452)
		(end 98.341434 -211.5312)
		(stroke
			(width 0.068326)
			(type default)
		)
		(layer "F.Cu")
	)
	(gr_arc
		(start 98.341434 -211.2772)
		(mid 98.316893 -211.154294)
		(end 98.2472 -211.050124)
		(stroke
			(width 0.068326)
			(type default)
		)
		(layer "F.Cu")
	)
	(gr_arc
		(start 98.347784 -213.723474)
		(mid 98.255365 -213.25885)
		(end 97.992184 -212.864954)
		(stroke
			(width 0.068326)
			(type default)
		)
		(layer "F.Cu")
	)
	(gr_arc
		(start 98.646234 -211.5312)
		(mid 98.661518 -211.607654)
		(end 98.704908 -211.672424)
		(stroke
			(width 0.068326)
			(type default)
		)
		(layer "F.Cu")
	)
	(gr_arc
		(start 98.652838 -224.133664)
		(mid 98.673004 -224.23483)
		(end 98.730308 -224.320608)
		(stroke
			(width 0.068326)
			(type default)
		)
		(layer "F.Cu")
	)
	(gr_line
		(start 98.704908 -211.672424)
		(end 99.008184 -211.975954)
		(stroke
			(width 0.068326)
			(type default)
		)
		(layer "F.Cu")
	)
	(gr_arc
		(start 98.73996 -211.063078)
		(mid 98.670605 -211.166918)
		(end 98.646234 -211.289392)
		(stroke
			(width 0.068326)
			(type default)
		)
		(layer "F.Cu")
	)
	(gr_line
		(start 98.73996 -211.063078)
		(end 98.906584 -210.896454)
		(stroke
			(width 0.068326)
			(type default)
		)
		(layer "F.Cu")
	)
	(gr_line
		(start 98.89998 -224.828608)
		(end 98.89998 -225.54438)
		(stroke
			(width 0.068326)
			(type default)
		)
		(layer "F.Cu")
	)
	(gr_line
		(start 98.89998 -224.828608)
		(end 98.900234 -224.828354)
		(stroke
			(width 0.068326)
			(type default)
		)
		(layer "F.Cu")
	)
	(gr_arc
		(start 98.900234 -224.828354)
		(mid 98.856597 -224.560646)
		(end 98.730308 -224.320608)
		(stroke
			(width 0.068326)
			(type default)
		)
		(layer "F.Cu")
	)
	(gr_arc
		(start 99.008184 -212.864954)
		(mid 98.745191 -213.258484)
		(end 98.652838 -213.722712)
		(stroke
			(width 0.068326)
			(type default)
		)
		(layer "F.Cu")
	)
	(gr_line
		(start 101.192076 -211.975954)
		(end 101.473762 -211.694268)
		(stroke
			(width 0.068326)
			(type default)
		)
		(layer "F.Cu")
	)
	(gr_line
		(start 101.293676 -210.896454)
		(end 101.435154 -211.037932)
		(stroke
			(width 0.068326)
			(type default)
		)
		(layer "F.Cu")
	)
	(gr_line
		(start 101.300026 -224.828608)
		(end 101.300026 -225.54438)
		(stroke
			(width 0.068326)
			(type default)
		)
		(layer "F.Cu")
	)
	(gr_line
		(start 101.300026 -224.828608)
		(end 101.30028 -224.828354)
		(stroke
			(width 0.068326)
			(type default)
		)
		(layer "F.Cu")
	)
	(gr_arc
		(start 101.468428 -224.32264)
		(mid 101.343401 -224.561883)
		(end 101.30028 -224.828354)
		(stroke
			(width 0.068326)
			(type default)
		)
		(layer "F.Cu")
	)
	(gr_arc
		(start 101.468428 -224.32264)
		(mid 101.527062 -224.234888)
		(end 101.547676 -224.131378)
		(stroke
			(width 0.068326)
			(type default)
		)
		(layer "F.Cu")
	)
	(gr_arc
		(start 101.473762 -211.694268)
		(mid 101.523753 -211.619452)
		(end 101.541326 -211.5312)
		(stroke
			(width 0.068326)
			(type default)
		)
		(layer "F.Cu")
	)
	(gr_arc
		(start 101.547676 -213.723474)
		(mid 101.455257 -213.25885)
		(end 101.192076 -212.864954)
		(stroke
			(width 0.068326)
			(type default)
		)
		(layer "F.Cu")
	)
	(gr_arc
		(start 101.846126 -211.5312)
		(mid 101.861409 -211.607654)
		(end 101.9048 -211.672424)
		(stroke
			(width 0.068326)
			(type default)
		)
		(layer "F.Cu")
	)
	(gr_arc
		(start 101.85273 -224.133664)
		(mid 101.872902 -224.234825)
		(end 101.9302 -224.320608)
		(stroke
			(width 0.068326)
			(type default)
		)
		(layer "F.Cu")
	)
	(gr_line
		(start 101.9048 -211.672424)
		(end 102.208076 -211.975954)
		(stroke
			(width 0.068326)
			(type default)
		)
		(layer "F.Cu")
	)
	(gr_arc
		(start 101.934518 -211.068412)
		(mid 101.869084 -211.166296)
		(end 101.846126 -211.281772)
		(stroke
			(width 0.068326)
			(type default)
		)
		(layer "F.Cu")
	)
	(gr_line
		(start 101.934518 -211.068412)
		(end 102.106476 -210.896454)
		(stroke
			(width 0.068326)
			(type default)
		)
		(layer "F.Cu")
	)
	(gr_arc
		(start 102.100126 -224.828354)
		(mid 102.056489 -224.560646)
		(end 101.9302 -224.320608)
		(stroke
			(width 0.068326)
			(type default)
		)
		(layer "F.Cu")
	)
	(gr_line
		(start 102.100126 -224.828354)
		(end 102.100126 -225.54438)
		(stroke
			(width 0.068326)
			(type default)
		)
		(layer "F.Cu")
	)
	(gr_arc
		(start 102.208076 -212.864954)
		(mid 101.945085 -213.258485)
		(end 101.85273 -213.722712)
		(stroke
			(width 0.068326)
			(type default)
		)
		(layer "F.Cu")
	)
	(gr_arc
		(start 102.21976 -81.407)
		(mid 102.507154 -81.287982)
		(end 102.62616 -81.0006)
		(stroke
			(width 0.068326)
			(type default)
		)
		(layer "F.Cu")
	)
	(gr_arc
		(start 102.62616 -82.1182)
		(mid 102.541241 -81.834416)
		(end 102.271576 -81.7118)
		(stroke
			(width 0.068326)
			(type default)
		)
		(layer "F.Cu")
	)
	(gr_line
		(start 104.12603 -200.802494)
		(end 104.13873 -200.811384)
		(stroke
			(width 0.068326)
			(type default)
		)
		(layer "F.Cu")
	)
	(gr_line
		(start 104.13873 -200.811384)
		(end 104.14762 -200.824084)
		(stroke
			(width 0.068326)
			(type default)
		)
		(layer "F.Cu")
	)
	(gr_line
		(start 104.392222 -211.975954)
		(end 104.673908 -211.694268)
		(stroke
			(width 0.068326)
			(type default)
		)
		(layer "F.Cu")
	)
	(gr_line
		(start 104.493822 -210.896454)
		(end 104.635808 -211.03844)
		(stroke
			(width 0.068326)
			(type default)
		)
		(layer "F.Cu")
	)
	(gr_line
		(start 104.500172 -224.828608)
		(end 104.500172 -225.54438)
		(stroke
			(width 0.068326)
			(type default)
		)
		(layer "F.Cu")
	)
	(gr_line
		(start 104.500172 -224.828608)
		(end 104.500426 -224.828354)
		(stroke
			(width 0.068326)
			(type default)
		)
		(layer "F.Cu")
	)
	(gr_arc
		(start 104.668574 -224.32264)
		(mid 104.543554 -224.561885)
		(end 104.500426 -224.828354)
		(stroke
			(width 0.068326)
			(type default)
		)
		(layer "F.Cu")
	)
	(gr_arc
		(start 104.668574 -224.32264)
		(mid 104.727208 -224.234888)
		(end 104.747822 -224.131378)
		(stroke
			(width 0.068326)
			(type default)
		)
		(layer "F.Cu")
	)
	(gr_arc
		(start 104.673908 -211.694268)
		(mid 104.723899 -211.619452)
		(end 104.741472 -211.5312)
		(stroke
			(width 0.068326)
			(type default)
		)
		(layer "F.Cu")
	)
	(gr_arc
		(start 104.747822 -213.723474)
		(mid 104.655403 -213.25885)
		(end 104.392222 -212.864954)
		(stroke
			(width 0.068326)
			(type default)
		)
		(layer "F.Cu")
	)
	(gr_arc
		(start 105.046272 -211.5312)
		(mid 105.061552 -211.607657)
		(end 105.104946 -211.672424)
		(stroke
			(width 0.068326)
			(type default)
		)
		(layer "F.Cu")
	)
	(gr_arc
		(start 105.052876 -224.133664)
		(mid 105.073044 -224.234828)
		(end 105.130346 -224.320608)
		(stroke
			(width 0.068326)
			(type default)
		)
		(layer "F.Cu")
	)
	(gr_line
		(start 105.104946 -211.672424)
		(end 105.408222 -211.975954)
		(stroke
			(width 0.068326)
			(type default)
		)
		(layer "F.Cu")
	)
	(gr_arc
		(start 105.141014 -211.061808)
		(mid 105.070855 -211.166936)
		(end 105.046272 -211.290916)
		(stroke
			(width 0.068326)
			(type default)
		)
		(layer "F.Cu")
	)
	(gr_line
		(start 105.141014 -211.061808)
		(end 105.306622 -210.896454)
		(stroke
			(width 0.068326)
			(type default)
		)
		(layer "F.Cu")
	)
	(gr_line
		(start 105.300018 -224.828608)
		(end 105.300018 -225.54438)
		(stroke
			(width 0.068326)
			(type default)
		)
		(layer "F.Cu")
	)
	(gr_line
		(start 105.300018 -224.828608)
		(end 105.300272 -224.828354)
		(stroke
			(width 0.068326)
			(type default)
		)
		(layer "F.Cu")
	)
	(gr_arc
		(start 105.300272 -224.828354)
		(mid 105.256635 -224.560646)
		(end 105.130346 -224.320608)
		(stroke
			(width 0.068326)
			(type default)
		)
		(layer "F.Cu")
	)
	(gr_arc
		(start 105.408222 -212.864954)
		(mid 105.145221 -213.258482)
		(end 105.052876 -213.722712)
		(stroke
			(width 0.068326)
			(type default)
		)
		(layer "F.Cu")
	)
	(gr_line
		(start 107.592114 -211.975954)
		(end 107.8738 -211.694268)
		(stroke
			(width 0.068326)
			(type default)
		)
		(layer "F.Cu")
	)
	(gr_line
		(start 107.693714 -210.896454)
		(end 107.814618 -211.017358)
		(stroke
			(width 0.068326)
			(type default)
		)
		(layer "F.Cu")
	)
	(gr_line
		(start 107.700064 -224.828608)
		(end 107.700064 -225.54438)
		(stroke
			(width 0.068326)
			(type default)
		)
		(layer "F.Cu")
	)
	(gr_line
		(start 107.700064 -224.828608)
		(end 107.700318 -224.828354)
		(stroke
			(width 0.068326)
			(type default)
		)
		(layer "F.Cu")
	)
	(gr_arc
		(start 107.868466 -224.32264)
		(mid 107.743448 -224.561885)
		(end 107.700318 -224.828354)
		(stroke
			(width 0.068326)
			(type default)
		)
		(layer "F.Cu")
	)
	(gr_arc
		(start 107.868466 -224.32264)
		(mid 107.9271 -224.234888)
		(end 107.947714 -224.131378)
		(stroke
			(width 0.068326)
			(type default)
		)
		(layer "F.Cu")
	)
	(gr_arc
		(start 107.8738 -211.694268)
		(mid 107.923791 -211.619452)
		(end 107.941364 -211.5312)
		(stroke
			(width 0.068326)
			(type default)
		)
		(layer "F.Cu")
	)
	(gr_arc
		(start 107.941364 -211.323428)
		(mid 107.908418 -211.157796)
		(end 107.814618 -211.017358)
		(stroke
			(width 0.068326)
			(type default)
		)
		(layer "F.Cu")
	)
	(gr_arc
		(start 107.947714 -213.723474)
		(mid 107.855295 -213.25885)
		(end 107.592114 -212.864954)
		(stroke
			(width 0.068326)
			(type default)
		)
		(layer "F.Cu")
	)
	(gr_arc
		(start 108.246164 -211.5312)
		(mid 108.261449 -211.607652)
		(end 108.304838 -211.672424)
		(stroke
			(width 0.068326)
			(type default)
		)
		(layer "F.Cu")
	)
	(gr_arc
		(start 108.252768 -224.133664)
		(mid 108.272936 -224.234828)
		(end 108.330238 -224.320608)
		(stroke
			(width 0.068326)
			(type default)
		)
		(layer "F.Cu")
	)
	(gr_line
		(start 108.304838 -211.672424)
		(end 108.608114 -211.975954)
		(stroke
			(width 0.068326)
			(type default)
		)
		(layer "F.Cu")
	)
	(gr_arc
		(start 108.37545 -211.027518)
		(mid 108.279764 -211.170745)
		(end 108.246164 -211.339684)
		(stroke
			(width 0.068326)
			(type default)
		)
		(layer "F.Cu")
	)
	(gr_line
		(start 108.37545 -211.027518)
		(end 108.506514 -210.896454)
		(stroke
			(width 0.068326)
			(type default)
		)
		(layer "F.Cu")
	)
	(gr_arc
		(start 108.500164 -224.828354)
		(mid 108.456527 -224.560646)
		(end 108.330238 -224.320608)
		(stroke
			(width 0.068326)
			(type default)
		)
		(layer "F.Cu")
	)
	(gr_line
		(start 108.500164 -224.828354)
		(end 108.500164 -225.54438)
		(stroke
			(width 0.068326)
			(type default)
		)
		(layer "F.Cu")
	)
	(gr_arc
		(start 108.608114 -212.864954)
		(mid 108.345115 -213.258482)
		(end 108.252768 -213.722712)
		(stroke
			(width 0.068326)
			(type default)
		)
		(layer "F.Cu")
	)
	(gr_line
		(start 110.099856 -225.5266)
		(end 110.10011 -225.526854)
		(stroke
			(width 0.068326)
			(type default)
		)
		(layer "F.Cu")
	)
	(gr_line
		(start 110.099856 -224.828608)
		(end 110.099856 -225.5266)
		(stroke
			(width 0.068326)
			(type default)
		)
		(layer "F.Cu")
	)
	(gr_line
		(start 110.099856 -224.828608)
		(end 110.10011 -224.828354)
		(stroke
			(width 0.068326)
			(type default)
		)
		(layer "F.Cu")
	)
	(gr_line
		(start 110.10011 -225.526854)
		(end 110.10011 -225.54438)
		(stroke
			(width 0.068326)
			(type default)
		)
		(layer "F.Cu")
	)
	(gr_arc
		(start 110.268258 -224.32264)
		(mid 110.143241 -224.561885)
		(end 110.10011 -224.828354)
		(stroke
			(width 0.068326)
			(type default)
		)
		(layer "F.Cu")
	)
	(gr_arc
		(start 110.268258 -224.32264)
		(mid 110.326892 -224.234888)
		(end 110.347506 -224.131378)
		(stroke
			(width 0.068326)
			(type default)
		)
		(layer "F.Cu")
	)
	(gr_arc
		(start 110.65256 -224.133664)
		(mid 110.672727 -224.234829)
		(end 110.73003 -224.320608)
		(stroke
			(width 0.068326)
			(type default)
		)
		(layer "F.Cu")
	)
	(gr_arc
		(start 110.899956 -224.828354)
		(mid 110.856319 -224.560646)
		(end 110.73003 -224.320608)
		(stroke
			(width 0.068326)
			(type default)
		)
		(layer "F.Cu")
	)
	(gr_line
		(start 110.899956 -224.828354)
		(end 110.899956 -225.54438)
		(stroke
			(width 0.068326)
			(type default)
		)
		(layer "F.Cu")
	)
	(gr_line
		(start 116.3066 -206.5274)
		(end 116.381784 -206.452216)
		(stroke
			(width 0.060198)
			(type default)
		)
		(layer "F.Cu")
	)
	(gr_line
		(start 117.095016 -206.452216)
		(end 117.1702 -206.5274)
		(stroke
			(width 0.060198)
			(type default)
		)
		(layer "F.Cu")
	)
	(gr_line
		(start 117.568472 -31.082996)
		(end 117.771672 -31.286196)
		(stroke
			(width 0.060198)
			(type default)
		)
		(layer "F.Cu")
	)
	(gr_line
		(start 118.275862 -31.401004)
		(end 118.59387 -31.084012)
		(stroke
			(width 0.060198)
			(type default)
		)
		(layer "F.Cu")
	)
	(gr_line
		(start 119.3927 -96.41332)
		(end 120.51792 -96.41332)
		(stroke
			(width 0.060198)
			(type default)
		)
		(layer "F.Cu")
	)
	(gr_line
		(start 119.3927 -95.76308)
		(end 120.64492 -95.76308)
		(stroke
			(width 0.060198)
			(type default)
		)
		(layer "F.Cu")
	)
	(gr_line
		(start 120.51792 -96.41332)
		(end 121.169684 -97.065084)
		(stroke
			(width 0.060198)
			(type default)
		)
		(layer "F.Cu")
	)
	(gr_line
		(start 120.64492 -95.76308)
		(end 121.106184 -95.301816)
		(stroke
			(width 0.060198)
			(type default)
		)
		(layer "F.Cu")
	)
	(gr_line
		(start 120.9548 -100.9777)
		(end 121.0183 -100.9142)
		(stroke
			(width 0.060198)
			(type default)
		)
		(layer "F.Cu")
	)
	(gr_line
		(start 120.9548 -99.8347)
		(end 121.0183 -99.8982)
		(stroke
			(width 0.060198)
			(type default)
		)
		(layer "F.Cu")
	)
	(gr_line
		(start 120.9548 -98.7552)
		(end 120.9548 -99.8347)
		(stroke
			(width 0.060198)
			(type default)
		)
		(layer "F.Cu")
	)
	(gr_line
		(start 120.9548 -98.7552)
		(end 121.279412 -98.430334)
		(stroke
			(width 0.060198)
			(type default)
		)
		(layer "F.Cu")
	)
	(gr_line
		(start 120.9548 -93.4212)
		(end 121.169684 -93.636084)
		(stroke
			(width 0.060198)
			(type default)
		)
		(layer "F.Cu")
	)
	(gr_line
		(start 120.9548 -92.2147)
		(end 120.9548 -93.4212)
		(stroke
			(width 0.060198)
			(type default)
		)
		(layer "F.Cu")
	)
	(gr_line
		(start 121.0183 -99.8982)
		(end 121.0183 -100.9142)
		(stroke
			(width 0.060198)
			(type default)
		)
		(layer "F.Cu")
	)
	(gr_line
		(start 121.785888 -98.443288)
		(end 122.0978 -98.7552)
		(stroke
			(width 0.060198)
			(type default)
		)
		(layer "F.Cu")
	)
	(gr_line
		(start 121.819416 -95.301816)
		(end 122.28068 -95.76308)
		(stroke
			(width 0.060198)
			(type default)
		)
		(layer "F.Cu")
	)
	(gr_line
		(start 121.882916 -97.065084)
		(end 122.53468 -96.41332)
		(stroke
			(width 0.060198)
			(type default)
		)
		(layer "F.Cu")
	)
	(gr_line
		(start 121.882916 -93.636084)
		(end 122.0978 -93.4212)
		(stroke
			(width 0.060198)
			(type default)
		)
		(layer "F.Cu")
	)
	(gr_line
		(start 122.0343 -100.9142)
		(end 122.0978 -100.9777)
		(stroke
			(width 0.060198)
			(type default)
		)
		(layer "F.Cu")
	)
	(gr_line
		(start 122.0343 -99.8982)
		(end 122.0343 -100.9142)
		(stroke
			(width 0.060198)
			(type default)
		)
		(layer "F.Cu")
	)
	(gr_line
		(start 122.0343 -99.8982)
		(end 122.0978 -99.8347)
		(stroke
			(width 0.060198)
			(type default)
		)
		(layer "F.Cu")
	)
	(gr_line
		(start 122.0978 -98.7552)
		(end 122.0978 -99.8347)
		(stroke
			(width 0.060198)
			(type default)
		)
		(layer "F.Cu")
	)
	(gr_line
		(start 122.0978 -92.2147)
		(end 122.0978 -93.4212)
		(stroke
			(width 0.060198)
			(type default)
		)
		(layer "F.Cu")
	)
	(gr_line
		(start 122.28068 -95.76308)
		(end 123.5329 -95.76308)
		(stroke
			(width 0.060198)
			(type default)
		)
		(layer "F.Cu")
	)
	(gr_line
		(start 122.53468 -96.41332)
		(end 123.5329 -96.41332)
		(stroke
			(width 0.060198)
			(type default)
		)
		(layer "F.Cu")
	)
	(gr_line
		(start 123.001786 -86.116414)
		(end 123.954286 -86.116414)
		(stroke
			(width 0.060198)
			(type default)
		)
		(layer "F.Cu")
	)
	(gr_line
		(start 123.001786 -84.846414)
		(end 123.979686 -84.846414)
		(stroke
			(width 0.060198)
			(type default)
		)
		(layer "F.Cu")
	)
	(gr_line
		(start 123.928124 -210.160362)
		(end 124.079508 -210.311746)
		(stroke
			(width 0.060198)
			(type default)
		)
		(layer "F.Cu")
	)
	(gr_line
		(start 123.928124 -207.579722)
		(end 123.928124 -208.444592)
		(stroke
			(width 0.060198)
			(type default)
		)
		(layer "F.Cu")
	)
	(gr_line
		(start 123.928124 -207.579722)
		(end 124.01677 -207.491076)
		(stroke
			(width 0.060198)
			(type default)
		)
		(layer "F.Cu")
	)
	(gr_line
		(start 123.954286 -86.116414)
		(end 125.452886 -86.116414)
		(stroke
			(width 0.060198)
			(type default)
		)
		(layer "F.Cu")
	)
	(gr_line
		(start 123.979686 -84.846414)
		(end 125.452886 -84.846414)
		(stroke
			(width 0.060198)
			(type default)
		)
		(layer "F.Cu")
	)
	(gr_line
		(start 124.01677 -207.491076)
		(end 124.15139 -207.356456)
		(stroke
			(width 0.060198)
			(type default)
		)
		(layer "F.Cu")
	)
	(gr_line
		(start 124.15139 -207.356456)
		(end 124.439934 -207.356456)
		(stroke
			(width 0.060198)
			(type default)
		)
		(layer "F.Cu")
	)
	(gr_line
		(start 124.442474 -207.356456)
		(end 124.60732 -207.356456)
		(stroke
			(width 0.060198)
			(type default)
		)
		(layer "F.Cu")
	)
	(gr_line
		(start 124.60732 -207.356456)
		(end 124.841508 -207.122268)
		(stroke
			(width 0.060198)
			(type default)
		)
		(layer "F.Cu")
	)
	(gr_line
		(start 124.79274 -210.311746)
		(end 124.944124 -210.160362)
		(stroke
			(width 0.060198)
			(type default)
		)
		(layer "F.Cu")
	)
	(gr_line
		(start 124.843286 -207.12049)
		(end 125.051312 -206.912464)
		(stroke
			(width 0.060198)
			(type default)
		)
		(layer "F.Cu")
	)
	(gr_line
		(start 124.944124 -207.860646)
		(end 124.944124 -208.444592)
		(stroke
			(width 0.060198)
			(type default)
		)
		(layer "F.Cu")
	)
	(gr_line
		(start 124.944124 -207.823562)
		(end 124.944124 -207.858106)
		(stroke
			(width 0.060198)
			(type default)
		)
		(layer "F.Cu")
	)
	(gr_line
		(start 124.944124 -207.823562)
		(end 125.28677 -207.480916)
		(stroke
			(width 0.060198)
			(type default)
		)
		(layer "F.Cu")
	)
	(gr_line
		(start 125.051312 -206.912464)
		(end 125.224794 -206.912464)
		(stroke
			(width 0.060198)
			(type default)
		)
		(layer "F.Cu")
	)
	(gr_line
		(start 125.224794 -206.912464)
		(end 125.635512 -206.501746)
		(stroke
			(width 0.060198)
			(type default)
		)
		(layer "F.Cu")
	)
	(gr_line
		(start 125.28677 -207.480916)
		(end 125.478032 -207.289654)
		(stroke
			(width 0.060198)
			(type default)
		)
		(layer "F.Cu")
	)
	(gr_line
		(start 125.447044 -206.186532)
		(end 125.635512 -206.375)
		(stroke
			(width 0.060198)
			(type default)
		)
		(layer "F.Cu")
	)
	(gr_line
		(start 125.447044 -205.87335)
		(end 125.447044 -206.186532)
		(stroke
			(width 0.060198)
			(type default)
		)
		(layer "F.Cu")
	)
	(gr_line
		(start 125.447044 -205.612492)
		(end 125.447044 -205.87081)
		(stroke
			(width 0.060198)
			(type default)
		)
		(layer "F.Cu")
	)
	(gr_line
		(start 125.478032 -207.04556)
		(end 125.478032 -207.289654)
		(stroke
			(width 0.060198)
			(type default)
		)
		(layer "F.Cu")
	)
	(gr_line
		(start 125.478032 -207.04556)
		(end 125.908562 -206.61503)
		(stroke
			(width 0.060198)
			(type default)
		)
		(layer "F.Cu")
	)
	(gr_line
		(start 125.635512 -206.375)
		(end 125.635512 -206.501746)
		(stroke
			(width 0.060198)
			(type default)
		)
		(layer "F.Cu")
	)
	(gr_line
		(start 125.908562 -206.375)
		(end 125.908562 -206.61503)
		(stroke
			(width 0.060198)
			(type default)
		)
		(layer "F.Cu")
	)
	(gr_line
		(start 125.908562 -206.375)
		(end 126.097284 -206.186278)
		(stroke
			(width 0.060198)
			(type default)
		)
		(layer "F.Cu")
	)
	(gr_line
		(start 126.097284 -205.87335)
		(end 126.097284 -206.186278)
		(stroke
			(width 0.060198)
			(type default)
		)
		(layer "F.Cu")
	)
	(gr_line
		(start 126.097284 -205.612492)
		(end 126.097284 -205.87081)
		(stroke
			(width 0.060198)
			(type default)
		)
		(layer "F.Cu")
	)
	(gr_arc
		(start 127.071628 -33.159192)
		(mid 127.309431 -32.976088)
		(end 127.399542 -32.6898)
		(stroke
			(width 0.068326)
			(type default)
		)
		(layer "F.Cu")
	)
	(gr_arc
		(start 127.43307 -34.672016)
		(mid 127.333008 -34.303484)
		(end 127.060452 -34.036)
		(stroke
			(width 0.068326)
			(type default)
		)
		(layer "F.Cu")
	)
	(gr_arc
		(start 127.704342 -32.6898)
		(mid 127.809964 -32.985361)
		(end 128.078992 -33.147)
		(stroke
			(width 0.068326)
			(type default)
		)
		(layer "F.Cu")
	)
	(gr_arc
		(start 128.078992 -34.036)
		(mid 127.828499 -34.312724)
		(end 127.73787 -34.67481)
		(stroke
			(width 0.068326)
			(type default)
		)
		(layer "F.Cu")
	)
	(gr_line
		(start 131.0513 -33.98774)
		(end 131.23037 -34.166556)
		(stroke
			(width 0.068326)
			(type default)
		)
		(layer "F.Cu")
	)
	(gr_arc
		(start 131.0513 -33.09874)
		(mid 131.264751 -32.896749)
		(end 131.3434 -32.6136)
		(stroke
			(width 0.068326)
			(type default)
		)
		(layer "F.Cu")
	)
	(gr_arc
		(start 131.0894 -35.273234)
		(mid 131.269005 -35.198839)
		(end 131.3434 -35.019234)
		(stroke
			(width 0.068326)
			(type default)
		)
		(layer "F.Cu")
	)
	(gr_arc
		(start 131.3434 -34.43986)
		(mid 131.314075 -34.291963)
		(end 131.23037 -34.166556)
		(stroke
			(width 0.068326)
			(type default)
		)
		(layer "F.Cu")
	)
	(gr_arc
		(start 131.6482 -35.019234)
		(mid 131.722607 -35.198817)
		(end 131.9022 -35.273234)
		(stroke
			(width 0.068326)
			(type default)
		)
		(layer "F.Cu")
	)
	(gr_arc
		(start 131.6482 -32.6136)
		(mid 131.726864 -32.89674)
		(end 131.9403 -33.09874)
		(stroke
			(width 0.068326)
			(type default)
		)
		(layer "F.Cu")
	)
	(gr_line
		(start 131.746244 -42.6847)
		(end 131.746244 -42.7228)
		(stroke
			(width 0.068326)
			(type default)
		)
		(layer "F.Cu")
	)
	(gr_arc
		(start 131.746244 -41.6052)
		(mid 131.857839 -41.874592)
		(end 132.127244 -41.9862)
		(stroke
			(width 0.068326)
			(type default)
		)
		(layer "F.Cu")
	)
	(gr_arc
		(start 131.76123 -34.166556)
		(mid 131.677523 -34.291962)
		(end 131.6482 -34.43986)
		(stroke
			(width 0.068326)
			(type default)
		)
		(layer "F.Cu")
	)
	(gr_line
		(start 131.76123 -34.166556)
		(end 131.9403 -33.98774)
		(stroke
			(width 0.068326)
			(type default)
		)
		(layer "F.Cu")
	)
	(gr_arc
		(start 132.139944 -42.291)
		(mid 131.861528 -42.406297)
		(end 131.746244 -42.6847)
		(stroke
			(width 0.068326)
			(type default)
		)
		(layer "F.Cu")
	)
	(gr_line
		(start 133.134354 -25.33015)
		(end 133.134608 -25.062688)
		(stroke
			(width 0.068326)
			(type default)
		)
		(layer "F.Cu")
	)
	(gr_arc
		(start 133.2103 -33.09874)
		(mid 133.423751 -32.896749)
		(end 133.5024 -32.6136)
		(stroke
			(width 0.068326)
			(type default)
		)
		(layer "F.Cu")
	)
	(gr_arc
		(start 133.355334 -24.779224)
		(mid 133.196388 -24.883123)
		(end 133.134608 -25.062688)
		(stroke
			(width 0.068326)
			(type default)
		)
		(layer "F.Cu")
	)
	(gr_arc
		(start 133.5024 -34.3916)
		(mid 133.421748 -34.14237)
		(end 133.2103 -33.98774)
		(stroke
			(width 0.068326)
			(type default)
		)
		(layer "F.Cu")
	)
	(gr_arc
		(start 133.576822 -24.843232)
		(mid 133.470615 -24.795528)
		(end 133.355334 -24.779224)
		(stroke
			(width 0.068326)
			(type default)
		)
		(layer "F.Cu")
	)
	(gr_arc
		(start 133.600698 -24.859488)
		(mid 133.588903 -24.85115)
		(end 133.576822 -24.843232)
		(stroke
			(width 0.068326)
			(type default)
		)
		(layer "F.Cu")
	)
	(gr_arc
		(start 133.648196 -24.900382)
		(mid 133.625226 -24.87903)
		(end 133.600698 -24.859488)
		(stroke
			(width 0.068326)
			(type default)
		)
		(layer "F.Cu")
	)
	(gr_line
		(start 133.648196 -24.900382)
		(end 133.695186 -24.947626)
		(stroke
			(width 0.068326)
			(type default)
		)
		(layer "F.Cu")
	)
	(gr_arc
		(start 133.8072 -32.6136)
		(mid 133.885864 -32.89674)
		(end 134.0993 -33.09874)
		(stroke
			(width 0.068326)
			(type default)
		)
		(layer "F.Cu")
	)
	(gr_arc
		(start 133.852158 -35.739832)
		(mid 134.031802 -35.665454)
		(end 134.106158 -35.485832)
		(stroke
			(width 0.068326)
			(type default)
		)
		(layer "F.Cu")
	)
	(gr_arc
		(start 133.884162 -24.474678)
		(mid 133.889211 -24.559244)
		(end 133.904482 -24.642572)
		(stroke
			(width 0.068326)
			(type default)
		)
		(layer "F.Cu")
	)
	(gr_line
		(start 133.884162 -23.930356)
		(end 133.884162 -24.474678)
		(stroke
			(width 0.068326)
			(type default)
		)
		(layer "F.Cu")
	)
	(gr_line
		(start 133.884162 -23.930356)
		(end 133.884416 -23.930102)
		(stroke
			(width 0.068326)
			(type default)
		)
		(layer "F.Cu")
	)
	(gr_arc
		(start 133.904482 -24.642572)
		(mid 133.907308 -24.653899)
		(end 133.910324 -24.665178)
		(stroke
			(width 0.068326)
			(type default)
		)
		(layer "F.Cu")
	)
	(gr_arc
		(start 133.910324 -24.665178)
		(mid 133.926617 -24.715268)
		(end 133.946646 -24.763984)
		(stroke
			(width 0.068326)
			(type default)
		)
		(layer "F.Cu")
	)
	(gr_line
		(start 133.946646 -24.763984)
		(end 133.953758 -24.778716)
		(stroke
			(width 0.068326)
			(type default)
		)
		(layer "F.Cu")
	)
	(gr_line
		(start 134.106158 -35.41395)
		(end 134.106158 -35.485832)
		(stroke
			(width 0.068326)
			(type default)
		)
		(layer "F.Cu")
	)
	(gr_line
		(start 134.413498 -35.4076)
		(end 134.414514 -35.433)
		(stroke
			(width 0.068326)
			(type default)
		)
		(layer "F.Cu")
	)
	(gr_arc
		(start 134.414514 -35.433)
		(mid 134.488507 -35.628243)
		(end 134.664958 -35.739832)
		(stroke
			(width 0.068326)
			(type default)
		)
		(layer "F.Cu")
	)
	(gr_line
		(start 135.3693 -33.98774)
		(end 135.522462 -34.140648)
		(stroke
			(width 0.068326)
			(type default)
		)
		(layer "F.Cu")
	)
	(gr_arc
		(start 135.3693 -33.09874)
		(mid 135.582751 -32.896749)
		(end 135.6614 -32.6136)
		(stroke
			(width 0.068326)
			(type default)
		)
		(layer "F.Cu")
	)
	(gr_line
		(start 135.38454 -25.062942)
		(end 135.38454 -25.33015)
		(stroke
			(width 0.068326)
			(type default)
		)
		(layer "F.Cu")
	)
	(gr_line
		(start 135.38454 -25.062942)
		(end 135.384794 -25.062688)
		(stroke
			(width 0.068326)
			(type default)
		)
		(layer "F.Cu")
	)
	(gr_line
		(start 135.38454 -21.26488)
		(end 135.38454 -21.530056)
		(stroke
			(width 0.068326)
			(type default)
		)
		(layer "F.Cu")
	)
	(gr_arc
		(start 135.400288 -21.164042)
		(mid 135.388532 -21.213855)
		(end 135.38454 -21.26488)
		(stroke
			(width 0.068326)
			(type default)
		)
		(layer "F.Cu")
	)
	(gr_arc
		(start 135.60552 -24.779224)
		(mid 135.446502 -24.883086)
		(end 135.384794 -25.062688)
		(stroke
			(width 0.068326)
			(type default)
		)
		(layer "F.Cu")
	)
	(gr_arc
		(start 135.637778 -21.006562)
		(mid 135.4953 -21.04951)
		(end 135.400288 -21.164042)
		(stroke
			(width 0.068326)
			(type default)
		)
		(layer "F.Cu")
	)
	(gr_arc
		(start 135.6614 -34.476436)
		(mid 135.625318 -34.294728)
		(end 135.522462 -34.140648)
		(stroke
			(width 0.068326)
			(type default)
		)
		(layer "F.Cu")
	)
	(gr_arc
		(start 135.732774 -21.00326)
		(mid 135.685246 -21.004054)
		(end 135.637778 -21.006562)
		(stroke
			(width 0.068326)
			(type default)
		)
		(layer "F.Cu")
	)
	(gr_arc
		(start 135.868664 -21.052536)
		(mid 135.802496 -21.022994)
		(end 135.732774 -21.00326)
		(stroke
			(width 0.068326)
			(type default)
		)
		(layer "F.Cu")
	)
	(gr_arc
		(start 135.871966 -21.054314)
		(mid 135.870317 -21.053422)
		(end 135.868664 -21.052536)
		(stroke
			(width 0.068326)
			(type default)
		)
		(layer "F.Cu")
	)
	(gr_arc
		(start 135.898382 -24.900382)
		(mid 135.764001 -24.810684)
		(end 135.60552 -24.779224)
		(stroke
			(width 0.068326)
			(type default)
		)
		(layer "F.Cu")
	)
	(gr_line
		(start 135.898382 -24.900382)
		(end 135.950706 -24.95296)
		(stroke
			(width 0.068326)
			(type default)
		)
		(layer "F.Cu")
	)
	(gr_arc
		(start 135.9662 -32.6136)
		(mid 136.044864 -32.89674)
		(end 136.2583 -33.09874)
		(stroke
			(width 0.068326)
			(type default)
		)
		(layer "F.Cu")
	)
	(gr_arc
		(start 135.985758 -21.16582)
		(mid 135.933371 -21.105465)
		(end 135.871966 -21.054314)
		(stroke
			(width 0.068326)
			(type default)
		)
		(layer "F.Cu")
	)
	(gr_arc
		(start 136.105138 -34.140648)
		(mid 136.002281 -34.294724)
		(end 135.9662 -34.476436)
		(stroke
			(width 0.068326)
			(type default)
		)
		(layer "F.Cu")
	)
	(gr_line
		(start 136.105138 -34.140648)
		(end 136.2583 -33.98774)
		(stroke
			(width 0.068326)
			(type default)
		)
		(layer "F.Cu")
	)
	(gr_arc
		(start 136.134348 -24.474678)
		(mid 136.139397 -24.559244)
		(end 136.154668 -24.642572)
		(stroke
			(width 0.068326)
			(type default)
		)
		(layer "F.Cu")
	)
	(gr_line
		(start 136.134348 -23.930102)
		(end 136.134348 -24.474678)
		(stroke
			(width 0.068326)
			(type default)
		)
		(layer "F.Cu")
	)
	(gr_line
		(start 136.134348 -20.499578)
		(end 136.156446 -20.743672)
		(stroke
			(width 0.068326)
			(type default)
		)
		(layer "F.Cu")
	)
	(gr_line
		(start 136.134348 -20.130008)
		(end 136.134348 -20.499578)
		(stroke
			(width 0.068326)
			(type default)
		)
		(layer "F.Cu")
	)
	(gr_line
		(start 136.156446 -20.743672)
		(end 136.170416 -20.757642)
		(stroke
			(width 0.068326)
			(type default)
		)
		(layer "F.Cu")
	)
	(gr_line
		(start 136.169146 -25.304496)
		(end 136.1694 -25.305004)
		(stroke
			(width 0.068326)
			(type default)
		)
		(layer "F.Cu")
	)
	(gr_arc
		(start 136.170416 -20.757642)
		(mid 136.173397 -20.808036)
		(end 136.182354 -20.857718)
		(stroke
			(width 0.068326)
			(type default)
		)
		(layer "F.Cu")
	)
	(gr_arc
		(start 136.184132 -20.866354)
		(mid 136.18501 -20.869405)
		(end 136.18591 -20.87245)
		(stroke
			(width 0.068326)
			(type default)
		)
		(layer "F.Cu")
	)
	(gr_arc
		(start 136.18591 -20.87245)
		(mid 136.186164 -20.872958)
		(end 136.186418 -20.873466)
		(stroke
			(width 0.068326)
			(type default)
		)
		(layer "F.Cu")
	)
	(gr_line
		(start 137.5283 -33.98774)
		(end 137.780268 -34.239454)
		(stroke
			(width 0.068326)
			(type default)
		)
		(layer "F.Cu")
	)
	(gr_arc
		(start 137.5283 -33.09874)
		(mid 137.741712 -32.896735)
		(end 137.8204 -32.6136)
		(stroke
			(width 0.068326)
			(type default)
		)
		(layer "F.Cu")
	)
	(gr_arc
		(start 137.5664 -34.993326)
		(mid 137.746014 -34.918933)
		(end 137.8204 -34.739326)
		(stroke
			(width 0.068326)
			(type default)
		)
		(layer "F.Cu")
	)
	(gr_line
		(start 137.634472 -25.213056)
		(end 137.634472 -25.33015)
		(stroke
			(width 0.068326)
			(type default)
		)
		(layer "F.Cu")
	)
	(gr_line
		(start 137.634472 -21.330158)
		(end 137.634472 -21.530056)
		(stroke
			(width 0.068326)
			(type default)
		)
		(layer "F.Cu")
	)
	(gr_arc
		(start 137.721594 -24.902414)
		(mid 137.656623 -25.051731)
		(end 137.634472 -25.213056)
		(stroke
			(width 0.068326)
			(type default)
		)
		(layer "F.Cu")
	)
	(gr_arc
		(start 137.738104 -21.079968)
		(mid 137.661393 -21.194754)
		(end 137.634472 -21.330158)
		(stroke
			(width 0.068326)
			(type default)
		)
		(layer "F.Cu")
	)
	(gr_line
		(start 137.738104 -21.079968)
		(end 137.770362 -21.04771)
		(stroke
			(width 0.068326)
			(type default)
		)
		(layer "F.Cu")
	)
	(gr_arc
		(start 137.8204 -34.336228)
		(mid 137.809996 -34.283832)
		(end 137.780268 -34.239454)
		(stroke
			(width 0.068326)
			(type default)
		)
		(layer "F.Cu")
	)
	(gr_arc
		(start 138.09853 -21.04771)
		(mid 137.934446 -20.979744)
		(end 137.770362 -21.04771)
		(stroke
			(width 0.068326)
			(type default)
		)
		(layer "F.Cu")
	)
	(gr_line
		(start 138.09853 -21.04771)
		(end 138.213338 -21.162518)
		(stroke
			(width 0.068326)
			(type default)
		)
		(layer "F.Cu")
	)
	(gr_arc
		(start 138.1252 -34.682176)
		(mid 138.19677 -34.882986)
		(end 138.3792 -34.993326)
		(stroke
			(width 0.068326)
			(type default)
		)
		(layer "F.Cu")
	)
	(gr_arc
		(start 138.1252 -32.6136)
		(mid 138.203864 -32.89674)
		(end 138.4173 -33.09874)
		(stroke
			(width 0.068326)
			(type default)
		)
		(layer "F.Cu")
	)
	(gr_arc
		(start 138.15314 -24.90978)
		(mid 137.939607 -24.777434)
		(end 137.721594 -24.902414)
		(stroke
			(width 0.068326)
			(type default)
		)
		(layer "F.Cu")
	)
	(gr_arc
		(start 138.231626 -34.17316)
		(mid 138.15283 -34.291226)
		(end 138.1252 -34.430462)
		(stroke
			(width 0.068326)
			(type default)
		)
		(layer "F.Cu")
	)
	(gr_line
		(start 138.231626 -34.17316)
		(end 138.4173 -33.98774)
		(stroke
			(width 0.068326)
			(type default)
		)
		(layer "F.Cu")
	)
	(gr_line
		(start 138.384534 -23.930102)
		(end 138.384534 -24.60625)
		(stroke
			(width 0.068326)
			(type default)
		)
		(layer "F.Cu")
	)
	(gr_line
		(start 138.384534 -20.130008)
		(end 138.384534 -20.653756)
		(stroke
			(width 0.068326)
			(type default)
		)
		(layer "F.Cu")
	)
	(gr_line
		(start 138.392154 -211.975954)
		(end 138.67384 -211.694268)
		(stroke
			(width 0.068326)
			(type default)
		)
		(layer "F.Cu")
	)
	(gr_line
		(start 138.493754 -210.896454)
		(end 138.593322 -210.996276)
		(stroke
			(width 0.068326)
			(type default)
		)
		(layer "F.Cu")
	)
	(gr_line
		(start 138.500104 -224.828608)
		(end 138.500104 -225.54438)
		(stroke
			(width 0.068326)
			(type default)
		)
		(layer "F.Cu")
	)
	(gr_line
		(start 138.500104 -224.828608)
		(end 138.500358 -224.828354)
		(stroke
			(width 0.068326)
			(type default)
		)
		(layer "F.Cu")
	)
	(gr_arc
		(start 138.557 -38.6588)
		(mid 138.723133 -38.535648)
		(end 138.786362 -38.33876)
		(stroke
			(width 0.068326)
			(type default)
		)
		(layer "F.Cu")
	)
	(gr_arc
		(start 138.668506 -224.32264)
		(mid 138.543482 -224.561884)
		(end 138.500358 -224.828354)
		(stroke
			(width 0.068326)
			(type default)
		)
		(layer "F.Cu")
	)
	(gr_arc
		(start 138.668506 -224.32264)
		(mid 138.72714 -224.234888)
		(end 138.747754 -224.131378)
		(stroke
			(width 0.068326)
			(type default)
		)
		(layer "F.Cu")
	)
	(gr_arc
		(start 138.67384 -211.694268)
		(mid 138.723831 -211.619452)
		(end 138.741404 -211.5312)
		(stroke
			(width 0.068326)
			(type default)
		)
		(layer "F.Cu")
	)
	(gr_arc
		(start 138.741404 -211.3534)
		(mid 138.702865 -211.16012)
		(end 138.593322 -210.996276)
		(stroke
			(width 0.068326)
			(type default)
		)
		(layer "F.Cu")
	)
	(gr_arc
		(start 138.747754 -213.723474)
		(mid 138.655335 -213.25885)
		(end 138.392154 -212.864954)
		(stroke
			(width 0.068326)
			(type default)
		)
		(layer "F.Cu")
	)
	(gr_arc
		(start 139.046204 -211.5312)
		(mid 139.061486 -211.607655)
		(end 139.104878 -211.672424)
		(stroke
			(width 0.068326)
			(type default)
		)
		(layer "F.Cu")
	)
	(gr_arc
		(start 139.052808 -224.133664)
		(mid 139.072978 -224.234826)
		(end 139.130278 -224.320608)
		(stroke
			(width 0.068326)
			(type default)
		)
		(layer "F.Cu")
	)
	(gr_arc
		(start 139.091162 -38.33876)
		(mid 139.170584 -38.550922)
		(end 139.3698 -38.6588)
		(stroke
			(width 0.068326)
			(type default)
		)
		(layer "F.Cu")
	)
	(gr_line
		(start 139.104878 -211.672424)
		(end 139.408154 -211.975954)
		(stroke
			(width 0.068326)
			(type default)
		)
		(layer "F.Cu")
	)
	(gr_arc
		(start 139.13612 -211.067142)
		(mid 139.069607 -211.166531)
		(end 139.046204 -211.283804)
		(stroke
			(width 0.068326)
			(type default)
		)
		(layer "F.Cu")
	)
	(gr_line
		(start 139.13612 -211.067142)
		(end 139.306554 -210.896454)
		(stroke
			(width 0.068326)
			(type default)
		)
		(layer "F.Cu")
	)
	(gr_arc
		(start 139.300204 -224.828354)
		(mid 139.256567 -224.560646)
		(end 139.130278 -224.320608)
		(stroke
			(width 0.068326)
			(type default)
		)
		(layer "F.Cu")
	)
	(gr_line
		(start 139.300204 -224.828354)
		(end 139.300204 -225.54438)
		(stroke
			(width 0.068326)
			(type default)
		)
		(layer "F.Cu")
	)
	(gr_arc
		(start 139.408154 -212.864954)
		(mid 139.145168 -213.258486)
		(end 139.052808 -213.722712)
		(stroke
			(width 0.068326)
			(type default)
		)
		(layer "F.Cu")
	)
	(gr_line
		(start 140.221208 -24.66848)
		(end 140.23594 -24.683466)
		(stroke
			(width 0.068326)
			(type default)
		)
		(layer "F.Cu")
	)
	(gr_arc
		(start 140.77442 -33.9217)
		(mid 141.02537 -33.75976)
		(end 141.122908 -33.477454)
		(stroke
			(width 0.068326)
			(type default)
		)
		(layer "F.Cu")
	)
	(gr_arc
		(start 141.427708 -33.530286)
		(mid 141.536394 -33.792697)
		(end 141.798802 -33.90138)
		(stroke
			(width 0.068326)
			(type default)
		)
		(layer "F.Cu")
	)
	(gr_line
		(start 141.592046 -212.864954)
		(end 141.592554 -212.865208)
		(stroke
			(width 0.068326)
			(type default)
		)
		(layer "F.Cu")
	)
	(gr_line
		(start 141.592046 -211.975954)
		(end 141.5923 -211.975954)
		(stroke
			(width 0.068326)
			(type default)
		)
		(layer "F.Cu")
	)
	(gr_line
		(start 141.5923 -211.975954)
		(end 141.873986 -211.694268)
		(stroke
			(width 0.068326)
			(type default)
		)
		(layer "F.Cu")
	)
	(gr_line
		(start 141.6939 -210.896454)
		(end 141.86535 -211.067904)
		(stroke
			(width 0.068326)
			(type default)
		)
		(layer "F.Cu")
	)
	(gr_line
		(start 141.699996 -224.828862)
		(end 141.699996 -225.54438)
		(stroke
			(width 0.068326)
			(type default)
		)
		(layer "F.Cu")
	)
	(gr_line
		(start 141.699996 -224.828862)
		(end 141.700504 -224.828354)
		(stroke
			(width 0.068326)
			(type default)
		)
		(layer "F.Cu")
	)
	(gr_arc
		(start 141.868652 -224.32264)
		(mid 141.743636 -224.561885)
		(end 141.700504 -224.828354)
		(stroke
			(width 0.068326)
			(type default)
		)
		(layer "F.Cu")
	)
	(gr_arc
		(start 141.868652 -224.32264)
		(mid 141.927286 -224.234888)
		(end 141.9479 -224.131378)
		(stroke
			(width 0.068326)
			(type default)
		)
		(layer "F.Cu")
	)
	(gr_arc
		(start 141.873986 -211.694268)
		(mid 141.923977 -211.619452)
		(end 141.94155 -211.5312)
		(stroke
			(width 0.068326)
			(type default)
		)
		(layer "F.Cu")
	)
	(gr_arc
		(start 141.94155 -211.2518)
		(mid 141.921751 -211.152266)
		(end 141.86535 -211.067904)
		(stroke
			(width 0.068326)
			(type default)
		)
		(layer "F.Cu")
	)
	(gr_arc
		(start 141.9479 -213.723474)
		(mid 141.855602 -213.258991)
		(end 141.592554 -212.865208)
		(stroke
			(width 0.068326)
			(type default)
		)
		(layer "F.Cu")
	)
	(gr_arc
		(start 142.24635 -211.5312)
		(mid 142.261634 -211.607653)
		(end 142.305024 -211.672424)
		(stroke
			(width 0.068326)
			(type default)
		)
		(layer "F.Cu")
	)
	(gr_arc
		(start 142.252954 -224.133664)
		(mid 142.273121 -224.234829)
		(end 142.330424 -224.320608)
		(stroke
			(width 0.068326)
			(type default)
		)
		(layer "F.Cu")
	)
	(gr_line
		(start 142.305024 -211.672424)
		(end 142.608046 -211.975446)
		(stroke
			(width 0.068326)
			(type default)
		)
		(layer "F.Cu")
	)
	(gr_arc
		(start 142.322042 -211.080858)
		(mid 142.265979 -211.164894)
		(end 142.24635 -211.263992)
		(stroke
			(width 0.068326)
			(type default)
		)
		(layer "F.Cu")
	)
	(gr_line
		(start 142.322042 -211.080858)
		(end 142.5067 -210.896454)
		(stroke
			(width 0.068326)
			(type default)
		)
		(layer "F.Cu")
	)
	(gr_line
		(start 142.500096 -224.828608)
		(end 142.500096 -225.54438)
		(stroke
			(width 0.068326)
			(type default)
		)
		(layer "F.Cu")
	)
	(gr_line
		(start 142.500096 -224.828608)
		(end 142.50035 -224.828354)
		(stroke
			(width 0.068326)
			(type default)
		)
		(layer "F.Cu")
	)
	(gr_arc
		(start 142.50035 -224.828354)
		(mid 142.456713 -224.560646)
		(end 142.330424 -224.320608)
		(stroke
			(width 0.068326)
			(type default)
		)
		(layer "F.Cu")
	)
	(gr_arc
		(start 142.608046 -212.864954)
		(mid 142.345226 -213.258258)
		(end 142.252954 -213.722204)
		(stroke
			(width 0.068326)
			(type default)
		)
		(layer "F.Cu")
	)
	(gr_line
		(start 142.608046 -211.975446)
		(end 142.608046 -211.975954)
		(stroke
			(width 0.068326)
			(type default)
		)
		(layer "F.Cu")
	)
	(gr_arc
		(start 143.68526 -33.01492)
		(mid 143.941168 -32.866346)
		(end 144.04213 -32.5882)
		(stroke
			(width 0.068326)
			(type default)
		)
		(layer "F.Cu")
	)
	(gr_arc
		(start 144.0688 -12.90955)
		(mid 144.226803 -12.897595)
		(end 144.38122 -12.862052)
		(stroke
			(width 0.068326)
			(type default)
		)
		(layer "F.Cu")
	)
	(gr_line
		(start 144.134332 -25.12568)
		(end 144.134332 -25.33015)
		(stroke
			(width 0.068326)
			(type default)
		)
		(layer "F.Cu")
	)
	(gr_line
		(start 144.134332 -13.930122)
		(end 144.244314 -13.930122)
		(stroke
			(width 0.068326)
			(type default)
		)
		(layer "F.Cu")
	)
	(gr_arc
		(start 144.244314 -13.930122)
		(mid 144.602222 -13.5722)
		(end 144.244314 -13.21435)
		(stroke
			(width 0.068326)
			(type default)
		)
		(layer "F.Cu")
	)
	(gr_arc
		(start 144.25422 -24.83612)
		(mid 144.165513 -24.968988)
		(end 144.134332 -25.12568)
		(stroke
			(width 0.068326)
			(type default)
		)
		(layer "F.Cu")
	)
	(gr_arc
		(start 144.34693 -32.598868)
		(mid 144.448376 -32.872915)
		(end 144.7038 -33.01492)
		(stroke
			(width 0.068326)
			(type default)
		)
		(layer "F.Cu")
	)
	(gr_arc
		(start 144.38122 -12.862052)
		(mid 144.613118 -12.757908)
		(end 144.813274 -12.601194)
		(stroke
			(width 0.068326)
			(type default)
		)
		(layer "F.Cu")
	)
	(gr_arc
		(start 144.4244 -24.7904)
		(mid 144.336277 -24.801975)
		(end 144.25422 -24.83612)
		(stroke
			(width 0.068326)
			(type default)
		)
		(layer "F.Cu")
	)
	(gr_arc
		(start 144.55521 -24.844756)
		(mid 144.49521 -24.804564)
		(end 144.4244 -24.7904)
		(stroke
			(width 0.068326)
			(type default)
		)
		(layer "F.Cu")
	)
	(gr_line
		(start 144.55521 -24.844756)
		(end 144.70888 -24.998172)
		(stroke
			(width 0.068326)
			(type default)
		)
		(layer "F.Cu")
	)
	(gr_line
		(start 144.792192 -211.975954)
		(end 145.073878 -211.694268)
		(stroke
			(width 0.068326)
			(type default)
		)
		(layer "F.Cu")
	)
	(gr_line
		(start 144.813274 -12.601194)
		(end 144.884394 -12.530074)
		(stroke
			(width 0.068326)
			(type default)
		)
		(layer "F.Cu")
	)
	(gr_arc
		(start 144.884394 -24.562816)
		(mid 144.88767 -24.618458)
		(end 144.897602 -24.673306)
		(stroke
			(width 0.068326)
			(type default)
		)
		(layer "F.Cu")
	)
	(gr_line
		(start 144.884394 -23.930102)
		(end 144.884394 -24.562816)
		(stroke
			(width 0.068326)
			(type default)
		)
		(layer "F.Cu")
	)
	(gr_line
		(start 144.893792 -210.896454)
		(end 145.025364 -211.027772)
		(stroke
			(width 0.068326)
			(type default)
		)
		(layer "F.Cu")
	)
	(gr_arc
		(start 144.897602 -24.673306)
		(mid 144.931239 -24.765684)
		(end 144.983708 -24.84882)
		(stroke
			(width 0.068326)
			(type default)
		)
		(layer "F.Cu")
	)
	(gr_line
		(start 144.900142 -224.828608)
		(end 144.900142 -225.54438)
		(stroke
			(width 0.068326)
			(type default)
		)
		(layer "F.Cu")
	)
	(gr_line
		(start 144.900142 -224.828608)
		(end 144.900396 -224.828354)
		(stroke
			(width 0.068326)
			(type default)
		)
		(layer "F.Cu")
	)
	(gr_arc
		(start 145.068544 -224.32264)
		(mid 144.943529 -224.561886)
		(end 144.900396 -224.828354)
		(stroke
			(width 0.068326)
			(type default)
		)
		(layer "F.Cu")
	)
	(gr_arc
		(start 145.068544 -224.32264)
		(mid 145.127178 -224.234888)
		(end 145.147792 -224.131378)
		(stroke
			(width 0.068326)
			(type default)
		)
		(layer "F.Cu")
	)
	(gr_arc
		(start 145.073878 -211.694268)
		(mid 145.123869 -211.619452)
		(end 145.141442 -211.5312)
		(stroke
			(width 0.068326)
			(type default)
		)
		(layer "F.Cu")
	)
	(gr_arc
		(start 145.141442 -211.308442)
		(mid 145.111324 -211.156559)
		(end 145.025364 -211.027772)
		(stroke
			(width 0.068326)
			(type default)
		)
		(layer "F.Cu")
	)
	(gr_arc
		(start 145.147792 -213.723474)
		(mid 145.055373 -213.25885)
		(end 144.792192 -212.864954)
		(stroke
			(width 0.068326)
			(type default)
		)
		(layer "F.Cu")
	)
	(gr_arc
		(start 145.446242 -211.5312)
		(mid 145.461526 -211.607653)
		(end 145.504916 -211.672424)
		(stroke
			(width 0.068326)
			(type default)
		)
		(layer "F.Cu")
	)
	(gr_arc
		(start 145.452846 -224.133664)
		(mid 145.473013 -224.23483)
		(end 145.530316 -224.320608)
		(stroke
			(width 0.068326)
			(type default)
		)
		(layer "F.Cu")
	)
	(gr_line
		(start 145.504916 -211.672424)
		(end 145.808192 -211.975954)
		(stroke
			(width 0.068326)
			(type default)
		)
		(layer "F.Cu")
	)
	(gr_arc
		(start 145.553684 -211.049362)
		(mid 145.474156 -211.168339)
		(end 145.446242 -211.308696)
		(stroke
			(width 0.068326)
			(type default)
		)
		(layer "F.Cu")
	)
	(gr_line
		(start 145.553684 -211.049362)
		(end 145.706592 -210.896454)
		(stroke
			(width 0.068326)
			(type default)
		)
		(layer "F.Cu")
	)
	(gr_arc
		(start 145.700242 -224.828354)
		(mid 145.656605 -224.560646)
		(end 145.530316 -224.320608)
		(stroke
			(width 0.068326)
			(type default)
		)
		(layer "F.Cu")
	)
	(gr_line
		(start 145.700242 -224.828354)
		(end 145.700242 -225.54438)
		(stroke
			(width 0.068326)
			(type default)
		)
		(layer "F.Cu")
	)
	(gr_arc
		(start 145.808192 -212.864954)
		(mid 145.545198 -213.258484)
		(end 145.452846 -213.722712)
		(stroke
			(width 0.068326)
			(type default)
		)
		(layer "F.Cu")
	)
	(gr_line
		(start 145.8722 -33.96742)
		(end 146.074384 -34.169858)
		(stroke
			(width 0.068326)
			(type default)
		)
		(layer "F.Cu")
	)
	(gr_arc
		(start 145.8722 -33.07842)
		(mid 146.072271 -32.897993)
		(end 146.14652 -32.639)
		(stroke
			(width 0.068326)
			(type default)
		)
		(layer "F.Cu")
	)
	(gr_line
		(start 145.9103 -34.99612)
		(end 146.055842 -34.850578)
		(stroke
			(width 0.068326)
			(type default)
		)
		(layer "F.Cu")
	)
	(gr_arc
		(start 146.055842 -34.850578)
		(mid 146.13611 -34.730426)
		(end 146.1643 -34.588704)
		(stroke
			(width 0.068326)
			(type default)
		)
		(layer "F.Cu")
	)
	(gr_arc
		(start 146.1643 -34.38652)
		(mid 146.1409 -34.26924)
		(end 146.074384 -34.169858)
		(stroke
			(width 0.068326)
			(type default)
		)
		(layer "F.Cu")
	)
	(gr_arc
		(start 146.45132 -32.639)
		(mid 146.531013 -32.902813)
		(end 146.74342 -33.07842)
		(stroke
			(width 0.068326)
			(type default)
		)
		(layer "F.Cu")
	)
	(gr_arc
		(start 146.4691 -34.588704)
		(mid 146.49729 -34.730424)
		(end 146.577558 -34.850578)
		(stroke
			(width 0.068326)
			(type default)
		)
		(layer "F.Cu")
	)
	(gr_arc
		(start 146.475704 -24.888952)
		(mid 146.338626 -25.090658)
		(end 146.384518 -25.33015)
		(stroke
			(width 0.068326)
			(type default)
		)
		(layer "F.Cu")
	)
	(gr_line
		(start 146.475704 -24.888952)
		(end 146.588988 -24.81453)
		(stroke
			(width 0.068326)
			(type default)
		)
		(layer "F.Cu")
	)
	(gr_arc
		(start 146.571462 -34.139378)
		(mid 146.495697 -34.252768)
		(end 146.4691 -34.38652)
		(stroke
			(width 0.068326)
			(type default)
		)
		(layer "F.Cu")
	)
	(gr_line
		(start 146.571462 -34.139378)
		(end 146.74342 -33.96742)
		(stroke
			(width 0.068326)
			(type default)
		)
		(layer "F.Cu")
	)
	(gr_line
		(start 146.577558 -34.850578)
		(end 146.7231 -34.99612)
		(stroke
			(width 0.068326)
			(type default)
		)
		(layer "F.Cu")
	)
	(gr_arc
		(start 146.850354 -21.119846)
		(mid 146.424973 -21.106402)
		(end 146.384518 -21.530056)
		(stroke
			(width 0.068326)
			(type default)
		)
		(layer "F.Cu")
	)
	(gr_line
		(start 146.850354 -21.119846)
		(end 147.01393 -21.283422)
		(stroke
			(width 0.068326)
			(type default)
		)
		(layer "F.Cu")
	)
	(gr_arc
		(start 146.906996 -24.928576)
		(mid 146.767021 -24.818481)
		(end 146.588988 -24.81453)
		(stroke
			(width 0.068326)
			(type default)
		)
		(layer "F.Cu")
	)
	(gr_line
		(start 146.906996 -24.928576)
		(end 146.961606 -25.011634)
		(stroke
			(width 0.068326)
			(type default)
		)
		(layer "F.Cu")
	)
	(gr_arc
		(start 147.134326 -23.930102)
		(mid 147.16012 -24.405586)
		(end 147.237196 -24.87549)
		(stroke
			(width 0.068326)
			(type default)
		)
		(layer "F.Cu")
	)
	(gr_arc
		(start 147.134326 -20.530312)
		(mid 147.142377 -20.66096)
		(end 147.16633 -20.789646)
		(stroke
			(width 0.068326)
			(type default)
		)
		(layer "F.Cu")
	)
	(gr_line
		(start 147.134326 -20.130008)
		(end 147.134326 -20.530312)
		(stroke
			(width 0.068326)
			(type default)
		)
		(layer "F.Cu")
	)
	(gr_arc
		(start 147.16633 -20.789646)
		(mid 147.169312 -20.801347)
		(end 147.172426 -20.813014)
		(stroke
			(width 0.068326)
			(type default)
		)
		(layer "F.Cu")
	)
	(gr_arc
		(start 147.172426 -20.813014)
		(mid 147.172932 -20.81492)
		(end 147.173442 -20.816824)
		(stroke
			(width 0.068326)
			(type default)
		)
		(layer "F.Cu")
	)
	(gr_arc
		(start 147.173442 -20.816824)
		(mid 147.174452 -20.820509)
		(end 147.175474 -20.82419)
		(stroke
			(width 0.068326)
			(type default)
		)
		(layer "F.Cu")
	)
	(gr_arc
		(start 147.175474 -20.82419)
		(mid 147.179083 -20.836531)
		(end 147.18284 -20.848828)
		(stroke
			(width 0.068326)
			(type default)
		)
		(layer "F.Cu")
	)
	(gr_arc
		(start 147.18284 -20.848828)
		(mid 147.288472 -21.083024)
		(end 147.447 -21.2852)
		(stroke
			(width 0.068326)
			(type default)
		)
		(layer "F.Cu")
	)
	(gr_line
		(start 147.69592 -21.533866)
		(end 147.700238 -21.542248)
		(stroke
			(width 0.068326)
			(type default)
		)
		(layer "F.Cu")
	)
	(gr_line
		(start 147.96262 -22.698964)
		(end 147.9804 -22.733)
		(stroke
			(width 0.068326)
			(type default)
		)
		(layer "F.Cu")
	)
	(gr_line
		(start 147.9804 -22.733)
		(end 148.01215 -22.75459)
		(stroke
			(width 0.068326)
			(type default)
		)
		(layer "F.Cu")
	)
	(gr_line
		(start 147.992084 -211.975954)
		(end 148.27377 -211.694268)
		(stroke
			(width 0.068326)
			(type default)
		)
		(layer "F.Cu")
	)
	(gr_line
		(start 148.093684 -210.896454)
		(end 148.243544 -211.04606)
		(stroke
			(width 0.068326)
			(type default)
		)
		(layer "F.Cu")
	)
	(gr_line
		(start 148.100034 -224.828608)
		(end 148.100034 -225.54438)
		(stroke
			(width 0.068326)
			(type default)
		)
		(layer "F.Cu")
	)
	(gr_line
		(start 148.100034 -224.828608)
		(end 148.100288 -224.828354)
		(stroke
			(width 0.068326)
			(type default)
		)
		(layer "F.Cu")
	)
	(gr_arc
		(start 148.268436 -224.32264)
		(mid 148.143407 -224.561883)
		(end 148.100288 -224.828354)
		(stroke
			(width 0.068326)
			(type default)
		)
		(layer "F.Cu")
	)
	(gr_arc
		(start 148.268436 -224.32264)
		(mid 148.32707 -224.234888)
		(end 148.347684 -224.131378)
		(stroke
			(width 0.068326)
			(type default)
		)
		(layer "F.Cu")
	)
	(gr_arc
		(start 148.27377 -211.694268)
		(mid 148.323761 -211.619452)
		(end 148.341334 -211.5312)
		(stroke
			(width 0.068326)
			(type default)
		)
		(layer "F.Cu")
	)
	(gr_arc
		(start 148.341334 -211.282534)
		(mid 148.315973 -211.154563)
		(end 148.243544 -211.04606)
		(stroke
			(width 0.068326)
			(type default)
		)
		(layer "F.Cu")
	)
	(gr_arc
		(start 148.347684 -213.723474)
		(mid 148.255265 -213.25885)
		(end 147.992084 -212.864954)
		(stroke
			(width 0.068326)
			(type default)
		)
		(layer "F.Cu")
	)
	(gr_line
		(start 148.463 -33.9725)
		(end 148.665184 -34.174938)
		(stroke
			(width 0.068326)
			(type default)
		)
		(layer "F.Cu")
	)
	(gr_arc
		(start 148.463 -33.0835)
		(mid 148.674919 -32.919845)
		(end 148.7551 -32.6644)
		(stroke
			(width 0.068326)
			(type default)
		)
		(layer "F.Cu")
	)
	(gr_line
		(start 148.5011 -35.0012)
		(end 148.646642 -34.855658)
		(stroke
			(width 0.068326)
			(type default)
		)
		(layer "F.Cu")
	)
	(gr_line
		(start 148.56968 -23.133558)
		(end 148.6154 -23.1648)
		(stroke
			(width 0.068326)
			(type default)
		)
		(layer "F.Cu")
	)
	(gr_line
		(start 148.6154 -23.1648)
		(end 148.670772 -23.164292)
		(stroke
			(width 0.068326)
			(type default)
		)
		(layer "F.Cu")
	)
	(gr_line
		(start 148.63445 -25.107392)
		(end 148.63445 -25.33015)
		(stroke
			(width 0.068326)
			(type default)
		)
		(layer "F.Cu")
	)
	(gr_line
		(start 148.63445 -21.241004)
		(end 148.63445 -21.530056)
		(stroke
			(width 0.068326)
			(type default)
		)
		(layer "F.Cu")
	)
	(gr_arc
		(start 148.646134 -211.5312)
		(mid 148.661418 -211.607654)
		(end 148.704808 -211.672424)
		(stroke
			(width 0.068326)
			(type default)
		)
		(layer "F.Cu")
	)
	(gr_arc
		(start 148.646642 -34.855658)
		(mid 148.726903 -34.735504)
		(end 148.7551 -34.593784)
		(stroke
			(width 0.068326)
			(type default)
		)
		(layer "F.Cu")
	)
	(gr_arc
		(start 148.652738 -224.133664)
		(mid 148.672904 -224.23483)
		(end 148.730208 -224.320608)
		(stroke
			(width 0.068326)
			(type default)
		)
		(layer "F.Cu")
	)
	(gr_arc
		(start 148.669756 -21.083778)
		(mid 148.64339 -21.160436)
		(end 148.63445 -21.241004)
		(stroke
			(width 0.068326)
			(type default)
		)
		(layer "F.Cu")
	)
	(gr_line
		(start 148.669756 -21.083778)
		(end 148.722842 -21.030438)
		(stroke
			(width 0.068326)
			(type default)
		)
		(layer "F.Cu")
	)
	(gr_line
		(start 148.704808 -211.672424)
		(end 149.008084 -211.975954)
		(stroke
			(width 0.068326)
			(type default)
		)
		(layer "F.Cu")
	)
	(gr_arc
		(start 148.735288 -211.067904)
		(mid 148.669359 -211.166488)
		(end 148.646134 -211.282788)
		(stroke
			(width 0.068326)
			(type default)
		)
		(layer "F.Cu")
	)
	(gr_line
		(start 148.735288 -211.067904)
		(end 148.906484 -210.896454)
		(stroke
			(width 0.068326)
			(type default)
		)
		(layer "F.Cu")
	)
	(gr_arc
		(start 148.7551 -34.3916)
		(mid 148.731693 -34.274324)
		(end 148.665184 -34.174938)
		(stroke
			(width 0.068326)
			(type default)
		)
		(layer "F.Cu")
	)
	(gr_arc
		(start 148.761196 -24.801322)
		(mid 148.667413 -24.941761)
		(end 148.63445 -25.107392)
		(stroke
			(width 0.068326)
			(type default)
		)
		(layer "F.Cu")
	)
	(gr_arc
		(start 148.844 -20.9804)
		(mid 148.778432 -20.993348)
		(end 148.722842 -21.030438)
		(stroke
			(width 0.068326)
			(type default)
		)
		(layer "F.Cu")
	)
	(gr_arc
		(start 148.8694 -24.7777)
		(mid 148.814025 -24.783682)
		(end 148.761196 -24.801322)
		(stroke
			(width 0.068326)
			(type default)
		)
		(layer "F.Cu")
	)
	(gr_arc
		(start 148.900134 -224.828354)
		(mid 148.856497 -224.560646)
		(end 148.730208 -224.320608)
		(stroke
			(width 0.068326)
			(type default)
		)
		(layer "F.Cu")
	)
	(gr_line
		(start 148.900134 -224.828354)
		(end 148.900134 -225.54438)
		(stroke
			(width 0.068326)
			(type default)
		)
		(layer "F.Cu")
	)
	(gr_arc
		(start 149.008084 -212.864954)
		(mid 148.745091 -213.258484)
		(end 148.652738 -213.722712)
		(stroke
			(width 0.068326)
			(type default)
		)
		(layer "F.Cu")
	)
	(gr_arc
		(start 149.018498 -21.052536)
		(mid 148.938423 -20.999124)
		(end 148.844 -20.9804)
		(stroke
			(width 0.068326)
			(type default)
		)
		(layer "F.Cu")
	)
	(gr_line
		(start 149.018498 -21.052536)
		(end 149.047454 -21.081746)
		(stroke
			(width 0.068326)
			(type default)
		)
		(layer "F.Cu")
	)
	(gr_arc
		(start 149.022054 -24.840946)
		(mid 148.952021 -24.794127)
		(end 148.8694 -24.7777)
		(stroke
			(width 0.068326)
			(type default)
		)
		(layer "F.Cu")
	)
	(gr_line
		(start 149.022054 -24.840946)
		(end 149.318472 -25.137364)
		(stroke
			(width 0.068326)
			(type default)
		)
		(layer "F.Cu")
	)
	(gr_line
		(start 149.047454 -21.081746)
		(end 149.21103 -21.245322)
		(stroke
			(width 0.068326)
			(type default)
		)
		(layer "F.Cu")
	)
	(gr_arc
		(start 149.0599 -34.593784)
		(mid 149.08809 -34.735504)
		(end 149.168358 -34.855658)
		(stroke
			(width 0.068326)
			(type default)
		)
		(layer "F.Cu")
	)
	(gr_arc
		(start 149.0599 -32.6644)
		(mid 149.140151 -32.919816)
		(end 149.352 -33.0835)
		(stroke
			(width 0.068326)
			(type default)
		)
		(layer "F.Cu")
	)
	(gr_arc
		(start 149.167596 -34.15665)
		(mid 149.087865 -34.276115)
		(end 149.0599 -34.417)
		(stroke
			(width 0.068326)
			(type default)
		)
		(layer "F.Cu")
	)
	(gr_line
		(start 149.167596 -34.15665)
		(end 149.352 -33.9725)
		(stroke
			(width 0.068326)
			(type default)
		)
		(layer "F.Cu")
	)
	(gr_line
		(start 149.168358 -34.855658)
		(end 149.3139 -35.0012)
		(stroke
			(width 0.068326)
			(type default)
		)
		(layer "F.Cu")
	)
	(gr_arc
		(start 149.384512 -24.56053)
		(mid 149.386671 -24.608874)
		(end 149.393402 -24.656796)
		(stroke
			(width 0.068326)
			(type default)
		)
		(layer "F.Cu")
	)
	(gr_line
		(start 149.384512 -23.930102)
		(end 149.384512 -24.56053)
		(stroke
			(width 0.068326)
			(type default)
		)
		(layer "F.Cu")
	)
	(gr_arc
		(start 149.384512 -20.620482)
		(mid 149.391294 -20.729643)
		(end 149.411436 -20.837144)
		(stroke
			(width 0.068326)
			(type default)
		)
		(layer "F.Cu")
	)
	(gr_line
		(start 149.384512 -20.130008)
		(end 149.384512 -20.620482)
		(stroke
			(width 0.068326)
			(type default)
		)
		(layer "F.Cu")
	)
	(gr_arc
		(start 149.393402 -24.656796)
		(mid 149.393902 -24.659718)
		(end 149.394418 -24.662638)
		(stroke
			(width 0.068326)
			(type default)
		)
		(layer "F.Cu")
	)
	(gr_arc
		(start 149.394418 -24.662638)
		(mid 149.394923 -24.664417)
		(end 149.395434 -24.666194)
		(stroke
			(width 0.068326)
			(type default)
		)
		(layer "F.Cu")
	)
	(gr_arc
		(start 149.395434 -24.666194)
		(mid 149.446225 -24.804023)
		(end 149.534118 -24.921718)
		(stroke
			(width 0.068326)
			(type default)
		)
		(layer "F.Cu")
	)
	(gr_arc
		(start 149.411436 -20.837144)
		(mid 149.500018 -21.05787)
		(end 149.6441 -21.2471)
		(stroke
			(width 0.068326)
			(type default)
		)
		(layer "F.Cu")
	)
	(gr_line
		(start 149.814788 -21.771356)
		(end 149.81809 -21.772626)
		(stroke
			(width 0.068326)
			(type default)
		)
		(layer "F.Cu")
	)
	(gr_line
		(start 149.93112 -21.48967)
		(end 149.931374 -21.48967)
		(stroke
			(width 0.068326)
			(type default)
		)
		(layer "F.Cu")
	)
	(gr_line
		(start 149.931374 -21.48967)
		(end 149.931882 -21.489924)
		(stroke
			(width 0.068326)
			(type default)
		)
		(layer "F.Cu")
	)
	(gr_arc
		(start 150.622 -33.0835)
		(mid 150.833919 -32.919845)
		(end 150.9141 -32.6644)
		(stroke
			(width 0.068326)
			(type default)
		)
		(layer "F.Cu")
	)
	(gr_arc
		(start 150.9141 -38.0873)
		(mid 151.091835 -37.867466)
		(end 151.1554 -37.592)
		(stroke
			(width 0.068326)
			(type default)
		)
		(layer "F.Cu")
	)
	(gr_arc
		(start 150.9141 -34.737548)
		(mid 150.83862 -34.328078)
		(end 150.622 -33.9725)
		(stroke
			(width 0.068326)
			(type default)
		)
		(layer "F.Cu")
	)
	(gr_line
		(start 151.19223 -211.975954)
		(end 151.473916 -211.694268)
		(stroke
			(width 0.068326)
			(type default)
		)
		(layer "F.Cu")
	)
	(gr_arc
		(start 151.2189 -32.6644)
		(mid 151.299151 -32.919816)
		(end 151.511 -33.0835)
		(stroke
			(width 0.068326)
			(type default)
		)
		(layer "F.Cu")
	)
	(gr_line
		(start 151.29383 -210.896454)
		(end 151.447246 -211.050124)
		(stroke
			(width 0.068326)
			(type default)
		)
		(layer "F.Cu")
	)
	(gr_line
		(start 151.30018 -224.828608)
		(end 151.30018 -225.54438)
		(stroke
			(width 0.068326)
			(type default)
		)
		(layer "F.Cu")
	)
	(gr_line
		(start 151.30018 -224.828608)
		(end 151.300434 -224.828354)
		(stroke
			(width 0.068326)
			(type default)
		)
		(layer "F.Cu")
	)
	(gr_arc
		(start 151.4602 -37.5158)
		(mid 151.530152 -37.831139)
		(end 151.7269 -38.0873)
		(stroke
			(width 0.068326)
			(type default)
		)
		(layer "F.Cu")
	)
	(gr_arc
		(start 151.468582 -224.32264)
		(mid 151.343561 -224.561885)
		(end 151.300434 -224.828354)
		(stroke
			(width 0.068326)
			(type default)
		)
		(layer "F.Cu")
	)
	(gr_arc
		(start 151.468582 -224.32264)
		(mid 151.527216 -224.234888)
		(end 151.54783 -224.131378)
		(stroke
			(width 0.068326)
			(type default)
		)
		(layer "F.Cu")
	)
	(gr_arc
		(start 151.473916 -211.694268)
		(mid 151.523907 -211.619452)
		(end 151.54148 -211.5312)
		(stroke
			(width 0.068326)
			(type default)
		)
		(layer "F.Cu")
	)
	(gr_arc
		(start 151.511 -33.9725)
		(mid 151.294389 -34.328086)
		(end 151.2189 -34.737548)
		(stroke
			(width 0.068326)
			(type default)
		)
		(layer "F.Cu")
	)
	(gr_arc
		(start 151.54148 -211.2772)
		(mid 151.516939 -211.154294)
		(end 151.447246 -211.050124)
		(stroke
			(width 0.068326)
			(type default)
		)
		(layer "F.Cu")
	)
	(gr_arc
		(start 151.54783 -213.723474)
		(mid 151.455411 -213.25885)
		(end 151.19223 -212.864954)
		(stroke
			(width 0.068326)
			(type default)
		)
		(layer "F.Cu")
	)
	(gr_arc
		(start 151.84628 -211.5312)
		(mid 151.86156 -211.607657)
		(end 151.904954 -211.672424)
		(stroke
			(width 0.068326)
			(type default)
		)
		(layer "F.Cu")
	)
	(gr_arc
		(start 151.852884 -224.133664)
		(mid 151.873053 -224.234828)
		(end 151.930354 -224.320608)
		(stroke
			(width 0.068326)
			(type default)
		)
		(layer "F.Cu")
	)
	(gr_line
		(start 151.904954 -211.672424)
		(end 152.20823 -211.975954)
		(stroke
			(width 0.068326)
			(type default)
		)
		(layer "F.Cu")
	)
	(gr_arc
		(start 151.931116 -211.071714)
		(mid 151.86827 -211.165887)
		(end 151.84628 -211.276946)
		(stroke
			(width 0.068326)
			(type default)
		)
		(layer "F.Cu")
	)
	(gr_line
		(start 151.931116 -211.071714)
		(end 152.10663 -210.896454)
		(stroke
			(width 0.068326)
			(type default)
		)
		(layer "F.Cu")
	)
	(gr_line
		(start 152.100026 -224.828608)
		(end 152.100026 -225.54438)
		(stroke
			(width 0.068326)
			(type default)
		)
		(layer "F.Cu")
	)
	(gr_line
		(start 152.100026 -224.828608)
		(end 152.10028 -224.828354)
		(stroke
			(width 0.068326)
			(type default)
		)
		(layer "F.Cu")
	)
	(gr_arc
		(start 152.10028 -224.828354)
		(mid 152.056643 -224.560646)
		(end 151.930354 -224.320608)
		(stroke
			(width 0.068326)
			(type default)
		)
		(layer "F.Cu")
	)
	(gr_arc
		(start 152.20823 -212.864954)
		(mid 151.945249 -213.258487)
		(end 151.852884 -213.722712)
		(stroke
			(width 0.068326)
			(type default)
		)
		(layer "F.Cu")
	)
	(gr_arc
		(start 152.6032 -33.0581)
		(mid 152.815036 -32.89441)
		(end 152.8953 -32.639)
		(stroke
			(width 0.068326)
			(type default)
		)
		(layer "F.Cu")
	)
	(gr_arc
		(start 152.7175 -34.99612)
		(mid 152.879809 -34.815332)
		(end 152.93848 -34.57956)
		(stroke
			(width 0.068326)
			(type default)
		)
		(layer "F.Cu")
	)
	(gr_arc
		(start 152.93848 -34.40684)
		(mid 152.845737 -34.122355)
		(end 152.6032 -33.9471)
		(stroke
			(width 0.068326)
			(type default)
		)
		(layer "F.Cu")
	)
	(gr_arc
		(start 153.2001 -32.639)
		(mid 153.280351 -32.894416)
		(end 153.4922 -33.0581)
		(stroke
			(width 0.068326)
			(type default)
		)
		(layer "F.Cu")
	)
	(gr_arc
		(start 153.24328 -34.57956)
		(mid 153.321984 -34.83249)
		(end 153.5303 -34.99612)
		(stroke
			(width 0.068326)
			(type default)
		)
		(layer "F.Cu")
	)
	(gr_arc
		(start 153.4922 -33.9471)
		(mid 153.309465 -34.145426)
		(end 153.24328 -34.40684)
		(stroke
			(width 0.068326)
			(type default)
		)
		(layer "F.Cu")
	)
	(gr_line
		(start 154.392122 -211.975954)
		(end 154.673808 -211.694268)
		(stroke
			(width 0.068326)
			(type default)
		)
		(layer "F.Cu")
	)
	(gr_line
		(start 154.493722 -210.896454)
		(end 154.647138 -211.050124)
		(stroke
			(width 0.068326)
			(type default)
		)
		(layer "F.Cu")
	)
	(gr_line
		(start 154.500072 -224.828608)
		(end 154.500072 -225.54438)
		(stroke
			(width 0.068326)
			(type default)
		)
		(layer "F.Cu")
	)
	(gr_line
		(start 154.500072 -224.828608)
		(end 154.500326 -224.828354)
		(stroke
			(width 0.068326)
			(type default)
		)
		(layer "F.Cu")
	)
	(gr_arc
		(start 154.668474 -224.32264)
		(mid 154.543454 -224.561885)
		(end 154.500326 -224.828354)
		(stroke
			(width 0.068326)
			(type default)
		)
		(layer "F.Cu")
	)
	(gr_arc
		(start 154.668474 -224.32264)
		(mid 154.727108 -224.234888)
		(end 154.747722 -224.131378)
		(stroke
			(width 0.068326)
			(type default)
		)
		(layer "F.Cu")
	)
	(gr_arc
		(start 154.673808 -211.694268)
		(mid 154.723799 -211.619452)
		(end 154.741372 -211.5312)
		(stroke
			(width 0.068326)
			(type default)
		)
		(layer "F.Cu")
	)
	(gr_arc
		(start 154.741372 -211.2772)
		(mid 154.716831 -211.154294)
		(end 154.647138 -211.050124)
		(stroke
			(width 0.068326)
			(type default)
		)
		(layer "F.Cu")
	)
	(gr_arc
		(start 154.747722 -213.723474)
		(mid 154.655303 -213.25885)
		(end 154.392122 -212.864954)
		(stroke
			(width 0.068326)
			(type default)
		)
		(layer "F.Cu")
	)
	(gr_arc
		(start 155.046172 -211.5312)
		(mid 155.061452 -211.607657)
		(end 155.104846 -211.672424)
		(stroke
			(width 0.068326)
			(type default)
		)
		(layer "F.Cu")
	)
	(gr_arc
		(start 155.052776 -224.133664)
		(mid 155.072944 -224.234828)
		(end 155.130246 -224.320608)
		(stroke
			(width 0.068326)
			(type default)
		)
		(layer "F.Cu")
	)
	(gr_line
		(start 155.104846 -211.672424)
		(end 155.408122 -211.975954)
		(stroke
			(width 0.068326)
			(type default)
		)
		(layer "F.Cu")
	)
	(gr_arc
		(start 155.113228 -211.089494)
		(mid 155.063562 -211.163976)
		(end 155.046172 -211.2518)
		(stroke
			(width 0.068326)
			(type default)
		)
		(layer "F.Cu")
	)
	(gr_line
		(start 155.113228 -211.089494)
		(end 155.306522 -210.896454)
		(stroke
			(width 0.068326)
			(type default)
		)
		(layer "F.Cu")
	)
	(gr_line
		(start 155.134564 -25.11552)
		(end 155.134564 -25.33015)
		(stroke
			(width 0.068326)
			(type default)
		)
		(layer "F.Cu")
	)
	(gr_arc
		(start 155.240736 -24.859234)
		(mid 155.162168 -24.976819)
		(end 155.134564 -25.11552)
		(stroke
			(width 0.068326)
			(type default)
		)
		(layer "F.Cu")
	)
	(gr_arc
		(start 155.300172 -224.828354)
		(mid 155.256535 -224.560646)
		(end 155.130246 -224.320608)
		(stroke
			(width 0.068326)
			(type default)
		)
		(layer "F.Cu")
	)
	(gr_line
		(start 155.300172 -224.828354)
		(end 155.300172 -225.54438)
		(stroke
			(width 0.068326)
			(type default)
		)
		(layer "F.Cu")
	)
	(gr_arc
		(start 155.335986 -24.822658)
		(mid 155.287155 -24.837804)
		(end 155.240736 -24.859234)
		(stroke
			(width 0.068326)
			(type default)
		)
		(layer "F.Cu")
	)
	(gr_line
		(start 155.335986 -24.822658)
		(end 155.423108 -24.822658)
		(stroke
			(width 0.068326)
			(type default)
		)
		(layer "F.Cu")
	)
	(gr_arc
		(start 155.408122 -212.864954)
		(mid 155.145121 -213.258482)
		(end 155.052776 -213.722712)
		(stroke
			(width 0.068326)
			(type default)
		)
		(layer "F.Cu")
	)
	(gr_line
		(start 155.50642 -26.819098)
		(end 155.513024 -26.802334)
		(stroke
			(width 0.068326)
			(type default)
		)
		(layer "F.Cu")
	)
	(gr_arc
		(start 155.56484 -24.881332)
		(mid 155.499813 -24.837882)
		(end 155.423108 -24.822658)
		(stroke
			(width 0.068326)
			(type default)
		)
		(layer "F.Cu")
	)
	(gr_line
		(start 155.56484 -24.881332)
		(end 155.867354 -25.183846)
		(stroke
			(width 0.068326)
			(type default)
		)
		(layer "F.Cu")
	)
	(gr_line
		(start 155.882086 -32.977074)
		(end 156.172916 -32.686244)
		(stroke
			(width 0.068326)
			(type default)
		)
		(layer "F.Cu")
	)
	(gr_arc
		(start 155.884372 -24.417528)
		(mid 155.950309 -24.749089)
		(end 156.138118 -25.030176)
		(stroke
			(width 0.068326)
			(type default)
		)
		(layer "F.Cu")
	)
	(gr_line
		(start 155.884372 -23.930102)
		(end 155.884372 -24.417528)
		(stroke
			(width 0.068326)
			(type default)
		)
		(layer "F.Cu")
	)
	(gr_arc
		(start 155.898342 -25.218644)
		(mid 155.883372 -25.200778)
		(end 155.867354 -25.183846)
		(stroke
			(width 0.068326)
			(type default)
		)
		(layer "F.Cu")
	)
	(gr_line
		(start 156.138118 -25.030176)
		(end 156.138118 -25.03043)
		(stroke
			(width 0.068326)
			(type default)
		)
		(layer "F.Cu")
	)
	(gr_line
		(start 156.607764 -32.686244)
		(end 156.898594 -32.977074)
		(stroke
			(width 0.068326)
			(type default)
		)
		(layer "F.Cu")
	)
	(gr_line
		(start 157.384496 -25.071832)
		(end 157.384496 -25.33015)
		(stroke
			(width 0.068326)
			(type default)
		)
		(layer "F.Cu")
	)
	(gr_line
		(start 157.384496 -21.23186)
		(end 157.384496 -21.530056)
		(stroke
			(width 0.068326)
			(type default)
		)
		(layer "F.Cu")
	)
	(gr_arc
		(start 157.484318 -24.830786)
		(mid 157.410429 -24.941382)
		(end 157.384496 -25.071832)
		(stroke
			(width 0.068326)
			(type default)
		)
		(layer "F.Cu")
	)
	(gr_line
		(start 157.592268 -211.975954)
		(end 157.873954 -211.694268)
		(stroke
			(width 0.068326)
			(type default)
		)
		(layer "F.Cu")
	)
	(gr_arc
		(start 157.6324 -24.7904)
		(mid 157.555655 -24.800686)
		(end 157.484318 -24.830786)
		(stroke
			(width 0.068326)
			(type default)
		)
		(layer "F.Cu")
	)
	(gr_line
		(start 157.693868 -210.896454)
		(end 157.865318 -211.067904)
		(stroke
			(width 0.068326)
			(type default)
		)
		(layer "F.Cu")
	)
	(gr_line
		(start 157.700218 -224.828608)
		(end 157.700218 -225.54438)
		(stroke
			(width 0.068326)
			(type default)
		)
		(layer "F.Cu")
	)
	(gr_line
		(start 157.700218 -224.828608)
		(end 157.700472 -224.828354)
		(stroke
			(width 0.068326)
			(type default)
		)
		(layer "F.Cu")
	)
	(gr_arc
		(start 157.791658 -21.063204)
		(mid 157.531719 -21.01151)
		(end 157.384496 -21.23186)
		(stroke
			(width 0.068326)
			(type default)
		)
		(layer "F.Cu")
	)
	(gr_line
		(start 157.791658 -21.063204)
		(end 158.215584 -21.486876)
		(stroke
			(width 0.068326)
			(type default)
		)
		(layer "F.Cu")
	)
	(gr_arc
		(start 157.806898 -24.862536)
		(mid 157.726833 -24.80909)
		(end 157.6324 -24.7904)
		(stroke
			(width 0.068326)
			(type default)
		)
		(layer "F.Cu")
	)
	(gr_line
		(start 157.806898 -24.862536)
		(end 158.14421 -25.200356)
		(stroke
			(width 0.068326)
			(type default)
		)
		(layer "F.Cu")
	)
	(gr_arc
		(start 157.86862 -224.32264)
		(mid 157.743594 -224.561883)
		(end 157.700472 -224.828354)
		(stroke
			(width 0.068326)
			(type default)
		)
		(layer "F.Cu")
	)
	(gr_arc
		(start 157.86862 -224.32264)
		(mid 157.927254 -224.234888)
		(end 157.947868 -224.131378)
		(stroke
			(width 0.068326)
			(type default)
		)
		(layer "F.Cu")
	)
	(gr_arc
		(start 157.873954 -211.694268)
		(mid 157.923945 -211.619452)
		(end 157.941518 -211.5312)
		(stroke
			(width 0.068326)
			(type default)
		)
		(layer "F.Cu")
	)
	(gr_arc
		(start 157.941518 -211.2518)
		(mid 157.921719 -211.152266)
		(end 157.865318 -211.067904)
		(stroke
			(width 0.068326)
			(type default)
		)
		(layer "F.Cu")
	)
	(gr_arc
		(start 157.947868 -213.723474)
		(mid 157.855449 -213.25885)
		(end 157.592268 -212.864954)
		(stroke
			(width 0.068326)
			(type default)
		)
		(layer "F.Cu")
	)
	(gr_arc
		(start 158.134558 -24.403304)
		(mid 158.199898 -24.731971)
		(end 158.386018 -25.010618)
		(stroke
			(width 0.068326)
			(type default)
		)
		(layer "F.Cu")
	)
	(gr_line
		(start 158.134558 -23.930102)
		(end 158.134558 -24.403304)
		(stroke
			(width 0.068326)
			(type default)
		)
		(layer "F.Cu")
	)
	(gr_arc
		(start 158.134558 -20.517358)
		(mid 158.143248 -20.655346)
		(end 158.169102 -20.79117)
		(stroke
			(width 0.068326)
			(type default)
		)
		(layer "F.Cu")
	)
	(gr_line
		(start 158.134558 -20.130008)
		(end 158.134558 -20.517358)
		(stroke
			(width 0.068326)
			(type default)
		)
		(layer "F.Cu")
	)
	(gr_arc
		(start 158.169102 -20.79117)
		(mid 158.173655 -20.808735)
		(end 158.1785 -20.826222)
		(stroke
			(width 0.068326)
			(type default)
		)
		(layer "F.Cu")
	)
	(gr_arc
		(start 158.1785 -20.826222)
		(mid 158.189932 -20.862754)
		(end 158.20263 -20.898866)
		(stroke
			(width 0.068326)
			(type default)
		)
		(layer "F.Cu")
	)
	(gr_arc
		(start 158.20263 -20.898866)
		(mid 158.308614 -21.112232)
		(end 158.4579 -21.2979)
		(stroke
			(width 0.068326)
			(type default)
		)
		(layer "F.Cu")
	)
	(gr_arc
		(start 158.246318 -211.5312)
		(mid 158.261601 -211.607654)
		(end 158.304992 -211.672424)
		(stroke
			(width 0.068326)
			(type default)
		)
		(layer "F.Cu")
	)
	(gr_arc
		(start 158.252922 -224.133664)
		(mid 158.273093 -224.234825)
		(end 158.330392 -224.320608)
		(stroke
			(width 0.068326)
			(type default)
		)
		(layer "F.Cu")
	)
	(gr_line
		(start 158.304992 -211.672424)
		(end 158.608268 -211.975954)
		(stroke
			(width 0.068326)
			(type default)
		)
		(layer "F.Cu")
	)
	(gr_arc
		(start 158.313374 -211.089494)
		(mid 158.263698 -211.163974)
		(end 158.246318 -211.2518)
		(stroke
			(width 0.068326)
			(type default)
		)
		(layer "F.Cu")
	)
	(gr_line
		(start 158.313374 -211.089494)
		(end 158.506668 -210.896454)
		(stroke
			(width 0.068326)
			(type default)
		)
		(layer "F.Cu")
	)
	(gr_line
		(start 158.496 -86.918038)
		(end 158.795466 -87.217504)
		(stroke
			(width 0.060198)
			(type default)
		)
		(layer "F.Cu")
	)
	(gr_line
		(start 158.496 -85.6869)
		(end 158.496 -86.918038)
		(stroke
			(width 0.060198)
			(type default)
		)
		(layer "F.Cu")
	)
	(gr_line
		(start 158.500064 -224.828608)
		(end 158.500064 -225.54438)
		(stroke
			(width 0.068326)
			(type default)
		)
		(layer "F.Cu")
	)
	(gr_line
		(start 158.500064 -224.828608)
		(end 158.500318 -224.828354)
		(stroke
			(width 0.068326)
			(type default)
		)
		(layer "F.Cu")
	)
	(gr_arc
		(start 158.500318 -224.828354)
		(mid 158.456681 -224.560646)
		(end 158.330392 -224.320608)
		(stroke
			(width 0.068326)
			(type default)
		)
		(layer "F.Cu")
	)
	(gr_arc
		(start 158.540704 -33.0835)
		(mid 158.752621 -32.919844)
		(end 158.832804 -32.6644)
		(stroke
			(width 0.068326)
			(type default)
		)
		(layer "F.Cu")
	)
	(gr_arc
		(start 158.608268 -212.864954)
		(mid 158.345279 -213.258485)
		(end 158.252922 -213.722712)
		(stroke
			(width 0.068326)
			(type default)
		)
		(layer "F.Cu")
	)
	(gr_arc
		(start 158.655004 -35.02152)
		(mid 158.817312 -34.840732)
		(end 158.875984 -34.60496)
		(stroke
			(width 0.068326)
			(type default)
		)
		(layer "F.Cu")
	)
	(gr_line
		(start 158.675324 -21.515324)
		(end 158.678118 -21.518118)
		(stroke
			(width 0.068326)
			(type default)
		)
		(layer "F.Cu")
	)
	(gr_line
		(start 158.678118 -21.518118)
		(end 158.68015 -21.52142)
		(stroke
			(width 0.068326)
			(type default)
		)
		(layer "F.Cu")
	)
	(gr_line
		(start 158.795466 -87.217504)
		(end 159.328358 -87.217504)
		(stroke
			(width 0.060198)
			(type default)
		)
		(layer "F.Cu")
	)
	(gr_arc
		(start 158.875984 -34.43224)
		(mid 158.783242 -34.147754)
		(end 158.540704 -33.9725)
		(stroke
			(width 0.068326)
			(type default)
		)
		(layer "F.Cu")
	)
	(gr_line
		(start 158.939738 -22.607524)
		(end 158.9532 -22.6314)
		(stroke
			(width 0.068326)
			(type default)
		)
		(layer "F.Cu")
	)
	(gr_line
		(start 158.9532 -22.6314)
		(end 158.975298 -22.647656)
		(stroke
			(width 0.068326)
			(type default)
		)
		(layer "F.Cu")
	)
	(gr_line
		(start 159.07004 -86.637114)
		(end 159.132778 -86.699852)
		(stroke
			(width 0.060198)
			(type default)
		)
		(layer "F.Cu")
	)
	(gr_line
		(start 159.07004 -86.12886)
		(end 159.07004 -86.637114)
		(stroke
			(width 0.060198)
			(type default)
		)
		(layer "F.Cu")
	)
	(gr_line
		(start 159.07004 -86.12886)
		(end 159.512 -85.6869)
		(stroke
			(width 0.060198)
			(type default)
		)
		(layer "F.Cu")
	)
	(gr_arc
		(start 159.137604 -32.6644)
		(mid 159.217827 -32.919839)
		(end 159.429704 -33.0835)
		(stroke
			(width 0.068326)
			(type default)
		)
		(layer "F.Cu")
	)
	(gr_line
		(start 159.14878 -86.715854)
		(end 159.259778 -86.826852)
		(stroke
			(width 0.060198)
			(type default)
		)
		(layer "F.Cu")
	)
	(gr_arc
		(start 159.180784 -34.60496)
		(mid 159.259488 -34.85789)
		(end 159.467804 -35.02152)
		(stroke
			(width 0.068326)
			(type default)
		)
		(layer "F.Cu")
	)
	(gr_line
		(start 159.259778 -86.826852)
		(end 159.663638 -86.826852)
		(stroke
			(width 0.060198)
			(type default)
		)
		(layer "F.Cu")
	)
	(gr_line
		(start 159.328358 -87.217504)
		(end 159.45358 -87.342726)
		(stroke
			(width 0.060198)
			(type default)
		)
		(layer "F.Cu")
	)
	(gr_arc
		(start 159.429704 -33.9725)
		(mid 159.246969 -34.170826)
		(end 159.180784 -34.43224)
		(stroke
			(width 0.068326)
			(type default)
		)
		(layer "F.Cu")
	)
	(gr_line
		(start 159.455358 -87.344504)
		(end 159.527748 -87.416894)
		(stroke
			(width 0.060198)
			(type default)
		)
		(layer "F.Cu")
	)
	(gr_line
		(start 159.530288 -87.419434)
		(end 159.532066 -87.421212)
		(stroke
			(width 0.060198)
			(type default)
		)
		(layer "F.Cu")
	)
	(gr_line
		(start 159.532066 -87.421212)
		(end 159.532066 -88.088978)
		(stroke
			(width 0.060198)
			(type default)
		)
		(layer "F.Cu")
	)
	(gr_line
		(start 159.59963 -23.10384)
		(end 159.648398 -23.1394)
		(stroke
			(width 0.068326)
			(type default)
		)
		(layer "F.Cu")
	)
	(gr_line
		(start 159.634428 -25.064466)
		(end 159.634428 -25.33015)
		(stroke
			(width 0.068326)
			(type default)
		)
		(layer "F.Cu")
	)
	(gr_line
		(start 159.634428 -21.530056)
		(end 159.873442 -21.291042)
		(stroke
			(width 0.068326)
			(type default)
		)
		(layer "F.Cu")
	)
	(gr_line
		(start 159.663638 -86.826852)
		(end 160.031938 -87.195152)
		(stroke
			(width 0.060198)
			(type default)
		)
		(layer "F.Cu")
	)
	(gr_arc
		(start 159.726376 -24.84247)
		(mid 159.658315 -24.944322)
		(end 159.634428 -25.064466)
		(stroke
			(width 0.068326)
			(type default)
		)
		(layer "F.Cu")
	)
	(gr_arc
		(start 159.9184 -24.7904)
		(mid 159.818907 -24.803598)
		(end 159.726376 -24.84247)
		(stroke
			(width 0.068326)
			(type default)
		)
		(layer "F.Cu")
	)
	(gr_line
		(start 160.031938 -87.195152)
		(end 160.031938 -88.088978)
		(stroke
			(width 0.060198)
			(type default)
		)
		(layer "F.Cu")
	)
	(gr_arc
		(start 160.04921 -24.844756)
		(mid 159.98921 -24.804564)
		(end 159.9184 -24.7904)
		(stroke
			(width 0.068326)
			(type default)
		)
		(layer "F.Cu")
	)
	(gr_line
		(start 160.04921 -24.844756)
		(end 160.342072 -25.137364)
		(stroke
			(width 0.068326)
			(type default)
		)
		(layer "F.Cu")
	)
	(gr_arc
		(start 160.245298 -21.255736)
		(mid 160.053013 -21.206478)
		(end 159.873442 -21.291042)
		(stroke
			(width 0.068326)
			(type default)
		)
		(layer "F.Cu")
	)
	(gr_line
		(start 160.25495 -21.265388)
		(end 160.260538 -21.270976)
		(stroke
			(width 0.068326)
			(type default)
		)
		(layer "F.Cu")
	)
	(gr_arc
		(start 160.274 -20.574)
		(mid 160.325353 -20.832167)
		(end 160.471612 -21.051012)
		(stroke
			(width 0.068326)
			(type default)
		)
		(layer "F.Cu")
	)
	(gr_line
		(start 160.274 -20.396708)
		(end 160.274 -20.574)
		(stroke
			(width 0.068326)
			(type default)
		)
		(layer "F.Cu")
	)
	(gr_arc
		(start 160.38449 -24.503634)
		(mid 160.42956 -24.729887)
		(end 160.557718 -24.921718)
		(stroke
			(width 0.068326)
			(type default)
		)
		(layer "F.Cu")
	)
	(gr_line
		(start 160.38449 -23.930102)
		(end 160.38449 -24.503634)
		(stroke
			(width 0.068326)
			(type default)
		)
		(layer "F.Cu")
	)
	(gr_arc
		(start 160.38449 -20.130008)
		(mid 160.30273 -20.252371)
		(end 160.274 -20.396708)
		(stroke
			(width 0.068326)
			(type default)
		)
		(layer "F.Cu")
	)
	(gr_line
		(start 160.471612 -21.051012)
		(end 160.476184 -21.055584)
		(stroke
			(width 0.068326)
			(type default)
		)
		(layer "F.Cu")
	)
	(gr_line
		(start 160.725104 -21.674836)
		(end 160.740598 -21.682202)
		(stroke
			(width 0.068326)
			(type default)
		)
		(layer "F.Cu")
	)
	(gr_line
		(start 160.79216 -211.975954)
		(end 161.073846 -211.694268)
		(stroke
			(width 0.068326)
			(type default)
		)
		(layer "F.Cu")
	)
	(gr_line
		(start 160.89376 -210.896454)
		(end 161.047176 -211.050124)
		(stroke
			(width 0.068326)
			(type default)
		)
		(layer "F.Cu")
	)
	(gr_line
		(start 160.90011 -224.828608)
		(end 160.90011 -225.54438)
		(stroke
			(width 0.068326)
			(type default)
		)
		(layer "F.Cu")
	)
	(gr_line
		(start 160.90011 -224.828608)
		(end 160.900364 -224.828354)
		(stroke
			(width 0.068326)
			(type default)
		)
		(layer "F.Cu")
	)
	(gr_arc
		(start 161.031936 -93.34246)
		(mid 161.045676 -93.411467)
		(end 161.084768 -93.469968)
		(stroke
			(width 0.068326)
			(type default)
		)
		(layer "F.Cu")
	)
	(gr_line
		(start 161.031936 -93.063822)
		(end 161.031936 -93.34246)
		(stroke
			(width 0.068326)
			(type default)
		)
		(layer "F.Cu")
	)
	(gr_line
		(start 161.031936 -87.726266)
		(end 161.031936 -88.088978)
		(stroke
			(width 0.068326)
			(type default)
		)
		(layer "F.Cu")
	)
	(gr_arc
		(start 161.068512 -224.32264)
		(mid 160.943487 -224.561884)
		(end 160.900364 -224.828354)
		(stroke
			(width 0.068326)
			(type default)
		)
		(layer "F.Cu")
	)
	(gr_arc
		(start 161.068512 -224.32264)
		(mid 161.127146 -224.234888)
		(end 161.14776 -224.131378)
		(stroke
			(width 0.068326)
			(type default)
		)
		(layer "F.Cu")
	)
	(gr_arc
		(start 161.073846 -211.694268)
		(mid 161.123837 -211.619452)
		(end 161.14141 -211.5312)
		(stroke
			(width 0.068326)
			(type default)
		)
		(layer "F.Cu")
	)
	(gr_arc
		(start 161.075116 -87.622126)
		(mid 161.043168 -87.669901)
		(end 161.031936 -87.726266)
		(stroke
			(width 0.068326)
			(type default)
		)
		(layer "F.Cu")
	)
	(gr_arc
		(start 161.075116 -87.622126)
		(mid 161.106886 -87.574579)
		(end 161.118042 -87.518494)
		(stroke
			(width 0.068326)
			(type default)
		)
		(layer "F.Cu")
	)
	(gr_arc
		(start 161.1376 -93.597476)
		(mid 161.123872 -93.528463)
		(end 161.084768 -93.469968)
		(stroke
			(width 0.068326)
			(type default)
		)
		(layer "F.Cu")
	)
	(gr_arc
		(start 161.14141 -211.2772)
		(mid 161.116869 -211.154294)
		(end 161.047176 -211.050124)
		(stroke
			(width 0.068326)
			(type default)
		)
		(layer "F.Cu")
	)
	(gr_arc
		(start 161.14776 -213.723474)
		(mid 161.055341 -213.25885)
		(end 160.79216 -212.864954)
		(stroke
			(width 0.068326)
			(type default)
		)
		(layer "F.Cu")
	)
	(gr_arc
		(start 161.163 -33.0835)
		(mid 161.374919 -32.919845)
		(end 161.4551 -32.6644)
		(stroke
			(width 0.068326)
			(type default)
		)
		(layer "F.Cu")
	)
	(gr_arc
		(start 161.2773 -35.02152)
		(mid 161.439609 -34.840732)
		(end 161.49828 -34.60496)
		(stroke
			(width 0.068326)
			(type default)
		)
		(layer "F.Cu")
	)
	(gr_arc
		(start 161.422842 -87.511636)
		(mid 161.437793 -87.580909)
		(end 161.477452 -87.639652)
		(stroke
			(width 0.068326)
			(type default)
		)
		(layer "F.Cu")
	)
	(gr_arc
		(start 161.44621 -211.5312)
		(mid 161.461492 -211.607655)
		(end 161.504884 -211.672424)
		(stroke
			(width 0.068326)
			(type default)
		)
		(layer "F.Cu")
	)
	(gr_arc
		(start 161.452814 -224.133664)
		(mid 161.472985 -224.234826)
		(end 161.530284 -224.320608)
		(stroke
			(width 0.068326)
			(type default)
		)
		(layer "F.Cu")
	)
	(gr_arc
		(start 161.487358 -93.503496)
		(mid 161.454133 -93.553126)
		(end 161.4424 -93.6117)
		(stroke
			(width 0.068326)
			(type default)
		)
		(layer "F.Cu")
	)
	(gr_line
		(start 161.487358 -93.503496)
		(end 161.487612 -93.503242)
		(stroke
			(width 0.068326)
			(type default)
		)
		(layer "F.Cu")
	)
	(gr_arc
		(start 161.487612 -93.503242)
		(mid 161.520542 -93.453671)
		(end 161.532062 -93.395292)
		(stroke
			(width 0.068326)
			(type default)
		)
		(layer "F.Cu")
	)
	(gr_arc
		(start 161.49828 -34.43224)
		(mid 161.405537 -34.147755)
		(end 161.163 -33.9725)
		(stroke
			(width 0.068326)
			(type default)
		)
		(layer "F.Cu")
	)
	(gr_line
		(start 161.504884 -211.672424)
		(end 161.80816 -211.975954)
		(stroke
			(width 0.068326)
			(type default)
		)
		(layer "F.Cu")
	)
	(gr_arc
		(start 161.5313 -211.071714)
		(mid 161.468351 -211.166004)
		(end 161.44621 -211.2772)
		(stroke
			(width 0.068326)
			(type default)
		)
		(layer "F.Cu")
	)
	(gr_line
		(start 161.5313 -211.071714)
		(end 161.70656 -210.896454)
		(stroke
			(width 0.068326)
			(type default)
		)
		(layer "F.Cu")
	)
	(gr_line
		(start 161.532062 -93.063822)
		(end 161.532062 -93.395292)
		(stroke
			(width 0.068326)
			(type default)
		)
		(layer "F.Cu")
	)
	(gr_arc
		(start 161.532062 -87.771478)
		(mid 161.51787 -87.700132)
		(end 161.477452 -87.639652)
		(stroke
			(width 0.068326)
			(type default)
		)
		(layer "F.Cu")
	)
	(gr_line
		(start 161.532062 -87.771478)
		(end 161.532062 -88.088978)
		(stroke
			(width 0.068326)
			(type default)
		)
		(layer "F.Cu")
	)
	(gr_line
		(start 161.544 -85.6869)
		(end 161.753804 -85.89645)
		(stroke
			(width 0.068326)
			(type default)
		)
		(layer "F.Cu")
	)
	(gr_line
		(start 161.544 -84.7979)
		(end 161.711132 -84.631022)
		(stroke
			(width 0.068326)
			(type default)
		)
		(layer "F.Cu")
	)
	(gr_line
		(start 161.6202 -97.3836)
		(end 161.798 -97.5614)
		(stroke
			(width 0.068326)
			(type default)
		)
		(layer "F.Cu")
	)
	(gr_line
		(start 161.6202 -96.3549)
		(end 161.6202 -97.3836)
		(stroke
			(width 0.068326)
			(type default)
		)
		(layer "F.Cu")
	)
	(gr_line
		(start 161.6202 -95.4659)
		(end 161.86023 -95.22587)
		(stroke
			(width 0.068326)
			(type default)
		)
		(layer "F.Cu")
	)
	(gr_arc
		(start 161.70021 -224.828354)
		(mid 161.656573 -224.560646)
		(end 161.530284 -224.320608)
		(stroke
			(width 0.068326)
			(type default)
		)
		(layer "F.Cu")
	)
	(gr_line
		(start 161.70021 -224.828354)
		(end 161.70021 -225.54438)
		(stroke
			(width 0.068326)
			(type default)
		)
		(layer "F.Cu")
	)
	(gr_arc
		(start 161.711132 -84.631022)
		(mid 161.850665 -84.422058)
		(end 161.8996 -84.1756)
		(stroke
			(width 0.068326)
			(type default)
		)
		(layer "F.Cu")
	)
	(gr_arc
		(start 161.7599 -32.6644)
		(mid 161.840151 -32.919816)
		(end 162.052 -33.0835)
		(stroke
			(width 0.068326)
			(type default)
		)
		(layer "F.Cu")
	)
	(gr_arc
		(start 161.7853 -38.0111)
		(mid 161.99913 -37.719514)
		(end 162.07486 -37.36594)
		(stroke
			(width 0.068326)
			(type default)
		)
		(layer "F.Cu")
	)
	(gr_arc
		(start 161.80308 -34.60496)
		(mid 161.881784 -34.85789)
		(end 162.0901 -35.02152)
		(stroke
			(width 0.068326)
			(type default)
		)
		(layer "F.Cu")
	)
	(gr_arc
		(start 161.80816 -212.864954)
		(mid 161.545173 -213.258486)
		(end 161.452814 -213.722712)
		(stroke
			(width 0.068326)
			(type default)
		)
		(layer "F.Cu")
	)
	(gr_arc
		(start 161.86023 -95.22587)
		(mid 161.952815 -95.00226)
		(end 161.86023 -94.778576)
		(stroke
			(width 0.068326)
			(type default)
		)
		(layer "F.Cu")
	)
	(gr_arc
		(start 162.052 -33.9725)
		(mid 161.869265 -34.170826)
		(end 161.80308 -34.43224)
		(stroke
			(width 0.068326)
			(type default)
		)
		(layer "F.Cu")
	)
	(gr_arc
		(start 162.2044 -84.1756)
		(mid 162.253347 -84.422049)
		(end 162.392868 -84.631022)
		(stroke
			(width 0.068326)
			(type default)
		)
		(layer "F.Cu")
	)
	(gr_arc
		(start 162.267138 -85.979508)
		(mid 162.220543 -86.049055)
		(end 162.204146 -86.131146)
		(stroke
			(width 0.068326)
			(type default)
		)
		(layer "F.Cu")
	)
	(gr_line
		(start 162.267138 -85.979508)
		(end 162.56 -85.6869)
		(stroke
			(width 0.068326)
			(type default)
		)
		(layer "F.Cu")
	)
	(gr_line
		(start 162.392868 -84.631022)
		(end 162.56 -84.7979)
		(stroke
			(width 0.068326)
			(type default)
		)
		(layer "F.Cu")
	)
	(gr_line
		(start 162.687 -97.1804)
		(end 163.068 -97.5614)
		(stroke
			(width 0.068326)
			(type default)
		)
		(layer "F.Cu")
	)
	(gr_line
		(start 162.687 -96.3549)
		(end 162.687 -97.1804)
		(stroke
			(width 0.068326)
			(type default)
		)
		(layer "F.Cu")
	)
	(gr_arc
		(start 162.687 -95.4659)
		(mid 162.379195 -94.939737)
		(end 161.986468 -94.473522)
		(stroke
			(width 0.068326)
			(type default)
		)
		(layer "F.Cu")
	)
	(gr_line
		(start 162.6997 -81.661)
		(end 162.83178 -81.792826)
		(stroke
			(width 0.068326)
			(type default)
		)
		(layer "F.Cu")
	)
	(gr_arc
		(start 162.9664 -82.117946)
		(mid 162.931419 -81.941997)
		(end 162.83178 -81.792826)
		(stroke
			(width 0.068326)
			(type default)
		)
		(layer "F.Cu")
	)
	(gr_line
		(start 163.195 -33.9725)
		(end 163.36137 -34.13887)
		(stroke
			(width 0.068326)
			(type default)
		)
		(layer "F.Cu")
	)
	(gr_arc
		(start 163.195 -33.0835)
		(mid 163.406919 -32.919845)
		(end 163.4871 -32.6644)
		(stroke
			(width 0.068326)
			(type default)
		)
		(layer "F.Cu")
	)
	(gr_line
		(start 163.269422 -91.826334)
		(end 163.58616 -91.826334)
		(stroke
			(width 0.068326)
			(type default)
		)
		(layer "F.Cu")
	)
	(gr_line
		(start 163.269422 -91.326462)
		(end 163.563046 -91.326462)
		(stroke
			(width 0.068326)
			(type default)
		)
		(layer "F.Cu")
	)
	(gr_line
		(start 163.269422 -89.826338)
		(end 163.603432 -89.826338)
		(stroke
			(width 0.068326)
			(type default)
		)
		(layer "F.Cu")
	)
	(gr_line
		(start 163.269422 -89.326466)
		(end 163.596574 -89.326466)
		(stroke
			(width 0.068326)
			(type default)
		)
		(layer "F.Cu")
	)
	(gr_arc
		(start 163.423854 -81.749646)
		(mid 163.310888 -81.918745)
		(end 163.2712 -82.1182)
		(stroke
			(width 0.068326)
			(type default)
		)
		(layer "F.Cu")
	)
	(gr_line
		(start 163.423854 -81.749646)
		(end 163.5125 -81.661)
		(stroke
			(width 0.068326)
			(type default)
		)
		(layer "F.Cu")
	)
	(gr_arc
		(start 163.4871 -34.4424)
		(mid 163.454425 -34.278129)
		(end 163.36137 -34.13887)
		(stroke
			(width 0.068326)
			(type default)
		)
		(layer "F.Cu")
	)
	(gr_arc
		(start 163.58616 -91.826334)
		(mid 163.642245 -91.815178)
		(end 163.689792 -91.783408)
		(stroke
			(width 0.068326)
			(type default)
		)
		(layer "F.Cu")
	)
	(gr_arc
		(start 163.603432 -89.826338)
		(mid 163.660878 -89.814911)
		(end 163.709604 -89.782396)
		(stroke
			(width 0.068326)
			(type default)
		)
		(layer "F.Cu")
	)
	(gr_arc
		(start 163.694872 -91.381072)
		(mid 163.634386 -91.340677)
		(end 163.563046 -91.326462)
		(stroke
			(width 0.068326)
			(type default)
		)
		(layer "F.Cu")
	)
	(gr_arc
		(start 163.72586 -89.38006)
		(mid 163.66655 -89.340392)
		(end 163.596574 -89.326466)
		(stroke
			(width 0.068326)
			(type default)
		)
		(layer "F.Cu")
	)
	(gr_arc
		(start 163.72586 -89.38006)
		(mid 163.785075 -89.419563)
		(end 163.854892 -89.4334)
		(stroke
			(width 0.068326)
			(type default)
		)
		(layer "F.Cu")
	)
	(gr_arc
		(start 163.7919 -32.6644)
		(mid 163.872123 -32.919839)
		(end 164.084 -33.0835)
		(stroke
			(width 0.068326)
			(type default)
		)
		(layer "F.Cu")
	)
	(gr_arc
		(start 163.793424 -91.740482)
		(mid 163.737336 -91.751633)
		(end 163.689792 -91.783408)
		(stroke
			(width 0.068326)
			(type default)
		)
		(layer "F.Cu")
	)
	(gr_line
		(start 163.793424 -91.739466)
		(end 163.793424 -91.740482)
		(stroke
			(width 0.068326)
			(type default)
		)
		(layer "F.Cu")
	)
	(gr_arc
		(start 163.81603 -89.7382)
		(mid 163.758402 -89.749666)
		(end 163.709604 -89.782396)
		(stroke
			(width 0.068326)
			(type default)
		)
		(layer "F.Cu")
	)
	(gr_line
		(start 163.826698 -91.435682)
		(end 163.91509 -91.435682)
		(stroke
			(width 0.068326)
			(type default)
		)
		(layer "F.Cu")
	)
	(gr_arc
		(start 163.91763 -34.13887)
		(mid 163.824566 -34.278127)
		(end 163.7919 -34.4424)
		(stroke
			(width 0.068326)
			(type default)
		)
		(layer "F.Cu")
	)
	(gr_line
		(start 163.91763 -34.13887)
		(end 164.084 -33.9725)
		(stroke
			(width 0.068326)
			(type default)
		)
		(layer "F.Cu")
	)
	(gr_line
		(start 164.196268 -91.857068)
		(end 164.196522 -91.857068)
		(stroke
			(width 0.068326)
			(type default)
		)
		(layer "F.Cu")
	)
	(gr_line
		(start 164.338 -36.322)
		(end 166.243 -36.322)
		(stroke
			(width 0.060198)
			(type default)
		)
		(layer "F.Cu")
	)
	(gr_arc
		(start 165.083744 -92.456)
		(mid 165.180931 -92.43665)
		(end 165.263322 -92.381578)
		(stroke
			(width 0.068326)
			(type default)
		)
		(layer "F.Cu")
	)
	(gr_arc
		(start 165.1254 -88.9)
		(mid 165.301486 -88.865068)
		(end 165.450774 -88.76538)
		(stroke
			(width 0.068326)
			(type default)
		)
		(layer "F.Cu")
	)
	(gr_line
		(start 165.263322 -92.381578)
		(end 165.6715 -91.9734)
		(stroke
			(width 0.068326)
			(type default)
		)
		(layer "F.Cu")
	)
	(gr_arc
		(start 165.269672 -92.841572)
		(mid 165.180163 -92.781803)
		(end 165.0746 -92.7608)
		(stroke
			(width 0.068326)
			(type default)
		)
		(layer "F.Cu")
	)
	(gr_line
		(start 165.269672 -92.841572)
		(end 165.6715 -93.2434)
		(stroke
			(width 0.068326)
			(type default)
		)
		(layer "F.Cu")
	)
	(gr_arc
		(start 165.42385 -89.31275)
		(mid 165.304284 -89.232865)
		(end 165.163246 -89.2048)
		(stroke
			(width 0.068326)
			(type default)
		)
		(layer "F.Cu")
	)
	(gr_line
		(start 165.42385 -89.31275)
		(end 165.6715 -89.5604)
		(stroke
			(width 0.068326)
			(type default)
		)
		(layer "F.Cu")
	)
	(gr_line
		(start 165.450774 -88.76538)
		(end 165.6715 -88.5444)
		(stroke
			(width 0.068326)
			(type default)
		)
		(layer "F.Cu")
	)
	(gr_line
		(start 166.134542 -25.33015)
		(end 166.244016 -25.22093)
		(stroke
			(width 0.068326)
			(type default)
		)
		(layer "F.Cu")
	)
	(gr_line
		(start 166.134542 -13.930122)
		(end 166.182294 -13.882116)
		(stroke
			(width 0.068326)
			(type default)
		)
		(layer "F.Cu")
	)
	(gr_line
		(start 166.392098 -211.975954)
		(end 166.673784 -211.694268)
		(stroke
			(width 0.068326)
			(type default)
		)
		(layer "F.Cu")
	)
	(gr_line
		(start 166.493698 -210.896454)
		(end 166.638224 -211.04098)
		(stroke
			(width 0.068326)
			(type default)
		)
		(layer "F.Cu")
	)
	(gr_line
		(start 166.500048 -224.828608)
		(end 166.500048 -225.54438)
		(stroke
			(width 0.068326)
			(type default)
		)
		(layer "F.Cu")
	)
	(gr_line
		(start 166.500048 -224.828608)
		(end 166.500302 -224.828354)
		(stroke
			(width 0.068326)
			(type default)
		)
		(layer "F.Cu")
	)
	(gr_arc
		(start 166.5224 -13.7414)
		(mid 166.338344 -13.777917)
		(end 166.182294 -13.882116)
		(stroke
			(width 0.068326)
			(type default)
		)
		(layer "F.Cu")
	)
	(gr_line
		(start 166.5224 -13.7414)
		(end 166.7002 -13.7414)
		(stroke
			(width 0.068326)
			(type default)
		)
		(layer "F.Cu")
	)
	(gr_arc
		(start 166.5478 -25.094946)
		(mid 166.383389 -25.127743)
		(end 166.244016 -25.22093)
		(stroke
			(width 0.068326)
			(type default)
		)
		(layer "F.Cu")
	)
	(gr_line
		(start 166.5478 -25.094946)
		(end 166.624 -25.094946)
		(stroke
			(width 0.068326)
			(type default)
		)
		(layer "F.Cu")
	)
	(gr_line
		(start 166.5605 -93.2434)
		(end 166.59098 -93.27388)
		(stroke
			(width 0.068326)
			(type default)
		)
		(layer "F.Cu")
	)
	(gr_line
		(start 166.5605 -91.9734)
		(end 167.7162 -91.9734)
		(stroke
			(width 0.068326)
			(type default)
		)
		(layer "F.Cu")
	)
	(gr_line
		(start 166.5605 -89.5604)
		(end 166.851076 -89.269824)
		(stroke
			(width 0.068326)
			(type default)
		)
		(layer "F.Cu")
	)
	(gr_line
		(start 166.5605 -88.5444)
		(end 166.851076 -88.834976)
		(stroke
			(width 0.068326)
			(type default)
		)
		(layer "F.Cu")
	)
	(gr_line
		(start 166.59098 -93.27388)
		(end 167.73652 -93.27388)
		(stroke
			(width 0.068326)
			(type default)
		)
		(layer "F.Cu")
	)
	(gr_arc
		(start 166.66845 -224.32264)
		(mid 166.543434 -224.561886)
		(end 166.500302 -224.828354)
		(stroke
			(width 0.068326)
			(type default)
		)
		(layer "F.Cu")
	)
	(gr_arc
		(start 166.66845 -224.32264)
		(mid 166.727084 -224.234888)
		(end 166.747698 -224.131378)
		(stroke
			(width 0.068326)
			(type default)
		)
		(layer "F.Cu")
	)
	(gr_arc
		(start 166.673784 -211.694268)
		(mid 166.723775 -211.619452)
		(end 166.741348 -211.5312)
		(stroke
			(width 0.068326)
			(type default)
		)
		(layer "F.Cu")
	)
	(gr_arc
		(start 166.741348 -211.2899)
		(mid 166.71455 -211.155179)
		(end 166.638224 -211.04098)
		(stroke
			(width 0.068326)
			(type default)
		)
		(layer "F.Cu")
	)
	(gr_arc
		(start 166.747698 -213.723474)
		(mid 166.655279 -213.25885)
		(end 166.392098 -212.864954)
		(stroke
			(width 0.068326)
			(type default)
		)
		(layer "F.Cu")
	)
	(gr_arc
		(start 166.841424 -25.184862)
		(mid 166.741654 -25.118291)
		(end 166.624 -25.094946)
		(stroke
			(width 0.068326)
			(type default)
		)
		(layer "F.Cu")
	)
	(gr_line
		(start 166.841424 -25.184862)
		(end 166.939722 -25.283414)
		(stroke
			(width 0.068326)
			(type default)
		)
		(layer "F.Cu")
	)
	(gr_arc
		(start 166.88435 -24.356822)
		(mid 166.961529 -24.754245)
		(end 167.181784 -25.09393)
		(stroke
			(width 0.068326)
			(type default)
		)
		(layer "F.Cu")
	)
	(gr_line
		(start 166.88435 -23.930102)
		(end 166.88435 -24.356822)
		(stroke
			(width 0.068326)
			(type default)
		)
		(layer "F.Cu")
	)
	(gr_arc
		(start 166.88435 -12.981432)
		(mid 166.955232 -13.337881)
		(end 167.157146 -13.640054)
		(stroke
			(width 0.068326)
			(type default)
		)
		(layer "F.Cu")
	)
	(gr_line
		(start 166.88435 -12.530074)
		(end 166.88435 -12.981432)
		(stroke
			(width 0.068326)
			(type default)
		)
		(layer "F.Cu")
	)
	(gr_arc
		(start 166.916862 -13.831316)
		(mid 166.817472 -13.764813)
		(end 166.7002 -13.7414)
		(stroke
			(width 0.068326)
			(type default)
		)
		(layer "F.Cu")
	)
	(gr_arc
		(start 167.046148 -211.5312)
		(mid 167.061432 -211.607653)
		(end 167.104822 -211.672424)
		(stroke
			(width 0.068326)
			(type default)
		)
		(layer "F.Cu")
	)
	(gr_arc
		(start 167.052752 -224.133664)
		(mid 167.072919 -224.234829)
		(end 167.130222 -224.320608)
		(stroke
			(width 0.068326)
			(type default)
		)
		(layer "F.Cu")
	)
	(gr_line
		(start 167.104822 -211.672424)
		(end 167.408098 -211.975954)
		(stroke
			(width 0.068326)
			(type default)
		)
		(layer "F.Cu")
	)
	(gr_arc
		(start 167.140382 -211.062824)
		(mid 167.07068 -211.166992)
		(end 167.046148 -211.2899)
		(stroke
			(width 0.068326)
			(type default)
		)
		(layer "F.Cu")
	)
	(gr_line
		(start 167.140382 -211.062824)
		(end 167.306498 -210.896454)
		(stroke
			(width 0.068326)
			(type default)
		)
		(layer "F.Cu")
	)
	(gr_arc
		(start 167.300148 -224.828354)
		(mid 167.256511 -224.560646)
		(end 167.130222 -224.320608)
		(stroke
			(width 0.068326)
			(type default)
		)
		(layer "F.Cu")
	)
	(gr_line
		(start 167.300148 -224.828354)
		(end 167.300148 -225.54438)
		(stroke
			(width 0.068326)
			(type default)
		)
		(layer "F.Cu")
	)
	(gr_arc
		(start 167.408098 -212.864954)
		(mid 167.145102 -213.258483)
		(end 167.052752 -213.722712)
		(stroke
			(width 0.068326)
			(type default)
		)
		(layer "F.Cu")
	)
	(gr_line
		(start 167.505126 -26.010108)
		(end 167.515794 -26.025602)
		(stroke
			(width 0.068326)
			(type default)
		)
		(layer "F.Cu")
	)
	(gr_line
		(start 167.513 -89.269824)
		(end 167.701976 -89.4588)
		(stroke
			(width 0.068326)
			(type default)
		)
		(layer "F.Cu")
	)
	(gr_line
		(start 167.513 -88.834976)
		(end 167.701976 -88.646)
		(stroke
			(width 0.068326)
			(type default)
		)
		(layer "F.Cu")
	)
	(gr_line
		(start 167.515794 -26.025602)
		(end 167.531288 -26.036524)
		(stroke
			(width 0.068326)
			(type default)
		)
		(layer "F.Cu")
	)
	(gr_line
		(start 167.64635 -29.85135)
		(end 167.656002 -29.865066)
		(stroke
			(width 0.068326)
			(type default)
		)
		(layer "F.Cu")
	)
	(gr_line
		(start 167.656002 -29.865066)
		(end 167.669718 -29.874718)
		(stroke
			(width 0.068326)
			(type default)
		)
		(layer "F.Cu")
	)
	(gr_line
		(start 167.7162 -91.9734)
		(end 167.767 -92.0242)
		(stroke
			(width 0.068326)
			(type default)
		)
		(layer "F.Cu")
	)
	(gr_line
		(start 167.73652 -93.27388)
		(end 167.767 -93.2434)
		(stroke
			(width 0.068326)
			(type default)
		)
		(layer "F.Cu")
	)
	(gr_line
		(start 168.384474 -25.33015)
		(end 168.540684 -25.17394)
		(stroke
			(width 0.068326)
			(type default)
		)
		(layer "F.Cu")
	)
	(gr_line
		(start 168.384474 -21.530056)
		(end 168.49725 -21.41728)
		(stroke
			(width 0.068326)
			(type default)
		)
		(layer "F.Cu")
	)
	(gr_arc
		(start 168.783 -21.298916)
		(mid 168.628354 -21.329679)
		(end 168.49725 -21.41728)
		(stroke
			(width 0.068326)
			(type default)
		)
		(layer "F.Cu")
	)
	(gr_line
		(start 168.783 -21.298916)
		(end 168.91 -21.298916)
		(stroke
			(width 0.068326)
			(type default)
		)
		(layer "F.Cu")
	)
	(gr_arc
		(start 168.823386 -25.056846)
		(mid 168.670396 -25.087286)
		(end 168.540684 -25.17394)
		(stroke
			(width 0.068326)
			(type default)
		)
		(layer "F.Cu")
	)
	(gr_arc
		(start 169.038524 -25.167336)
		(mid 168.939597 -25.095265)
		(end 168.823386 -25.056846)
		(stroke
			(width 0.068326)
			(type default)
		)
		(layer "F.Cu")
	)
	(gr_arc
		(start 169.102786 -21.378926)
		(mid 169.014342 -21.319767)
		(end 168.91 -21.298916)
		(stroke
			(width 0.068326)
			(type default)
		)
		(layer "F.Cu")
	)
	(gr_line
		(start 169.102786 -21.378926)
		(end 169.11193 -21.387816)
		(stroke
			(width 0.068326)
			(type default)
		)
		(layer "F.Cu")
	)
	(gr_arc
		(start 169.134536 -24.151336)
		(mid 169.163047 -24.509787)
		(end 169.24782 -24.859234)
		(stroke
			(width 0.068326)
			(type default)
		)
		(layer "F.Cu")
	)
	(gr_line
		(start 169.134536 -23.930102)
		(end 169.134536 -24.151336)
		(stroke
			(width 0.068326)
			(type default)
		)
		(layer "F.Cu")
	)
	(gr_arc
		(start 169.134536 -20.598384)
		(mid 169.163474 -20.827471)
		(end 169.248582 -21.042122)
		(stroke
			(width 0.068326)
			(type default)
		)
		(layer "F.Cu")
	)
	(gr_line
		(start 169.134536 -20.130008)
		(end 169.134536 -20.598384)
		(stroke
			(width 0.068326)
			(type default)
		)
		(layer "F.Cu")
	)
	(gr_arc
		(start 169.24782 -24.859234)
		(mid 169.254948 -24.881115)
		(end 169.262298 -24.902922)
		(stroke
			(width 0.068326)
			(type default)
		)
		(layer "F.Cu")
	)
	(gr_arc
		(start 169.248582 -21.042122)
		(mid 169.258916 -21.060403)
		(end 169.269664 -21.078444)
		(stroke
			(width 0.068326)
			(type default)
		)
		(layer "F.Cu")
	)
	(gr_arc
		(start 169.269664 -21.078444)
		(mid 169.331701 -21.167368)
		(end 169.403776 -21.24837)
		(stroke
			(width 0.068326)
			(type default)
		)
		(layer "F.Cu")
	)
	(gr_line
		(start 169.59199 -211.975954)
		(end 169.873676 -211.694268)
		(stroke
			(width 0.068326)
			(type default)
		)
		(layer "F.Cu")
	)
	(gr_line
		(start 169.69359 -210.896454)
		(end 169.839132 -211.041742)
		(stroke
			(width 0.068326)
			(type default)
		)
		(layer "F.Cu")
	)
	(gr_line
		(start 169.700194 -224.828354)
		(end 169.700194 -225.54438)
		(stroke
			(width 0.068326)
			(type default)
		)
		(layer "F.Cu")
	)
	(gr_line
		(start 169.72788 -21.572474)
		(end 169.73677 -21.595334)
		(stroke
			(width 0.068326)
			(type default)
		)
		(layer "F.Cu")
	)
	(gr_line
		(start 169.742104 -22.43836)
		(end 169.7482 -22.4536)
		(stroke
			(width 0.068326)
			(type default)
		)
		(layer "F.Cu")
	)
	(gr_line
		(start 169.7482 -22.4536)
		(end 169.759122 -22.466046)
		(stroke
			(width 0.068326)
			(type default)
		)
		(layer "F.Cu")
	)
	(gr_arc
		(start 169.868342 -224.32264)
		(mid 169.743327 -224.561886)
		(end 169.700194 -224.828354)
		(stroke
			(width 0.068326)
			(type default)
		)
		(layer "F.Cu")
	)
	(gr_arc
		(start 169.868342 -224.32264)
		(mid 169.926976 -224.234888)
		(end 169.94759 -224.131378)
		(stroke
			(width 0.068326)
			(type default)
		)
		(layer "F.Cu")
	)
	(gr_arc
		(start 169.873676 -211.694268)
		(mid 169.923667 -211.619452)
		(end 169.94124 -211.5312)
		(stroke
			(width 0.068326)
			(type default)
		)
		(layer "F.Cu")
	)
	(gr_arc
		(start 169.94759 -213.723474)
		(mid 169.855171 -213.25885)
		(end 169.59199 -212.864954)
		(stroke
			(width 0.068326)
			(type default)
		)
		(layer "F.Cu")
	)
	(gr_line
		(start 170.10634 -22.859492)
		(end 170.1292 -22.8854)
		(stroke
			(width 0.068326)
			(type default)
		)
		(layer "F.Cu")
	)
	(gr_line
		(start 170.1292 -22.8854)
		(end 170.161204 -22.8981)
		(stroke
			(width 0.068326)
			(type default)
		)
		(layer "F.Cu")
	)
	(gr_arc
		(start 170.24604 -211.5312)
		(mid 170.261324 -211.607653)
		(end 170.304714 -211.672424)
		(stroke
			(width 0.068326)
			(type default)
		)
		(layer "F.Cu")
	)
	(gr_arc
		(start 170.252644 -224.133664)
		(mid 170.272811 -224.23483)
		(end 170.330114 -224.320608)
		(stroke
			(width 0.068326)
			(type default)
		)
		(layer "F.Cu")
	)
	(gr_line
		(start 170.304714 -211.672424)
		(end 170.60799 -211.975954)
		(stroke
			(width 0.068326)
			(type default)
		)
		(layer "F.Cu")
	)
	(gr_arc
		(start 170.336464 -211.066126)
		(mid 170.269492 -211.166474)
		(end 170.24604 -211.28482)
		(stroke
			(width 0.068326)
			(type default)
		)
		(layer "F.Cu")
	)
	(gr_line
		(start 170.336464 -211.066126)
		(end 170.50639 -210.896454)
		(stroke
			(width 0.068326)
			(type default)
		)
		(layer "F.Cu")
	)
	(gr_arc
		(start 170.50004 -224.828354)
		(mid 170.456403 -224.560646)
		(end 170.330114 -224.320608)
		(stroke
			(width 0.068326)
			(type default)
		)
		(layer "F.Cu")
	)
	(gr_line
		(start 170.50004 -224.828354)
		(end 170.50004 -225.54438)
		(stroke
			(width 0.068326)
			(type default)
		)
		(layer "F.Cu")
	)
	(gr_arc
		(start 170.60799 -212.864954)
		(mid 170.344996 -213.258484)
		(end 170.252644 -213.722712)
		(stroke
			(width 0.068326)
			(type default)
		)
		(layer "F.Cu")
	)
	(gr_line
		(start 170.634406 -21.530056)
		(end 170.691048 -21.472906)
		(stroke
			(width 0.068326)
			(type default)
		)
		(layer "F.Cu")
	)
	(gr_line
		(start 170.727116 -23.124668)
		(end 170.7642 -23.1394)
		(stroke
			(width 0.068326)
			(type default)
		)
		(layer "F.Cu")
	)
	(gr_line
		(start 170.7642 -23.1394)
		(end 170.803824 -23.134574)
		(stroke
			(width 0.068326)
			(type default)
		)
		(layer "F.Cu")
	)
	(gr_arc
		(start 170.787314 -21.393404)
		(mid 170.737221 -21.430782)
		(end 170.691048 -21.472906)
		(stroke
			(width 0.068326)
			(type default)
		)
		(layer "F.Cu")
	)
	(gr_line
		(start 170.787314 -21.393404)
		(end 170.923966 -21.301456)
		(stroke
			(width 0.068326)
			(type default)
		)
		(layer "F.Cu")
	)
	(gr_arc
		(start 171.078906 -25.146)
		(mid 170.838332 -25.193853)
		(end 170.634406 -25.33015)
		(stroke
			(width 0.068326)
			(type default)
		)
		(layer "F.Cu")
	)
	(gr_line
		(start 171.078906 -25.146)
		(end 171.109132 -25.146)
		(stroke
			(width 0.068326)
			(type default)
		)
		(layer "F.Cu")
	)
	(gr_arc
		(start 171.138342 -21.301456)
		(mid 171.031154 -21.28012)
		(end 170.923966 -21.301456)
		(stroke
			(width 0.068326)
			(type default)
		)
		(layer "F.Cu")
	)
	(gr_line
		(start 171.138342 -21.301456)
		(end 171.342812 -21.386292)
		(stroke
			(width 0.068326)
			(type default)
		)
		(layer "F.Cu")
	)
	(gr_arc
		(start 171.37126 -21.401278)
		(mid 171.357403 -21.393089)
		(end 171.342812 -21.386292)
		(stroke
			(width 0.068326)
			(type default)
		)
		(layer "F.Cu")
	)
	(gr_arc
		(start 171.384468 -24.242268)
		(mid 171.478323 -24.714192)
		(end 171.745656 -25.11425)
		(stroke
			(width 0.068326)
			(type default)
		)
		(layer "F.Cu")
	)
	(gr_line
		(start 171.384468 -23.930102)
		(end 171.384468 -24.242268)
		(stroke
			(width 0.068326)
			(type default)
		)
		(layer "F.Cu")
	)
	(gr_arc
		(start 171.384468 -20.554188)
		(mid 171.420903 -20.825319)
		(end 171.527724 -21.077174)
		(stroke
			(width 0.068326)
			(type default)
		)
		(layer "F.Cu")
	)
	(gr_line
		(start 171.384468 -20.130008)
		(end 171.384468 -20.554188)
		(stroke
			(width 0.068326)
			(type default)
		)
		(layer "F.Cu")
	)
	(gr_arc
		(start 171.396152 -21.421852)
		(mid 171.384192 -21.410977)
		(end 171.37126 -21.401278)
		(stroke
			(width 0.068326)
			(type default)
		)
		(layer "F.Cu")
	)
	(gr_line
		(start 171.396152 -21.421852)
		(end 171.51985 -21.54555)
		(stroke
			(width 0.068326)
			(type default)
		)
		(layer "F.Cu")
	)
	(gr_arc
		(start 171.512484 -25.312878)
		(mid 171.327396 -25.189333)
		(end 171.109132 -25.146)
		(stroke
			(width 0.068326)
			(type default)
		)
		(layer "F.Cu")
	)
	(gr_arc
		(start 171.527724 -21.077174)
		(mid 171.599879 -21.183062)
		(end 171.684696 -21.279104)
		(stroke
			(width 0.068326)
			(type default)
		)
		(layer "F.Cu")
	)
	(gr_line
		(start 171.64685 -21.634958)
		(end 171.710858 -21.665438)
		(stroke
			(width 0.068326)
			(type default)
		)
		(layer "F.Cu")
	)
	(gr_line
		(start 172.792136 -211.975954)
		(end 173.073822 -211.694268)
		(stroke
			(width 0.068326)
			(type default)
		)
		(layer "F.Cu")
	)
	(gr_line
		(start 172.893736 -210.896454)
		(end 173.039786 -211.042504)
		(stroke
			(width 0.068326)
			(type default)
		)
		(layer "F.Cu")
	)
	(gr_line
		(start 172.900086 -224.828608)
		(end 172.900086 -225.54438)
		(stroke
			(width 0.068326)
			(type default)
		)
		(layer "F.Cu")
	)
	(gr_line
		(start 172.900086 -224.828608)
		(end 172.90034 -224.828354)
		(stroke
			(width 0.068326)
			(type default)
		)
		(layer "F.Cu")
	)
	(gr_arc
		(start 173.068488 -224.32264)
		(mid 172.943466 -224.561884)
		(end 172.90034 -224.828354)
		(stroke
			(width 0.068326)
			(type default)
		)
		(layer "F.Cu")
	)
	(gr_arc
		(start 173.068488 -224.32264)
		(mid 173.127122 -224.234888)
		(end 173.147736 -224.131378)
		(stroke
			(width 0.068326)
			(type default)
		)
		(layer "F.Cu")
	)
	(gr_arc
		(start 173.073822 -211.694268)
		(mid 173.123813 -211.619452)
		(end 173.141386 -211.5312)
		(stroke
			(width 0.068326)
			(type default)
		)
		(layer "F.Cu")
	)
	(gr_arc
		(start 173.141386 -211.287868)
		(mid 173.114975 -211.155091)
		(end 173.039786 -211.042504)
		(stroke
			(width 0.068326)
			(type default)
		)
		(layer "F.Cu")
	)
	(gr_arc
		(start 173.147736 -213.723474)
		(mid 173.055317 -213.25885)
		(end 172.792136 -212.864954)
		(stroke
			(width 0.068326)
			(type default)
		)
		(layer "F.Cu")
	)
	(gr_arc
		(start 173.446186 -211.5312)
		(mid 173.461467 -211.607656)
		(end 173.50486 -211.672424)
		(stroke
			(width 0.068326)
			(type default)
		)
		(layer "F.Cu")
	)
	(gr_arc
		(start 173.45279 -224.133664)
		(mid 173.472959 -224.234827)
		(end 173.53026 -224.320608)
		(stroke
			(width 0.068326)
			(type default)
		)
		(layer "F.Cu")
	)
	(gr_line
		(start 173.50486 -211.672424)
		(end 173.808136 -211.975954)
		(stroke
			(width 0.068326)
			(type default)
		)
		(layer "F.Cu")
	)
	(gr_arc
		(start 173.538896 -211.064094)
		(mid 173.470281 -211.166757)
		(end 173.446186 -211.287868)
		(stroke
			(width 0.068326)
			(type default)
		)
		(layer "F.Cu")
	)
	(gr_line
		(start 173.538896 -211.064094)
		(end 173.706536 -210.896454)
		(stroke
			(width 0.068326)
			(type default)
		)
		(layer "F.Cu")
	)
	(gr_arc
		(start 173.700186 -224.828354)
		(mid 173.656549 -224.560646)
		(end 173.53026 -224.320608)
		(stroke
			(width 0.068326)
			(type default)
		)
		(layer "F.Cu")
	)
	(gr_line
		(start 173.700186 -224.828354)
		(end 173.700186 -225.54438)
		(stroke
			(width 0.068326)
			(type default)
		)
		(layer "F.Cu")
	)
	(gr_arc
		(start 173.808136 -212.864954)
		(mid 173.545154 -213.258487)
		(end 173.45279 -213.722712)
		(stroke
			(width 0.068326)
			(type default)
		)
		(layer "F.Cu")
	)
	(gr_line
		(start 175.992028 -211.975954)
		(end 176.273714 -211.694268)
		(stroke
			(width 0.068326)
			(type default)
		)
		(layer "F.Cu")
	)
	(gr_line
		(start 176.093628 -210.896454)
		(end 176.24044 -211.043012)
		(stroke
			(width 0.068326)
			(type default)
		)
		(layer "F.Cu")
	)
	(gr_line
		(start 176.100232 -224.828354)
		(end 176.100232 -225.54438)
		(stroke
			(width 0.068326)
			(type default)
		)
		(layer "F.Cu")
	)
	(gr_arc
		(start 176.26838 -224.32264)
		(mid 176.14336 -224.561885)
		(end 176.100232 -224.828354)
		(stroke
			(width 0.068326)
			(type default)
		)
		(layer "F.Cu")
	)
	(gr_arc
		(start 176.26838 -224.32264)
		(mid 176.327014 -224.234888)
		(end 176.347628 -224.131378)
		(stroke
			(width 0.068326)
			(type default)
		)
		(layer "F.Cu")
	)
	(gr_arc
		(start 176.273714 -211.694268)
		(mid 176.323705 -211.619452)
		(end 176.341278 -211.5312)
		(stroke
			(width 0.068326)
			(type default)
		)
		(layer "F.Cu")
	)
	(gr_arc
		(start 176.341278 -211.286852)
		(mid 176.315124 -211.154896)
		(end 176.24044 -211.043012)
		(stroke
			(width 0.068326)
			(type default)
		)
		(layer "F.Cu")
	)
	(gr_arc
		(start 176.347628 -213.723474)
		(mid 176.255209 -213.25885)
		(end 175.992028 -212.864954)
		(stroke
			(width 0.068326)
			(type default)
		)
		(layer "F.Cu")
	)
	(gr_arc
		(start 176.646078 -211.5312)
		(mid 176.661358 -211.607657)
		(end 176.704752 -211.672424)
		(stroke
			(width 0.068326)
			(type default)
		)
		(layer "F.Cu")
	)
	(gr_arc
		(start 176.652682 -224.133664)
		(mid 176.672851 -224.234828)
		(end 176.730152 -224.320608)
		(stroke
			(width 0.068326)
			(type default)
		)
		(layer "F.Cu")
	)
	(gr_line
		(start 176.704752 -211.672424)
		(end 177.008028 -211.975954)
		(stroke
			(width 0.068326)
			(type default)
		)
		(layer "F.Cu")
	)
	(gr_arc
		(start 176.73828 -211.064856)
		(mid 176.670107 -211.166823)
		(end 176.646078 -211.287106)
		(stroke
			(width 0.068326)
			(type default)
		)
		(layer "F.Cu")
	)
	(gr_line
		(start 176.73828 -211.064856)
		(end 176.906428 -210.896454)
		(stroke
			(width 0.068326)
			(type default)
		)
		(layer "F.Cu")
	)
	(gr_arc
		(start 176.900078 -224.828354)
		(mid 176.856441 -224.560646)
		(end 176.730152 -224.320608)
		(stroke
			(width 0.068326)
			(type default)
		)
		(layer "F.Cu")
	)
	(gr_line
		(start 176.900078 -224.828354)
		(end 176.900078 -225.54438)
		(stroke
			(width 0.068326)
			(type default)
		)
		(layer "F.Cu")
	)
	(gr_arc
		(start 177.008028 -212.864954)
		(mid 176.745026 -213.258482)
		(end 176.652682 -213.722712)
		(stroke
			(width 0.068326)
			(type default)
		)
		(layer "F.Cu")
	)
	(gr_line
		(start 177.163476 -47.309024)
		(end 177.357786 -47.114714)
		(stroke
			(width 0.060198)
			(type default)
		)
		(layer "F.Cu")
	)
	(gr_line
		(start 177.163476 -46.207426)
		(end 177.357786 -46.401736)
		(stroke
			(width 0.060198)
			(type default)
		)
		(layer "F.Cu")
	)
	(gr_arc
		(start 180.460396 -21.8821)
		(mid 180.842009 -21.806192)
		(end 181.1655 -21.59)
		(stroke
			(width 0.068326)
			(type default)
		)
		(layer "F.Cu")
	)
	(gr_arc
		(start 180.460396 -20.1041)
		(mid 180.842009 -20.028192)
		(end 181.1655 -19.812)
		(stroke
			(width 0.068326)
			(type default)
		)
		(layer "F.Cu")
	)
	(gr_arc
		(start 180.6194 -26.2001)
		(mid 180.929042 -26.122464)
		(end 181.1655 -25.908)
		(stroke
			(width 0.068326)
			(type default)
		)
		(layer "F.Cu")
	)
	(gr_arc
		(start 180.6448 -23.880572)
		(mid 180.935475 -23.812364)
		(end 181.1655 -23.622)
		(stroke
			(width 0.068326)
			(type default)
		)
		(layer "F.Cu")
	)
	(gr_arc
		(start 180.721 -29.2481)
		(mid 180.986963 -29.16855)
		(end 181.1655 -28.956)
		(stroke
			(width 0.068326)
			(type default)
		)
		(layer "F.Cu")
	)
	(gr_line
		(start 180.894736 -13.889736)
		(end 181.19344 -14.18844)
		(stroke
			(width 0.068326)
			(type default)
		)
		(layer "F.Cu")
	)
	(gr_line
		(start 180.894736 -13.454888)
		(end 181.19344 -13.156184)
		(stroke
			(width 0.068326)
			(type default)
		)
		(layer "F.Cu")
	)
	(gr_arc
		(start 181.1655 -29.845)
		(mid 180.986923 -29.632511)
		(end 180.721 -29.5529)
		(stroke
			(width 0.068326)
			(type default)
		)
		(layer "F.Cu")
	)
	(gr_arc
		(start 181.1655 -26.797)
		(mid 180.92906 -26.582502)
		(end 180.6194 -26.5049)
		(stroke
			(width 0.068326)
			(type default)
		)
		(layer "F.Cu")
	)
	(gr_arc
		(start 181.1655 -24.511)
		(mid 180.951869 -24.273478)
		(end 180.6448 -24.185372)
		(stroke
			(width 0.068326)
			(type default)
		)
		(layer "F.Cu")
	)
	(gr_arc
		(start 181.1655 -22.479)
		(mid 180.842124 -22.262848)
		(end 180.46065 -22.1869)
		(stroke
			(width 0.068326)
			(type default)
		)
		(layer "F.Cu")
	)
	(gr_arc
		(start 181.1655 -20.701)
		(mid 180.842007 -20.484799)
		(end 180.460396 -20.4089)
		(stroke
			(width 0.068326)
			(type default)
		)
		(layer "F.Cu")
	)
	(gr_line
		(start 182.0545 -29.845)
		(end 182.256938 -29.642816)
		(stroke
			(width 0.068326)
			(type default)
		)
		(layer "F.Cu")
	)
	(gr_line
		(start 182.0545 -28.956)
		(end 182.23865 -29.140404)
		(stroke
			(width 0.068326)
			(type default)
		)
		(layer "F.Cu")
	)
	(gr_line
		(start 182.0545 -26.797)
		(end 182.256938 -26.594816)
		(stroke
			(width 0.068326)
			(type default)
		)
		(layer "F.Cu")
	)
	(gr_line
		(start 182.0545 -25.908)
		(end 182.23865 -26.092404)
		(stroke
			(width 0.068326)
			(type default)
		)
		(layer "F.Cu")
	)
	(gr_line
		(start 182.0545 -24.511)
		(end 182.127652 -24.438102)
		(stroke
			(width 0.068326)
			(type default)
		)
		(layer "F.Cu")
	)
	(gr_line
		(start 182.0545 -23.622)
		(end 182.23865 -23.806404)
		(stroke
			(width 0.068326)
			(type default)
		)
		(layer "F.Cu")
	)
	(gr_arc
		(start 182.0545 -21.59)
		(mid 182.358151 -21.815053)
		(end 182.7276 -21.8948)
		(stroke
			(width 0.068326)
			(type default)
		)
		(layer "F.Cu")
	)
	(gr_line
		(start 182.0545 -20.701)
		(end 182.23992 -20.515834)
		(stroke
			(width 0.068326)
			(type default)
		)
		(layer "F.Cu")
	)
	(gr_line
		(start 182.0545 -19.812)
		(end 182.285132 -20.042632)
		(stroke
			(width 0.068326)
			(type default)
		)
		(layer "F.Cu")
	)
	(gr_arc
		(start 182.23865 -29.140404)
		(mid 182.358115 -29.220135)
		(end 182.499 -29.2481)
		(stroke
			(width 0.068326)
			(type default)
		)
		(layer "F.Cu")
	)
	(gr_arc
		(start 182.23865 -26.092404)
		(mid 182.358115 -26.172135)
		(end 182.499 -26.2001)
		(stroke
			(width 0.068326)
			(type default)
		)
		(layer "F.Cu")
	)
	(gr_arc
		(start 182.23865 -23.806404)
		(mid 182.358115 -23.886135)
		(end 182.499 -23.9141)
		(stroke
			(width 0.068326)
			(type default)
		)
		(layer "F.Cu")
	)
	(gr_arc
		(start 182.285132 -20.042632)
		(mid 182.352937 -20.088049)
		(end 182.43296 -20.1041)
		(stroke
			(width 0.068326)
			(type default)
		)
		(layer "F.Cu")
	)
	(gr_arc
		(start 182.331868 -24.301196)
		(mid 182.223064 -24.359663)
		(end 182.127652 -24.438102)
		(stroke
			(width 0.068326)
			(type default)
		)
		(layer "F.Cu")
	)
	(gr_line
		(start 182.331868 -24.301196)
		(end 182.396384 -24.274272)
		(stroke
			(width 0.068326)
			(type default)
		)
		(layer "F.Cu")
	)
	(gr_arc
		(start 182.4736 -29.5529)
		(mid 182.356324 -29.576307)
		(end 182.256938 -29.642816)
		(stroke
			(width 0.068326)
			(type default)
		)
		(layer "F.Cu")
	)
	(gr_arc
		(start 182.4736 -26.5049)
		(mid 182.356324 -26.528307)
		(end 182.256938 -26.594816)
		(stroke
			(width 0.068326)
			(type default)
		)
		(layer "F.Cu")
	)
	(gr_arc
		(start 182.498238 -20.4089)
		(mid 182.358448 -20.436688)
		(end 182.23992 -20.515834)
		(stroke
			(width 0.068326)
			(type default)
		)
		(layer "F.Cu")
	)
	(gr_line
		(start 182.499 -23.9141)
		(end 182.671466 -23.9141)
		(stroke
			(width 0.068326)
			(type default)
		)
		(layer "F.Cu")
	)
	(gr_arc
		(start 182.499254 -24.25319)
		(mid 182.446807 -24.258792)
		(end 182.396384 -24.274272)
		(stroke
			(width 0.068326)
			(type default)
		)
		(layer "F.Cu")
	)
	(gr_line
		(start 182.499254 -24.25319)
		(end 182.682134 -24.25319)
		(stroke
			(width 0.068326)
			(type default)
		)
		(layer "F.Cu")
	)
	(gr_arc
		(start 182.646066 -26.2001)
		(mid 182.815294 -26.166438)
		(end 182.95874 -26.07056)
		(stroke
			(width 0.068326)
			(type default)
		)
		(layer "F.Cu")
	)
	(gr_arc
		(start 182.660544 -29.2481)
		(mid 182.816304 -29.217024)
		(end 182.948326 -29.12872)
		(stroke
			(width 0.068326)
			(type default)
		)
		(layer "F.Cu")
	)
	(gr_arc
		(start 182.671466 -23.9141)
		(mid 182.817171 -23.885117)
		(end 182.940706 -23.802594)
		(stroke
			(width 0.068326)
			(type default)
		)
		(layer "F.Cu")
	)
	(gr_arc
		(start 182.72252 -20.1041)
		(mid 182.943111 -20.034251)
		(end 183.0832 -19.8501)
		(stroke
			(width 0.068326)
			(type default)
		)
		(layer "F.Cu")
	)
	(gr_arc
		(start 182.7276 -22.1996)
		(mid 182.363208 -22.272225)
		(end 182.0545 -22.479)
		(stroke
			(width 0.068326)
			(type default)
		)
		(layer "F.Cu")
	)
	(gr_line
		(start 182.940706 -23.802594)
		(end 183.0832 -23.6601)
		(stroke
			(width 0.068326)
			(type default)
		)
		(layer "F.Cu")
	)
	(gr_line
		(start 182.948326 -29.12872)
		(end 183.0832 -28.9941)
		(stroke
			(width 0.068326)
			(type default)
		)
		(layer "F.Cu")
	)
	(gr_arc
		(start 182.95874 -26.63444)
		(mid 182.815294 -26.538552)
		(end 182.646066 -26.5049)
		(stroke
			(width 0.068326)
			(type default)
		)
		(layer "F.Cu")
	)
	(gr_line
		(start 182.95874 -26.63444)
		(end 183.0832 -26.7589)
		(stroke
			(width 0.068326)
			(type default)
		)
		(layer "F.Cu")
	)
	(gr_line
		(start 182.95874 -26.07056)
		(end 183.0832 -25.9461)
		(stroke
			(width 0.068326)
			(type default)
		)
		(layer "F.Cu")
	)
	(gr_arc
		(start 182.962804 -29.686504)
		(mid 182.814798 -29.58763)
		(end 182.640224 -29.5529)
		(stroke
			(width 0.068326)
			(type default)
		)
		(layer "F.Cu")
	)
	(gr_line
		(start 182.962804 -29.686504)
		(end 183.0832 -29.8069)
		(stroke
			(width 0.068326)
			(type default)
		)
		(layer "F.Cu")
	)
	(gr_arc
		(start 182.99176 -24.38146)
		(mid 182.849703 -24.286544)
		(end 182.682134 -24.25319)
		(stroke
			(width 0.068326)
			(type default)
		)
		(layer "F.Cu")
	)
	(gr_line
		(start 182.99176 -24.38146)
		(end 183.0832 -24.4729)
		(stroke
			(width 0.068326)
			(type default)
		)
		(layer "F.Cu")
	)
	(gr_arc
		(start 183.0832 -20.6629)
		(mid 182.942922 -20.478808)
		(end 182.722266 -20.4089)
		(stroke
			(width 0.068326)
			(type default)
		)
		(layer "F.Cu")
	)
	(gr_line
		(start 183.992012 -211.975954)
		(end 183.992266 -211.975954)
		(stroke
			(width 0.068326)
			(type default)
		)
		(layer "F.Cu")
	)
	(gr_line
		(start 183.992012 -211.975954)
		(end 184.273698 -211.694268)
		(stroke
			(width 0.068326)
			(type default)
		)
		(layer "F.Cu")
	)
	(gr_line
		(start 184.093612 -210.896454)
		(end 184.242202 -211.04479)
		(stroke
			(width 0.068326)
			(type default)
		)
		(layer "F.Cu")
	)
	(gr_line
		(start 184.100216 -224.828354)
		(end 184.100216 -225.54438)
		(stroke
			(width 0.068326)
			(type default)
		)
		(layer "F.Cu")
	)
	(gr_arc
		(start 184.268364 -224.32264)
		(mid 184.143346 -224.561885)
		(end 184.100216 -224.828354)
		(stroke
			(width 0.068326)
			(type default)
		)
		(layer "F.Cu")
	)
	(gr_arc
		(start 184.268364 -224.32264)
		(mid 184.326998 -224.234888)
		(end 184.347612 -224.131378)
		(stroke
			(width 0.068326)
			(type default)
		)
		(layer "F.Cu")
	)
	(gr_arc
		(start 184.273698 -211.694268)
		(mid 184.323689 -211.619452)
		(end 184.341262 -211.5312)
		(stroke
			(width 0.068326)
			(type default)
		)
		(layer "F.Cu")
	)
	(gr_arc
		(start 184.341262 -211.284312)
		(mid 184.315572 -211.154689)
		(end 184.242202 -211.04479)
		(stroke
			(width 0.068326)
			(type default)
		)
		(layer "F.Cu")
	)
	(gr_arc
		(start 184.347612 -213.722712)
		(mid 184.25527 -213.258477)
		(end 183.992266 -212.864954)
		(stroke
			(width 0.068326)
			(type default)
		)
		(layer "F.Cu")
	)
	(gr_arc
		(start 184.646062 -211.5312)
		(mid 184.661347 -211.607652)
		(end 184.704736 -211.672424)
		(stroke
			(width 0.068326)
			(type default)
		)
		(layer "F.Cu")
	)
	(gr_arc
		(start 184.652666 -224.133664)
		(mid 184.672834 -224.234829)
		(end 184.730136 -224.320608)
		(stroke
			(width 0.068326)
			(type default)
		)
		(layer "F.Cu")
	)
	(gr_line
		(start 184.704736 -211.672424)
		(end 185.008266 -211.975954)
		(stroke
			(width 0.068326)
			(type default)
		)
		(layer "F.Cu")
	)
	(gr_arc
		(start 184.736486 -211.066634)
		(mid 184.669606 -211.166612)
		(end 184.646062 -211.284566)
		(stroke
			(width 0.068326)
			(type default)
		)
		(layer "F.Cu")
	)
	(gr_line
		(start 184.736486 -211.066634)
		(end 184.906412 -210.896454)
		(stroke
			(width 0.068326)
			(type default)
		)
		(layer "F.Cu")
	)
	(gr_arc
		(start 184.900062 -224.828354)
		(mid 184.856425 -224.560646)
		(end 184.730136 -224.320608)
		(stroke
			(width 0.068326)
			(type default)
		)
		(layer "F.Cu")
	)
	(gr_line
		(start 184.900062 -224.828354)
		(end 184.900062 -225.54438)
		(stroke
			(width 0.068326)
			(type default)
		)
		(layer "F.Cu")
	)
	(gr_arc
		(start 185.007758 -212.865462)
		(mid 184.744959 -213.258772)
		(end 184.652666 -213.722712)
		(stroke
			(width 0.068326)
			(type default)
		)
		(layer "F.Cu")
	)
	(gr_line
		(start 185.007758 -212.865462)
		(end 185.008266 -212.864954)
		(stroke
			(width 0.068326)
			(type default)
		)
		(layer "F.Cu")
	)
	(gr_arc
		(start 185.78957 -25.264364)
		(mid 185.977289 -25.186634)
		(end 186.055 -24.998934)
		(stroke
			(width 0.068326)
			(type default)
		)
		(layer "F.Cu")
	)
	(gr_arc
		(start 186.055 -25.811734)
		(mid 185.983953 -25.640211)
		(end 185.81243 -25.569164)
		(stroke
			(width 0.068326)
			(type default)
		)
		(layer "F.Cu")
	)
	(gr_arc
		(start 186.47283 -28.227274)
		(mid 186.685637 -28.139104)
		(end 186.77382 -27.926284)
		(stroke
			(width 0.068326)
			(type default)
		)
		(layer "F.Cu")
	)
	(gr_line
		(start 186.77382 -27.79014)
		(end 186.77382 -27.926284)
		(stroke
			(width 0.068326)
			(type default)
		)
		(layer "F.Cu")
	)
	(gr_arc
		(start 186.7789 -28.838144)
		(mid 186.689254 -28.62172)
		(end 186.47283 -28.532074)
		(stroke
			(width 0.068326)
			(type default)
		)
		(layer "F.Cu")
	)
	(gr_line
		(start 186.7789 -28.838144)
		(end 186.7789 -28.96108)
		(stroke
			(width 0.068326)
			(type default)
		)
		(layer "F.Cu")
	)
	(gr_line
		(start 187.192158 -211.975954)
		(end 187.473844 -211.694268)
		(stroke
			(width 0.068326)
			(type default)
		)
		(layer "F.Cu")
	)
	(gr_line
		(start 187.293758 -210.896454)
		(end 187.442602 -211.045298)
		(stroke
			(width 0.068326)
			(type default)
		)
		(layer "F.Cu")
	)
	(gr_line
		(start 187.300108 -224.828608)
		(end 187.300108 -225.54438)
		(stroke
			(width 0.068326)
			(type default)
		)
		(layer "F.Cu")
	)
	(gr_line
		(start 187.300108 -224.828608)
		(end 187.300362 -224.828354)
		(stroke
			(width 0.068326)
			(type default)
		)
		(layer "F.Cu")
	)
	(gr_arc
		(start 187.46851 -224.32264)
		(mid 187.343485 -224.561884)
		(end 187.300362 -224.828354)
		(stroke
			(width 0.068326)
			(type default)
		)
		(layer "F.Cu")
	)
	(gr_arc
		(start 187.46851 -224.32264)
		(mid 187.527144 -224.234888)
		(end 187.547758 -224.131378)
		(stroke
			(width 0.068326)
			(type default)
		)
		(layer "F.Cu")
	)
	(gr_arc
		(start 187.473844 -211.694268)
		(mid 187.523835 -211.619452)
		(end 187.541408 -211.5312)
		(stroke
			(width 0.068326)
			(type default)
		)
		(layer "F.Cu")
	)
	(gr_arc
		(start 187.541408 -211.283804)
		(mid 187.515732 -211.15472)
		(end 187.442602 -211.045298)
		(stroke
			(width 0.068326)
			(type default)
		)
		(layer "F.Cu")
	)
	(gr_arc
		(start 187.547758 -213.723474)
		(mid 187.455339 -213.25885)
		(end 187.192158 -212.864954)
		(stroke
			(width 0.068326)
			(type default)
		)
		(layer "F.Cu")
	)
	(gr_arc
		(start 187.846208 -211.5312)
		(mid 187.86149 -211.607655)
		(end 187.904882 -211.672424)
		(stroke
			(width 0.068326)
			(type default)
		)
		(layer "F.Cu")
	)
	(gr_arc
		(start 187.852812 -224.133664)
		(mid 187.872983 -224.234826)
		(end 187.930282 -224.320608)
		(stroke
			(width 0.068326)
			(type default)
		)
		(layer "F.Cu")
	)
	(gr_line
		(start 187.904882 -211.672424)
		(end 188.208158 -211.975954)
		(stroke
			(width 0.068326)
			(type default)
		)
		(layer "F.Cu")
	)
	(gr_arc
		(start 187.936124 -211.067142)
		(mid 187.86961 -211.166531)
		(end 187.846208 -211.283804)
		(stroke
			(width 0.068326)
			(type default)
		)
		(layer "F.Cu")
	)
	(gr_line
		(start 187.936124 -211.067142)
		(end 188.106558 -210.896454)
		(stroke
			(width 0.068326)
			(type default)
		)
		(layer "F.Cu")
	)
	(gr_arc
		(start 188.100208 -224.828354)
		(mid 188.056571 -224.560646)
		(end 187.930282 -224.320608)
		(stroke
			(width 0.068326)
			(type default)
		)
		(layer "F.Cu")
	)
	(gr_line
		(start 188.100208 -224.828354)
		(end 188.100208 -225.54438)
		(stroke
			(width 0.068326)
			(type default)
		)
		(layer "F.Cu")
	)
	(gr_arc
		(start 188.208158 -212.864954)
		(mid 187.945171 -213.258486)
		(end 187.852812 -213.722712)
		(stroke
			(width 0.068326)
			(type default)
		)
		(layer "F.Cu")
	)
	(gr_line
		(start 190.392304 -211.9757)
		(end 190.392304 -211.975954)
		(stroke
			(width 0.068326)
			(type default)
		)
		(layer "F.Cu")
	)
	(gr_line
		(start 190.392304 -211.9757)
		(end 190.673736 -211.694268)
		(stroke
			(width 0.068326)
			(type default)
		)
		(layer "F.Cu")
	)
	(gr_line
		(start 190.49365 -210.896454)
		(end 190.64351 -211.04606)
		(stroke
			(width 0.068326)
			(type default)
		)
		(layer "F.Cu")
	)
	(gr_line
		(start 190.5 -224.828608)
		(end 190.5 -225.54438)
		(stroke
			(width 0.068326)
			(type default)
		)
		(layer "F.Cu")
	)
	(gr_line
		(start 190.5 -224.828608)
		(end 190.500254 -224.828354)
		(stroke
			(width 0.068326)
			(type default)
		)
		(layer "F.Cu")
	)
	(gr_arc
		(start 190.668402 -224.32264)
		(mid 190.543378 -224.561884)
		(end 190.500254 -224.828354)
		(stroke
			(width 0.068326)
			(type default)
		)
		(layer "F.Cu")
	)
	(gr_arc
		(start 190.668402 -224.32264)
		(mid 190.727036 -224.234888)
		(end 190.74765 -224.131378)
		(stroke
			(width 0.068326)
			(type default)
		)
		(layer "F.Cu")
	)
	(gr_arc
		(start 190.673736 -211.694268)
		(mid 190.723727 -211.619452)
		(end 190.7413 -211.5312)
		(stroke
			(width 0.068326)
			(type default)
		)
		(layer "F.Cu")
	)
	(gr_arc
		(start 190.7413 -211.282534)
		(mid 190.715939 -211.154563)
		(end 190.64351 -211.04606)
		(stroke
			(width 0.068326)
			(type default)
		)
		(layer "F.Cu")
	)
	(gr_arc
		(start 190.74765 -213.722712)
		(mid 190.655308 -213.258477)
		(end 190.392304 -212.864954)
		(stroke
			(width 0.068326)
			(type default)
		)
		(layer "F.Cu")
	)
	(gr_arc
		(start 191.0461 -211.5312)
		(mid 191.061382 -211.607656)
		(end 191.104774 -211.672424)
		(stroke
			(width 0.068326)
			(type default)
		)
		(layer "F.Cu")
	)
	(gr_arc
		(start 191.052704 -224.133664)
		(mid 191.072874 -224.234826)
		(end 191.130174 -224.320608)
		(stroke
			(width 0.068326)
			(type default)
		)
		(layer "F.Cu")
	)
	(gr_line
		(start 191.104774 -211.672424)
		(end 191.408304 -211.975954)
		(stroke
			(width 0.068326)
			(type default)
		)
		(layer "F.Cu")
	)
	(gr_arc
		(start 191.142112 -211.060538)
		(mid 191.071002 -211.16706)
		(end 191.0461 -211.292694)
		(stroke
			(width 0.068326)
			(type default)
		)
		(layer "F.Cu")
	)
	(gr_line
		(start 191.142112 -211.060538)
		(end 191.30645 -210.896454)
		(stroke
			(width 0.068326)
			(type default)
		)
		(layer "F.Cu")
	)
	(gr_arc
		(start 191.3001 -224.828354)
		(mid 191.256463 -224.560646)
		(end 191.130174 -224.320608)
		(stroke
			(width 0.068326)
			(type default)
		)
		(layer "F.Cu")
	)
	(gr_line
		(start 191.3001 -224.828354)
		(end 191.3001 -225.54438)
		(stroke
			(width 0.068326)
			(type default)
		)
		(layer "F.Cu")
	)
	(gr_arc
		(start 191.407796 -212.865462)
		(mid 191.144989 -213.25877)
		(end 191.052704 -213.722712)
		(stroke
			(width 0.068326)
			(type default)
		)
		(layer "F.Cu")
	)
	(gr_line
		(start 191.407796 -212.865462)
		(end 191.408304 -212.864954)
		(stroke
			(width 0.068326)
			(type default)
		)
		(layer "F.Cu")
	)
	(gr_line
		(start 193.592196 -211.975954)
		(end 193.873882 -211.694268)
		(stroke
			(width 0.068326)
			(type default)
		)
		(layer "F.Cu")
	)
	(gr_line
		(start 193.693796 -210.896454)
		(end 193.82613 -211.028788)
		(stroke
			(width 0.068326)
			(type default)
		)
		(layer "F.Cu")
	)
	(gr_line
		(start 193.700146 -224.828608)
		(end 193.700146 -225.54438)
		(stroke
			(width 0.068326)
			(type default)
		)
		(layer "F.Cu")
	)
	(gr_line
		(start 193.700146 -224.828608)
		(end 193.7004 -224.828354)
		(stroke
			(width 0.068326)
			(type default)
		)
		(layer "F.Cu")
	)
	(gr_arc
		(start 193.868548 -224.32264)
		(mid 193.743532 -224.561886)
		(end 193.7004 -224.828354)
		(stroke
			(width 0.068326)
			(type default)
		)
		(layer "F.Cu")
	)
	(gr_arc
		(start 193.868548 -224.32264)
		(mid 193.927182 -224.234888)
		(end 193.947796 -224.131378)
		(stroke
			(width 0.068326)
			(type default)
		)
		(layer "F.Cu")
	)
	(gr_arc
		(start 193.873882 -211.694268)
		(mid 193.923873 -211.619452)
		(end 193.941446 -211.5312)
		(stroke
			(width 0.068326)
			(type default)
		)
		(layer "F.Cu")
	)
	(gr_arc
		(start 193.941446 -211.307172)
		(mid 193.911477 -211.15651)
		(end 193.82613 -211.028788)
		(stroke
			(width 0.068326)
			(type default)
		)
		(layer "F.Cu")
	)
	(gr_arc
		(start 193.947796 -213.723474)
		(mid 193.855377 -213.25885)
		(end 193.592196 -212.864954)
		(stroke
			(width 0.068326)
			(type default)
		)
		(layer "F.Cu")
	)
	(gr_arc
		(start 194.246246 -211.5312)
		(mid 194.26153 -211.607653)
		(end 194.30492 -211.672424)
		(stroke
			(width 0.068326)
			(type default)
		)
		(layer "F.Cu")
	)
	(gr_arc
		(start 194.25285 -224.133664)
		(mid 194.273017 -224.234829)
		(end 194.33032 -224.320608)
		(stroke
			(width 0.068326)
			(type default)
		)
		(layer "F.Cu")
	)
	(gr_line
		(start 194.30492 -211.672424)
		(end 194.608196 -211.975954)
		(stroke
			(width 0.068326)
			(type default)
		)
		(layer "F.Cu")
	)
	(gr_arc
		(start 194.352672 -211.050632)
		(mid 194.27397 -211.168325)
		(end 194.246246 -211.307172)
		(stroke
			(width 0.068326)
			(type default)
		)
		(layer "F.Cu")
	)
	(gr_line
		(start 194.352672 -211.050632)
		(end 194.506596 -210.896454)
		(stroke
			(width 0.068326)
			(type default)
		)
		(layer "F.Cu")
	)
	(gr_arc
		(start 194.500246 -224.828354)
		(mid 194.456609 -224.560646)
		(end 194.33032 -224.320608)
		(stroke
			(width 0.068326)
			(type default)
		)
		(layer "F.Cu")
	)
	(gr_line
		(start 194.500246 -224.828354)
		(end 194.500246 -225.54438)
		(stroke
			(width 0.068326)
			(type default)
		)
		(layer "F.Cu")
	)
	(gr_arc
		(start 194.608196 -212.864954)
		(mid 194.345201 -213.258483)
		(end 194.25285 -213.722712)
		(stroke
			(width 0.068326)
			(type default)
		)
		(layer "F.Cu")
	)
	(gr_line
		(start 196.792088 -211.975954)
		(end 197.073774 -211.694268)
		(stroke
			(width 0.068326)
			(type default)
		)
		(layer "F.Cu")
	)
	(gr_line
		(start 196.893688 -210.896454)
		(end 197.042278 -211.04479)
		(stroke
			(width 0.068326)
			(type default)
		)
		(layer "F.Cu")
	)
	(gr_line
		(start 196.900038 -224.828608)
		(end 196.900038 -225.54438)
		(stroke
			(width 0.068326)
			(type default)
		)
		(layer "F.Cu")
	)
	(gr_line
		(start 196.900038 -224.828608)
		(end 196.900292 -224.828354)
		(stroke
			(width 0.068326)
			(type default)
		)
		(layer "F.Cu")
	)
	(gr_arc
		(start 197.06844 -224.32264)
		(mid 196.943425 -224.561886)
		(end 196.900292 -224.828354)
		(stroke
			(width 0.068326)
			(type default)
		)
		(layer "F.Cu")
	)
	(gr_arc
		(start 197.06844 -224.32264)
		(mid 197.127074 -224.234888)
		(end 197.147688 -224.131378)
		(stroke
			(width 0.068326)
			(type default)
		)
		(layer "F.Cu")
	)
	(gr_arc
		(start 197.073774 -211.694268)
		(mid 197.123765 -211.619452)
		(end 197.141338 -211.5312)
		(stroke
			(width 0.068326)
			(type default)
		)
		(layer "F.Cu")
	)
	(gr_arc
		(start 197.141338 -211.284312)
		(mid 197.115648 -211.154689)
		(end 197.042278 -211.04479)
		(stroke
			(width 0.068326)
			(type default)
		)
		(layer "F.Cu")
	)
	(gr_arc
		(start 197.147688 -213.723474)
		(mid 197.055269 -213.25885)
		(end 196.792088 -212.864954)
		(stroke
			(width 0.068326)
			(type default)
		)
		(layer "F.Cu")
	)
	(gr_arc
		(start 197.446138 -211.5312)
		(mid 197.461422 -211.607653)
		(end 197.504812 -211.672424)
		(stroke
			(width 0.068326)
			(type default)
		)
		(layer "F.Cu")
	)
	(gr_arc
		(start 197.452742 -224.133664)
		(mid 197.472908 -224.23483)
		(end 197.530212 -224.320608)
		(stroke
			(width 0.068326)
			(type default)
		)
		(layer "F.Cu")
	)
	(gr_line
		(start 197.504812 -211.672424)
		(end 197.808088 -211.975954)
		(stroke
			(width 0.068326)
			(type default)
		)
		(layer "F.Cu")
	)
	(gr_arc
		(start 197.536562 -211.066634)
		(mid 197.469687 -211.166614)
		(end 197.446138 -211.284566)
		(stroke
			(width 0.068326)
			(type default)
		)
		(layer "F.Cu")
	)
	(gr_line
		(start 197.536562 -211.066634)
		(end 197.706488 -210.896454)
		(stroke
			(width 0.068326)
			(type default)
		)
		(layer "F.Cu")
	)
	(gr_arc
		(start 197.700138 -224.828354)
		(mid 197.656501 -224.560646)
		(end 197.530212 -224.320608)
		(stroke
			(width 0.068326)
			(type default)
		)
		(layer "F.Cu")
	)
	(gr_line
		(start 197.700138 -224.828354)
		(end 197.700138 -225.54438)
		(stroke
			(width 0.068326)
			(type default)
		)
		(layer "F.Cu")
	)
	(gr_arc
		(start 197.808088 -212.864954)
		(mid 197.545095 -213.258484)
		(end 197.452742 -213.722712)
		(stroke
			(width 0.068326)
			(type default)
		)
		(layer "F.Cu")
	)
	(gr_arc
		(start 197.816978 -45.629576)
		(mid 197.923205 -45.886071)
		(end 198.17969 -45.992288)
		(stroke
			(width 0.068326)
			(type default)
		)
		(layer "F.Cu")
	)
	(gr_line
		(start 197.816978 -45.59046)
		(end 197.816978 -45.629576)
		(stroke
			(width 0.068326)
			(type default)
		)
		(layer "F.Cu")
	)
	(gr_arc
		(start 198.275956 -46.297088)
		(mid 197.967872 -46.414822)
		(end 197.816978 -46.70806)
		(stroke
			(width 0.068326)
			(type default)
		)
		(layer "F.Cu")
	)
	(gr_line
		(start 198.976234 -46.297088)
		(end 199.03821 -46.235112)
		(stroke
			(width 0.068326)
			(type default)
		)
		(layer "F.Cu")
	)
	(gr_line
		(start 199.745346 -44.458128)
		(end 199.748902 -44.440602)
		(stroke
			(width 0.068326)
			(type default)
		)
		(layer "F.Cu")
	)
	(gr_line
		(start 199.748902 -44.440602)
		(end 199.759062 -44.424854)
		(stroke
			(width 0.068326)
			(type default)
		)
		(layer "F.Cu")
	)
	(gr_line
		(start 199.815958 -45.456602)
		(end 199.852026 -45.420534)
		(stroke
			(width 0.068326)
			(type default)
		)
		(layer "F.Cu")
	)
	(gr_line
		(start 199.852026 -45.420534)
		(end 199.862694 -45.370496)
		(stroke
			(width 0.068326)
			(type default)
		)
		(layer "F.Cu")
	)
	(gr_line
		(start 199.99198 -211.975954)
		(end 200.273666 -211.694268)
		(stroke
			(width 0.068326)
			(type default)
		)
		(layer "F.Cu")
	)
	(gr_arc
		(start 200.0504 -49.734216)
		(mid 200.3495 -49.577649)
		(end 200.4695 -49.26203)
		(stroke
			(width 0.068326)
			(type default)
		)
		(layer "F.Cu")
	)
	(gr_line
		(start 200.09358 -210.896454)
		(end 200.227438 -211.030566)
		(stroke
			(width 0.068326)
			(type default)
		)
		(layer "F.Cu")
	)
	(gr_line
		(start 200.100184 -224.828354)
		(end 200.100184 -225.54438)
		(stroke
			(width 0.068326)
			(type default)
		)
		(layer "F.Cu")
	)
	(gr_arc
		(start 200.268332 -224.32264)
		(mid 200.143304 -224.561883)
		(end 200.100184 -224.828354)
		(stroke
			(width 0.068326)
			(type default)
		)
		(layer "F.Cu")
	)
	(gr_arc
		(start 200.268332 -224.32264)
		(mid 200.326966 -224.234888)
		(end 200.34758 -224.131378)
		(stroke
			(width 0.068326)
			(type default)
		)
		(layer "F.Cu")
	)
	(gr_arc
		(start 200.273666 -211.694268)
		(mid 200.323657 -211.619452)
		(end 200.34123 -211.5312)
		(stroke
			(width 0.068326)
			(type default)
		)
		(layer "F.Cu")
	)
	(gr_arc
		(start 200.34123 -211.304886)
		(mid 200.311604 -211.156416)
		(end 200.227438 -211.030566)
		(stroke
			(width 0.068326)
			(type default)
		)
		(layer "F.Cu")
	)
	(gr_arc
		(start 200.34758 -213.723474)
		(mid 200.255161 -213.25885)
		(end 199.99198 -212.864954)
		(stroke
			(width 0.068326)
			(type default)
		)
		(layer "F.Cu")
	)
	(gr_line
		(start 200.543414 -48.560228)
		(end 200.547224 -48.542702)
		(stroke
			(width 0.068326)
			(type default)
		)
		(layer "F.Cu")
	)
	(gr_line
		(start 200.547224 -48.542702)
		(end 200.556876 -48.527716)
		(stroke
			(width 0.068326)
			(type default)
		)
		(layer "F.Cu")
	)
	(gr_arc
		(start 200.64603 -211.5312)
		(mid 200.661313 -211.607654)
		(end 200.704704 -211.672424)
		(stroke
			(width 0.068326)
			(type default)
		)
		(layer "F.Cu")
	)
	(gr_arc
		(start 200.652634 -224.133664)
		(mid 200.672806 -224.234825)
		(end 200.730104 -224.320608)
		(stroke
			(width 0.068326)
			(type default)
		)
		(layer "F.Cu")
	)
	(gr_line
		(start 200.704704 -211.672424)
		(end 201.00798 -211.975954)
		(stroke
			(width 0.068326)
			(type default)
		)
		(layer "F.Cu")
	)
	(gr_arc
		(start 200.750678 -211.05241)
		(mid 200.673269 -211.168115)
		(end 200.64603 -211.304632)
		(stroke
			(width 0.068326)
			(type default)
		)
		(layer "F.Cu")
	)
	(gr_line
		(start 200.750678 -211.05241)
		(end 200.90638 -210.896454)
		(stroke
			(width 0.068326)
			(type default)
		)
		(layer "F.Cu")
	)
	(gr_arc
		(start 200.7743 -49.2506)
		(mid 200.894152 -49.552637)
		(end 201.168 -49.727612)
		(stroke
			(width 0.068326)
			(type default)
		)
		(layer "F.Cu")
	)
	(gr_line
		(start 200.7997 -48.154336)
		(end 200.813416 -48.132746)
		(stroke
			(width 0.068326)
			(type default)
		)
		(layer "F.Cu")
	)
	(gr_line
		(start 200.813416 -48.132746)
		(end 200.835768 -48.118268)
		(stroke
			(width 0.068326)
			(type default)
		)
		(layer "F.Cu")
	)
	(gr_arc
		(start 200.90003 -224.828354)
		(mid 200.856393 -224.560646)
		(end 200.730104 -224.320608)
		(stroke
			(width 0.068326)
			(type default)
		)
		(layer "F.Cu")
	)
	(gr_line
		(start 200.90003 -224.828354)
		(end 200.90003 -225.54438)
		(stroke
			(width 0.068326)
			(type default)
		)
		(layer "F.Cu")
	)
	(gr_arc
		(start 201.00798 -212.864954)
		(mid 200.744988 -213.258484)
		(end 200.652634 -213.722712)
		(stroke
			(width 0.068326)
			(type default)
		)
		(layer "F.Cu")
	)
	(gr_arc
		(start 201.36104 -44.714922)
		(mid 201.470961 -45.018609)
		(end 201.76744 -45.146722)
		(stroke
			(width 0.068326)
			(type default)
		)
		(layer "F.Cu")
	)
	(gr_arc
		(start 201.76744 -45.451522)
		(mid 201.488876 -45.561628)
		(end 201.36104 -45.832522)
		(stroke
			(width 0.068326)
			(type default)
		)
		(layer "F.Cu")
	)
	(gr_line
		(start 202.142852 -24.257)
		(end 203.09459 -24.257)
		(stroke
			(width 0.060198)
			(type default)
		)
		(layer "F.Cu")
	)
	(gr_line
		(start 202.142852 -23.60676)
		(end 203.105004 -23.60676)
		(stroke
			(width 0.060198)
			(type default)
		)
		(layer "F.Cu")
	)
	(gr_line
		(start 202.524868 -45.451522)
		(end 202.568048 -45.423582)
		(stroke
			(width 0.068326)
			(type default)
		)
		(layer "F.Cu")
	)
	(gr_line
		(start 202.624436 -46.957742)
		(end 202.639422 -46.94809)
		(stroke
			(width 0.068326)
			(type default)
		)
		(layer "F.Cu")
	)
	(gr_line
		(start 202.639422 -46.94809)
		(end 202.656948 -46.94428)
		(stroke
			(width 0.068326)
			(type default)
		)
		(layer "F.Cu")
	)
	(gr_line
		(start 202.879452 -32.2326)
		(end 203.839826 -32.2326)
		(stroke
			(width 0.060198)
			(type default)
		)
		(layer "F.Cu")
	)
	(gr_line
		(start 202.879452 -31.58236)
		(end 203.84008 -31.58236)
		(stroke
			(width 0.060198)
			(type default)
		)
		(layer "F.Cu")
	)
	(gr_line
		(start 202.966574 -45.16501)
		(end 202.98791 -45.15104)
		(stroke
			(width 0.068326)
			(type default)
		)
		(layer "F.Cu")
	)
	(gr_line
		(start 202.98791 -45.15104)
		(end 203.00188 -45.129704)
		(stroke
			(width 0.068326)
			(type default)
		)
		(layer "F.Cu")
	)
	(gr_line
		(start 203.192126 -211.975954)
		(end 203.473812 -211.694268)
		(stroke
			(width 0.068326)
			(type default)
		)
		(layer "F.Cu")
	)
	(gr_line
		(start 203.227686 -43.591226)
		(end 203.230734 -43.579288)
		(stroke
			(width 0.068326)
			(type default)
		)
		(layer "F.Cu")
	)
	(gr_line
		(start 203.230734 -43.579288)
		(end 203.237592 -43.56862)
		(stroke
			(width 0.068326)
			(type default)
		)
		(layer "F.Cu")
	)
	(gr_line
		(start 203.241148 -44.761912)
		(end 203.247752 -44.751752)
		(stroke
			(width 0.068326)
			(type default)
		)
		(layer "F.Cu")
	)
	(gr_line
		(start 203.247752 -44.751752)
		(end 203.2508 -44.739814)
		(stroke
			(width 0.068326)
			(type default)
		)
		(layer "F.Cu")
	)
	(gr_line
		(start 203.293726 -210.896454)
		(end 203.446126 -211.048854)
		(stroke
			(width 0.068326)
			(type default)
		)
		(layer "F.Cu")
	)
	(gr_line
		(start 203.300076 -224.828608)
		(end 203.300076 -225.54438)
		(stroke
			(width 0.068326)
			(type default)
		)
		(layer "F.Cu")
	)
	(gr_line
		(start 203.300076 -224.828608)
		(end 203.30033 -224.828354)
		(stroke
			(width 0.068326)
			(type default)
		)
		(layer "F.Cu")
	)
	(gr_arc
		(start 203.468478 -224.32264)
		(mid 203.343458 -224.561885)
		(end 203.30033 -224.828354)
		(stroke
			(width 0.068326)
			(type default)
		)
		(layer "F.Cu")
	)
	(gr_arc
		(start 203.468478 -224.32264)
		(mid 203.527112 -224.234888)
		(end 203.547726 -224.131378)
		(stroke
			(width 0.068326)
			(type default)
		)
		(layer "F.Cu")
	)
	(gr_arc
		(start 203.473812 -211.694268)
		(mid 203.523803 -211.619452)
		(end 203.541376 -211.5312)
		(stroke
			(width 0.068326)
			(type default)
		)
		(layer "F.Cu")
	)
	(gr_arc
		(start 203.541376 -211.278724)
		(mid 203.516628 -211.154306)
		(end 203.446126 -211.048854)
		(stroke
			(width 0.068326)
			(type default)
		)
		(layer "F.Cu")
	)
	(gr_arc
		(start 203.547726 -213.723474)
		(mid 203.455307 -213.25885)
		(end 203.192126 -212.864954)
		(stroke
			(width 0.068326)
			(type default)
		)
		(layer "F.Cu")
	)
	(gr_line
		(start 203.63307 -42.959528)
		(end 203.647548 -42.937176)
		(stroke
			(width 0.068326)
			(type default)
		)
		(layer "F.Cu")
	)
	(gr_line
		(start 203.647548 -42.937176)
		(end 203.6699 -42.922698)
		(stroke
			(width 0.068326)
			(type default)
		)
		(layer "F.Cu")
	)
	(gr_line
		(start 203.68514 -40.731948)
		(end 203.700126 -40.722296)
		(stroke
			(width 0.068326)
			(type default)
		)
		(layer "F.Cu")
	)
	(gr_line
		(start 203.700126 -40.722296)
		(end 203.717398 -40.71874)
		(stroke
			(width 0.068326)
			(type default)
		)
		(layer "F.Cu")
	)
	(gr_arc
		(start 203.846176 -211.5312)
		(mid 203.861456 -211.607657)
		(end 203.90485 -211.672424)
		(stroke
			(width 0.068326)
			(type default)
		)
		(layer "F.Cu")
	)
	(gr_arc
		(start 203.85278 -224.133664)
		(mid 203.872949 -224.234828)
		(end 203.93025 -224.320608)
		(stroke
			(width 0.068326)
			(type default)
		)
		(layer "F.Cu")
	)
	(gr_line
		(start 203.90485 -211.672424)
		(end 204.208126 -211.975954)
		(stroke
			(width 0.068326)
			(type default)
		)
		(layer "F.Cu")
	)
	(gr_arc
		(start 203.939394 -211.063586)
		(mid 203.870406 -211.166837)
		(end 203.846176 -211.28863)
		(stroke
			(width 0.068326)
			(type default)
		)
		(layer "F.Cu")
	)
	(gr_line
		(start 203.939394 -211.063586)
		(end 204.106526 -210.896454)
		(stroke
			(width 0.068326)
			(type default)
		)
		(layer "F.Cu")
	)
	(gr_line
		(start 203.955396 -42.737532)
		(end 203.958444 -42.7355)
		(stroke
			(width 0.068326)
			(type default)
		)
		(layer "F.Cu")
	)
	(gr_line
		(start 203.990956 -42.714672)
		(end 204.004418 -42.705782)
		(stroke
			(width 0.068326)
			(type default)
		)
		(layer "F.Cu")
	)
	(gr_line
		(start 204.004418 -42.705782)
		(end 204.021182 -42.702226)
		(stroke
			(width 0.068326)
			(type default)
		)
		(layer "F.Cu")
	)
	(gr_arc
		(start 204.100176 -224.828354)
		(mid 204.056539 -224.560646)
		(end 203.93025 -224.320608)
		(stroke
			(width 0.068326)
			(type default)
		)
		(layer "F.Cu")
	)
	(gr_line
		(start 204.100176 -224.828354)
		(end 204.100176 -225.54438)
		(stroke
			(width 0.068326)
			(type default)
		)
		(layer "F.Cu")
	)
	(gr_line
		(start 204.113892 -42.998136)
		(end 204.122782 -42.992294)
		(stroke
			(width 0.068326)
			(type default)
		)
		(layer "F.Cu")
	)
	(gr_arc
		(start 204.208126 -212.864954)
		(mid 203.945125 -213.258482)
		(end 203.85278 -213.722712)
		(stroke
			(width 0.068326)
			(type default)
		)
		(layer "F.Cu")
	)
	(gr_line
		(start 204.775816 -24.905716)
		(end 204.9399 -25.0698)
		(stroke
			(width 0.060198)
			(type default)
		)
		(layer "F.Cu")
	)
	(gr_line
		(start 204.775816 -24.192484)
		(end 204.9399 -24.0284)
		(stroke
			(width 0.060198)
			(type default)
		)
		(layer "F.Cu")
	)
	(gr_line
		(start 205.709012 -42.343324)
		(end 206.338678 -42.209466)
		(stroke
			(width 0.068326)
			(type default)
		)
		(layer "F.Cu")
	)
	(gr_line
		(start 205.737206 -42.651426)
		(end 205.918816 -42.769282)
		(stroke
			(width 0.068326)
			(type default)
		)
		(layer "F.Cu")
	)
	(gr_line
		(start 205.741778 -40.287956)
		(end 205.776322 -40.28059)
		(stroke
			(width 0.068326)
			(type default)
		)
		(layer "F.Cu")
	)
	(gr_line
		(start 205.776322 -40.28059)
		(end 205.811374 -40.289988)
		(stroke
			(width 0.068326)
			(type default)
		)
		(layer "F.Cu")
	)
	(gr_line
		(start 205.8289 -25.0698)
		(end 206.248 -25.0698)
		(stroke
			(width 0.060198)
			(type default)
		)
		(layer "F.Cu")
	)
	(gr_line
		(start 205.8289 -24.0284)
		(end 206.247746 -24.0284)
		(stroke
			(width 0.060198)
			(type default)
		)
		(layer "F.Cu")
	)
	(gr_line
		(start 205.918816 -42.769282)
		(end 206.319882 -42.684192)
		(stroke
			(width 0.068326)
			(type default)
		)
		(layer "F.Cu")
	)
	(gr_line
		(start 206.014066 -32.26689)
		(end 206.16545 -32.418274)
		(stroke
			(width 0.060198)
			(type default)
		)
		(layer "F.Cu")
	)
	(gr_line
		(start 206.014066 -31.553658)
		(end 206.16545 -31.402274)
		(stroke
			(width 0.060198)
			(type default)
		)
		(layer "F.Cu")
	)
	(gr_line
		(start 206.247746 -24.0284)
		(end 206.412084 -24.192738)
		(stroke
			(width 0.060198)
			(type default)
		)
		(layer "F.Cu")
	)
	(gr_line
		(start 206.248 -25.0698)
		(end 206.412084 -24.905716)
		(stroke
			(width 0.060198)
			(type default)
		)
		(layer "F.Cu")
	)
	(gr_line
		(start 206.319882 -42.684192)
		(end 206.437738 -42.502582)
		(stroke
			(width 0.068326)
			(type default)
		)
		(layer "F.Cu")
	)
	(gr_line
		(start 206.392018 -211.975954)
		(end 206.673704 -211.694268)
		(stroke
			(width 0.068326)
			(type default)
		)
		(layer "F.Cu")
	)
	(gr_line
		(start 206.426562 -46.143164)
		(end 206.451708 -46.13783)
		(stroke
			(width 0.068326)
			(type default)
		)
		(layer "F.Cu")
	)
	(gr_line
		(start 206.451708 -46.13783)
		(end 206.476854 -46.143164)
		(stroke
			(width 0.068326)
			(type default)
		)
		(layer "F.Cu")
	)
	(gr_line
		(start 206.46644 -40.783256)
		(end 206.46771 -40.78351)
		(stroke
			(width 0.068326)
			(type default)
		)
		(layer "F.Cu")
	)
	(gr_line
		(start 206.493618 -210.896454)
		(end 206.629 -211.031836)
		(stroke
			(width 0.068326)
			(type default)
		)
		(layer "F.Cu")
	)
	(gr_line
		(start 206.499968 -224.828608)
		(end 206.500222 -224.828862)
		(stroke
			(width 0.068326)
			(type default)
		)
		(layer "F.Cu")
	)
	(gr_line
		(start 206.499968 -224.828608)
		(end 206.500222 -224.828354)
		(stroke
			(width 0.068326)
			(type default)
		)
		(layer "F.Cu")
	)
	(gr_line
		(start 206.500222 -224.828862)
		(end 206.500222 -225.54438)
		(stroke
			(width 0.068326)
			(type default)
		)
		(layer "F.Cu")
	)
	(gr_arc
		(start 206.66837 -224.32264)
		(mid 206.543351 -224.561885)
		(end 206.500222 -224.828354)
		(stroke
			(width 0.068326)
			(type default)
		)
		(layer "F.Cu")
	)
	(gr_arc
		(start 206.66837 -224.32264)
		(mid 206.727004 -224.234888)
		(end 206.747618 -224.131378)
		(stroke
			(width 0.068326)
			(type default)
		)
		(layer "F.Cu")
	)
	(gr_arc
		(start 206.673704 -211.694268)
		(mid 206.723695 -211.619452)
		(end 206.741268 -211.5312)
		(stroke
			(width 0.068326)
			(type default)
		)
		(layer "F.Cu")
	)
	(gr_arc
		(start 206.741268 -211.302854)
		(mid 206.712092 -211.156177)
		(end 206.629 -211.031836)
		(stroke
			(width 0.068326)
			(type default)
		)
		(layer "F.Cu")
	)
	(gr_arc
		(start 206.747618 -213.723474)
		(mid 206.655199 -213.25885)
		(end 206.392018 -212.864954)
		(stroke
			(width 0.068326)
			(type default)
		)
		(layer "F.Cu")
	)
	(gr_line
		(start 206.81442 -42.10812)
		(end 206.84109 -42.102532)
		(stroke
			(width 0.068326)
			(type default)
		)
		(layer "F.Cu")
	)
	(gr_line
		(start 206.84109 -42.102532)
		(end 206.86776 -42.108374)
		(stroke
			(width 0.068326)
			(type default)
		)
		(layer "F.Cu")
	)
	(gr_line
		(start 206.850742 -24.802592)
		(end 207.274922 -25.226772)
		(stroke
			(width 0.060198)
			(type default)
		)
		(layer "F.Cu")
	)
	(gr_arc
		(start 207.046068 -211.5312)
		(mid 207.061348 -211.607657)
		(end 207.104742 -211.672424)
		(stroke
			(width 0.068326)
			(type default)
		)
		(layer "F.Cu")
	)
	(gr_arc
		(start 207.052672 -224.133664)
		(mid 207.07284 -224.234828)
		(end 207.130142 -224.320608)
		(stroke
			(width 0.068326)
			(type default)
		)
		(layer "F.Cu")
	)
	(gr_line
		(start 207.05445 -32.418274)
		(end 207.205834 -32.26689)
		(stroke
			(width 0.060198)
			(type default)
		)
		(layer "F.Cu")
	)
	(gr_line
		(start 207.05445 -31.402274)
		(end 207.205834 -31.553658)
		(stroke
			(width 0.060198)
			(type default)
		)
		(layer "F.Cu")
	)
	(gr_line
		(start 207.101694 -24.298402)
		(end 207.274922 -24.125174)
		(stroke
			(width 0.060198)
			(type default)
		)
		(layer "F.Cu")
	)
	(gr_line
		(start 207.104742 -211.672424)
		(end 207.408018 -211.975954)
		(stroke
			(width 0.068326)
			(type default)
		)
		(layer "F.Cu")
	)
	(gr_arc
		(start 207.159098 -211.043774)
		(mid 207.075451 -211.168927)
		(end 207.046068 -211.31657)
		(stroke
			(width 0.068326)
			(type default)
		)
		(layer "F.Cu")
	)
	(gr_line
		(start 207.159098 -211.043774)
		(end 207.306418 -210.896454)
		(stroke
			(width 0.068326)
			(type default)
		)
		(layer "F.Cu")
	)
	(gr_arc
		(start 207.300068 -224.828354)
		(mid 207.256431 -224.560646)
		(end 207.130142 -224.320608)
		(stroke
			(width 0.068326)
			(type default)
		)
		(layer "F.Cu")
	)
	(gr_line
		(start 207.300068 -224.828354)
		(end 207.300068 -225.54438)
		(stroke
			(width 0.068326)
			(type default)
		)
		(layer "F.Cu")
	)
	(gr_arc
		(start 207.408018 -212.864954)
		(mid 207.145018 -213.258482)
		(end 207.052672 -213.722712)
		(stroke
			(width 0.068326)
			(type default)
		)
		(layer "F.Cu")
	)
	(gr_line
		(start 211.928964 -40.848534)
		(end 212.149944 -41.069514)
		(stroke
			(width 0.068326)
			(type default)
		)
		(layer "F.Cu")
	)
	(gr_line
		(start 211.928964 -40.41394)
		(end 212.149944 -40.19296)
		(stroke
			(width 0.068326)
			(type default)
		)
		(layer "F.Cu")
	)
	(gr_line
		(start 212.792056 -211.975954)
		(end 213.073742 -211.694268)
		(stroke
			(width 0.068326)
			(type default)
		)
		(layer "F.Cu")
	)
	(gr_line
		(start 212.893656 -210.896454)
		(end 213.030308 -211.033106)
		(stroke
			(width 0.068326)
			(type default)
		)
		(layer "F.Cu")
	)
	(gr_line
		(start 212.900006 -224.828608)
		(end 212.900006 -225.54438)
		(stroke
			(width 0.068326)
			(type default)
		)
		(layer "F.Cu")
	)
	(gr_line
		(start 212.900006 -224.828608)
		(end 212.90026 -224.828354)
		(stroke
			(width 0.068326)
			(type default)
		)
		(layer "F.Cu")
	)
	(gr_line
		(start 213.038944 -41.069514)
		(end 213.259924 -40.848534)
		(stroke
			(width 0.068326)
			(type default)
		)
		(layer "F.Cu")
	)
	(gr_line
		(start 213.038944 -40.19296)
		(end 213.259924 -40.41394)
		(stroke
			(width 0.068326)
			(type default)
		)
		(layer "F.Cu")
	)
	(gr_arc
		(start 213.068408 -224.32264)
		(mid 212.943384 -224.561884)
		(end 212.90026 -224.828354)
		(stroke
			(width 0.068326)
			(type default)
		)
		(layer "F.Cu")
	)
	(gr_arc
		(start 213.068408 -224.32264)
		(mid 213.127042 -224.234888)
		(end 213.147656 -224.131378)
		(stroke
			(width 0.068326)
			(type default)
		)
		(layer "F.Cu")
	)
	(gr_arc
		(start 213.073742 -211.694268)
		(mid 213.123733 -211.619452)
		(end 213.141306 -211.5312)
		(stroke
			(width 0.068326)
			(type default)
		)
		(layer "F.Cu")
	)
	(gr_arc
		(start 213.141306 -211.301076)
		(mid 213.112459 -211.156051)
		(end 213.030308 -211.033106)
		(stroke
			(width 0.068326)
			(type default)
		)
		(layer "F.Cu")
	)
	(gr_arc
		(start 213.147656 -213.723474)
		(mid 213.055237 -213.25885)
		(end 212.792056 -212.864954)
		(stroke
			(width 0.068326)
			(type default)
		)
		(layer "F.Cu")
	)
	(gr_arc
		(start 213.446106 -211.5312)
		(mid 213.461388 -211.607655)
		(end 213.50478 -211.672424)
		(stroke
			(width 0.068326)
			(type default)
		)
		(layer "F.Cu")
	)
	(gr_arc
		(start 213.45271 -224.133664)
		(mid 213.47288 -224.234826)
		(end 213.53018 -224.320608)
		(stroke
			(width 0.068326)
			(type default)
		)
		(layer "F.Cu")
	)
	(gr_line
		(start 213.50478 -211.672424)
		(end 213.808056 -211.975954)
		(stroke
			(width 0.068326)
			(type default)
		)
		(layer "F.Cu")
	)
	(gr_arc
		(start 213.548214 -211.05495)
		(mid 213.472689 -211.167863)
		(end 213.446106 -211.301076)
		(stroke
			(width 0.068326)
			(type default)
		)
		(layer "F.Cu")
	)
	(gr_line
		(start 213.548214 -211.05495)
		(end 213.706456 -210.896454)
		(stroke
			(width 0.068326)
			(type default)
		)
		(layer "F.Cu")
	)
	(gr_arc
		(start 213.700106 -224.828354)
		(mid 213.656469 -224.560646)
		(end 213.53018 -224.320608)
		(stroke
			(width 0.068326)
			(type default)
		)
		(layer "F.Cu")
	)
	(gr_line
		(start 213.700106 -224.828354)
		(end 213.700106 -225.54438)
		(stroke
			(width 0.068326)
			(type default)
		)
		(layer "F.Cu")
	)
	(gr_arc
		(start 213.808056 -212.864954)
		(mid 213.545069 -213.258486)
		(end 213.45271 -213.722712)
		(stroke
			(width 0.068326)
			(type default)
		)
		(layer "F.Cu")
	)
	(gr_line
		(start 214.434674 -40.78605)
		(end 214.587582 -40.938958)
		(stroke
			(width 0.068326)
			(type default)
		)
		(layer "F.Cu")
	)
	(gr_line
		(start 214.587582 -40.938958)
		(end 214.997538 -40.938958)
		(stroke
			(width 0.068326)
			(type default)
		)
		(layer "F.Cu")
	)
	(gr_line
		(start 214.739474 -40.47871)
		(end 214.845646 -40.47871)
		(stroke
			(width 0.068326)
			(type default)
		)
		(layer "F.Cu")
	)
	(gr_line
		(start 214.997538 -40.938958)
		(end 215.150446 -40.78605)
		(stroke
			(width 0.068326)
			(type default)
		)
		(layer "F.Cu")
	)
	(gr_line
		(start 215.21801 -48.313086)
		(end 215.243156 -48.31842)
		(stroke
			(width 0.068326)
			(type default)
		)
		(layer "F.Cu")
	)
	(gr_line
		(start 215.243156 -48.31842)
		(end 215.268302 -48.313086)
		(stroke
			(width 0.068326)
			(type default)
		)
		(layer "F.Cu")
	)
	(gr_line
		(start 215.565482 -40.78605)
		(end 215.71839 -40.938958)
		(stroke
			(width 0.068326)
			(type default)
		)
		(layer "F.Cu")
	)
	(gr_line
		(start 215.61806 -47.927006)
		(end 216.249758 -47.79264)
		(stroke
			(width 0.068326)
			(type default)
		)
		(layer "F.Cu")
	)
	(gr_line
		(start 215.647016 -48.235108)
		(end 215.828626 -48.352964)
		(stroke
			(width 0.068326)
			(type default)
		)
		(layer "F.Cu")
	)
	(gr_line
		(start 215.71839 -40.938958)
		(end 216.128346 -40.938958)
		(stroke
			(width 0.068326)
			(type default)
		)
		(layer "F.Cu")
	)
	(gr_line
		(start 215.828626 -48.352964)
		(end 216.229438 -48.26762)
		(stroke
			(width 0.068326)
			(type default)
		)
		(layer "F.Cu")
	)
	(gr_line
		(start 215.870282 -40.47871)
		(end 215.976454 -40.47871)
		(stroke
			(width 0.068326)
			(type default)
		)
		(layer "F.Cu")
	)
	(gr_line
		(start 215.991948 -211.975954)
		(end 216.273634 -211.694268)
		(stroke
			(width 0.068326)
			(type default)
		)
		(layer "F.Cu")
	)
	(gr_line
		(start 216.093548 -210.896454)
		(end 216.248996 -211.052156)
		(stroke
			(width 0.068326)
			(type default)
		)
		(layer "F.Cu")
	)
	(gr_line
		(start 216.100152 -224.828354)
		(end 216.100152 -225.54438)
		(stroke
			(width 0.068326)
			(type default)
		)
		(layer "F.Cu")
	)
	(gr_line
		(start 216.128346 -40.938958)
		(end 216.281254 -40.78605)
		(stroke
			(width 0.068326)
			(type default)
		)
		(layer "F.Cu")
	)
	(gr_line
		(start 216.229438 -48.26762)
		(end 216.347548 -48.086264)
		(stroke
			(width 0.068326)
			(type default)
		)
		(layer "F.Cu")
	)
	(gr_arc
		(start 216.2683 -224.32264)
		(mid 216.143277 -224.561884)
		(end 216.100152 -224.828354)
		(stroke
			(width 0.068326)
			(type default)
		)
		(layer "F.Cu")
	)
	(gr_arc
		(start 216.2683 -224.32264)
		(mid 216.326934 -224.234888)
		(end 216.347548 -224.131378)
		(stroke
			(width 0.068326)
			(type default)
		)
		(layer "F.Cu")
	)
	(gr_arc
		(start 216.273634 -211.694268)
		(mid 216.323625 -211.619452)
		(end 216.341198 -211.5312)
		(stroke
			(width 0.068326)
			(type default)
		)
		(layer "F.Cu")
	)
	(gr_arc
		(start 216.341198 -211.274406)
		(mid 216.317179 -211.154124)
		(end 216.248996 -211.052156)
		(stroke
			(width 0.068326)
			(type default)
		)
		(layer "F.Cu")
	)
	(gr_arc
		(start 216.347548 -213.723474)
		(mid 216.255129 -213.25885)
		(end 215.991948 -212.864954)
		(stroke
			(width 0.068326)
			(type default)
		)
		(layer "F.Cu")
	)
	(gr_arc
		(start 216.645998 -211.5312)
		(mid 216.661279 -211.607656)
		(end 216.704672 -211.672424)
		(stroke
			(width 0.068326)
			(type default)
		)
		(layer "F.Cu")
	)
	(gr_arc
		(start 216.652602 -224.133664)
		(mid 216.672772 -224.234827)
		(end 216.730072 -224.320608)
		(stroke
			(width 0.068326)
			(type default)
		)
		(layer "F.Cu")
	)
	(gr_line
		(start 216.69629 -40.78605)
		(end 216.849198 -40.938958)
		(stroke
			(width 0.068326)
			(type default)
		)
		(layer "F.Cu")
	)
	(gr_line
		(start 216.704672 -211.672424)
		(end 217.007948 -211.975954)
		(stroke
			(width 0.068326)
			(type default)
		)
		(layer "F.Cu")
	)
	(gr_line
		(start 216.724484 -47.691802)
		(end 217.355166 -47.55769)
		(stroke
			(width 0.068326)
			(type default)
		)
		(layer "F.Cu")
	)
	(gr_arc
		(start 216.729056 -211.073492)
		(mid 216.667548 -211.165686)
		(end 216.645998 -211.274406)
		(stroke
			(width 0.068326)
			(type default)
		)
		(layer "F.Cu")
	)
	(gr_line
		(start 216.729056 -211.073492)
		(end 216.906348 -210.896454)
		(stroke
			(width 0.068326)
			(type default)
		)
		(layer "F.Cu")
	)
	(gr_line
		(start 216.753186 -47.999904)
		(end 216.934542 -48.118014)
		(stroke
			(width 0.068326)
			(type default)
		)
		(layer "F.Cu")
	)
	(gr_line
		(start 216.849198 -40.938958)
		(end 217.259154 -40.938958)
		(stroke
			(width 0.068326)
			(type default)
		)
		(layer "F.Cu")
	)
	(gr_arc
		(start 216.899998 -224.828354)
		(mid 216.856361 -224.560646)
		(end 216.730072 -224.320608)
		(stroke
			(width 0.068326)
			(type default)
		)
		(layer "F.Cu")
	)
	(gr_line
		(start 216.899998 -224.828354)
		(end 216.899998 -225.54438)
		(stroke
			(width 0.068326)
			(type default)
		)
		(layer "F.Cu")
	)
	(gr_line
		(start 216.934542 -48.118014)
		(end 217.335608 -48.03267)
		(stroke
			(width 0.068326)
			(type default)
		)
		(layer "F.Cu")
	)
	(gr_line
		(start 217.00109 -40.47871)
		(end 217.107262 -40.47871)
		(stroke
			(width 0.068326)
			(type default)
		)
		(layer "F.Cu")
	)
	(gr_arc
		(start 217.007948 -212.864954)
		(mid 216.744963 -213.258486)
		(end 216.652602 -213.722712)
		(stroke
			(width 0.068326)
			(type default)
		)
		(layer "F.Cu")
	)
	(gr_line
		(start 217.259154 -40.938958)
		(end 217.412062 -40.78605)
		(stroke
			(width 0.068326)
			(type default)
		)
		(layer "F.Cu")
	)
	(gr_line
		(start 217.335608 -48.03267)
		(end 217.453718 -47.85106)
		(stroke
			(width 0.068326)
			(type default)
		)
		(layer "F.Cu")
	)
	(gr_line
		(start 217.781124 -201.826876)
		(end 217.781124 -202.602592)
		(stroke
			(width 0.060198)
			(type default)
		)
		(layer "F.Cu")
	)
	(gr_line
		(start 217.781124 -201.826876)
		(end 217.932 -201.676)
		(stroke
			(width 0.060198)
			(type default)
		)
		(layer "F.Cu")
	)
	(gr_line
		(start 217.932 -201.676)
		(end 217.93454 -201.67346)
		(stroke
			(width 0.060198)
			(type default)
		)
		(layer "F.Cu")
	)
	(gr_line
		(start 217.93454 -201.67346)
		(end 218.292934 -201.67346)
		(stroke
			(width 0.060198)
			(type default)
		)
		(layer "F.Cu")
	)
	(gr_line
		(start 218.295474 -201.67346)
		(end 218.458288 -201.67346)
		(stroke
			(width 0.060198)
			(type default)
		)
		(layer "F.Cu")
	)
	(gr_arc
		(start 218.713812 -47.269146)
		(mid 218.739942 -47.260764)
		(end 218.76385 -47.247302)
		(stroke
			(width 0.068326)
			(type default)
		)
		(layer "F.Cu")
	)
	(gr_line
		(start 218.728544 -201.139552)
		(end 218.728544 -201.399902)
		(stroke
			(width 0.060198)
			(type default)
		)
		(layer "F.Cu")
	)
	(gr_line
		(start 218.728544 -201.139552)
		(end 219.300044 -200.568052)
		(stroke
			(width 0.060198)
			(type default)
		)
		(layer "F.Cu")
	)
	(gr_line
		(start 218.797124 -202.17765)
		(end 218.797124 -202.602592)
		(stroke
			(width 0.060198)
			(type default)
		)
		(layer "F.Cu")
	)
	(gr_line
		(start 218.797124 -202.0443)
		(end 218.797124 -202.17511)
		(stroke
			(width 0.060198)
			(type default)
		)
		(layer "F.Cu")
	)
	(gr_line
		(start 218.81465 -47.559468)
		(end 218.864942 -47.5488)
		(stroke
			(width 0.068326)
			(type default)
		)
		(layer "F.Cu")
	)
	(gr_line
		(start 218.864942 -47.5488)
		(end 218.907614 -47.519082)
		(stroke
			(width 0.068326)
			(type default)
		)
		(layer "F.Cu")
	)
	(gr_line
		(start 219.296996 -201.382884)
		(end 219.296996 -201.544428)
		(stroke
			(width 0.060198)
			(type default)
		)
		(layer "F.Cu")
	)
	(gr_line
		(start 219.296996 -201.382884)
		(end 219.950284 -200.729596)
		(stroke
			(width 0.060198)
			(type default)
		)
		(layer "F.Cu")
	)
	(gr_line
		(start 219.300044 -199.770492)
		(end 219.300044 -200.568052)
		(stroke
			(width 0.060198)
			(type default)
		)
		(layer "F.Cu")
	)
	(gr_line
		(start 219.6592 -179.7558)
		(end 219.734384 -179.830984)
		(stroke
			(width 0.060198)
			(type default)
		)
		(layer "F.Cu")
	)
	(gr_line
		(start 219.950284 -199.770492)
		(end 219.950284 -200.729596)
		(stroke
			(width 0.060198)
			(type default)
		)
		(layer "F.Cu")
	)
	(gr_line
		(start 220.447616 -179.830984)
		(end 220.5228 -179.7558)
		(stroke
			(width 0.060198)
			(type default)
		)
		(layer "F.Cu")
	)
	(gr_line
		(start 221.120462 -42.948606)
		(end 221.246192 -43.074336)
		(stroke
			(width 0.068326)
			(type default)
		)
		(layer "F.Cu")
	)
	(gr_line
		(start 221.246192 -43.074336)
		(end 221.263972 -43.092116)
		(stroke
			(width 0.0508)
			(type default)
		)
		(layer "F.Cu")
	)
	(gr_line
		(start 221.263972 -43.092116)
		(end 221.273878 -43.092116)
		(stroke
			(width 0.0508)
			(type default)
		)
		(layer "F.Cu")
	)
	(gr_line
		(start 221.276418 -43.092116)
		(end 221.3356 -43.092116)
		(stroke
			(width 0.0508)
			(type default)
		)
		(layer "F.Cu")
	)
	(gr_line
		(start 221.3102 -44.651168)
		(end 221.317058 -44.64431)
		(stroke
			(width 0.0508)
			(type default)
		)
		(layer "F.Cu")
	)
	(gr_line
		(start 221.3102 -44.346368)
		(end 221.317058 -44.353226)
		(stroke
			(width 0.0508)
			(type default)
		)
		(layer "F.Cu")
	)
	(gr_line
		(start 221.318836 -44.642532)
		(end 221.361 -44.600368)
		(stroke
			(width 0.0508)
			(type default)
		)
		(layer "F.Cu")
	)
	(gr_line
		(start 221.318836 -44.355004)
		(end 221.361 -44.397168)
		(stroke
			(width 0.0508)
			(type default)
		)
		(layer "F.Cu")
	)
	(gr_line
		(start 221.320614 -45.45711)
		(end 221.332806 -45.448728)
		(stroke
			(width 0.068326)
			(type default)
		)
		(layer "F.Cu")
	)
	(gr_arc
		(start 221.411292 -45.42409)
		(mid 221.37016 -45.430386)
		(end 221.332806 -45.448728)
		(stroke
			(width 0.068326)
			(type default)
		)
		(layer "F.Cu")
	)
	(gr_line
		(start 221.461838 -42.85869)
		(end 221.479618 -42.87647)
		(stroke
			(width 0.0508)
			(type default)
		)
		(layer "F.Cu")
	)
	(gr_line
		(start 221.479618 -42.948606)
		(end 221.605348 -43.074336)
		(stroke
			(width 0.0508)
			(type default)
		)
		(layer "F.Cu")
	)
	(gr_line
		(start 221.479618 -42.888916)
		(end 221.479618 -42.948606)
		(stroke
			(width 0.0508)
			(type default)
		)
		(layer "F.Cu")
	)
	(gr_line
		(start 221.479618 -42.87647)
		(end 221.479618 -42.886376)
		(stroke
			(width 0.0508)
			(type default)
		)
		(layer "F.Cu")
	)
	(gr_line
		(start 222.10014 -58.499756)
		(end 222.600012 -57.999884)
		(stroke
			(width 0.068326)
			(type default)
		)
		(layer "F.Cu")
	)
	(gr_line
		(start 222.10014 -56.49976)
		(end 222.600012 -55.999888)
		(stroke
			(width 0.068326)
			(type default)
		)
		(layer "F.Cu")
	)
	(gr_line
		(start 222.10014 -54.499764)
		(end 222.600012 -53.999892)
		(stroke
			(width 0.068326)
			(type default)
		)
		(layer "F.Cu")
	)
	(gr_line
		(start 222.10014 -52.499768)
		(end 222.600012 -51.999896)
		(stroke
			(width 0.068326)
			(type default)
		)
		(layer "F.Cu")
	)
	(gr_line
		(start 222.10014 -49.499774)
		(end 222.600012 -48.999902)
		(stroke
			(width 0.068326)
			(type default)
		)
		(layer "F.Cu")
	)
	(gr_line
		(start 222.10014 -39.500048)
		(end 222.600012 -39.99992)
		(stroke
			(width 0.068326)
			(type default)
		)
		(layer "F.Cu")
	)
	(gr_line
		(start 222.10014 -37.500052)
		(end 222.600012 -37.999924)
		(stroke
			(width 0.068326)
			(type default)
		)
		(layer "F.Cu")
	)
	(gr_line
		(start 222.10014 -35.500056)
		(end 222.600012 -35.999928)
		(stroke
			(width 0.068326)
			(type default)
		)
		(layer "F.Cu")
	)
	(gr_line
		(start 222.10014 -33.50006)
		(end 222.600012 -33.999932)
		(stroke
			(width 0.068326)
			(type default)
		)
		(layer "F.Cu")
	)
	(gr_line
		(start 222.10014 -31.500064)
		(end 222.600012 -31.999936)
		(stroke
			(width 0.068326)
			(type default)
		)
		(layer "F.Cu")
	)
	(gr_line
		(start 222.10014 -30.500066)
		(end 222.600012 -30.999938)
		(stroke
			(width 0.068326)
			(type default)
		)
		(layer "F.Cu")
	)
	(gr_arc
		(start 222.205042 -46.4566)
		(mid 222.148276 -46.467891)
		(end 222.10014 -46.500034)
		(stroke
			(width 0.068326)
			(type default)
		)
		(layer "F.Cu")
	)
	(gr_line
		(start 222.205042 -46.4566)
		(end 222.380556 -46.4566)
		(stroke
			(width 0.068326)
			(type default)
		)
		(layer "F.Cu")
	)
	(gr_arc
		(start 222.586296 -46.594014)
		(mid 222.504255 -46.494126)
		(end 222.380556 -46.4566)
		(stroke
			(width 0.068326)
			(type default)
		)
		(layer "F.Cu")
	)
	(gr_line
		(start 222.586296 -46.594014)
		(end 222.593408 -46.611032)
		(stroke
			(width 0.068326)
			(type default)
		)
		(layer "F.Cu")
	)
	(gr_arc
		(start 222.600012 -46.644306)
		(mid 222.598379 -46.627336)
		(end 222.593408 -46.611032)
		(stroke
			(width 0.068326)
			(type default)
		)
		(layer "F.Cu")
	)
	(gr_line
		(start 222.600012 -46.644306)
		(end 222.600012 -46.999906)
		(stroke
			(width 0.068326)
			(type default)
		)
		(layer "F.Cu")
	)
	(gr_line
		(start 223.100138 -66.49974)
		(end 223.60001 -65.999868)
		(stroke
			(width 0.068326)
			(type default)
		)
		(layer "F.Cu")
	)
	(gr_line
		(start 223.100138 -65.499742)
		(end 223.60001 -64.99987)
		(stroke
			(width 0.068326)
			(type default)
		)
		(layer "F.Cu")
	)
	(gr_line
		(start 223.100138 -63.499746)
		(end 223.60001 -62.999874)
		(stroke
			(width 0.068326)
			(type default)
		)
		(layer "F.Cu")
	)
	(gr_line
		(start 223.100138 -62.499748)
		(end 223.60001 -61.999876)
		(stroke
			(width 0.068326)
			(type default)
		)
		(layer "F.Cu")
	)
	(gr_line
		(start 223.100138 -59.499754)
		(end 223.60001 -58.999882)
		(stroke
			(width 0.068326)
			(type default)
		)
		(layer "F.Cu")
	)
	(gr_line
		(start 223.100138 -58.499756)
		(end 223.60001 -57.999884)
		(stroke
			(width 0.068326)
			(type default)
		)
		(layer "F.Cu")
	)
	(gr_line
		(start 223.100138 -57.499758)
		(end 223.60001 -56.999886)
		(stroke
			(width 0.068326)
			(type default)
		)
		(layer "F.Cu")
	)
	(gr_line
		(start 223.100138 -56.49976)
		(end 223.60001 -55.999888)
		(stroke
			(width 0.068326)
			(type default)
		)
		(layer "F.Cu")
	)
	(gr_line
		(start 223.100138 -55.499762)
		(end 223.60001 -54.99989)
		(stroke
			(width 0.068326)
			(type default)
		)
		(layer "F.Cu")
	)
	(gr_line
		(start 223.100138 -54.499764)
		(end 223.60001 -53.999892)
		(stroke
			(width 0.068326)
			(type default)
		)
		(layer "F.Cu")
	)
	(gr_line
		(start 223.100138 -53.499766)
		(end 223.60001 -52.999894)
		(stroke
			(width 0.068326)
			(type default)
		)
		(layer "F.Cu")
	)
	(gr_line
		(start 223.100138 -52.499768)
		(end 223.60001 -51.999896)
		(stroke
			(width 0.068326)
			(type default)
		)
		(layer "F.Cu")
	)
	(gr_line
		(start 223.100138 -50.499772)
		(end 223.60001 -49.9999)
		(stroke
			(width 0.068326)
			(type default)
		)
		(layer "F.Cu")
	)
	(gr_line
		(start 223.100138 -49.499774)
		(end 223.60001 -48.999902)
		(stroke
			(width 0.068326)
			(type default)
		)
		(layer "F.Cu")
	)
	(gr_line
		(start 223.100138 -48.499776)
		(end 223.60001 -47.999904)
		(stroke
			(width 0.068326)
			(type default)
		)
		(layer "F.Cu")
	)
	(gr_line
		(start 223.100138 -46.500034)
		(end 223.60001 -46.999906)
		(stroke
			(width 0.068326)
			(type default)
		)
		(layer "F.Cu")
	)
	(gr_line
		(start 223.100138 -40.500046)
		(end 223.60001 -40.999918)
		(stroke
			(width 0.068326)
			(type default)
		)
		(layer "F.Cu")
	)
	(gr_line
		(start 223.100138 -39.500048)
		(end 223.60001 -39.99992)
		(stroke
			(width 0.068326)
			(type default)
		)
		(layer "F.Cu")
	)
	(gr_line
		(start 223.100138 -38.50005)
		(end 223.60001 -38.999922)
		(stroke
			(width 0.068326)
			(type default)
		)
		(layer "F.Cu")
	)
	(gr_line
		(start 223.100138 -37.500052)
		(end 223.60001 -37.999924)
		(stroke
			(width 0.068326)
			(type default)
		)
		(layer "F.Cu")
	)
	(gr_line
		(start 223.100138 -36.500054)
		(end 223.60001 -36.999926)
		(stroke
			(width 0.068326)
			(type default)
		)
		(layer "F.Cu")
	)
	(gr_line
		(start 223.100138 -35.500056)
		(end 223.60001 -35.999928)
		(stroke
			(width 0.068326)
			(type default)
		)
		(layer "F.Cu")
	)
	(gr_line
		(start 223.100138 -34.500058)
		(end 223.60001 -34.99993)
		(stroke
			(width 0.068326)
			(type default)
		)
		(layer "F.Cu")
	)
	(gr_line
		(start 223.100138 -33.50006)
		(end 223.60001 -33.999932)
		(stroke
			(width 0.068326)
			(type default)
		)
		(layer "F.Cu")
	)
	(gr_line
		(start 223.100138 -30.500066)
		(end 223.60001 -30.999938)
		(stroke
			(width 0.068326)
			(type default)
		)
		(layer "F.Cu")
	)
	(gr_line
		(start 223.100138 -29.500068)
		(end 223.60001 -29.99994)
		(stroke
			(width 0.068326)
			(type default)
		)
		(layer "F.Cu")
	)
	(gr_arc
		(start 223.303846 -45.736256)
		(mid 223.285792 -45.730778)
		(end 223.267016 -45.72889)
		(stroke
			(width 0.068326)
			(type default)
		)
		(layer "F.Cu")
	)
	(gr_arc
		(start 223.402398 -45.802042)
		(mid 223.356371 -45.764281)
		(end 223.303846 -45.736256)
		(stroke
			(width 0.068326)
			(type default)
		)
		(layer "F.Cu")
	)
	(gr_line
		(start 223.402398 -45.802042)
		(end 223.60001 -45.999908)
		(stroke
			(width 0.068326)
			(type default)
		)
		(layer "F.Cu")
	)
	(gr_line
		(start 223.60001 -43.999912)
		(end 223.818196 -43.999912)
		(stroke
			(width 0.0508)
			(type default)
		)
		(layer "F.Cu")
	)
	(gr_line
		(start 224.100136 -65.499742)
		(end 224.600008 -64.99987)
		(stroke
			(width 0.068326)
			(type default)
		)
		(layer "F.Cu")
	)
	(gr_line
		(start 224.100136 -64.499744)
		(end 224.600008 -63.999872)
		(stroke
			(width 0.068326)
			(type default)
		)
		(layer "F.Cu")
	)
	(gr_line
		(start 224.100136 -62.499748)
		(end 224.600008 -61.999876)
		(stroke
			(width 0.068326)
			(type default)
		)
		(layer "F.Cu")
	)
	(gr_line
		(start 224.100136 -61.49975)
		(end 224.600008 -60.999878)
		(stroke
			(width 0.068326)
			(type default)
		)
		(layer "F.Cu")
	)
	(gr_line
		(start 224.100136 -59.499754)
		(end 224.600008 -58.999882)
		(stroke
			(width 0.068326)
			(type default)
		)
		(layer "F.Cu")
	)
	(gr_line
		(start 224.100136 -57.499758)
		(end 224.600008 -56.999886)
		(stroke
			(width 0.068326)
			(type default)
		)
		(layer "F.Cu")
	)
	(gr_line
		(start 224.100136 -55.499762)
		(end 224.600008 -54.99989)
		(stroke
			(width 0.068326)
			(type default)
		)
		(layer "F.Cu")
	)
	(gr_line
		(start 224.100136 -53.499766)
		(end 224.600008 -52.999894)
		(stroke
			(width 0.068326)
			(type default)
		)
		(layer "F.Cu")
	)
	(gr_line
		(start 224.100136 -50.499772)
		(end 224.600008 -49.9999)
		(stroke
			(width 0.068326)
			(type default)
		)
		(layer "F.Cu")
	)
	(gr_line
		(start 224.100136 -48.499776)
		(end 224.600008 -47.999904)
		(stroke
			(width 0.068326)
			(type default)
		)
		(layer "F.Cu")
	)
	(gr_line
		(start 224.100136 -40.500046)
		(end 224.600008 -40.999918)
		(stroke
			(width 0.068326)
			(type default)
		)
		(layer "F.Cu")
	)
	(gr_line
		(start 224.100136 -38.50005)
		(end 224.600008 -38.999922)
		(stroke
			(width 0.068326)
			(type default)
		)
		(layer "F.Cu")
	)
	(gr_line
		(start 224.100136 -36.500054)
		(end 224.600008 -36.999926)
		(stroke
			(width 0.068326)
			(type default)
		)
		(layer "F.Cu")
	)
	(gr_line
		(start 224.100136 -34.500058)
		(end 224.600008 -34.99993)
		(stroke
			(width 0.068326)
			(type default)
		)
		(layer "F.Cu")
	)
	(gr_line
		(start 224.100136 -30.500066)
		(end 224.600008 -30.999938)
		(stroke
			(width 0.068326)
			(type default)
		)
		(layer "F.Cu")
	)
	(gr_line
		(start 224.1042 -31.504128)
		(end 224.600008 -31.999936)
		(stroke
			(width 0.068326)
			(type default)
		)
		(layer "F.Cu")
	)
	(gr_arc
		(start 224.201482 -43.819826)
		(mid 224.254228 -43.947166)
		(end 224.381568 -43.999912)
		(stroke
			(width 0.0508)
			(type default)
		)
		(layer "F.Cu")
	)
	(gr_line
		(start 224.381568 -43.999912)
		(end 224.600008 -43.999912)
		(stroke
			(width 0.0508)
			(type default)
		)
		(layer "F.Cu")
	)
	(gr_arc
		(start 224.600008 -45.999908)
		(mid 223.962206 -45.573742)
		(end 223.209866 -45.42409)
		(stroke
			(width 0.068326)
			(type default)
		)
		(layer "F.Cu")
	)
	(gr_line
		(start 225.100134 -66.49974)
		(end 225.600006 -65.999868)
		(stroke
			(width 0.068326)
			(type default)
		)
		(layer "F.Cu")
	)
	(gr_line
		(start 225.100134 -65.499742)
		(end 225.600006 -64.99987)
		(stroke
			(width 0.068326)
			(type default)
		)
		(layer "F.Cu")
	)
	(gr_line
		(start 225.100134 -63.499746)
		(end 225.600006 -62.999874)
		(stroke
			(width 0.068326)
			(type default)
		)
		(layer "F.Cu")
	)
	(gr_line
		(start 225.100134 -62.499748)
		(end 225.600006 -61.999876)
		(stroke
			(width 0.068326)
			(type default)
		)
		(layer "F.Cu")
	)
	(gr_line
		(start 225.100134 -58.499756)
		(end 225.210116 -58.499756)
		(stroke
			(width 0.068326)
			(type default)
		)
		(layer "F.Cu")
	)
	(gr_line
		(start 225.100134 -56.49976)
		(end 225.347022 -56.446166)
		(stroke
			(width 0.068326)
			(type default)
		)
		(layer "F.Cu")
	)
	(gr_line
		(start 225.100134 -54.499764)
		(end 225.25355 -54.499764)
		(stroke
			(width 0.068326)
			(type default)
		)
		(layer "F.Cu")
	)
	(gr_line
		(start 225.100134 -52.499768)
		(end 225.238056 -52.499768)
		(stroke
			(width 0.068326)
			(type default)
		)
		(layer "F.Cu")
	)
	(gr_line
		(start 225.100134 -49.499774)
		(end 225.227388 -49.499774)
		(stroke
			(width 0.068326)
			(type default)
		)
		(layer "F.Cu")
	)
	(gr_line
		(start 225.100134 -46.500034)
		(end 225.600006 -46.999906)
		(stroke
			(width 0.068326)
			(type default)
		)
		(layer "F.Cu")
	)
	(gr_line
		(start 225.100134 -39.500048)
		(end 225.600006 -39.99992)
		(stroke
			(width 0.068326)
			(type default)
		)
		(layer "F.Cu")
	)
	(gr_line
		(start 225.100134 -37.500052)
		(end 225.600006 -37.999924)
		(stroke
			(width 0.068326)
			(type default)
		)
		(layer "F.Cu")
	)
	(gr_line
		(start 225.100134 -35.500056)
		(end 225.600006 -35.999928)
		(stroke
			(width 0.068326)
			(type default)
		)
		(layer "F.Cu")
	)
	(gr_line
		(start 225.100134 -33.50006)
		(end 225.600006 -33.999932)
		(stroke
			(width 0.068326)
			(type default)
		)
		(layer "F.Cu")
	)
	(gr_line
		(start 225.100134 -30.500066)
		(end 225.600006 -30.999938)
		(stroke
			(width 0.068326)
			(type default)
		)
		(layer "F.Cu")
	)
	(gr_line
		(start 225.100134 -29.500068)
		(end 225.600006 -29.99994)
		(stroke
			(width 0.068326)
			(type default)
		)
		(layer "F.Cu")
	)
	(gr_arc
		(start 225.210116 -58.499756)
		(mid 225.311534 -58.479637)
		(end 225.397568 -58.422286)
		(stroke
			(width 0.068326)
			(type default)
		)
		(layer "F.Cu")
	)
	(gr_arc
		(start 225.227388 -49.499774)
		(mid 225.320575 -49.481182)
		(end 225.3996 -49.4284)
		(stroke
			(width 0.068326)
			(type default)
		)
		(layer "F.Cu")
	)
	(gr_arc
		(start 225.238056 -52.499768)
		(mid 225.365601 -52.474422)
		(end 225.473768 -52.402232)
		(stroke
			(width 0.068326)
			(type default)
		)
		(layer "F.Cu")
	)
	(gr_arc
		(start 225.25355 -54.499764)
		(mid 225.301075 -54.495092)
		(end 225.346768 -54.481222)
		(stroke
			(width 0.068326)
			(type default)
		)
		(layer "F.Cu")
	)
	(gr_line
		(start 225.346768 -54.481222)
		(end 225.400108 -54.459124)
		(stroke
			(width 0.068326)
			(type default)
		)
		(layer "F.Cu")
	)
	(gr_arc
		(start 225.347022 -56.446166)
		(mid 225.480218 -56.383703)
		(end 225.572828 -56.269382)
		(stroke
			(width 0.068326)
			(type default)
		)
		(layer "F.Cu")
	)
	(gr_line
		(start 225.397568 -58.422286)
		(end 225.460052 -58.359802)
		(stroke
			(width 0.068326)
			(type default)
		)
		(layer "F.Cu")
	)
	(gr_line
		(start 225.3996 -49.4284)
		(end 225.438716 -49.389284)
		(stroke
			(width 0.068326)
			(type default)
		)
		(layer "F.Cu")
	)
	(gr_arc
		(start 225.400108 -54.459124)
		(mid 225.483253 -54.403583)
		(end 225.538792 -54.32044)
		(stroke
			(width 0.068326)
			(type default)
		)
		(layer "F.Cu")
	)
	(gr_arc
		(start 225.438716 -49.389284)
		(mid 225.558101 -49.210638)
		(end 225.600006 -48.999902)
		(stroke
			(width 0.068326)
			(type default)
		)
		(layer "F.Cu")
	)
	(gr_arc
		(start 225.460052 -58.359802)
		(mid 225.563692 -58.204561)
		(end 225.600006 -58.021474)
		(stroke
			(width 0.068326)
			(type default)
		)
		(layer "F.Cu")
	)
	(gr_line
		(start 225.473768 -52.402232)
		(end 225.487992 -52.388008)
		(stroke
			(width 0.068326)
			(type default)
		)
		(layer "F.Cu")
	)
	(gr_arc
		(start 225.487992 -52.388008)
		(mid 225.570915 -52.264031)
		(end 225.600006 -52.117752)
		(stroke
			(width 0.068326)
			(type default)
		)
		(layer "F.Cu")
	)
	(gr_line
		(start 225.538792 -54.32044)
		(end 225.575622 -54.231286)
		(stroke
			(width 0.068326)
			(type default)
		)
		(layer "F.Cu")
	)
	(gr_arc
		(start 225.572828 -56.269382)
		(mid 225.59316 -56.212138)
		(end 225.600006 -56.15178)
		(stroke
			(width 0.068326)
			(type default)
		)
		(layer "F.Cu")
	)
	(gr_arc
		(start 225.575622 -54.231286)
		(mid 225.593832 -54.171013)
		(end 225.600006 -54.10835)
		(stroke
			(width 0.068326)
			(type default)
		)
		(layer "F.Cu")
	)
	(gr_line
		(start 225.600006 -57.999884)
		(end 225.600006 -58.021474)
		(stroke
			(width 0.068326)
			(type default)
		)
		(layer "F.Cu")
	)
	(gr_line
		(start 225.600006 -55.999888)
		(end 225.600006 -56.15178)
		(stroke
			(width 0.068326)
			(type default)
		)
		(layer "F.Cu")
	)
	(gr_line
		(start 225.600006 -53.999892)
		(end 225.600006 -54.10835)
		(stroke
			(width 0.068326)
			(type default)
		)
		(layer "F.Cu")
	)
	(gr_line
		(start 225.600006 -51.999896)
		(end 225.600006 -52.117752)
		(stroke
			(width 0.068326)
			(type default)
		)
		(layer "F.Cu")
	)
	(gr_line
		(start 226.100132 -65.499742)
		(end 226.600004 -64.99987)
		(stroke
			(width 0.068326)
			(type default)
		)
		(layer "F.Cu")
	)
	(gr_line
		(start 226.100132 -64.499744)
		(end 226.600004 -63.999872)
		(stroke
			(width 0.068326)
			(type default)
		)
		(layer "F.Cu")
	)
	(gr_line
		(start 226.100132 -62.499748)
		(end 226.600004 -61.999876)
		(stroke
			(width 0.068326)
			(type default)
		)
		(layer "F.Cu")
	)
	(gr_line
		(start 226.100132 -61.49975)
		(end 226.600004 -60.999878)
		(stroke
			(width 0.068326)
			(type default)
		)
		(layer "F.Cu")
	)
	(gr_arc
		(start 226.100132 -59.499754)
		(mid 226.300979 -59.499102)
		(end 226.4664 -59.3852)
		(stroke
			(width 0.068326)
			(type default)
		)
		(layer "F.Cu")
	)
	(gr_line
		(start 226.100132 -58.499756)
		(end 226.600004 -57.999884)
		(stroke
			(width 0.068326)
			(type default)
		)
		(layer "F.Cu")
	)
	(gr_line
		(start 226.100132 -57.499758)
		(end 226.233482 -57.499758)
		(stroke
			(width 0.068326)
			(type default)
		)
		(layer "F.Cu")
	)
	(gr_line
		(start 226.100132 -56.49976)
		(end 226.600004 -55.999888)
		(stroke
			(width 0.068326)
			(type default)
		)
		(layer "F.Cu")
	)
	(gr_line
		(start 226.100132 -55.499762)
		(end 226.206812 -55.499762)
		(stroke
			(width 0.068326)
			(type default)
		)
		(layer "F.Cu")
	)
	(gr_line
		(start 226.100132 -54.499764)
		(end 226.600004 -53.999892)
		(stroke
			(width 0.068326)
			(type default)
		)
		(layer "F.Cu")
	)
	(gr_line
		(start 226.100132 -53.499766)
		(end 226.394264 -53.440838)
		(stroke
			(width 0.068326)
			(type default)
		)
		(layer "F.Cu")
	)
	(gr_line
		(start 226.100132 -52.499768)
		(end 226.600004 -51.999896)
		(stroke
			(width 0.068326)
			(type default)
		)
		(layer "F.Cu")
	)
	(gr_line
		(start 226.100132 -50.499772)
		(end 226.260914 -50.499772)
		(stroke
			(width 0.068326)
			(type default)
		)
		(layer "F.Cu")
	)
	(gr_line
		(start 226.100132 -49.499774)
		(end 226.600004 -48.999902)
		(stroke
			(width 0.068326)
			(type default)
		)
		(layer "F.Cu")
	)
	(gr_line
		(start 226.100132 -48.499776)
		(end 226.600004 -47.999904)
		(stroke
			(width 0.068326)
			(type default)
		)
		(layer "F.Cu")
	)
	(gr_line
		(start 226.100132 -46.500034)
		(end 226.600004 -46.999906)
		(stroke
			(width 0.068326)
			(type default)
		)
		(layer "F.Cu")
	)
	(gr_line
		(start 226.100132 -45.500036)
		(end 226.600004 -45.999908)
		(stroke
			(width 0.068326)
			(type default)
		)
		(layer "F.Cu")
	)
	(gr_line
		(start 226.100132 -40.500046)
		(end 226.600004 -40.999918)
		(stroke
			(width 0.068326)
			(type default)
		)
		(layer "F.Cu")
	)
	(gr_line
		(start 226.100132 -39.500048)
		(end 226.600004 -39.99992)
		(stroke
			(width 0.068326)
			(type default)
		)
		(layer "F.Cu")
	)
	(gr_line
		(start 226.100132 -38.50005)
		(end 226.600004 -38.999922)
		(stroke
			(width 0.068326)
			(type default)
		)
		(layer "F.Cu")
	)
	(gr_line
		(start 226.100132 -37.500052)
		(end 226.600004 -37.999924)
		(stroke
			(width 0.068326)
			(type default)
		)
		(layer "F.Cu")
	)
	(gr_line
		(start 226.100132 -36.500054)
		(end 226.600004 -36.999926)
		(stroke
			(width 0.068326)
			(type default)
		)
		(layer "F.Cu")
	)
	(gr_line
		(start 226.100132 -35.500056)
		(end 226.600004 -35.999928)
		(stroke
			(width 0.068326)
			(type default)
		)
		(layer "F.Cu")
	)
	(gr_line
		(start 226.100132 -34.500058)
		(end 226.600004 -34.99993)
		(stroke
			(width 0.068326)
			(type default)
		)
		(layer "F.Cu")
	)
	(gr_line
		(start 226.100132 -33.50006)
		(end 226.600004 -33.999932)
		(stroke
			(width 0.068326)
			(type default)
		)
		(layer "F.Cu")
	)
	(gr_line
		(start 226.100132 -31.500064)
		(end 226.600004 -31.999936)
		(stroke
			(width 0.068326)
			(type default)
		)
		(layer "F.Cu")
	)
	(gr_line
		(start 226.100132 -30.500066)
		(end 226.600004 -30.999938)
		(stroke
			(width 0.068326)
			(type default)
		)
		(layer "F.Cu")
	)
	(gr_arc
		(start 226.206812 -55.499762)
		(mid 226.30525 -55.480146)
		(end 226.388676 -55.424324)
		(stroke
			(width 0.068326)
			(type default)
		)
		(layer "F.Cu")
	)
	(gr_arc
		(start 226.233482 -57.499758)
		(mid 226.27479 -57.495596)
		(end 226.314508 -57.483502)
		(stroke
			(width 0.068326)
			(type default)
		)
		(layer "F.Cu")
	)
	(gr_arc
		(start 226.260914 -50.499772)
		(mid 226.399624 -50.472184)
		(end 226.5172 -50.3936)
		(stroke
			(width 0.068326)
			(type default)
		)
		(layer "F.Cu")
	)
	(gr_line
		(start 226.314 -78.5749)
		(end 226.48164 -78.74254)
		(stroke
			(width 0.060198)
			(type default)
		)
		(layer "F.Cu")
	)
	(gr_line
		(start 226.314508 -57.483502)
		(end 226.395026 -57.450228)
		(stroke
			(width 0.068326)
			(type default)
		)
		(layer "F.Cu")
	)
	(gr_arc
		(start 226.388676 -55.424324)
		(mid 226.442154 -55.359194)
		(end 226.481894 -55.284878)
		(stroke
			(width 0.068326)
			(type default)
		)
		(layer "F.Cu")
	)
	(gr_arc
		(start 226.394264 -53.440838)
		(mid 226.487691 -53.397884)
		(end 226.551998 -53.317648)
		(stroke
			(width 0.068326)
			(type default)
		)
		(layer "F.Cu")
	)
	(gr_arc
		(start 226.395026 -57.450228)
		(mid 226.496375 -57.382569)
		(end 226.56419 -57.281318)
		(stroke
			(width 0.068326)
			(type default)
		)
		(layer "F.Cu")
	)
	(gr_arc
		(start 226.4664 -59.3852)
		(mid 226.565671 -59.203798)
		(end 226.600004 -58.999882)
		(stroke
			(width 0.068326)
			(type default)
		)
		(layer "F.Cu")
	)
	(gr_line
		(start 226.48164 -78.74254)
		(end 226.48164 -80.90154)
		(stroke
			(width 0.060198)
			(type default)
		)
		(layer "F.Cu")
	)
	(gr_line
		(start 226.481894 -55.284878)
		(end 226.600004 -54.99989)
		(stroke
			(width 0.068326)
			(type default)
		)
		(layer "F.Cu")
	)
	(gr_arc
		(start 226.5172 -50.3936)
		(mid 226.578482 -50.301886)
		(end 226.600004 -50.193702)
		(stroke
			(width 0.068326)
			(type default)
		)
		(layer "F.Cu")
	)
	(gr_line
		(start 226.551998 -53.317648)
		(end 226.574604 -53.269896)
		(stroke
			(width 0.068326)
			(type default)
		)
		(layer "F.Cu")
	)
	(gr_line
		(start 226.56419 -57.281318)
		(end 226.57943 -57.244488)
		(stroke
			(width 0.068326)
			(type default)
		)
		(layer "F.Cu")
	)
	(gr_arc
		(start 226.574604 -53.269896)
		(mid 226.593543 -53.215173)
		(end 226.600004 -53.157628)
		(stroke
			(width 0.068326)
			(type default)
		)
		(layer "F.Cu")
	)
	(gr_arc
		(start 226.57943 -57.244488)
		(mid 226.594805 -57.193942)
		(end 226.600004 -57.141364)
		(stroke
			(width 0.068326)
			(type default)
		)
		(layer "F.Cu")
	)
	(gr_line
		(start 226.600004 -56.999886)
		(end 226.600004 -57.141364)
		(stroke
			(width 0.068326)
			(type default)
		)
		(layer "F.Cu")
	)
	(gr_line
		(start 226.600004 -52.999894)
		(end 226.600004 -53.157628)
		(stroke
			(width 0.068326)
			(type default)
		)
		(layer "F.Cu")
	)
	(gr_line
		(start 226.600004 -49.9999)
		(end 226.600004 -50.193702)
		(stroke
			(width 0.068326)
			(type default)
		)
		(layer "F.Cu")
	)
	(gr_line
		(start 226.600004 -43.999912)
		(end 226.974146 -43.999912)
		(stroke
			(width 0.0508)
			(type default)
		)
		(layer "F.Cu")
	)
	(gr_line
		(start 226.974146 -43.999912)
		(end 227.031296 -43.942762)
		(stroke
			(width 0.0508)
			(type default)
		)
		(layer "F.Cu")
	)
	(gr_line
		(start 227.033074 -43.940984)
		(end 227.074476 -43.899582)
		(stroke
			(width 0.0508)
			(type default)
		)
		(layer "F.Cu")
	)
	(gr_line
		(start 227.10013 -66.49974)
		(end 227.600002 -65.999868)
		(stroke
			(width 0.068326)
			(type default)
		)
		(layer "F.Cu")
	)
	(gr_line
		(start 227.10013 -65.499742)
		(end 227.600002 -64.99987)
		(stroke
			(width 0.068326)
			(type default)
		)
		(layer "F.Cu")
	)
	(gr_line
		(start 227.10013 -63.499746)
		(end 227.600002 -62.999874)
		(stroke
			(width 0.068326)
			(type default)
		)
		(layer "F.Cu")
	)
	(gr_line
		(start 227.10013 -62.499748)
		(end 227.600002 -61.999876)
		(stroke
			(width 0.068326)
			(type default)
		)
		(layer "F.Cu")
	)
	(gr_line
		(start 227.10013 -59.499754)
		(end 227.600002 -58.999882)
		(stroke
			(width 0.068326)
			(type default)
		)
		(layer "F.Cu")
	)
	(gr_line
		(start 227.10013 -57.499758)
		(end 227.600002 -56.999886)
		(stroke
			(width 0.068326)
			(type default)
		)
		(layer "F.Cu")
	)
	(gr_line
		(start 227.10013 -55.499762)
		(end 227.600002 -54.99989)
		(stroke
			(width 0.068326)
			(type default)
		)
		(layer "F.Cu")
	)
	(gr_line
		(start 227.10013 -53.499766)
		(end 227.600002 -52.999894)
		(stroke
			(width 0.068326)
			(type default)
		)
		(layer "F.Cu")
	)
	(gr_line
		(start 227.10013 -50.499772)
		(end 227.600002 -49.9999)
		(stroke
			(width 0.068326)
			(type default)
		)
		(layer "F.Cu")
	)
	(gr_line
		(start 227.10013 -48.499776)
		(end 227.600002 -47.999904)
		(stroke
			(width 0.068326)
			(type default)
		)
		(layer "F.Cu")
	)
	(gr_line
		(start 227.10013 -45.500036)
		(end 227.600002 -45.999908)
		(stroke
			(width 0.068326)
			(type default)
		)
		(layer "F.Cu")
	)
	(gr_line
		(start 227.10013 -40.500046)
		(end 227.600002 -40.999918)
		(stroke
			(width 0.068326)
			(type default)
		)
		(layer "F.Cu")
	)
	(gr_line
		(start 227.10013 -38.50005)
		(end 227.600002 -38.999922)
		(stroke
			(width 0.068326)
			(type default)
		)
		(layer "F.Cu")
	)
	(gr_line
		(start 227.10013 -36.500054)
		(end 227.600002 -36.999926)
		(stroke
			(width 0.068326)
			(type default)
		)
		(layer "F.Cu")
	)
	(gr_line
		(start 227.10013 -34.500058)
		(end 227.600002 -34.99993)
		(stroke
			(width 0.068326)
			(type default)
		)
		(layer "F.Cu")
	)
	(gr_line
		(start 227.10013 -30.500066)
		(end 227.600002 -30.999938)
		(stroke
			(width 0.068326)
			(type default)
		)
		(layer "F.Cu")
	)
	(gr_line
		(start 227.10013 -29.500068)
		(end 227.600002 -29.99994)
		(stroke
			(width 0.068326)
			(type default)
		)
		(layer "F.Cu")
	)
	(gr_line
		(start 227.13188 -78.77302)
		(end 227.13188 -80.90154)
		(stroke
			(width 0.060198)
			(type default)
		)
		(layer "F.Cu")
	)
	(gr_line
		(start 227.13188 -78.77302)
		(end 227.33 -78.5749)
		(stroke
			(width 0.060198)
			(type default)
		)
		(layer "F.Cu")
	)
	(gr_line
		(start 227.277676 -43.898058)
		(end 227.320602 -43.940984)
		(stroke
			(width 0.0508)
			(type default)
		)
		(layer "F.Cu")
	)
	(gr_line
		(start 227.32238 -43.942762)
		(end 227.37953 -43.999912)
		(stroke
			(width 0.0508)
			(type default)
		)
		(layer "F.Cu")
	)
	(gr_line
		(start 227.33 -9.144)
		(end 228.346 -9.144)
		(stroke
			(width 0.060198)
			(type default)
		)
		(layer "F.Cu")
	)
	(gr_line
		(start 227.33 -7.874)
		(end 228.346 -7.874)
		(stroke
			(width 0.060198)
			(type default)
		)
		(layer "F.Cu")
	)
	(gr_line
		(start 227.37953 -43.999912)
		(end 227.600002 -43.999912)
		(stroke
			(width 0.0508)
			(type default)
		)
		(layer "F.Cu")
	)
	(gr_line
		(start 228.100128 -65.499742)
		(end 228.6 -64.99987)
		(stroke
			(width 0.068326)
			(type default)
		)
		(layer "F.Cu")
	)
	(gr_line
		(start 228.100128 -64.499744)
		(end 228.6 -63.999872)
		(stroke
			(width 0.068326)
			(type default)
		)
		(layer "F.Cu")
	)
	(gr_line
		(start 228.100128 -62.499748)
		(end 228.6 -61.999876)
		(stroke
			(width 0.068326)
			(type default)
		)
		(layer "F.Cu")
	)
	(gr_line
		(start 228.100128 -61.49975)
		(end 228.6 -60.999878)
		(stroke
			(width 0.068326)
			(type default)
		)
		(layer "F.Cu")
	)
	(gr_line
		(start 228.100128 -31.500064)
		(end 228.6 -31.999936)
		(stroke
			(width 0.068326)
			(type default)
		)
		(layer "F.Cu")
	)
	(gr_line
		(start 228.100128 -30.500066)
		(end 228.6 -30.999938)
		(stroke
			(width 0.068326)
			(type default)
		)
		(layer "F.Cu")
	)
	(gr_line
		(start 228.346 -9.144)
		(end 228.854 -8.636)
		(stroke
			(width 0.060198)
			(type default)
		)
		(layer "F.Cu")
	)
	(gr_line
		(start 228.346 -7.874)
		(end 228.854 -7.366)
		(stroke
			(width 0.060198)
			(type default)
		)
		(layer "F.Cu")
	)
	(gr_line
		(start 228.854 -8.636)
		(end 229.108 -8.382)
		(stroke
			(width 0.060198)
			(type default)
		)
		(layer "F.Cu")
	)
	(gr_line
		(start 228.854 -7.366)
		(end 229.8065 -7.366)
		(stroke
			(width 0.060198)
			(type default)
		)
		(layer "F.Cu")
	)
	(gr_line
		(start 229.100126 -66.49974)
		(end 229.599998 -65.999868)
		(stroke
			(width 0.068326)
			(type default)
		)
		(layer "F.Cu")
	)
	(gr_line
		(start 229.100126 -65.499742)
		(end 229.599998 -64.99987)
		(stroke
			(width 0.068326)
			(type default)
		)
		(layer "F.Cu")
	)
	(gr_line
		(start 229.100126 -63.499746)
		(end 229.599998 -62.999874)
		(stroke
			(width 0.068326)
			(type default)
		)
		(layer "F.Cu")
	)
	(gr_line
		(start 229.100126 -62.499748)
		(end 229.599998 -61.999876)
		(stroke
			(width 0.068326)
			(type default)
		)
		(layer "F.Cu")
	)
	(gr_line
		(start 229.100126 -30.500066)
		(end 229.599998 -30.999938)
		(stroke
			(width 0.068326)
			(type default)
		)
		(layer "F.Cu")
	)
	(gr_line
		(start 229.100126 -29.500068)
		(end 229.599998 -29.99994)
		(stroke
			(width 0.068326)
			(type default)
		)
		(layer "F.Cu")
	)
	(gr_line
		(start 229.108 -8.382)
		(end 229.8065 -8.382)
		(stroke
			(width 0.060198)
			(type default)
		)
		(layer "F.Cu")
	)
	(gr_line
		(start 230.100124 -65.499742)
		(end 230.599996 -64.99987)
		(stroke
			(width 0.068326)
			(type default)
		)
		(layer "F.Cu")
	)
	(gr_line
		(start 230.100124 -64.499744)
		(end 230.599996 -63.999872)
		(stroke
			(width 0.068326)
			(type default)
		)
		(layer "F.Cu")
	)
	(gr_line
		(start 230.100124 -62.499748)
		(end 230.599996 -61.999876)
		(stroke
			(width 0.068326)
			(type default)
		)
		(layer "F.Cu")
	)
	(gr_line
		(start 230.100124 -61.49975)
		(end 230.599996 -60.999878)
		(stroke
			(width 0.068326)
			(type default)
		)
		(layer "F.Cu")
	)
	(gr_line
		(start 230.6955 -8.382)
		(end 230.846884 -8.230616)
		(stroke
			(width 0.060198)
			(type default)
		)
		(layer "F.Cu")
	)
	(gr_line
		(start 230.6955 -7.366)
		(end 230.846884 -7.517384)
		(stroke
			(width 0.060198)
			(type default)
		)
		(layer "F.Cu")
	)
	(gr_line
		(start 231.100122 -31.500064)
		(end 231.599994 -31.999936)
		(stroke
			(width 0.068326)
			(type default)
		)
		(layer "F.Cu")
	)
	(gr_line
		(start 231.100122 -30.500066)
		(end 231.599994 -30.999938)
		(stroke
			(width 0.068326)
			(type default)
		)
		(layer "F.Cu")
	)
	(gr_line
		(start 232.10012 -66.49974)
		(end 232.599992 -65.999868)
		(stroke
			(width 0.068326)
			(type default)
		)
		(layer "F.Cu")
	)
	(gr_line
		(start 232.10012 -65.499742)
		(end 232.599992 -64.99987)
		(stroke
			(width 0.068326)
			(type default)
		)
		(layer "F.Cu")
	)
	(gr_line
		(start 232.10012 -63.499746)
		(end 232.599992 -62.999874)
		(stroke
			(width 0.068326)
			(type default)
		)
		(layer "F.Cu")
	)
	(gr_line
		(start 232.10012 -62.499748)
		(end 232.599992 -61.999876)
		(stroke
			(width 0.068326)
			(type default)
		)
		(layer "F.Cu")
	)
	(gr_line
		(start 232.10012 -30.500066)
		(end 232.599992 -30.999938)
		(stroke
			(width 0.068326)
			(type default)
		)
		(layer "F.Cu")
	)
	(gr_line
		(start 232.10012 -29.500068)
		(end 232.599992 -29.99994)
		(stroke
			(width 0.068326)
			(type default)
		)
		(layer "F.Cu")
	)
	(gr_line
		(start 232.533444 -10.42162)
		(end 232.653078 -10.301986)
		(stroke
			(width 0.060198)
			(type default)
		)
		(layer "F.Cu")
	)
	(gr_line
		(start 233.100118 -65.499742)
		(end 233.59999 -64.99987)
		(stroke
			(width 0.068326)
			(type default)
		)
		(layer "F.Cu")
	)
	(gr_line
		(start 233.100118 -64.499744)
		(end 233.59999 -63.999872)
		(stroke
			(width 0.068326)
			(type default)
		)
		(layer "F.Cu")
	)
	(gr_line
		(start 233.100118 -62.499748)
		(end 233.59999 -61.999876)
		(stroke
			(width 0.068326)
			(type default)
		)
		(layer "F.Cu")
	)
	(gr_line
		(start 233.100118 -61.49975)
		(end 233.59999 -60.999878)
		(stroke
			(width 0.068326)
			(type default)
		)
		(layer "F.Cu")
	)
	(gr_line
		(start 233.100118 -31.500064)
		(end 233.59999 -31.999936)
		(stroke
			(width 0.068326)
			(type default)
		)
		(layer "F.Cu")
	)
	(gr_line
		(start 233.100118 -30.500066)
		(end 233.59999 -30.999938)
		(stroke
			(width 0.068326)
			(type default)
		)
		(layer "F.Cu")
	)
	(gr_line
		(start 233.157268 -10.07618)
		(end 233.413808 -10.33272)
		(stroke
			(width 0.060198)
			(type default)
		)
		(layer "F.Cu")
	)
	(gr_line
		(start 234.100116 -66.49974)
		(end 234.599988 -65.999868)
		(stroke
			(width 0.068326)
			(type default)
		)
		(layer "F.Cu")
	)
	(gr_line
		(start 234.100116 -65.499742)
		(end 234.599988 -64.99987)
		(stroke
			(width 0.068326)
			(type default)
		)
		(layer "F.Cu")
	)
	(gr_line
		(start 234.100116 -63.499746)
		(end 234.599988 -62.999874)
		(stroke
			(width 0.068326)
			(type default)
		)
		(layer "F.Cu")
	)
	(gr_line
		(start 234.100116 -62.499748)
		(end 234.599988 -61.999876)
		(stroke
			(width 0.068326)
			(type default)
		)
		(layer "F.Cu")
	)
	(gr_line
		(start 234.100116 -30.500066)
		(end 234.599988 -30.999938)
		(stroke
			(width 0.068326)
			(type default)
		)
		(layer "F.Cu")
	)
	(gr_line
		(start 234.100116 -29.500068)
		(end 234.599988 -29.99994)
		(stroke
			(width 0.068326)
			(type default)
		)
		(layer "F.Cu")
	)
	(gr_line
		(start 235.100114 -65.499742)
		(end 235.599986 -64.99987)
		(stroke
			(width 0.068326)
			(type default)
		)
		(layer "F.Cu")
	)
	(gr_line
		(start 235.100114 -64.499744)
		(end 235.599986 -63.999872)
		(stroke
			(width 0.068326)
			(type default)
		)
		(layer "F.Cu")
	)
	(gr_line
		(start 235.100114 -62.499748)
		(end 235.599986 -61.999876)
		(stroke
			(width 0.068326)
			(type default)
		)
		(layer "F.Cu")
	)
	(gr_line
		(start 235.100114 -61.49975)
		(end 235.599986 -60.999878)
		(stroke
			(width 0.068326)
			(type default)
		)
		(layer "F.Cu")
	)
	(gr_line
		(start 235.100114 -34.500058)
		(end 235.599986 -34.99993)
		(stroke
			(width 0.068326)
			(type default)
		)
		(layer "F.Cu")
	)
	(gr_line
		(start 235.100114 -33.50006)
		(end 235.599986 -33.999932)
		(stroke
			(width 0.068326)
			(type default)
		)
		(layer "F.Cu")
	)
	(gr_line
		(start 235.100114 -31.500064)
		(end 235.599986 -31.999936)
		(stroke
			(width 0.068326)
			(type default)
		)
		(layer "F.Cu")
	)
	(gr_line
		(start 235.100114 -30.500066)
		(end 235.599986 -30.999938)
		(stroke
			(width 0.068326)
			(type default)
		)
		(layer "F.Cu")
	)
	(gr_line
		(start 236.100112 -66.49974)
		(end 236.599984 -65.999868)
		(stroke
			(width 0.068326)
			(type default)
		)
		(layer "F.Cu")
	)
	(gr_line
		(start 236.100112 -65.499742)
		(end 236.599984 -64.99987)
		(stroke
			(width 0.068326)
			(type default)
		)
		(layer "F.Cu")
	)
	(gr_line
		(start 236.100112 -63.499746)
		(end 236.599984 -62.999874)
		(stroke
			(width 0.068326)
			(type default)
		)
		(layer "F.Cu")
	)
	(gr_line
		(start 236.100112 -62.499748)
		(end 236.599984 -61.999876)
		(stroke
			(width 0.068326)
			(type default)
		)
		(layer "F.Cu")
	)
	(gr_line
		(start 236.100112 -36.500054)
		(end 236.599984 -36.999926)
		(stroke
			(width 0.068326)
			(type default)
		)
		(layer "F.Cu")
	)
	(gr_line
		(start 236.100112 -34.500058)
		(end 236.599984 -34.99993)
		(stroke
			(width 0.068326)
			(type default)
		)
		(layer "F.Cu")
	)
	(gr_line
		(start 236.100112 -33.50006)
		(end 236.599984 -33.999932)
		(stroke
			(width 0.068326)
			(type default)
		)
		(layer "F.Cu")
	)
	(gr_line
		(start 236.100112 -30.500066)
		(end 236.599984 -30.999938)
		(stroke
			(width 0.068326)
			(type default)
		)
		(layer "F.Cu")
	)
	(gr_line
		(start 236.100112 -29.500068)
		(end 236.599984 -29.99994)
		(stroke
			(width 0.068326)
			(type default)
		)
		(layer "F.Cu")
	)
	(gr_line
		(start 237.10011 -65.499742)
		(end 237.599982 -64.99987)
		(stroke
			(width 0.068326)
			(type default)
		)
		(layer "F.Cu")
	)
	(gr_line
		(start 237.10011 -64.499744)
		(end 237.599982 -63.999872)
		(stroke
			(width 0.068326)
			(type default)
		)
		(layer "F.Cu")
	)
	(gr_line
		(start 237.10011 -62.499748)
		(end 237.599982 -61.999876)
		(stroke
			(width 0.068326)
			(type default)
		)
		(layer "F.Cu")
	)
	(gr_line
		(start 237.10011 -61.49975)
		(end 237.599982 -60.999878)
		(stroke
			(width 0.068326)
			(type default)
		)
		(layer "F.Cu")
	)
	(gr_line
		(start 237.10011 -37.500052)
		(end 237.599982 -37.999924)
		(stroke
			(width 0.068326)
			(type default)
		)
		(layer "F.Cu")
	)
	(gr_line
		(start 237.10011 -36.500054)
		(end 237.599982 -36.999926)
		(stroke
			(width 0.068326)
			(type default)
		)
		(layer "F.Cu")
	)
	(gr_line
		(start 237.10011 -34.500058)
		(end 237.599982 -34.99993)
		(stroke
			(width 0.068326)
			(type default)
		)
		(layer "F.Cu")
	)
	(gr_line
		(start 237.10011 -33.50006)
		(end 237.599982 -33.999932)
		(stroke
			(width 0.068326)
			(type default)
		)
		(layer "F.Cu")
	)
	(gr_line
		(start 237.10011 -31.500064)
		(end 237.599982 -31.999936)
		(stroke
			(width 0.068326)
			(type default)
		)
		(layer "F.Cu")
	)
	(gr_line
		(start 237.10011 -30.500066)
		(end 237.599982 -30.999938)
		(stroke
			(width 0.068326)
			(type default)
		)
		(layer "F.Cu")
	)
	(gr_line
		(start 238.100108 -66.49974)
		(end 238.59998 -65.999868)
		(stroke
			(width 0.068326)
			(type default)
		)
		(layer "F.Cu")
	)
	(gr_line
		(start 238.100108 -65.499742)
		(end 238.59998 -64.99987)
		(stroke
			(width 0.068326)
			(type default)
		)
		(layer "F.Cu")
	)
	(gr_line
		(start 238.100108 -63.499746)
		(end 238.59998 -62.999874)
		(stroke
			(width 0.068326)
			(type default)
		)
		(layer "F.Cu")
	)
	(gr_line
		(start 238.100108 -62.499748)
		(end 238.59998 -61.999876)
		(stroke
			(width 0.068326)
			(type default)
		)
		(layer "F.Cu")
	)
	(gr_line
		(start 238.100108 -37.500052)
		(end 238.59998 -37.999924)
		(stroke
			(width 0.068326)
			(type default)
		)
		(layer "F.Cu")
	)
	(gr_line
		(start 238.100108 -36.500054)
		(end 238.59998 -36.999926)
		(stroke
			(width 0.068326)
			(type default)
		)
		(layer "F.Cu")
	)
	(gr_line
		(start 238.100108 -34.500058)
		(end 238.59998 -34.99993)
		(stroke
			(width 0.068326)
			(type default)
		)
		(layer "F.Cu")
	)
	(gr_line
		(start 238.100108 -33.50006)
		(end 238.59998 -33.999932)
		(stroke
			(width 0.068326)
			(type default)
		)
		(layer "F.Cu")
	)
	(gr_line
		(start 238.100108 -30.500066)
		(end 238.59998 -30.999938)
		(stroke
			(width 0.068326)
			(type default)
		)
		(layer "F.Cu")
	)
	(gr_line
		(start 238.100108 -29.500068)
		(end 238.59998 -29.99994)
		(stroke
			(width 0.068326)
			(type default)
		)
		(layer "F.Cu")
	)
	(gr_line
		(start 239.100106 -65.499742)
		(end 239.599978 -64.99987)
		(stroke
			(width 0.068326)
			(type default)
		)
		(layer "F.Cu")
	)
	(gr_line
		(start 239.100106 -64.499744)
		(end 239.599978 -63.999872)
		(stroke
			(width 0.068326)
			(type default)
		)
		(layer "F.Cu")
	)
	(gr_line
		(start 239.100106 -62.499748)
		(end 239.599978 -61.999876)
		(stroke
			(width 0.068326)
			(type default)
		)
		(layer "F.Cu")
	)
	(gr_line
		(start 239.100106 -61.49975)
		(end 239.599978 -60.999878)
		(stroke
			(width 0.068326)
			(type default)
		)
		(layer "F.Cu")
	)
	(gr_line
		(start 239.100106 -37.500052)
		(end 239.599978 -37.999924)
		(stroke
			(width 0.068326)
			(type default)
		)
		(layer "F.Cu")
	)
	(gr_line
		(start 239.100106 -36.500054)
		(end 239.599978 -36.999926)
		(stroke
			(width 0.068326)
			(type default)
		)
		(layer "F.Cu")
	)
	(gr_line
		(start 239.100106 -34.500058)
		(end 239.599978 -34.99993)
		(stroke
			(width 0.068326)
			(type default)
		)
		(layer "F.Cu")
	)
	(gr_line
		(start 239.100106 -33.50006)
		(end 239.599978 -33.999932)
		(stroke
			(width 0.068326)
			(type default)
		)
		(layer "F.Cu")
	)
	(gr_line
		(start 240.599976 -37.999924)
		(end 241.099848 -37.500052)
		(stroke
			(width 0.068326)
			(type default)
		)
		(layer "F.Cu")
	)
	(gr_line
		(start 240.599976 -36.999926)
		(end 241.099848 -36.500054)
		(stroke
			(width 0.068326)
			(type default)
		)
		(layer "F.Cu")
	)
	(gr_line
		(start 241.599974 -64.99987)
		(end 242.099846 -65.499742)
		(stroke
			(width 0.068326)
			(type default)
		)
		(layer "F.Cu")
	)
	(gr_line
		(start 241.599974 -63.999872)
		(end 242.099846 -64.499744)
		(stroke
			(width 0.068326)
			(type default)
		)
		(layer "F.Cu")
	)
	(gr_line
		(start 241.599974 -61.999876)
		(end 242.099846 -62.499748)
		(stroke
			(width 0.068326)
			(type default)
		)
		(layer "F.Cu")
	)
	(gr_line
		(start 241.599974 -60.999878)
		(end 242.099846 -61.49975)
		(stroke
			(width 0.068326)
			(type default)
		)
		(layer "F.Cu")
	)
	(gr_line
		(start 242.599972 -65.999868)
		(end 243.099844 -66.49974)
		(stroke
			(width 0.068326)
			(type default)
		)
		(layer "F.Cu")
	)
	(gr_line
		(start 242.599972 -64.99987)
		(end 243.099844 -65.499742)
		(stroke
			(width 0.068326)
			(type default)
		)
		(layer "F.Cu")
	)
	(gr_line
		(start 242.599972 -62.999874)
		(end 243.099844 -63.499746)
		(stroke
			(width 0.068326)
			(type default)
		)
		(layer "F.Cu")
	)
	(gr_line
		(start 242.599972 -61.999876)
		(end 243.099844 -62.499748)
		(stroke
			(width 0.068326)
			(type default)
		)
		(layer "F.Cu")
	)
	(gr_line
		(start 242.599972 -30.999938)
		(end 243.099844 -30.500066)
		(stroke
			(width 0.068326)
			(type default)
		)
		(layer "F.Cu")
	)
	(gr_line
		(start 242.599972 -29.99994)
		(end 243.099844 -29.500068)
		(stroke
			(width 0.068326)
			(type default)
		)
		(layer "F.Cu")
	)
	(gr_line
		(start 243.59997 -64.99987)
		(end 244.099842 -65.499742)
		(stroke
			(width 0.068326)
			(type default)
		)
		(layer "F.Cu")
	)
	(gr_line
		(start 243.59997 -63.999872)
		(end 244.099842 -64.499744)
		(stroke
			(width 0.068326)
			(type default)
		)
		(layer "F.Cu")
	)
	(gr_line
		(start 243.59997 -61.999876)
		(end 244.099842 -62.499748)
		(stroke
			(width 0.068326)
			(type default)
		)
		(layer "F.Cu")
	)
	(gr_line
		(start 243.59997 -60.999878)
		(end 244.099842 -61.49975)
		(stroke
			(width 0.068326)
			(type default)
		)
		(layer "F.Cu")
	)
	(gr_line
		(start 243.59997 -31.999936)
		(end 244.099842 -31.500064)
		(stroke
			(width 0.068326)
			(type default)
		)
		(layer "F.Cu")
	)
	(gr_line
		(start 243.59997 -30.999938)
		(end 244.099842 -30.500066)
		(stroke
			(width 0.068326)
			(type default)
		)
		(layer "F.Cu")
	)
	(gr_line
		(start 244.599968 -65.999868)
		(end 245.09984 -66.49974)
		(stroke
			(width 0.068326)
			(type default)
		)
		(layer "F.Cu")
	)
	(gr_line
		(start 244.599968 -64.99987)
		(end 245.09984 -65.499742)
		(stroke
			(width 0.068326)
			(type default)
		)
		(layer "F.Cu")
	)
	(gr_line
		(start 244.599968 -62.999874)
		(end 245.09984 -63.499746)
		(stroke
			(width 0.068326)
			(type default)
		)
		(layer "F.Cu")
	)
	(gr_line
		(start 244.599968 -61.999876)
		(end 245.09984 -62.499748)
		(stroke
			(width 0.068326)
			(type default)
		)
		(layer "F.Cu")
	)
	(gr_line
		(start 244.599968 -39.99992)
		(end 245.09984 -39.500048)
		(stroke
			(width 0.060198)
			(type default)
		)
		(layer "F.Cu")
	)
	(gr_line
		(start 244.599968 -38.999922)
		(end 245.09984 -38.50005)
		(stroke
			(width 0.060198)
			(type default)
		)
		(layer "F.Cu")
	)
	(gr_line
		(start 244.599968 -30.999938)
		(end 245.09984 -30.500066)
		(stroke
			(width 0.068326)
			(type default)
		)
		(layer "F.Cu")
	)
	(gr_line
		(start 244.599968 -29.99994)
		(end 245.09984 -29.500068)
		(stroke
			(width 0.068326)
			(type default)
		)
		(layer "F.Cu")
	)
	(gr_line
		(start 245.599966 -64.99987)
		(end 246.099838 -65.499742)
		(stroke
			(width 0.068326)
			(type default)
		)
		(layer "F.Cu")
	)
	(gr_line
		(start 245.599966 -63.999872)
		(end 246.099838 -64.499744)
		(stroke
			(width 0.068326)
			(type default)
		)
		(layer "F.Cu")
	)
	(gr_line
		(start 245.599966 -61.999876)
		(end 246.099838 -62.499748)
		(stroke
			(width 0.068326)
			(type default)
		)
		(layer "F.Cu")
	)
	(gr_line
		(start 245.599966 -60.999878)
		(end 246.099838 -61.49975)
		(stroke
			(width 0.068326)
			(type default)
		)
		(layer "F.Cu")
	)
	(gr_line
		(start 245.599966 -37.999924)
		(end 246.099838 -37.500052)
		(stroke
			(width 0.060198)
			(type default)
		)
		(layer "F.Cu")
	)
	(gr_line
		(start 245.599966 -34.99993)
		(end 246.099838 -34.500058)
		(stroke
			(width 0.060198)
			(type default)
		)
		(layer "F.Cu")
	)
	(gr_line
		(start 245.599966 -31.999936)
		(end 246.099838 -31.500064)
		(stroke
			(width 0.068326)
			(type default)
		)
		(layer "F.Cu")
	)
	(gr_line
		(start 245.599966 -30.999938)
		(end 246.099838 -30.500066)
		(stroke
			(width 0.068326)
			(type default)
		)
		(layer "F.Cu")
	)
	(gr_line
		(start 246.599964 -65.999868)
		(end 247.099836 -66.49974)
		(stroke
			(width 0.068326)
			(type default)
		)
		(layer "F.Cu")
	)
	(gr_line
		(start 246.599964 -64.99987)
		(end 247.099836 -65.499742)
		(stroke
			(width 0.068326)
			(type default)
		)
		(layer "F.Cu")
	)
	(gr_line
		(start 246.599964 -62.999874)
		(end 247.099836 -63.499746)
		(stroke
			(width 0.068326)
			(type default)
		)
		(layer "F.Cu")
	)
	(gr_line
		(start 246.599964 -61.999876)
		(end 247.099836 -62.499748)
		(stroke
			(width 0.068326)
			(type default)
		)
		(layer "F.Cu")
	)
	(gr_line
		(start 246.599964 -34.99993)
		(end 247.099836 -34.500058)
		(stroke
			(width 0.060198)
			(type default)
		)
		(layer "F.Cu")
	)
	(gr_line
		(start 246.599964 -33.999932)
		(end 247.099836 -33.50006)
		(stroke
			(width 0.060198)
			(type default)
		)
		(layer "F.Cu")
	)
	(gr_line
		(start 246.599964 -30.999938)
		(end 247.099836 -30.500066)
		(stroke
			(width 0.068326)
			(type default)
		)
		(layer "F.Cu")
	)
	(gr_line
		(start 246.599964 -29.99994)
		(end 247.099836 -29.500068)
		(stroke
			(width 0.068326)
			(type default)
		)
		(layer "F.Cu")
	)
	(gr_line
		(start 247.599962 -64.99987)
		(end 248.099834 -65.499742)
		(stroke
			(width 0.068326)
			(type default)
		)
		(layer "F.Cu")
	)
	(gr_line
		(start 247.599962 -63.999872)
		(end 248.099834 -64.499744)
		(stroke
			(width 0.068326)
			(type default)
		)
		(layer "F.Cu")
	)
	(gr_line
		(start 247.599962 -61.999876)
		(end 248.099834 -62.499748)
		(stroke
			(width 0.068326)
			(type default)
		)
		(layer "F.Cu")
	)
	(gr_line
		(start 247.599962 -60.999878)
		(end 248.099834 -61.49975)
		(stroke
			(width 0.068326)
			(type default)
		)
		(layer "F.Cu")
	)
	(gr_line
		(start 247.599962 -39.99992)
		(end 248.099834 -39.500048)
		(stroke
			(width 0.060198)
			(type default)
		)
		(layer "F.Cu")
	)
	(gr_line
		(start 247.599962 -35.999928)
		(end 248.099834 -35.500056)
		(stroke
			(width 0.060198)
			(type default)
		)
		(layer "F.Cu")
	)
	(gr_line
		(start 247.599962 -31.999936)
		(end 248.099834 -31.500064)
		(stroke
			(width 0.068326)
			(type default)
		)
		(layer "F.Cu")
	)
	(gr_line
		(start 247.599962 -30.999938)
		(end 248.099834 -30.500066)
		(stroke
			(width 0.068326)
			(type default)
		)
		(layer "F.Cu")
	)
	(gr_line
		(start 248.59996 -65.999868)
		(end 249.099832 -66.49974)
		(stroke
			(width 0.068326)
			(type default)
		)
		(layer "F.Cu")
	)
	(gr_line
		(start 248.59996 -64.99987)
		(end 249.099832 -65.499742)
		(stroke
			(width 0.068326)
			(type default)
		)
		(layer "F.Cu")
	)
	(gr_line
		(start 248.59996 -62.999874)
		(end 249.099832 -63.499746)
		(stroke
			(width 0.068326)
			(type default)
		)
		(layer "F.Cu")
	)
	(gr_line
		(start 248.59996 -61.999876)
		(end 249.099832 -62.499748)
		(stroke
			(width 0.068326)
			(type default)
		)
		(layer "F.Cu")
	)
	(gr_line
		(start 248.59996 -37.999924)
		(end 249.099832 -37.500052)
		(stroke
			(width 0.060198)
			(type default)
		)
		(layer "F.Cu")
	)
	(gr_line
		(start 248.59996 -36.999926)
		(end 249.099832 -36.500054)
		(stroke
			(width 0.060198)
			(type default)
		)
		(layer "F.Cu")
	)
	(gr_line
		(start 248.59996 -30.999938)
		(end 249.099832 -30.500066)
		(stroke
			(width 0.068326)
			(type default)
		)
		(layer "F.Cu")
	)
	(gr_line
		(start 248.59996 -29.99994)
		(end 249.099832 -29.500068)
		(stroke
			(width 0.068326)
			(type default)
		)
		(layer "F.Cu")
	)
	(gr_line
		(start 249.599958 -39.99992)
		(end 250.09983 -39.500048)
		(stroke
			(width 0.060198)
			(type default)
		)
		(layer "F.Cu")
	)
	(gr_line
		(start 249.599958 -36.999926)
		(end 250.09983 -36.500054)
		(stroke
			(width 0.060198)
			(type default)
		)
		(layer "F.Cu")
	)
	(gr_line
		(start 249.599958 -31.999936)
		(end 250.09983 -31.500064)
		(stroke
			(width 0.068326)
			(type default)
		)
		(layer "F.Cu")
	)
	(gr_line
		(start 249.599958 -30.999938)
		(end 250.09983 -30.500066)
		(stroke
			(width 0.068326)
			(type default)
		)
		(layer "F.Cu")
	)
	(gr_line
		(start 250.599956 -64.99987)
		(end 251.099828 -65.499742)
		(stroke
			(width 0.068326)
			(type default)
		)
		(layer "F.Cu")
	)
	(gr_line
		(start 250.599956 -63.999872)
		(end 251.099828 -64.499744)
		(stroke
			(width 0.068326)
			(type default)
		)
		(layer "F.Cu")
	)
	(gr_line
		(start 250.599956 -61.999876)
		(end 251.099828 -62.499748)
		(stroke
			(width 0.068326)
			(type default)
		)
		(layer "F.Cu")
	)
	(gr_line
		(start 250.599956 -60.999878)
		(end 251.099828 -61.49975)
		(stroke
			(width 0.068326)
			(type default)
		)
		(layer "F.Cu")
	)
	(gr_line
		(start 251.599954 -65.999868)
		(end 252.099826 -66.49974)
		(stroke
			(width 0.068326)
			(type default)
		)
		(layer "F.Cu")
	)
	(gr_line
		(start 251.599954 -64.99987)
		(end 252.099826 -65.499742)
		(stroke
			(width 0.068326)
			(type default)
		)
		(layer "F.Cu")
	)
	(gr_line
		(start 251.599954 -62.999874)
		(end 252.099826 -63.499746)
		(stroke
			(width 0.068326)
			(type default)
		)
		(layer "F.Cu")
	)
	(gr_line
		(start 251.599954 -61.999876)
		(end 252.099826 -62.499748)
		(stroke
			(width 0.068326)
			(type default)
		)
		(layer "F.Cu")
	)
	(gr_line
		(start 251.599954 -30.999938)
		(end 252.099826 -30.500066)
		(stroke
			(width 0.068326)
			(type default)
		)
		(layer "F.Cu")
	)
	(gr_line
		(start 251.599954 -29.99994)
		(end 252.099826 -29.500068)
		(stroke
			(width 0.068326)
			(type default)
		)
		(layer "F.Cu")
	)
	(gr_line
		(start 252.099826 -29.398468)
		(end 252.099826 -29.500068)
		(stroke
			(width 0.068326)
			(type default)
		)
		(layer "F.Cu")
	)
	(gr_line
		(start 252.125226 -6.920992)
		(end 252.292866 -6.753352)
		(stroke
			(width 0.060198)
			(type default)
		)
		(layer "F.Cu")
	)
	(gr_line
		(start 252.125226 -5.872734)
		(end 252.292866 -6.040374)
		(stroke
			(width 0.060198)
			(type default)
		)
		(layer "F.Cu")
	)
	(gr_line
		(start 252.473968 -6.146038)
		(end 252.4887 -6.146038)
		(stroke
			(width 0.060198)
			(type default)
		)
		(layer "F.Cu")
	)
	(gr_line
		(start 252.599952 -64.99987)
		(end 253.099824 -65.499742)
		(stroke
			(width 0.068326)
			(type default)
		)
		(layer "F.Cu")
	)
	(gr_line
		(start 252.599952 -63.999872)
		(end 253.099824 -64.499744)
		(stroke
			(width 0.068326)
			(type default)
		)
		(layer "F.Cu")
	)
	(gr_line
		(start 252.599952 -61.999876)
		(end 253.099824 -62.499748)
		(stroke
			(width 0.068326)
			(type default)
		)
		(layer "F.Cu")
	)
	(gr_line
		(start 252.599952 -60.999878)
		(end 253.099824 -61.49975)
		(stroke
			(width 0.068326)
			(type default)
		)
		(layer "F.Cu")
	)
	(gr_line
		(start 252.599952 -31.999936)
		(end 253.099824 -31.500064)
		(stroke
			(width 0.068326)
			(type default)
		)
		(layer "F.Cu")
	)
	(gr_line
		(start 252.599952 -30.999938)
		(end 253.099824 -30.500066)
		(stroke
			(width 0.068326)
			(type default)
		)
		(layer "F.Cu")
	)
	(gr_line
		(start 252.975618 -6.368796)
		(end 252.99035 -6.368796)
		(stroke
			(width 0.060198)
			(type default)
		)
		(layer "F.Cu")
	)
	(gr_line
		(start 253.59995 -65.999868)
		(end 254.099822 -66.49974)
		(stroke
			(width 0.068326)
			(type default)
		)
		(layer "F.Cu")
	)
	(gr_line
		(start 253.59995 -64.99987)
		(end 254.099822 -65.499742)
		(stroke
			(width 0.068326)
			(type default)
		)
		(layer "F.Cu")
	)
	(gr_line
		(start 253.59995 -62.999874)
		(end 254.099822 -63.499746)
		(stroke
			(width 0.068326)
			(type default)
		)
		(layer "F.Cu")
	)
	(gr_line
		(start 253.59995 -61.999876)
		(end 254.099822 -62.499748)
		(stroke
			(width 0.068326)
			(type default)
		)
		(layer "F.Cu")
	)
	(gr_line
		(start 253.59995 -58.999882)
		(end 254.099822 -59.499754)
		(stroke
			(width 0.068326)
			(type default)
		)
		(layer "F.Cu")
	)
	(gr_line
		(start 253.59995 -56.999886)
		(end 254.099822 -57.499758)
		(stroke
			(width 0.068326)
			(type default)
		)
		(layer "F.Cu")
	)
	(gr_line
		(start 253.59995 -54.99989)
		(end 254.099822 -55.499762)
		(stroke
			(width 0.068326)
			(type default)
		)
		(layer "F.Cu")
	)
	(gr_line
		(start 253.59995 -52.999894)
		(end 254.099822 -53.499766)
		(stroke
			(width 0.068326)
			(type default)
		)
		(layer "F.Cu")
	)
	(gr_line
		(start 253.59995 -49.9999)
		(end 254.099822 -50.499772)
		(stroke
			(width 0.068326)
			(type default)
		)
		(layer "F.Cu")
	)
	(gr_line
		(start 253.59995 -47.999904)
		(end 254.099822 -48.499776)
		(stroke
			(width 0.068326)
			(type default)
		)
		(layer "F.Cu")
	)
	(gr_line
		(start 253.59995 -45.999908)
		(end 254.099822 -45.500036)
		(stroke
			(width 0.068326)
			(type default)
		)
		(layer "F.Cu")
	)
	(gr_line
		(start 253.59995 -43.999912)
		(end 254.099822 -43.50004)
		(stroke
			(width 0.068326)
			(type default)
		)
		(layer "F.Cu")
	)
	(gr_line
		(start 253.59995 -40.999918)
		(end 254.099822 -40.500046)
		(stroke
			(width 0.068326)
			(type default)
		)
		(layer "F.Cu")
	)
	(gr_line
		(start 253.59995 -38.999922)
		(end 254.099822 -38.50005)
		(stroke
			(width 0.068326)
			(type default)
		)
		(layer "F.Cu")
	)
	(gr_line
		(start 253.59995 -36.999926)
		(end 254.099822 -36.500054)
		(stroke
			(width 0.068326)
			(type default)
		)
		(layer "F.Cu")
	)
	(gr_line
		(start 253.59995 -34.99993)
		(end 254.099822 -34.500058)
		(stroke
			(width 0.068326)
			(type default)
		)
		(layer "F.Cu")
	)
	(gr_line
		(start 253.59995 -30.999938)
		(end 254.099822 -30.500066)
		(stroke
			(width 0.068326)
			(type default)
		)
		(layer "F.Cu")
	)
	(gr_line
		(start 253.59995 -29.99994)
		(end 254.099822 -29.500068)
		(stroke
			(width 0.068326)
			(type default)
		)
		(layer "F.Cu")
	)
	(gr_line
		(start 254.599948 -64.99987)
		(end 255.09982 -65.499742)
		(stroke
			(width 0.068326)
			(type default)
		)
		(layer "F.Cu")
	)
	(gr_line
		(start 254.599948 -63.999872)
		(end 255.09982 -64.499744)
		(stroke
			(width 0.068326)
			(type default)
		)
		(layer "F.Cu")
	)
	(gr_line
		(start 254.599948 -61.999876)
		(end 255.09982 -62.499748)
		(stroke
			(width 0.068326)
			(type default)
		)
		(layer "F.Cu")
	)
	(gr_line
		(start 254.599948 -60.999878)
		(end 255.09982 -61.49975)
		(stroke
			(width 0.068326)
			(type default)
		)
		(layer "F.Cu")
	)
	(gr_line
		(start 254.599948 -58.999882)
		(end 255.09982 -59.499754)
		(stroke
			(width 0.068326)
			(type default)
		)
		(layer "F.Cu")
	)
	(gr_line
		(start 254.599948 -57.999884)
		(end 255.09982 -58.499756)
		(stroke
			(width 0.068326)
			(type default)
		)
		(layer "F.Cu")
	)
	(gr_line
		(start 254.599948 -56.999886)
		(end 255.09982 -57.499758)
		(stroke
			(width 0.068326)
			(type default)
		)
		(layer "F.Cu")
	)
	(gr_line
		(start 254.599948 -55.999888)
		(end 255.09982 -56.49976)
		(stroke
			(width 0.068326)
			(type default)
		)
		(layer "F.Cu")
	)
	(gr_line
		(start 254.599948 -54.99989)
		(end 255.09982 -55.499762)
		(stroke
			(width 0.068326)
			(type default)
		)
		(layer "F.Cu")
	)
	(gr_line
		(start 254.599948 -53.999892)
		(end 255.09982 -54.499764)
		(stroke
			(width 0.068326)
			(type default)
		)
		(layer "F.Cu")
	)
	(gr_line
		(start 254.599948 -52.999894)
		(end 255.09982 -53.499766)
		(stroke
			(width 0.068326)
			(type default)
		)
		(layer "F.Cu")
	)
	(gr_line
		(start 254.599948 -51.999896)
		(end 255.09982 -52.499768)
		(stroke
			(width 0.068326)
			(type default)
		)
		(layer "F.Cu")
	)
	(gr_line
		(start 254.599948 -49.9999)
		(end 255.09982 -50.499772)
		(stroke
			(width 0.068326)
			(type default)
		)
		(layer "F.Cu")
	)
	(gr_line
		(start 254.599948 -48.999902)
		(end 255.09982 -49.499774)
		(stroke
			(width 0.068326)
			(type default)
		)
		(layer "F.Cu")
	)
	(gr_line
		(start 254.599948 -47.999904)
		(end 255.09982 -48.499776)
		(stroke
			(width 0.068326)
			(type default)
		)
		(layer "F.Cu")
	)
	(gr_line
		(start 254.599948 -46.999906)
		(end 255.09982 -46.500034)
		(stroke
			(width 0.068326)
			(type default)
		)
		(layer "F.Cu")
	)
	(gr_line
		(start 254.599948 -45.999908)
		(end 255.09982 -45.500036)
		(stroke
			(width 0.068326)
			(type default)
		)
		(layer "F.Cu")
	)
	(gr_line
		(start 254.599948 -44.99991)
		(end 255.09982 -44.500038)
		(stroke
			(width 0.068326)
			(type default)
		)
		(layer "F.Cu")
	)
	(gr_line
		(start 254.599948 -43.999912)
		(end 255.09982 -43.50004)
		(stroke
			(width 0.068326)
			(type default)
		)
		(layer "F.Cu")
	)
	(gr_line
		(start 254.599948 -42.999914)
		(end 255.09982 -42.500042)
		(stroke
			(width 0.068326)
			(type default)
		)
		(layer "F.Cu")
	)
	(gr_line
		(start 254.599948 -40.999918)
		(end 255.09982 -40.500046)
		(stroke
			(width 0.068326)
			(type default)
		)
		(layer "F.Cu")
	)
	(gr_line
		(start 254.599948 -39.99992)
		(end 255.09982 -39.500048)
		(stroke
			(width 0.068326)
			(type default)
		)
		(layer "F.Cu")
	)
	(gr_line
		(start 254.599948 -38.999922)
		(end 255.09982 -38.50005)
		(stroke
			(width 0.068326)
			(type default)
		)
		(layer "F.Cu")
	)
	(gr_line
		(start 254.599948 -37.999924)
		(end 255.09982 -37.500052)
		(stroke
			(width 0.068326)
			(type default)
		)
		(layer "F.Cu")
	)
	(gr_line
		(start 254.599948 -36.999926)
		(end 255.09982 -36.500054)
		(stroke
			(width 0.068326)
			(type default)
		)
		(layer "F.Cu")
	)
	(gr_line
		(start 254.599948 -35.999928)
		(end 255.09982 -35.500056)
		(stroke
			(width 0.068326)
			(type default)
		)
		(layer "F.Cu")
	)
	(gr_line
		(start 254.599948 -34.99993)
		(end 255.09982 -34.500058)
		(stroke
			(width 0.068326)
			(type default)
		)
		(layer "F.Cu")
	)
	(gr_line
		(start 254.599948 -33.999932)
		(end 255.09982 -33.50006)
		(stroke
			(width 0.068326)
			(type default)
		)
		(layer "F.Cu")
	)
	(gr_line
		(start 254.599948 -31.999936)
		(end 255.09982 -31.500064)
		(stroke
			(width 0.068326)
			(type default)
		)
		(layer "F.Cu")
	)
	(gr_line
		(start 254.599948 -30.999938)
		(end 255.09982 -30.500066)
		(stroke
			(width 0.068326)
			(type default)
		)
		(layer "F.Cu")
	)
	(gr_line
		(start 255.207262 -4.114292)
		(end 255.482598 -4.389628)
		(stroke
			(width 0.060198)
			(type default)
		)
		(layer "F.Cu")
	)
	(gr_line
		(start 255.207262 -3.481578)
		(end 255.207262 -4.114292)
		(stroke
			(width 0.060198)
			(type default)
		)
		(layer "F.Cu")
	)
	(gr_line
		(start 255.599946 -65.999868)
		(end 256.099818 -66.49974)
		(stroke
			(width 0.068326)
			(type default)
		)
		(layer "F.Cu")
	)
	(gr_line
		(start 255.599946 -64.99987)
		(end 256.099818 -65.499742)
		(stroke
			(width 0.068326)
			(type default)
		)
		(layer "F.Cu")
	)
	(gr_line
		(start 255.599946 -62.999874)
		(end 256.099818 -63.499746)
		(stroke
			(width 0.068326)
			(type default)
		)
		(layer "F.Cu")
	)
	(gr_line
		(start 255.599946 -61.999876)
		(end 256.099818 -62.499748)
		(stroke
			(width 0.068326)
			(type default)
		)
		(layer "F.Cu")
	)
	(gr_line
		(start 255.599946 -57.999884)
		(end 256.099818 -58.499756)
		(stroke
			(width 0.068326)
			(type default)
		)
		(layer "F.Cu")
	)
	(gr_line
		(start 255.599946 -55.999888)
		(end 256.099818 -56.49976)
		(stroke
			(width 0.068326)
			(type default)
		)
		(layer "F.Cu")
	)
	(gr_line
		(start 255.599946 -53.999892)
		(end 256.099818 -54.499764)
		(stroke
			(width 0.068326)
			(type default)
		)
		(layer "F.Cu")
	)
	(gr_line
		(start 255.599946 -51.999896)
		(end 256.099818 -52.499768)
		(stroke
			(width 0.068326)
			(type default)
		)
		(layer "F.Cu")
	)
	(gr_line
		(start 255.599946 -48.999902)
		(end 256.099818 -49.499774)
		(stroke
			(width 0.068326)
			(type default)
		)
		(layer "F.Cu")
	)
	(gr_line
		(start 255.599946 -46.999906)
		(end 256.099818 -46.500034)
		(stroke
			(width 0.068326)
			(type default)
		)
		(layer "F.Cu")
	)
	(gr_line
		(start 255.599946 -44.99991)
		(end 256.099818 -44.500038)
		(stroke
			(width 0.068326)
			(type default)
		)
		(layer "F.Cu")
	)
	(gr_line
		(start 255.599946 -42.999914)
		(end 256.099818 -42.500042)
		(stroke
			(width 0.068326)
			(type default)
		)
		(layer "F.Cu")
	)
	(gr_line
		(start 255.599946 -39.99992)
		(end 256.099818 -39.500048)
		(stroke
			(width 0.068326)
			(type default)
		)
		(layer "F.Cu")
	)
	(gr_line
		(start 255.599946 -37.999924)
		(end 256.099818 -37.500052)
		(stroke
			(width 0.068326)
			(type default)
		)
		(layer "F.Cu")
	)
	(gr_line
		(start 255.599946 -35.999928)
		(end 256.099818 -35.500056)
		(stroke
			(width 0.068326)
			(type default)
		)
		(layer "F.Cu")
	)
	(gr_line
		(start 255.599946 -33.999932)
		(end 256.099818 -33.50006)
		(stroke
			(width 0.068326)
			(type default)
		)
		(layer "F.Cu")
	)
	(gr_line
		(start 255.599946 -30.999938)
		(end 256.099818 -30.500066)
		(stroke
			(width 0.068326)
			(type default)
		)
		(layer "F.Cu")
	)
	(gr_line
		(start 255.599946 -29.99994)
		(end 256.099818 -29.500068)
		(stroke
			(width 0.068326)
			(type default)
		)
		(layer "F.Cu")
	)
	(gr_line
		(start 256.19583 -4.389628)
		(end 256.477262 -4.108196)
		(stroke
			(width 0.060198)
			(type default)
		)
		(layer "F.Cu")
	)
	(gr_line
		(start 256.477262 -3.481578)
		(end 256.477262 -4.108196)
		(stroke
			(width 0.060198)
			(type default)
		)
		(layer "F.Cu")
	)
	(gr_line
		(start 256.599944 -64.99987)
		(end 257.099816 -65.499742)
		(stroke
			(width 0.068326)
			(type default)
		)
		(layer "F.Cu")
	)
	(gr_line
		(start 256.599944 -63.999872)
		(end 257.099816 -64.499744)
		(stroke
			(width 0.068326)
			(type default)
		)
		(layer "F.Cu")
	)
	(gr_line
		(start 256.599944 -61.999876)
		(end 257.099816 -62.499748)
		(stroke
			(width 0.068326)
			(type default)
		)
		(layer "F.Cu")
	)
	(gr_line
		(start 256.599944 -60.999878)
		(end 257.099816 -61.49975)
		(stroke
			(width 0.068326)
			(type default)
		)
		(layer "F.Cu")
	)
	(gr_line
		(start 256.599944 -58.999882)
		(end 257.099816 -59.499754)
		(stroke
			(width 0.068326)
			(type default)
		)
		(layer "F.Cu")
	)
	(gr_line
		(start 256.599944 -56.999886)
		(end 257.099816 -57.499758)
		(stroke
			(width 0.068326)
			(type default)
		)
		(layer "F.Cu")
	)
	(gr_line
		(start 256.599944 -54.99989)
		(end 257.099816 -55.499762)
		(stroke
			(width 0.068326)
			(type default)
		)
		(layer "F.Cu")
	)
	(gr_line
		(start 256.599944 -52.999894)
		(end 257.099816 -53.499766)
		(stroke
			(width 0.068326)
			(type default)
		)
		(layer "F.Cu")
	)
	(gr_line
		(start 256.599944 -49.9999)
		(end 257.099816 -50.499772)
		(stroke
			(width 0.068326)
			(type default)
		)
		(layer "F.Cu")
	)
	(gr_line
		(start 256.599944 -47.999904)
		(end 257.099816 -48.499776)
		(stroke
			(width 0.068326)
			(type default)
		)
		(layer "F.Cu")
	)
	(gr_line
		(start 256.599944 -45.999908)
		(end 257.099816 -45.500036)
		(stroke
			(width 0.068326)
			(type default)
		)
		(layer "F.Cu")
	)
	(gr_line
		(start 256.599944 -43.999912)
		(end 257.099816 -43.50004)
		(stroke
			(width 0.068326)
			(type default)
		)
		(layer "F.Cu")
	)
	(gr_line
		(start 256.599944 -40.999918)
		(end 257.099816 -40.500046)
		(stroke
			(width 0.068326)
			(type default)
		)
		(layer "F.Cu")
	)
	(gr_line
		(start 256.599944 -38.999922)
		(end 257.099816 -38.50005)
		(stroke
			(width 0.068326)
			(type default)
		)
		(layer "F.Cu")
	)
	(gr_line
		(start 256.599944 -36.999926)
		(end 257.099816 -36.500054)
		(stroke
			(width 0.068326)
			(type default)
		)
		(layer "F.Cu")
	)
	(gr_line
		(start 256.599944 -34.99993)
		(end 257.099816 -34.500058)
		(stroke
			(width 0.068326)
			(type default)
		)
		(layer "F.Cu")
	)
	(gr_line
		(start 256.599944 -31.999936)
		(end 257.099816 -31.500064)
		(stroke
			(width 0.068326)
			(type default)
		)
		(layer "F.Cu")
	)
	(gr_line
		(start 256.599944 -30.999938)
		(end 257.099816 -30.500066)
		(stroke
			(width 0.068326)
			(type default)
		)
		(layer "F.Cu")
	)
	(gr_line
		(start 257.599942 -65.999868)
		(end 258.099814 -66.49974)
		(stroke
			(width 0.068326)
			(type default)
		)
		(layer "F.Cu")
	)
	(gr_line
		(start 257.599942 -64.99987)
		(end 258.099814 -65.499742)
		(stroke
			(width 0.068326)
			(type default)
		)
		(layer "F.Cu")
	)
	(gr_line
		(start 257.599942 -62.999874)
		(end 258.099814 -63.499746)
		(stroke
			(width 0.068326)
			(type default)
		)
		(layer "F.Cu")
	)
	(gr_line
		(start 257.599942 -61.999876)
		(end 258.099814 -62.499748)
		(stroke
			(width 0.068326)
			(type default)
		)
		(layer "F.Cu")
	)
	(gr_line
		(start 257.599942 -58.999882)
		(end 258.099814 -59.499754)
		(stroke
			(width 0.068326)
			(type default)
		)
		(layer "F.Cu")
	)
	(gr_line
		(start 257.599942 -57.999884)
		(end 258.099814 -58.499756)
		(stroke
			(width 0.068326)
			(type default)
		)
		(layer "F.Cu")
	)
	(gr_line
		(start 257.599942 -56.999886)
		(end 258.099814 -57.499758)
		(stroke
			(width 0.068326)
			(type default)
		)
		(layer "F.Cu")
	)
	(gr_line
		(start 257.599942 -55.999888)
		(end 258.099814 -56.49976)
		(stroke
			(width 0.068326)
			(type default)
		)
		(layer "F.Cu")
	)
	(gr_line
		(start 257.599942 -54.99989)
		(end 258.099814 -55.499762)
		(stroke
			(width 0.068326)
			(type default)
		)
		(layer "F.Cu")
	)
	(gr_line
		(start 257.599942 -53.999892)
		(end 258.099814 -54.499764)
		(stroke
			(width 0.068326)
			(type default)
		)
		(layer "F.Cu")
	)
	(gr_line
		(start 257.599942 -52.999894)
		(end 258.099814 -53.499766)
		(stroke
			(width 0.068326)
			(type default)
		)
		(layer "F.Cu")
	)
	(gr_line
		(start 257.599942 -51.999896)
		(end 258.099814 -52.499768)
		(stroke
			(width 0.068326)
			(type default)
		)
		(layer "F.Cu")
	)
	(gr_line
		(start 257.599942 -49.9999)
		(end 258.099814 -50.499772)
		(stroke
			(width 0.068326)
			(type default)
		)
		(layer "F.Cu")
	)
	(gr_line
		(start 257.599942 -48.999902)
		(end 258.099814 -49.499774)
		(stroke
			(width 0.068326)
			(type default)
		)
		(layer "F.Cu")
	)
	(gr_line
		(start 257.599942 -47.999904)
		(end 258.099814 -48.499776)
		(stroke
			(width 0.068326)
			(type default)
		)
		(layer "F.Cu")
	)
	(gr_line
		(start 257.599942 -46.999906)
		(end 258.099814 -46.500034)
		(stroke
			(width 0.068326)
			(type default)
		)
		(layer "F.Cu")
	)
	(gr_line
		(start 257.599942 -45.999908)
		(end 258.099814 -45.500036)
		(stroke
			(width 0.068326)
			(type default)
		)
		(layer "F.Cu")
	)
	(gr_line
		(start 257.599942 -44.99991)
		(end 258.099814 -44.500038)
		(stroke
			(width 0.068326)
			(type default)
		)
		(layer "F.Cu")
	)
	(gr_line
		(start 257.599942 -43.999912)
		(end 258.099814 -43.50004)
		(stroke
			(width 0.068326)
			(type default)
		)
		(layer "F.Cu")
	)
	(gr_line
		(start 257.599942 -42.999914)
		(end 258.099814 -42.500042)
		(stroke
			(width 0.068326)
			(type default)
		)
		(layer "F.Cu")
	)
	(gr_line
		(start 257.599942 -40.999918)
		(end 258.099814 -40.500046)
		(stroke
			(width 0.068326)
			(type default)
		)
		(layer "F.Cu")
	)
	(gr_line
		(start 257.599942 -39.99992)
		(end 258.099814 -39.500048)
		(stroke
			(width 0.068326)
			(type default)
		)
		(layer "F.Cu")
	)
	(gr_line
		(start 257.599942 -38.999922)
		(end 258.099814 -38.50005)
		(stroke
			(width 0.068326)
			(type default)
		)
		(layer "F.Cu")
	)
	(gr_line
		(start 257.599942 -37.999924)
		(end 258.099814 -37.500052)
		(stroke
			(width 0.068326)
			(type default)
		)
		(layer "F.Cu")
	)
	(gr_line
		(start 257.599942 -36.999926)
		(end 258.099814 -36.500054)
		(stroke
			(width 0.068326)
			(type default)
		)
		(layer "F.Cu")
	)
	(gr_line
		(start 257.599942 -35.999928)
		(end 258.099814 -35.500056)
		(stroke
			(width 0.068326)
			(type default)
		)
		(layer "F.Cu")
	)
	(gr_line
		(start 257.599942 -34.99993)
		(end 258.099814 -34.500058)
		(stroke
			(width 0.068326)
			(type default)
		)
		(layer "F.Cu")
	)
	(gr_line
		(start 257.599942 -33.999932)
		(end 258.099814 -33.50006)
		(stroke
			(width 0.068326)
			(type default)
		)
		(layer "F.Cu")
	)
	(gr_line
		(start 257.599942 -30.999938)
		(end 258.099814 -30.500066)
		(stroke
			(width 0.068326)
			(type default)
		)
		(layer "F.Cu")
	)
	(gr_line
		(start 257.599942 -29.99994)
		(end 258.099814 -29.500068)
		(stroke
			(width 0.068326)
			(type default)
		)
		(layer "F.Cu")
	)
	(gr_line
		(start 258.59994 -57.999884)
		(end 259.099812 -58.499756)
		(stroke
			(width 0.068326)
			(type default)
		)
		(layer "F.Cu")
	)
	(gr_line
		(start 258.59994 -55.999888)
		(end 259.099812 -56.49976)
		(stroke
			(width 0.068326)
			(type default)
		)
		(layer "F.Cu")
	)
	(gr_line
		(start 258.59994 -53.999892)
		(end 259.099812 -54.499764)
		(stroke
			(width 0.068326)
			(type default)
		)
		(layer "F.Cu")
	)
	(gr_line
		(start 258.59994 -51.999896)
		(end 259.099812 -52.499768)
		(stroke
			(width 0.068326)
			(type default)
		)
		(layer "F.Cu")
	)
	(gr_line
		(start 258.59994 -48.999902)
		(end 259.099812 -49.499774)
		(stroke
			(width 0.068326)
			(type default)
		)
		(layer "F.Cu")
	)
	(gr_line
		(start 258.59994 -46.999906)
		(end 259.099812 -46.500034)
		(stroke
			(width 0.068326)
			(type default)
		)
		(layer "F.Cu")
	)
	(gr_line
		(start 258.59994 -44.99991)
		(end 259.099812 -44.500038)
		(stroke
			(width 0.068326)
			(type default)
		)
		(layer "F.Cu")
	)
	(gr_line
		(start 258.59994 -42.999914)
		(end 259.099812 -42.500042)
		(stroke
			(width 0.068326)
			(type default)
		)
		(layer "F.Cu")
	)
	(gr_line
		(start 258.59994 -39.99992)
		(end 259.099812 -39.500048)
		(stroke
			(width 0.068326)
			(type default)
		)
		(layer "F.Cu")
	)
	(gr_line
		(start 258.59994 -37.999924)
		(end 259.099812 -37.500052)
		(stroke
			(width 0.068326)
			(type default)
		)
		(layer "F.Cu")
	)
	(gr_line
		(start 258.59994 -35.999928)
		(end 259.099812 -35.500056)
		(stroke
			(width 0.068326)
			(type default)
		)
		(layer "F.Cu")
	)
	(gr_line
		(start 258.59994 -33.999932)
		(end 259.099812 -33.50006)
		(stroke
			(width 0.068326)
			(type default)
		)
		(layer "F.Cu")
	)
	(gr_line
		(start 258.59994 -31.812738)
		(end 258.59994 -31.999936)
		(stroke
			(width 0.068326)
			(type default)
		)
		(layer "F.Cu")
	)
	(gr_line
		(start 258.59994 -31.812738)
		(end 259.912612 -30.500066)
		(stroke
			(width 0.068326)
			(type default)
		)
		(layer "F.Cu")
	)
	(gr_line
		(start 258.59994 -30.999938)
		(end 259.099812 -30.500066)
		(stroke
			(width 0.068326)
			(type default)
		)
		(layer "F.Cu")
	)
	(gr_line
		(start 263.6266 -27.559)
		(end 263.701784 -27.634184)
		(stroke
			(width 0.060198)
			(type default)
		)
		(layer "F.Cu")
	)
	(gr_line
		(start 264.392156 -211.975954)
		(end 264.673842 -211.694268)
		(stroke
			(width 0.068326)
			(type default)
		)
		(layer "F.Cu")
	)
	(gr_line
		(start 264.415016 -27.634184)
		(end 264.4902 -27.559)
		(stroke
			(width 0.060198)
			(type default)
		)
		(layer "F.Cu")
	)
	(gr_line
		(start 264.493756 -210.896454)
		(end 264.647172 -211.050124)
		(stroke
			(width 0.068326)
			(type default)
		)
		(layer "F.Cu")
	)
	(gr_line
		(start 264.500106 -224.828608)
		(end 264.500106 -225.54438)
		(stroke
			(width 0.068326)
			(type default)
		)
		(layer "F.Cu")
	)
	(gr_line
		(start 264.500106 -224.828608)
		(end 264.50036 -224.828354)
		(stroke
			(width 0.068326)
			(type default)
		)
		(layer "F.Cu")
	)
	(gr_arc
		(start 264.668508 -224.32264)
		(mid 264.543484 -224.561884)
		(end 264.50036 -224.828354)
		(stroke
			(width 0.068326)
			(type default)
		)
		(layer "F.Cu")
	)
	(gr_arc
		(start 264.668508 -224.32264)
		(mid 264.727142 -224.234888)
		(end 264.747756 -224.131378)
		(stroke
			(width 0.068326)
			(type default)
		)
		(layer "F.Cu")
	)
	(gr_arc
		(start 264.673842 -211.694268)
		(mid 264.723833 -211.619452)
		(end 264.741406 -211.5312)
		(stroke
			(width 0.068326)
			(type default)
		)
		(layer "F.Cu")
	)
	(gr_arc
		(start 264.741406 -211.2772)
		(mid 264.716865 -211.154294)
		(end 264.647172 -211.050124)
		(stroke
			(width 0.068326)
			(type default)
		)
		(layer "F.Cu")
	)
	(gr_arc
		(start 264.747756 -213.723474)
		(mid 264.655337 -213.25885)
		(end 264.392156 -212.864954)
		(stroke
			(width 0.068326)
			(type default)
		)
		(layer "F.Cu")
	)
	(gr_arc
		(start 265.046206 -211.5312)
		(mid 265.061488 -211.607655)
		(end 265.10488 -211.672424)
		(stroke
			(width 0.068326)
			(type default)
		)
		(layer "F.Cu")
	)
	(gr_arc
		(start 265.05281 -224.133664)
		(mid 265.07298 -224.234826)
		(end 265.13028 -224.320608)
		(stroke
			(width 0.068326)
			(type default)
		)
		(layer "F.Cu")
	)
	(gr_line
		(start 265.10488 -211.672424)
		(end 265.408156 -211.975954)
		(stroke
			(width 0.068326)
			(type default)
		)
		(layer "F.Cu")
	)
	(gr_arc
		(start 265.131042 -211.071714)
		(mid 265.06819 -211.165886)
		(end 265.046206 -211.276946)
		(stroke
			(width 0.068326)
			(type default)
		)
		(layer "F.Cu")
	)
	(gr_line
		(start 265.131042 -211.071714)
		(end 265.306556 -210.896454)
		(stroke
			(width 0.068326)
			(type default)
		)
		(layer "F.Cu")
	)
	(gr_arc
		(start 265.300206 -224.828354)
		(mid 265.256569 -224.560646)
		(end 265.13028 -224.320608)
		(stroke
			(width 0.068326)
			(type default)
		)
		(layer "F.Cu")
	)
	(gr_line
		(start 265.300206 -224.828354)
		(end 265.300206 -225.54438)
		(stroke
			(width 0.068326)
			(type default)
		)
		(layer "F.Cu")
	)
	(gr_line
		(start 265.3538 -27.559)
		(end 265.428984 -27.634184)
		(stroke
			(width 0.060198)
			(type default)
		)
		(layer "F.Cu")
	)
	(gr_arc
		(start 265.408156 -212.864954)
		(mid 265.145169 -213.258486)
		(end 265.05281 -213.722712)
		(stroke
			(width 0.068326)
			(type default)
		)
		(layer "F.Cu")
	)
	(gr_line
		(start 266.142216 -27.634184)
		(end 266.2174 -27.559)
		(stroke
			(width 0.060198)
			(type default)
		)
		(layer "F.Cu")
	)
	(gr_line
		(start 267.592048 -211.975954)
		(end 267.873734 -211.694268)
		(stroke
			(width 0.068326)
			(type default)
		)
		(layer "F.Cu")
	)
	(gr_line
		(start 267.693648 -210.896454)
		(end 267.827506 -211.030058)
		(stroke
			(width 0.068326)
			(type default)
		)
		(layer "F.Cu")
	)
	(gr_line
		(start 267.699998 -224.828608)
		(end 267.699998 -225.54438)
		(stroke
			(width 0.068326)
			(type default)
		)
		(layer "F.Cu")
	)
	(gr_line
		(start 267.699998 -224.828608)
		(end 267.700252 -224.828354)
		(stroke
			(width 0.068326)
			(type default)
		)
		(layer "F.Cu")
	)
	(gr_arc
		(start 267.8684 -224.32264)
		(mid 267.743377 -224.561884)
		(end 267.700252 -224.828354)
		(stroke
			(width 0.068326)
			(type default)
		)
		(layer "F.Cu")
	)
	(gr_arc
		(start 267.8684 -224.32264)
		(mid 267.927034 -224.234888)
		(end 267.947648 -224.131378)
		(stroke
			(width 0.068326)
			(type default)
		)
		(layer "F.Cu")
	)
	(gr_arc
		(start 267.873734 -211.694268)
		(mid 267.923725 -211.619452)
		(end 267.941298 -211.5312)
		(stroke
			(width 0.068326)
			(type default)
		)
		(layer "F.Cu")
	)
	(gr_arc
		(start 267.941298 -211.30514)
		(mid 267.91178 -211.156271)
		(end 267.827506 -211.030058)
		(stroke
			(width 0.068326)
			(type default)
		)
		(layer "F.Cu")
	)
	(gr_arc
		(start 267.947648 -213.723474)
		(mid 267.855229 -213.25885)
		(end 267.592048 -212.864954)
		(stroke
			(width 0.068326)
			(type default)
		)
		(layer "F.Cu")
	)
	(gr_arc
		(start 268.246098 -211.5312)
		(mid 268.261379 -211.607656)
		(end 268.304772 -211.672424)
		(stroke
			(width 0.068326)
			(type default)
		)
		(layer "F.Cu")
	)
	(gr_arc
		(start 268.252702 -224.133664)
		(mid 268.272872 -224.234827)
		(end 268.330172 -224.320608)
		(stroke
			(width 0.068326)
			(type default)
		)
		(layer "F.Cu")
	)
	(gr_line
		(start 268.304772 -211.672424)
		(end 268.608048 -211.975954)
		(stroke
			(width 0.068326)
			(type default)
		)
		(layer "F.Cu")
	)
	(gr_arc
		(start 268.358112 -211.045044)
		(mid 268.275253 -211.168906)
		(end 268.246098 -211.315046)
		(stroke
			(width 0.068326)
			(type default)
		)
		(layer "F.Cu")
	)
	(gr_line
		(start 268.358112 -211.045044)
		(end 268.506448 -210.896454)
		(stroke
			(width 0.068326)
			(type default)
		)
		(layer "F.Cu")
	)
	(gr_line
		(start 268.478 -13.843)
		(end 268.606778 -13.972032)
		(stroke
			(width 0.068326)
			(type default)
		)
		(layer "F.Cu")
	)
	(gr_arc
		(start 268.500098 -224.828354)
		(mid 268.456461 -224.560646)
		(end 268.330172 -224.320608)
		(stroke
			(width 0.068326)
			(type default)
		)
		(layer "F.Cu")
	)
	(gr_line
		(start 268.500098 -224.828354)
		(end 268.500098 -225.54438)
		(stroke
			(width 0.068326)
			(type default)
		)
		(layer "F.Cu")
	)
	(gr_arc
		(start 268.606778 -13.972032)
		(mid 268.736962 -14.058931)
		(end 268.890496 -14.08938)
		(stroke
			(width 0.068326)
			(type default)
		)
		(layer "F.Cu")
	)
	(gr_arc
		(start 268.608048 -212.864954)
		(mid 268.345063 -213.258486)
		(end 268.252702 -213.722712)
		(stroke
			(width 0.068326)
			(type default)
		)
		(layer "F.Cu")
	)
	(gr_line
		(start 268.890496 -14.08938)
		(end 269.070074 -14.08938)
		(stroke
			(width 0.068326)
			(type default)
		)
		(layer "F.Cu")
	)
	(gr_arc
		(start 269.05839 -14.397736)
		(mid 268.744242 -14.4729)
		(end 268.478 -14.6558)
		(stroke
			(width 0.068326)
			(type default)
		)
		(layer "F.Cu")
	)
	(gr_line
		(start 269.05839 -14.397736)
		(end 269.078202 -14.39672)
		(stroke
			(width 0.068326)
			(type default)
		)
		(layer "F.Cu")
	)
	(gr_line
		(start 269.126716 -14.39418)
		(end 269.171674 -14.391894)
		(stroke
			(width 0.068326)
			(type default)
		)
		(layer "F.Cu")
	)
	(gr_line
		(start 270.792194 -211.975954)
		(end 271.07388 -211.694268)
		(stroke
			(width 0.068326)
			(type default)
		)
		(layer "F.Cu")
	)
	(gr_line
		(start 270.893794 -210.896454)
		(end 271.02943 -211.03209)
		(stroke
			(width 0.068326)
			(type default)
		)
		(layer "F.Cu")
	)
	(gr_line
		(start 270.900144 -224.828608)
		(end 270.900144 -225.54438)
		(stroke
			(width 0.068326)
			(type default)
		)
		(layer "F.Cu")
	)
	(gr_line
		(start 270.900144 -224.828608)
		(end 270.900398 -224.828354)
		(stroke
			(width 0.068326)
			(type default)
		)
		(layer "F.Cu")
	)
	(gr_arc
		(start 271.068546 -224.32264)
		(mid 270.943531 -224.561886)
		(end 270.900398 -224.828354)
		(stroke
			(width 0.068326)
			(type default)
		)
		(layer "F.Cu")
	)
	(gr_arc
		(start 271.068546 -224.32264)
		(mid 271.12718 -224.234888)
		(end 271.147794 -224.131378)
		(stroke
			(width 0.068326)
			(type default)
		)
		(layer "F.Cu")
	)
	(gr_arc
		(start 271.07388 -211.694268)
		(mid 271.123871 -211.619452)
		(end 271.141444 -211.5312)
		(stroke
			(width 0.068326)
			(type default)
		)
		(layer "F.Cu")
	)
	(gr_arc
		(start 271.141444 -211.3026)
		(mid 271.112326 -211.156214)
		(end 271.02943 -211.03209)
		(stroke
			(width 0.068326)
			(type default)
		)
		(layer "F.Cu")
	)
	(gr_arc
		(start 271.147794 -213.723474)
		(mid 271.055375 -213.25885)
		(end 270.792194 -212.864954)
		(stroke
			(width 0.068326)
			(type default)
		)
		(layer "F.Cu")
	)
	(gr_arc
		(start 271.446244 -211.5312)
		(mid 271.461528 -211.607653)
		(end 271.504918 -211.672424)
		(stroke
			(width 0.068326)
			(type default)
		)
		(layer "F.Cu")
	)
	(gr_arc
		(start 271.452848 -224.133664)
		(mid 271.473015 -224.23483)
		(end 271.530318 -224.320608)
		(stroke
			(width 0.068326)
			(type default)
		)
		(layer "F.Cu")
	)
	(gr_line
		(start 271.504918 -211.672424)
		(end 271.808194 -211.975954)
		(stroke
			(width 0.068326)
			(type default)
		)
		(layer "F.Cu")
	)
	(gr_arc
		(start 271.540732 -211.062316)
		(mid 271.470805 -211.166965)
		(end 271.446244 -211.290408)
		(stroke
			(width 0.068326)
			(type default)
		)
		(layer "F.Cu")
	)
	(gr_line
		(start 271.540732 -211.062316)
		(end 271.706594 -210.896454)
		(stroke
			(width 0.068326)
			(type default)
		)
		(layer "F.Cu")
	)
	(gr_arc
		(start 271.700244 -224.828354)
		(mid 271.656607 -224.560646)
		(end 271.530318 -224.320608)
		(stroke
			(width 0.068326)
			(type default)
		)
		(layer "F.Cu")
	)
	(gr_line
		(start 271.700244 -224.828354)
		(end 271.700244 -225.54438)
		(stroke
			(width 0.068326)
			(type default)
		)
		(layer "F.Cu")
	)
	(gr_arc
		(start 271.808194 -212.864954)
		(mid 271.545199 -213.258484)
		(end 271.452848 -213.722712)
		(stroke
			(width 0.068326)
			(type default)
		)
		(layer "F.Cu")
	)
	(gr_arc
		(start 272.06829 -14.52245)
		(mid 272.257384 -14.713003)
		(end 272.5166 -14.7828)
		(stroke
			(width 0.068326)
			(type default)
		)
		(layer "F.Cu")
	)
	(gr_arc
		(start 272.5166 -15.0876)
		(mid 272.260518 -15.153629)
		(end 272.06829 -15.33525)
		(stroke
			(width 0.068326)
			(type default)
		)
		(layer "F.Cu")
	)
	(gr_arc
		(start 272.95856 -12.921996)
		(mid 272.963894 -12.921888)
		(end 272.969228 -12.921742)
		(stroke
			(width 0.068326)
			(type default)
		)
		(layer "F.Cu")
	)
	(gr_arc
		(start 272.969228 -12.921742)
		(mid 273.25351 -12.862152)
		(end 273.4945 -12.7)
		(stroke
			(width 0.068326)
			(type default)
		)
		(layer "F.Cu")
	)
	(gr_arc
		(start 273.1262 -14.7828)
		(mid 273.365231 -14.696717)
		(end 273.4945 -14.478)
		(stroke
			(width 0.068326)
			(type default)
		)
		(layer "F.Cu")
	)
	(gr_arc
		(start 273.24431 -13.33881)
		(mid 273.120189 -13.25592)
		(end 272.9738 -13.226796)
		(stroke
			(width 0.068326)
			(type default)
		)
		(layer "F.Cu")
	)
	(gr_line
		(start 273.24431 -13.33881)
		(end 273.4945 -13.589)
		(stroke
			(width 0.068326)
			(type default)
		)
		(layer "F.Cu")
	)
	(gr_arc
		(start 273.4945 -15.367)
		(mid 273.357353 -15.165333)
		(end 273.1262 -15.0876)
		(stroke
			(width 0.068326)
			(type default)
		)
		(layer "F.Cu")
	)
	(gr_line
		(start 273.988276 -11.043412)
		(end 274.48637 -11.043412)
		(stroke
			(width 0.060198)
			(type default)
		)
		(layer "F.Cu")
	)
	(gr_line
		(start 273.992086 -211.975954)
		(end 274.273772 -211.694268)
		(stroke
			(width 0.068326)
			(type default)
		)
		(layer "F.Cu")
	)
	(gr_line
		(start 274.093686 -210.896454)
		(end 274.247102 -211.050124)
		(stroke
			(width 0.068326)
			(type default)
		)
		(layer "F.Cu")
	)
	(gr_line
		(start 274.100036 -224.828608)
		(end 274.100036 -225.54438)
		(stroke
			(width 0.068326)
			(type default)
		)
		(layer "F.Cu")
	)
	(gr_line
		(start 274.100036 -224.828608)
		(end 274.10029 -224.828354)
		(stroke
			(width 0.068326)
			(type default)
		)
		(layer "F.Cu")
	)
	(gr_line
		(start 274.144486 -1.397)
		(end 274.271486 -1.27)
		(stroke
			(width 0.060198)
			(type default)
		)
		(layer "F.Cu")
	)
	(gr_line
		(start 274.147026 -6.8453)
		(end 274.245578 -6.943852)
		(stroke
			(width 0.060198)
			(type default)
		)
		(layer "F.Cu")
	)
	(gr_line
		(start 274.245578 -6.943852)
		(end 275.385022 -6.943852)
		(stroke
			(width 0.060198)
			(type default)
		)
		(layer "F.Cu")
	)
	(gr_arc
		(start 274.268438 -224.32264)
		(mid 274.143409 -224.561883)
		(end 274.10029 -224.828354)
		(stroke
			(width 0.068326)
			(type default)
		)
		(layer "F.Cu")
	)
	(gr_arc
		(start 274.268438 -224.32264)
		(mid 274.327072 -224.234888)
		(end 274.347686 -224.131378)
		(stroke
			(width 0.068326)
			(type default)
		)
		(layer "F.Cu")
	)
	(gr_line
		(start 274.271486 -1.27)
		(end 275.14169 -1.27)
		(stroke
			(width 0.060198)
			(type default)
		)
		(layer "F.Cu")
	)
	(gr_arc
		(start 274.273772 -211.694268)
		(mid 274.323763 -211.619452)
		(end 274.341336 -211.5312)
		(stroke
			(width 0.068326)
			(type default)
		)
		(layer "F.Cu")
	)
	(gr_line
		(start 274.287996 -8.903716)
		(end 274.75561 -8.903716)
		(stroke
			(width 0.060198)
			(type default)
		)
		(layer "F.Cu")
	)
	(gr_arc
		(start 274.341336 -211.2772)
		(mid 274.316795 -211.154294)
		(end 274.247102 -211.050124)
		(stroke
			(width 0.068326)
			(type default)
		)
		(layer "F.Cu")
	)
	(gr_arc
		(start 274.347686 -213.723474)
		(mid 274.255267 -213.25885)
		(end 273.992086 -212.864954)
		(stroke
			(width 0.068326)
			(type default)
		)
		(layer "F.Cu")
	)
	(gr_line
		(start 274.3835 -14.478)
		(end 274.545298 -14.639544)
		(stroke
			(width 0.068326)
			(type default)
		)
		(layer "F.Cu")
	)
	(gr_arc
		(start 274.3835 -12.7)
		(mid 274.706993 -12.916201)
		(end 275.088604 -12.9921)
		(stroke
			(width 0.068326)
			(type default)
		)
		(layer "F.Cu")
	)
	(gr_line
		(start 274.48637 -11.043412)
		(end 274.79752 -11.354562)
		(stroke
			(width 0.060198)
			(type default)
		)
		(layer "F.Cu")
	)
	(gr_line
		(start 274.490688 -2.413)
		(end 274.5486 -2.413)
		(stroke
			(width 0.060198)
			(type default)
		)
		(layer "F.Cu")
	)
	(gr_arc
		(start 274.545298 -14.639544)
		(mid 274.703778 -14.745507)
		(end 274.890738 -14.7828)
		(stroke
			(width 0.068326)
			(type default)
		)
		(layer "F.Cu")
	)
	(gr_line
		(start 274.5486 -2.413)
		(end 275.050504 -2.914904)
		(stroke
			(width 0.060198)
			(type default)
		)
		(layer "F.Cu")
	)
	(gr_arc
		(start 274.646136 -211.5312)
		(mid 274.66142 -211.607653)
		(end 274.70481 -211.672424)
		(stroke
			(width 0.068326)
			(type default)
		)
		(layer "F.Cu")
	)
	(gr_arc
		(start 274.65274 -224.133664)
		(mid 274.672906 -224.23483)
		(end 274.73021 -224.320608)
		(stroke
			(width 0.068326)
			(type default)
		)
		(layer "F.Cu")
	)
	(gr_line
		(start 274.70481 -211.672424)
		(end 275.008086 -211.975954)
		(stroke
			(width 0.068326)
			(type default)
		)
		(layer "F.Cu")
	)
	(gr_arc
		(start 274.730972 -211.071714)
		(mid 274.668135 -211.16589)
		(end 274.646136 -211.276946)
		(stroke
			(width 0.068326)
			(type default)
		)
		(layer "F.Cu")
	)
	(gr_line
		(start 274.730972 -211.071714)
		(end 274.906486 -210.896454)
		(stroke
			(width 0.068326)
			(type default)
		)
		(layer "F.Cu")
	)
	(gr_line
		(start 274.75561 -8.903716)
		(end 275.16201 -9.310116)
		(stroke
			(width 0.060198)
			(type default)
		)
		(layer "F.Cu")
	)
	(gr_line
		(start 274.79752 -11.354562)
		(end 277.736046 -11.354562)
		(stroke
			(width 0.060198)
			(type default)
		)
		(layer "F.Cu")
	)
	(gr_arc
		(start 274.900136 -224.828354)
		(mid 274.856499 -224.560646)
		(end 274.73021 -224.320608)
		(stroke
			(width 0.068326)
			(type default)
		)
		(layer "F.Cu")
	)
	(gr_line
		(start 274.900136 -224.828354)
		(end 274.900136 -225.54438)
		(stroke
			(width 0.068326)
			(type default)
		)
		(layer "F.Cu")
	)
	(gr_arc
		(start 275.008086 -212.864954)
		(mid 274.745093 -213.258484)
		(end 274.65274 -213.722712)
		(stroke
			(width 0.068326)
			(type default)
		)
		(layer "F.Cu")
	)
	(gr_line
		(start 275.033232 -8.202168)
		(end 275.470112 -8.639048)
		(stroke
			(width 0.060198)
			(type default)
		)
		(layer "F.Cu")
	)
	(gr_line
		(start 275.033232 -7.772654)
		(end 275.033232 -8.202168)
		(stroke
			(width 0.060198)
			(type default)
		)
		(layer "F.Cu")
	)
	(gr_line
		(start 275.050504 -2.914904)
		(end 278.255984 -2.914904)
		(stroke
			(width 0.060198)
			(type default)
		)
		(layer "F.Cu")
	)
	(gr_arc
		(start 275.058124 -15.0876)
		(mid 274.693035 -15.160221)
		(end 274.3835 -15.367)
		(stroke
			(width 0.068326)
			(type default)
		)
		(layer "F.Cu")
	)
	(gr_arc
		(start 275.088604 -13.2969)
		(mid 274.706991 -13.372808)
		(end 274.3835 -13.589)
		(stroke
			(width 0.068326)
			(type default)
		)
		(layer "F.Cu")
	)
	(gr_line
		(start 275.14169 -1.27)
		(end 276.1615 -1.27)
		(stroke
			(width 0.060198)
			(type default)
		)
		(layer "F.Cu")
	)
	(gr_line
		(start 275.385022 -6.943852)
		(end 275.41093 -6.96976)
		(stroke
			(width 0.060198)
			(type default)
		)
		(layer "F.Cu")
	)
	(gr_line
		(start 275.41093 -6.96976)
		(end 276.06498 -6.96976)
		(stroke
			(width 0.060198)
			(type default)
		)
		(layer "F.Cu")
	)
	(gr_line
		(start 275.470112 -8.639048)
		(end 280.575766 -8.639048)
		(stroke
			(width 0.060198)
			(type default)
		)
		(layer "F.Cu")
	)
	(gr_line
		(start 275.5392 -2.3876)
		(end 276.1615 -1.7653)
		(stroke
			(width 0.060198)
			(type default)
		)
		(layer "F.Cu")
	)
	(gr_line
		(start 276.06498 -6.96976)
		(end 276.807168 -7.711948)
		(stroke
			(width 0.060198)
			(type default)
		)
		(layer "F.Cu")
	)
	(gr_line
		(start 276.1615 -1.27)
		(end 276.1615 -1.7653)
		(stroke
			(width 0.060198)
			(type default)
		)
		(layer "F.Cu")
	)
	(gr_line
		(start 276.807168 -7.711948)
		(end 277.391876 -7.711948)
		(stroke
			(width 0.060198)
			(type default)
		)
		(layer "F.Cu")
	)
	(gr_line
		(start 276.85365 -3.600958)
		(end 277.363174 -4.110482)
		(stroke
			(width 0.068326)
			(type default)
		)
		(layer "F.Cu")
	)
	(gr_line
		(start 276.904958 -4.70535)
		(end 277.192486 -4.417822)
		(stroke
			(width 0.068326)
			(type default)
		)
		(layer "F.Cu")
	)
	(gr_line
		(start 277.191978 -211.975954)
		(end 277.473664 -211.694268)
		(stroke
			(width 0.068326)
			(type default)
		)
		(layer "F.Cu")
	)
	(gr_line
		(start 277.293578 -210.896454)
		(end 277.446994 -211.050124)
		(stroke
			(width 0.068326)
			(type default)
		)
		(layer "F.Cu")
	)
	(gr_line
		(start 277.300182 -224.828354)
		(end 277.300182 -225.54438)
		(stroke
			(width 0.068326)
			(type default)
		)
		(layer "F.Cu")
	)
	(gr_arc
		(start 277.46833 -224.32264)
		(mid 277.343302 -224.561883)
		(end 277.300182 -224.828354)
		(stroke
			(width 0.068326)
			(type default)
		)
		(layer "F.Cu")
	)
	(gr_arc
		(start 277.46833 -224.32264)
		(mid 277.526964 -224.234888)
		(end 277.547578 -224.131378)
		(stroke
			(width 0.068326)
			(type default)
		)
		(layer "F.Cu")
	)
	(gr_arc
		(start 277.473664 -211.694268)
		(mid 277.523655 -211.619452)
		(end 277.541228 -211.5312)
		(stroke
			(width 0.068326)
			(type default)
		)
		(layer "F.Cu")
	)
	(gr_arc
		(start 277.541228 -211.2772)
		(mid 277.516687 -211.154294)
		(end 277.446994 -211.050124)
		(stroke
			(width 0.068326)
			(type default)
		)
		(layer "F.Cu")
	)
	(gr_arc
		(start 277.547578 -213.723474)
		(mid 277.455159 -213.25885)
		(end 277.191978 -212.864954)
		(stroke
			(width 0.068326)
			(type default)
		)
		(layer "F.Cu")
	)
	(gr_line
		(start 277.736046 -11.354562)
		(end 279.651968 -13.270484)
		(stroke
			(width 0.060198)
			(type default)
		)
		(layer "F.Cu")
	)
	(gr_arc
		(start 277.846028 -211.5312)
		(mid 277.861311 -211.607654)
		(end 277.904702 -211.672424)
		(stroke
			(width 0.068326)
			(type default)
		)
		(layer "F.Cu")
	)
	(gr_arc
		(start 277.852632 -224.133664)
		(mid 277.872804 -224.234825)
		(end 277.930102 -224.320608)
		(stroke
			(width 0.068326)
			(type default)
		)
		(layer "F.Cu")
	)
	(gr_line
		(start 277.904702 -211.672424)
		(end 278.207978 -211.975954)
		(stroke
			(width 0.068326)
			(type default)
		)
		(layer "F.Cu")
	)
	(gr_arc
		(start 277.930864 -211.071714)
		(mid 277.868029 -211.16589)
		(end 277.846028 -211.276946)
		(stroke
			(width 0.068326)
			(type default)
		)
		(layer "F.Cu")
	)
	(gr_line
		(start 277.930864 -211.071714)
		(end 278.106378 -210.896454)
		(stroke
			(width 0.068326)
			(type default)
		)
		(layer "F.Cu")
	)
	(gr_arc
		(start 278.100028 -224.828354)
		(mid 278.056391 -224.560646)
		(end 277.930102 -224.320608)
		(stroke
			(width 0.068326)
			(type default)
		)
		(layer "F.Cu")
	)
	(gr_line
		(start 278.100028 -224.828354)
		(end 278.100028 -225.54438)
		(stroke
			(width 0.068326)
			(type default)
		)
		(layer "F.Cu")
	)
	(gr_arc
		(start 278.207978 -212.864954)
		(mid 277.944987 -213.258485)
		(end 277.852632 -213.722712)
		(stroke
			(width 0.068326)
			(type default)
		)
		(layer "F.Cu")
	)
	(gr_line
		(start 278.255984 -2.914904)
		(end 278.487124 -3.146044)
		(stroke
			(width 0.060198)
			(type default)
		)
		(layer "F.Cu")
	)
	(gr_line
		(start 278.487124 -3.146044)
		(end 299.809916 -3.146044)
		(stroke
			(width 0.060198)
			(type default)
		)
		(layer "F.Cu")
	)
	(gr_line
		(start 279.651968 -13.270484)
		(end 279.651968 -13.302996)
		(stroke
			(width 0.060198)
			(type default)
		)
		(layer "F.Cu")
	)
	(gr_line
		(start 280.392124 -211.975954)
		(end 280.67381 -211.694268)
		(stroke
			(width 0.068326)
			(type default)
		)
		(layer "F.Cu")
	)
	(gr_line
		(start 280.493724 -210.896454)
		(end 280.64714 -211.050124)
		(stroke
			(width 0.068326)
			(type default)
		)
		(layer "F.Cu")
	)
	(gr_line
		(start 280.500074 -224.828608)
		(end 280.500074 -225.54438)
		(stroke
			(width 0.068326)
			(type default)
		)
		(layer "F.Cu")
	)
	(gr_line
		(start 280.500074 -224.828608)
		(end 280.500328 -224.828354)
		(stroke
			(width 0.068326)
			(type default)
		)
		(layer "F.Cu")
	)
	(gr_line
		(start 280.575766 -8.639048)
		(end 283.106114 -6.1087)
		(stroke
			(width 0.060198)
			(type default)
		)
		(layer "F.Cu")
	)
	(gr_arc
		(start 280.668476 -224.32264)
		(mid 280.543456 -224.561885)
		(end 280.500328 -224.828354)
		(stroke
			(width 0.068326)
			(type default)
		)
		(layer "F.Cu")
	)
	(gr_arc
		(start 280.668476 -224.32264)
		(mid 280.72711 -224.234888)
		(end 280.747724 -224.131378)
		(stroke
			(width 0.068326)
			(type default)
		)
		(layer "F.Cu")
	)
	(gr_arc
		(start 280.67381 -211.694268)
		(mid 280.723801 -211.619452)
		(end 280.741374 -211.5312)
		(stroke
			(width 0.068326)
			(type default)
		)
		(layer "F.Cu")
	)
	(gr_arc
		(start 280.741374 -211.2772)
		(mid 280.716833 -211.154294)
		(end 280.64714 -211.050124)
		(stroke
			(width 0.068326)
			(type default)
		)
		(layer "F.Cu")
	)
	(gr_arc
		(start 280.747724 -213.723474)
		(mid 280.655305 -213.25885)
		(end 280.392124 -212.864954)
		(stroke
			(width 0.068326)
			(type default)
		)
		(layer "F.Cu")
	)
	(gr_arc
		(start 281.046174 -211.5312)
		(mid 281.061454 -211.607657)
		(end 281.104848 -211.672424)
		(stroke
			(width 0.068326)
			(type default)
		)
		(layer "F.Cu")
	)
	(gr_arc
		(start 281.052778 -224.133664)
		(mid 281.072947 -224.234828)
		(end 281.130248 -224.320608)
		(stroke
			(width 0.068326)
			(type default)
		)
		(layer "F.Cu")
	)
	(gr_line
		(start 281.104848 -211.672424)
		(end 281.408124 -211.975954)
		(stroke
			(width 0.068326)
			(type default)
		)
		(layer "F.Cu")
	)
	(gr_arc
		(start 281.13101 -211.071714)
		(mid 281.068165 -211.165887)
		(end 281.046174 -211.276946)
		(stroke
			(width 0.068326)
			(type default)
		)
		(layer "F.Cu")
	)
	(gr_line
		(start 281.13101 -211.071714)
		(end 281.306524 -210.896454)
		(stroke
			(width 0.068326)
			(type default)
		)
		(layer "F.Cu")
	)
	(gr_arc
		(start 281.300174 -224.828354)
		(mid 281.256537 -224.560646)
		(end 281.130248 -224.320608)
		(stroke
			(width 0.068326)
			(type default)
		)
		(layer "F.Cu")
	)
	(gr_line
		(start 281.300174 -224.828354)
		(end 281.300174 -225.54438)
		(stroke
			(width 0.068326)
			(type default)
		)
		(layer "F.Cu")
	)
	(gr_arc
		(start 281.408124 -212.864954)
		(mid 281.145123 -213.258482)
		(end 281.052778 -213.722712)
		(stroke
			(width 0.068326)
			(type default)
		)
		(layer "F.Cu")
	)
	(gr_line
		(start 283.106114 -6.1087)
		(end 292.053772 -6.1087)
		(stroke
			(width 0.060198)
			(type default)
		)
		(layer "F.Cu")
	)
	(gr_line
		(start 283.592016 -211.975954)
		(end 283.873702 -211.694268)
		(stroke
			(width 0.068326)
			(type default)
		)
		(layer "F.Cu")
	)
	(gr_line
		(start 283.693616 -210.896454)
		(end 283.847032 -211.050124)
		(stroke
			(width 0.068326)
			(type default)
		)
		(layer "F.Cu")
	)
	(gr_line
		(start 283.70022 -224.828354)
		(end 283.70022 -225.54438)
		(stroke
			(width 0.068326)
			(type default)
		)
		(layer "F.Cu")
	)
	(gr_arc
		(start 283.868368 -224.32264)
		(mid 283.743349 -224.561885)
		(end 283.70022 -224.828354)
		(stroke
			(width 0.068326)
			(type default)
		)
		(layer "F.Cu")
	)
	(gr_arc
		(start 283.868368 -224.32264)
		(mid 283.927002 -224.234888)
		(end 283.947616 -224.131378)
		(stroke
			(width 0.068326)
			(type default)
		)
		(layer "F.Cu")
	)
	(gr_arc
		(start 283.873702 -211.694268)
		(mid 283.923693 -211.619452)
		(end 283.941266 -211.5312)
		(stroke
			(width 0.068326)
			(type default)
		)
		(layer "F.Cu")
	)
	(gr_arc
		(start 283.941266 -211.2772)
		(mid 283.916725 -211.154294)
		(end 283.847032 -211.050124)
		(stroke
			(width 0.068326)
			(type default)
		)
		(layer "F.Cu")
	)
	(gr_arc
		(start 283.947616 -213.723474)
		(mid 283.855197 -213.25885)
		(end 283.592016 -212.864954)
		(stroke
			(width 0.068326)
			(type default)
		)
		(layer "F.Cu")
	)
	(gr_arc
		(start 284.246066 -211.5312)
		(mid 284.261351 -211.607652)
		(end 284.30474 -211.672424)
		(stroke
			(width 0.068326)
			(type default)
		)
		(layer "F.Cu")
	)
	(gr_arc
		(start 284.25267 -224.133664)
		(mid 284.272838 -224.234828)
		(end 284.33014 -224.320608)
		(stroke
			(width 0.068326)
			(type default)
		)
		(layer "F.Cu")
	)
	(gr_line
		(start 284.30474 -211.672424)
		(end 284.608016 -211.975954)
		(stroke
			(width 0.068326)
			(type default)
		)
		(layer "F.Cu")
	)
	(gr_arc
		(start 284.330902 -211.071714)
		(mid 284.268059 -211.165888)
		(end 284.246066 -211.276946)
		(stroke
			(width 0.068326)
			(type default)
		)
		(layer "F.Cu")
	)
	(gr_line
		(start 284.330902 -211.071714)
		(end 284.506416 -210.896454)
		(stroke
			(width 0.068326)
			(type default)
		)
		(layer "F.Cu")
	)
	(gr_arc
		(start 284.500066 -224.828354)
		(mid 284.456429 -224.560646)
		(end 284.33014 -224.320608)
		(stroke
			(width 0.068326)
			(type default)
		)
		(layer "F.Cu")
	)
	(gr_line
		(start 284.500066 -224.828354)
		(end 284.500066 -225.54438)
		(stroke
			(width 0.068326)
			(type default)
		)
		(layer "F.Cu")
	)
	(gr_arc
		(start 284.608016 -212.864954)
		(mid 284.345017 -213.258482)
		(end 284.25267 -213.722712)
		(stroke
			(width 0.068326)
			(type default)
		)
		(layer "F.Cu")
	)
	(gr_line
		(start 284.988254 -33.864296)
		(end 285.20644 -33.64611)
		(stroke
			(width 0.068326)
			(type default)
		)
		(layer "F.Cu")
	)
	(gr_line
		(start 284.988254 -33.051496)
		(end 285.098998 -33.161986)
		(stroke
			(width 0.068326)
			(type default)
		)
		(layer "F.Cu")
	)
	(gr_arc
		(start 285.098998 -33.161986)
		(mid 285.222857 -33.24486)
		(end 285.369 -33.274)
		(stroke
			(width 0.068326)
			(type default)
		)
		(layer "F.Cu")
	)
	(gr_arc
		(start 285.369 -33.5788)
		(mid 285.281021 -33.596275)
		(end 285.20644 -33.64611)
		(stroke
			(width 0.068326)
			(type default)
		)
		(layer "F.Cu")
	)
	(gr_arc
		(start 285.635446 -33.274)
		(mid 285.729481 -33.2552)
		(end 285.809182 -33.201864)
		(stroke
			(width 0.068326)
			(type default)
		)
		(layer "F.Cu")
	)
	(gr_line
		(start 285.809182 -33.201864)
		(end 286.0421 -32.9692)
		(stroke
			(width 0.068326)
			(type default)
		)
		(layer "F.Cu")
	)
	(gr_arc
		(start 285.85287 -33.668716)
		(mid 285.753113 -33.602094)
		(end 285.635446 -33.5788)
		(stroke
			(width 0.068326)
			(type default)
		)
		(layer "F.Cu")
	)
	(gr_line
		(start 285.85287 -33.668716)
		(end 286.0421 -33.8582)
		(stroke
			(width 0.068326)
			(type default)
		)
		(layer "F.Cu")
	)
	(gr_line
		(start 286.792162 -211.975954)
		(end 287.073848 -211.694268)
		(stroke
			(width 0.068326)
			(type default)
		)
		(layer "F.Cu")
	)
	(gr_line
		(start 286.893762 -210.896454)
		(end 287.03143 -211.034376)
		(stroke
			(width 0.068326)
			(type default)
		)
		(layer "F.Cu")
	)
	(gr_line
		(start 286.900112 -224.828608)
		(end 286.900112 -225.54438)
		(stroke
			(width 0.068326)
			(type default)
		)
		(layer "F.Cu")
	)
	(gr_line
		(start 286.900112 -224.828608)
		(end 286.900366 -224.828354)
		(stroke
			(width 0.068326)
			(type default)
		)
		(layer "F.Cu")
	)
	(gr_line
		(start 286.9311 -33.8582)
		(end 287.004252 -33.784794)
		(stroke
			(width 0.068326)
			(type default)
		)
		(layer "F.Cu")
	)
	(gr_line
		(start 286.9311 -32.9692)
		(end 287.119314 -33.15716)
		(stroke
			(width 0.068326)
			(type default)
		)
		(layer "F.Cu")
	)
	(gr_arc
		(start 287.068514 -224.32264)
		(mid 286.943489 -224.561884)
		(end 286.900366 -224.828354)
		(stroke
			(width 0.068326)
			(type default)
		)
		(layer "F.Cu")
	)
	(gr_arc
		(start 287.068514 -224.32264)
		(mid 287.127148 -224.234888)
		(end 287.147762 -224.131378)
		(stroke
			(width 0.068326)
			(type default)
		)
		(layer "F.Cu")
	)
	(gr_arc
		(start 287.073848 -211.694268)
		(mid 287.123839 -211.619452)
		(end 287.141412 -211.5312)
		(stroke
			(width 0.068326)
			(type default)
		)
		(layer "F.Cu")
	)
	(gr_arc
		(start 287.119314 -33.15716)
		(mid 287.248539 -33.243597)
		(end 287.401 -33.274)
		(stroke
			(width 0.068326)
			(type default)
		)
		(layer "F.Cu")
	)
	(gr_arc
		(start 287.147762 -213.723474)
		(mid 287.055343 -213.25885)
		(end 286.792162 -212.864954)
		(stroke
			(width 0.068326)
			(type default)
		)
		(layer "F.Cu")
	)
	(gr_line
		(start 287.401 -33.274)
		(end 287.6423 -33.274)
		(stroke
			(width 0.068326)
			(type default)
		)
		(layer "F.Cu")
	)
	(gr_arc
		(start 287.446212 -211.5312)
		(mid 287.461494 -211.607655)
		(end 287.504886 -211.672424)
		(stroke
			(width 0.068326)
			(type default)
		)
		(layer "F.Cu")
	)
	(gr_arc
		(start 287.452816 -224.133664)
		(mid 287.472987 -224.234826)
		(end 287.530286 -224.320608)
		(stroke
			(width 0.068326)
			(type default)
		)
		(layer "F.Cu")
	)
	(gr_arc
		(start 287.5026 -33.578546)
		(mid 287.232909 -33.632097)
		(end 287.004252 -33.784794)
		(stroke
			(width 0.068326)
			(type default)
		)
		(layer "F.Cu")
	)
	(gr_line
		(start 287.5026 -33.578546)
		(end 287.5026 -33.5788)
		(stroke
			(width 0.068326)
			(type default)
		)
		(layer "F.Cu")
	)
	(gr_line
		(start 287.504886 -211.672424)
		(end 287.808162 -211.975954)
		(stroke
			(width 0.068326)
			(type default)
		)
		(layer "F.Cu")
	)
	(gr_arc
		(start 287.539684 -211.063078)
		(mid 287.470451 -211.166807)
		(end 287.446212 -211.289138)
		(stroke
			(width 0.068326)
			(type default)
		)
		(layer "F.Cu")
	)
	(gr_line
		(start 287.539684 -211.063078)
		(end 287.706562 -210.896454)
		(stroke
			(width 0.068326)
			(type default)
		)
		(layer "F.Cu")
	)
	(gr_arc
		(start 287.700212 -224.828354)
		(mid 287.656575 -224.560646)
		(end 287.530286 -224.320608)
		(stroke
			(width 0.068326)
			(type default)
		)
		(layer "F.Cu")
	)
	(gr_line
		(start 287.700212 -224.828354)
		(end 287.700212 -225.54438)
		(stroke
			(width 0.068326)
			(type default)
		)
		(layer "F.Cu")
	)
	(gr_line
		(start 287.794954 -33.210754)
		(end 287.796478 -33.20923)
		(stroke
			(width 0.068326)
			(type default)
		)
		(layer "F.Cu")
	)
	(gr_arc
		(start 287.808162 -212.864954)
		(mid 287.545174 -213.258485)
		(end 287.452816 -213.722712)
		(stroke
			(width 0.068326)
			(type default)
		)
		(layer "F.Cu")
	)
	(gr_line
		(start 287.921954 -33.0835)
		(end 287.921954 -33.083754)
		(stroke
			(width 0.068326)
			(type default)
		)
		(layer "F.Cu")
	)
	(gr_line
		(start 288.1376 -33.299146)
		(end 288.1376 -33.2994)
		(stroke
			(width 0.068326)
			(type default)
		)
		(layer "F.Cu")
	)
	(gr_line
		(start 288.285682 -24.916638)
		(end 288.384488 -25.33015)
		(stroke
			(width 0.068326)
			(type default)
		)
		(layer "F.Cu")
	)
	(gr_line
		(start 288.285682 -24.814276)
		(end 288.285682 -24.916638)
		(stroke
			(width 0.068326)
			(type default)
		)
		(layer "F.Cu")
	)
	(gr_arc
		(start 288.344102 -24.673306)
		(mid 288.300874 -24.737978)
		(end 288.285682 -24.814276)
		(stroke
			(width 0.068326)
			(type default)
		)
		(layer "F.Cu")
	)
	(gr_line
		(start 288.344102 -24.673306)
		(end 288.373566 -24.643842)
		(stroke
			(width 0.068326)
			(type default)
		)
		(layer "F.Cu")
	)
	(gr_arc
		(start 288.384488 -21.530056)
		(mid 288.589269 -21.139788)
		(end 288.433002 -20.72767)
		(stroke
			(width 0.068326)
			(type default)
		)
		(layer "F.Cu")
	)
	(gr_arc
		(start 288.483294 -24.598376)
		(mid 288.423898 -24.610184)
		(end 288.373566 -24.643842)
		(stroke
			(width 0.068326)
			(type default)
		)
		(layer "F.Cu")
	)
	(gr_line
		(start 288.483294 -24.598376)
		(end 288.619946 -24.598376)
		(stroke
			(width 0.068326)
			(type default)
		)
		(layer "F.Cu")
	)
	(gr_arc
		(start 288.511742 -20.374864)
		(mid 288.903164 -20.456258)
		(end 289.134296 -20.130008)
		(stroke
			(width 0.068326)
			(type default)
		)
		(layer "F.Cu")
	)
	(gr_arc
		(start 288.763456 -24.657812)
		(mid 288.697611 -24.613819)
		(end 288.619946 -24.598376)
		(stroke
			(width 0.068326)
			(type default)
		)
		(layer "F.Cu")
	)
	(gr_line
		(start 288.763456 -24.657812)
		(end 288.818066 -24.712168)
		(stroke
			(width 0.068326)
			(type default)
		)
		(layer "F.Cu")
	)
	(gr_line
		(start 288.967164 -24.919178)
		(end 288.967164 -24.919432)
		(stroke
			(width 0.068326)
			(type default)
		)
		(layer "F.Cu")
	)
	(gr_line
		(start 289.134296 -24.205946)
		(end 289.13455 -24.2062)
		(stroke
			(width 0.068326)
			(type default)
		)
		(layer "F.Cu")
	)
	(gr_line
		(start 289.134296 -23.930102)
		(end 289.134296 -24.205946)
		(stroke
			(width 0.068326)
			(type default)
		)
		(layer "F.Cu")
	)
	(gr_arc
		(start 289.13455 -24.333708)
		(mid 289.142574 -24.461082)
		(end 289.166554 -24.586438)
		(stroke
			(width 0.068326)
			(type default)
		)
		(layer "F.Cu")
	)
	(gr_line
		(start 289.13455 -24.2062)
		(end 289.13455 -24.333708)
		(stroke
			(width 0.068326)
			(type default)
		)
		(layer "F.Cu")
	)
	(gr_arc
		(start 289.166554 -24.586438)
		(mid 289.198248 -24.686909)
		(end 289.240214 -24.783542)
		(stroke
			(width 0.068326)
			(type default)
		)
		(layer "F.Cu")
	)
	(gr_line
		(start 289.179 -33.9725)
		(end 289.388804 -34.18205)
		(stroke
			(width 0.068326)
			(type default)
		)
		(layer "F.Cu")
	)
	(gr_arc
		(start 289.179 -33.0835)
		(mid 289.383289 -32.886951)
		(end 289.4584 -32.6136)
		(stroke
			(width 0.068326)
			(type default)
		)
		(layer "F.Cu")
	)
	(gr_line
		(start 289.2298 -35.014154)
		(end 289.37966 -34.864548)
		(stroke
			(width 0.068326)
			(type default)
		)
		(layer "F.Cu")
	)
	(gr_arc
		(start 289.37966 -34.864548)
		(mid 289.46619 -34.734953)
		(end 289.4965 -34.5821)
		(stroke
			(width 0.068326)
			(type default)
		)
		(layer "F.Cu")
	)
	(gr_arc
		(start 289.4965 -34.4424)
		(mid 289.468526 -34.301525)
		(end 289.388804 -34.18205)
		(stroke
			(width 0.068326)
			(type default)
		)
		(layer "F.Cu")
	)
	(gr_arc
		(start 289.7632 -32.6136)
		(mid 289.846074 -32.893647)
		(end 290.068 -33.0835)
		(stroke
			(width 0.068326)
			(type default)
		)
		(layer "F.Cu")
	)
	(gr_arc
		(start 289.8013 -34.5821)
		(mid 289.836354 -34.758326)
		(end 289.936174 -34.907728)
		(stroke
			(width 0.068326)
			(type default)
		)
		(layer "F.Cu")
	)
	(gr_line
		(start 289.936174 -34.907728)
		(end 290.0426 -35.014154)
		(stroke
			(width 0.068326)
			(type default)
		)
		(layer "F.Cu")
	)
	(gr_arc
		(start 289.945064 -34.09569)
		(mid 289.838693 -34.254747)
		(end 289.8013 -34.4424)
		(stroke
			(width 0.068326)
			(type default)
		)
		(layer "F.Cu")
	)
	(gr_line
		(start 289.945064 -34.09569)
		(end 290.068 -33.9725)
		(stroke
			(width 0.068326)
			(type default)
		)
		(layer "F.Cu")
	)
	(gr_line
		(start 289.992054 -211.975954)
		(end 290.27374 -211.694268)
		(stroke
			(width 0.068326)
			(type default)
		)
		(layer "F.Cu")
	)
	(gr_line
		(start 290.093654 -210.896454)
		(end 290.22929 -211.03209)
		(stroke
			(width 0.068326)
			(type default)
		)
		(layer "F.Cu")
	)
	(gr_line
		(start 290.100004 -224.828608)
		(end 290.100004 -225.54438)
		(stroke
			(width 0.068326)
			(type default)
		)
		(layer "F.Cu")
	)
	(gr_line
		(start 290.100004 -224.828608)
		(end 290.100258 -224.828354)
		(stroke
			(width 0.068326)
			(type default)
		)
		(layer "F.Cu")
	)
	(gr_arc
		(start 290.268406 -224.32264)
		(mid 290.143382 -224.561884)
		(end 290.100258 -224.828354)
		(stroke
			(width 0.068326)
			(type default)
		)
		(layer "F.Cu")
	)
	(gr_arc
		(start 290.268406 -224.32264)
		(mid 290.32704 -224.234888)
		(end 290.347654 -224.131378)
		(stroke
			(width 0.068326)
			(type default)
		)
		(layer "F.Cu")
	)
	(gr_arc
		(start 290.27374 -211.694268)
		(mid 290.323731 -211.619452)
		(end 290.341304 -211.5312)
		(stroke
			(width 0.068326)
			(type default)
		)
		(layer "F.Cu")
	)
	(gr_arc
		(start 290.341304 -211.3026)
		(mid 290.312186 -211.156214)
		(end 290.22929 -211.03209)
		(stroke
			(width 0.068326)
			(type default)
		)
		(layer "F.Cu")
	)
	(gr_arc
		(start 290.347654 -213.723474)
		(mid 290.255235 -213.25885)
		(end 289.992054 -212.864954)
		(stroke
			(width 0.068326)
			(type default)
		)
		(layer "F.Cu")
	)
	(gr_line
		(start 290.551616 -24.983948)
		(end 290.63442 -25.33015)
		(stroke
			(width 0.068326)
			(type default)
		)
		(layer "F.Cu")
	)
	(gr_line
		(start 290.63442 -21.18106)
		(end 290.63442 -21.530056)
		(stroke
			(width 0.068326)
			(type default)
		)
		(layer "F.Cu")
	)
	(gr_arc
		(start 290.646104 -211.5312)
		(mid 290.661386 -211.607655)
		(end 290.704778 -211.672424)
		(stroke
			(width 0.068326)
			(type default)
		)
		(layer "F.Cu")
	)
	(gr_arc
		(start 290.652708 -224.133664)
		(mid 290.672878 -224.234826)
		(end 290.730178 -224.320608)
		(stroke
			(width 0.068326)
			(type default)
		)
		(layer "F.Cu")
	)
	(gr_arc
		(start 290.680394 -24.636222)
		(mid 290.563271 -24.790558)
		(end 290.551616 -24.983948)
		(stroke
			(width 0.068326)
			(type default)
		)
		(layer "F.Cu")
	)
	(gr_arc
		(start 290.697666 -21.028406)
		(mid 290.650862 -21.098441)
		(end 290.63442 -21.18106)
		(stroke
			(width 0.068326)
			(type default)
		)
		(layer "F.Cu")
	)
	(gr_line
		(start 290.704778 -211.672424)
		(end 291.008054 -211.975954)
		(stroke
			(width 0.068326)
			(type default)
		)
		(layer "F.Cu")
	)
	(gr_arc
		(start 290.749228 -211.05368)
		(mid 290.672887 -211.167877)
		(end 290.646104 -211.3026)
		(stroke
			(width 0.068326)
			(type default)
		)
		(layer "F.Cu")
	)
	(gr_line
		(start 290.749228 -211.05368)
		(end 290.906454 -210.896454)
		(stroke
			(width 0.068326)
			(type default)
		)
		(layer "F.Cu")
	)
	(gr_arc
		(start 290.820348 -20.977606)
		(mid 290.753954 -20.990801)
		(end 290.697666 -21.028406)
		(stroke
			(width 0.068326)
			(type default)
		)
		(layer "F.Cu")
	)
	(gr_line
		(start 290.820348 -20.977606)
		(end 290.870132 -20.977606)
		(stroke
			(width 0.068326)
			(type default)
		)
		(layer "F.Cu")
	)
	(gr_arc
		(start 290.900104 -224.828354)
		(mid 290.856467 -224.560646)
		(end 290.730178 -224.320608)
		(stroke
			(width 0.068326)
			(type default)
		)
		(layer "F.Cu")
	)
	(gr_line
		(start 290.900104 -224.828354)
		(end 290.900104 -225.54438)
		(stroke
			(width 0.068326)
			(type default)
		)
		(layer "F.Cu")
	)
	(gr_arc
		(start 291.008054 -212.864954)
		(mid 290.745068 -213.258486)
		(end 290.652708 -213.722712)
		(stroke
			(width 0.068326)
			(type default)
		)
		(layer "F.Cu")
	)
	(gr_arc
		(start 291.018722 -24.662892)
		(mid 290.854467 -24.587259)
		(end 290.680394 -24.636222)
		(stroke
			(width 0.068326)
			(type default)
		)
		(layer "F.Cu")
	)
	(gr_line
		(start 291.018722 -24.662892)
		(end 291.067998 -24.712168)
		(stroke
			(width 0.068326)
			(type default)
		)
		(layer "F.Cu")
	)
	(gr_arc
		(start 291.041074 -21.041868)
		(mid 290.96144 -20.994211)
		(end 290.870132 -20.977606)
		(stroke
			(width 0.068326)
			(type default)
		)
		(layer "F.Cu")
	)
	(gr_arc
		(start 291.051234 -21.051266)
		(mid 291.046218 -21.046498)
		(end 291.041074 -21.041868)
		(stroke
			(width 0.068326)
			(type default)
		)
		(layer "F.Cu")
	)
	(gr_arc
		(start 291.05352 -21.053552)
		(mid 291.052381 -21.052405)
		(end 291.051234 -21.051266)
		(stroke
			(width 0.068326)
			(type default)
		)
		(layer "F.Cu")
	)
	(gr_line
		(start 291.05352 -21.053552)
		(end 291.23132 -21.231352)
		(stroke
			(width 0.068326)
			(type default)
		)
		(layer "F.Cu")
	)
	(gr_arc
		(start 291.384482 -24.333708)
		(mid 291.411294 -24.564734)
		(end 291.490146 -24.783542)
		(stroke
			(width 0.068326)
			(type default)
		)
		(layer "F.Cu")
	)
	(gr_line
		(start 291.384482 -23.930102)
		(end 291.384482 -24.333708)
		(stroke
			(width 0.068326)
			(type default)
		)
		(layer "F.Cu")
	)
	(gr_arc
		(start 291.384482 -20.86483)
		(mid 291.384957 -20.880106)
		(end 291.386514 -20.89531)
		(stroke
			(width 0.068326)
			(type default)
		)
		(layer "F.Cu")
	)
	(gr_line
		(start 291.384482 -20.130008)
		(end 291.384482 -20.86483)
		(stroke
			(width 0.068326)
			(type default)
		)
		(layer "F.Cu")
	)
	(gr_arc
		(start 291.386514 -20.89531)
		(mid 291.407016 -20.960384)
		(end 291.446966 -21.015706)
		(stroke
			(width 0.068326)
			(type default)
		)
		(layer "F.Cu")
	)
	(gr_line
		(start 292.053772 -6.1087)
		(end 293.2049 -7.259828)
		(stroke
			(width 0.060198)
			(type default)
		)
		(layer "F.Cu")
	)
	(gr_line
		(start 293.191946 -211.975954)
		(end 293.473632 -211.694268)
		(stroke
			(width 0.068326)
			(type default)
		)
		(layer "F.Cu")
	)
	(gr_line
		(start 293.2049 -14.5923)
		(end 297.13428 -18.52168)
		(stroke
			(width 0.060198)
			(type default)
		)
		(layer "F.Cu")
	)
	(gr_line
		(start 293.2049 -7.259828)
		(end 293.2049 -14.5923)
		(stroke
			(width 0.060198)
			(type default)
		)
		(layer "F.Cu")
	)
	(gr_line
		(start 293.293546 -210.896454)
		(end 293.432992 -211.035646)
		(stroke
			(width 0.068326)
			(type default)
		)
		(layer "F.Cu")
	)
	(gr_line
		(start 293.30015 -224.828354)
		(end 293.30015 -225.54438)
		(stroke
			(width 0.068326)
			(type default)
		)
		(layer "F.Cu")
	)
	(gr_arc
		(start 293.468298 -224.32264)
		(mid 293.343275 -224.561884)
		(end 293.30015 -224.828354)
		(stroke
			(width 0.068326)
			(type default)
		)
		(layer "F.Cu")
	)
	(gr_arc
		(start 293.468298 -224.32264)
		(mid 293.526932 -224.234888)
		(end 293.547546 -224.131378)
		(stroke
			(width 0.068326)
			(type default)
		)
		(layer "F.Cu")
	)
	(gr_arc
		(start 293.473632 -211.694268)
		(mid 293.523623 -211.619452)
		(end 293.541196 -211.5312)
		(stroke
			(width 0.068326)
			(type default)
		)
		(layer "F.Cu")
	)
	(gr_arc
		(start 293.541196 -211.297266)
		(mid 293.513128 -211.155687)
		(end 293.432992 -211.035646)
		(stroke
			(width 0.068326)
			(type default)
		)
		(layer "F.Cu")
	)
	(gr_arc
		(start 293.547546 -213.723474)
		(mid 293.455127 -213.25885)
		(end 293.191946 -212.864954)
		(stroke
			(width 0.068326)
			(type default)
		)
		(layer "F.Cu")
	)
	(gr_arc
		(start 293.845996 -211.5312)
		(mid 293.861277 -211.607656)
		(end 293.90467 -211.672424)
		(stroke
			(width 0.068326)
			(type default)
		)
		(layer "F.Cu")
	)
	(gr_arc
		(start 293.8526 -224.133664)
		(mid 293.87277 -224.234827)
		(end 293.93007 -224.320608)
		(stroke
			(width 0.068326)
			(type default)
		)
		(layer "F.Cu")
	)
	(gr_line
		(start 293.90467 -211.672424)
		(end 294.207946 -211.975954)
		(stroke
			(width 0.068326)
			(type default)
		)
		(layer "F.Cu")
	)
	(gr_arc
		(start 293.957756 -211.045044)
		(mid 293.875015 -211.168794)
		(end 293.845996 -211.314792)
		(stroke
			(width 0.068326)
			(type default)
		)
		(layer "F.Cu")
	)
	(gr_line
		(start 293.957756 -211.045044)
		(end 294.106346 -210.896454)
		(stroke
			(width 0.068326)
			(type default)
		)
		(layer "F.Cu")
	)
	(gr_arc
		(start 294.099996 -224.828354)
		(mid 294.056359 -224.560646)
		(end 293.93007 -224.320608)
		(stroke
			(width 0.068326)
			(type default)
		)
		(layer "F.Cu")
	)
	(gr_line
		(start 294.099996 -224.828354)
		(end 294.099996 -225.54438)
		(stroke
			(width 0.068326)
			(type default)
		)
		(layer "F.Cu")
	)
	(gr_line
		(start 294.108378 -34.138616)
		(end 294.318182 -34.348166)
		(stroke
			(width 0.068326)
			(type default)
		)
		(layer "F.Cu")
	)
	(gr_arc
		(start 294.108378 -33.249616)
		(mid 294.321757 -33.048481)
		(end 294.400478 -32.766)
		(stroke
			(width 0.068326)
			(type default)
		)
		(layer "F.Cu")
	)
	(gr_line
		(start 294.159178 -35.18027)
		(end 294.309038 -35.030664)
		(stroke
			(width 0.068326)
			(type default)
		)
		(layer "F.Cu")
	)
	(gr_arc
		(start 294.207946 -212.864954)
		(mid 293.944961 -213.258486)
		(end 293.8526 -213.722712)
		(stroke
			(width 0.068326)
			(type default)
		)
		(layer "F.Cu")
	)
	(gr_arc
		(start 294.309038 -35.030664)
		(mid 294.395578 -34.901071)
		(end 294.425878 -34.748216)
		(stroke
			(width 0.068326)
			(type default)
		)
		(layer "F.Cu")
	)
	(gr_arc
		(start 294.425878 -34.608516)
		(mid 294.397914 -34.467633)
		(end 294.318182 -34.348166)
		(stroke
			(width 0.068326)
			(type default)
		)
		(layer "F.Cu")
	)
	(gr_arc
		(start 294.705278 -32.766)
		(mid 294.783973 -33.048486)
		(end 294.997378 -33.249616)
		(stroke
			(width 0.068326)
			(type default)
		)
		(layer "F.Cu")
	)
	(gr_arc
		(start 294.730678 -34.748216)
		(mid 294.765732 -34.924442)
		(end 294.865552 -35.073844)
		(stroke
			(width 0.068326)
			(type default)
		)
		(layer "F.Cu")
	)
	(gr_line
		(start 294.865552 -35.073844)
		(end 294.971978 -35.18027)
		(stroke
			(width 0.068326)
			(type default)
		)
		(layer "F.Cu")
	)
	(gr_arc
		(start 294.874442 -34.261806)
		(mid 294.768071 -34.420863)
		(end 294.730678 -34.608516)
		(stroke
			(width 0.068326)
			(type default)
		)
		(layer "F.Cu")
	)
	(gr_line
		(start 294.874442 -34.261806)
		(end 294.997378 -34.138616)
		(stroke
			(width 0.068326)
			(type default)
		)
		(layer "F.Cu")
	)
	(gr_arc
		(start 296.633646 -12.382754)
		(mid 296.796797 -12.491768)
		(end 296.989246 -12.530074)
		(stroke
			(width 0.068326)
			(type default)
		)
		(layer "F.Cu")
	)
	(gr_line
		(start 296.635424 -12.815824)
		(end 296.773092 -12.953492)
		(stroke
			(width 0.068326)
			(type default)
		)
		(layer "F.Cu")
	)
	(gr_line
		(start 296.989246 -12.530074)
		(end 297.884342 -12.530074)
		(stroke
			(width 0.068326)
			(type default)
		)
		(layer "F.Cu")
	)
	(gr_line
		(start 297.044618 -33.052004)
		(end 297.310302 -32.786574)
		(stroke
			(width 0.068326)
			(type default)
		)
		(layer "F.Cu")
	)
	(gr_line
		(start 297.13428 -24.981154)
		(end 297.13428 -25.33015)
		(stroke
			(width 0.068326)
			(type default)
		)
		(layer "F.Cu")
	)
	(gr_line
		(start 297.13428 -18.52168)
		(end 297.13428 -21.530056)
		(stroke
			(width 0.060198)
			(type default)
		)
		(layer "F.Cu")
	)
	(gr_arc
		(start 297.13428 -13.825474)
		(mid 297.040403 -13.353565)
		(end 296.773092 -12.953492)
		(stroke
			(width 0.068326)
			(type default)
		)
		(layer "F.Cu")
	)
	(gr_line
		(start 297.13428 -13.825474)
		(end 297.13428 -13.930122)
		(stroke
			(width 0.068326)
			(type default)
		)
		(layer "F.Cu")
	)
	(gr_arc
		(start 297.197526 -24.8285)
		(mid 297.150729 -24.898537)
		(end 297.13428 -24.981154)
		(stroke
			(width 0.068326)
			(type default)
		)
		(layer "F.Cu")
	)
	(gr_arc
		(start 297.310302 -32.786574)
		(mid 297.373698 -32.691589)
		(end 297.3959 -32.579564)
		(stroke
			(width 0.068326)
			(type default)
		)
		(layer "F.Cu")
	)
	(gr_arc
		(start 297.320208 -24.7777)
		(mid 297.253801 -24.790875)
		(end 297.197526 -24.8285)
		(stroke
			(width 0.068326)
			(type default)
		)
		(layer "F.Cu")
	)
	(gr_line
		(start 297.320208 -24.7777)
		(end 297.369992 -24.7777)
		(stroke
			(width 0.068326)
			(type default)
		)
		(layer "F.Cu")
	)
	(gr_arc
		(start 297.551094 -24.85136)
		(mid 297.467744 -24.796818)
		(end 297.369992 -24.7777)
		(stroke
			(width 0.068326)
			(type default)
		)
		(layer "F.Cu")
	)
	(gr_arc
		(start 297.55338 -24.853646)
		(mid 297.552241 -24.852499)
		(end 297.551094 -24.85136)
		(stroke
			(width 0.068326)
			(type default)
		)
		(layer "F.Cu")
	)
	(gr_line
		(start 297.55338 -24.853646)
		(end 297.73118 -25.031446)
		(stroke
			(width 0.068326)
			(type default)
		)
		(layer "F.Cu")
	)
	(gr_arc
		(start 297.602402 -26.455624)
		(mid 297.564851 -26.496153)
		(end 297.53052 -26.539444)
		(stroke
			(width 0.068326)
			(type default)
		)
		(layer "F.Cu")
	)
	(gr_arc
		(start 297.7007 -32.579564)
		(mid 297.720544 -32.679504)
		(end 297.777154 -32.764222)
		(stroke
			(width 0.068326)
			(type default)
		)
		(layer "F.Cu")
	)
	(gr_line
		(start 297.777154 -32.764222)
		(end 298.063666 -33.050734)
		(stroke
			(width 0.068326)
			(type default)
		)
		(layer "F.Cu")
	)
	(gr_arc
		(start 297.884342 -24.664924)
		(mid 297.900564 -24.746584)
		(end 297.946826 -24.8158)
		(stroke
			(width 0.068326)
			(type default)
		)
		(layer "F.Cu")
	)
	(gr_line
		(start 297.884342 -23.930102)
		(end 297.884342 -24.664924)
		(stroke
			(width 0.068326)
			(type default)
		)
		(layer "F.Cu")
	)
	(gr_line
		(start 298.792138 -211.975954)
		(end 299.073824 -211.694268)
		(stroke
			(width 0.068326)
			(type default)
		)
		(layer "F.Cu")
	)
	(gr_line
		(start 298.893738 -210.896454)
		(end 299.065188 -211.067904)
		(stroke
			(width 0.068326)
			(type default)
		)
		(layer "F.Cu")
	)
	(gr_line
		(start 298.900088 -224.828608)
		(end 298.900088 -225.54438)
		(stroke
			(width 0.068326)
			(type default)
		)
		(layer "F.Cu")
	)
	(gr_line
		(start 298.900088 -224.828608)
		(end 298.900342 -224.828354)
		(stroke
			(width 0.068326)
			(type default)
		)
		(layer "F.Cu")
	)
	(gr_arc
		(start 299.06849 -224.32264)
		(mid 298.943468 -224.561884)
		(end 298.900342 -224.828354)
		(stroke
			(width 0.068326)
			(type default)
		)
		(layer "F.Cu")
	)
	(gr_arc
		(start 299.06849 -224.32264)
		(mid 299.127124 -224.234888)
		(end 299.147738 -224.131378)
		(stroke
			(width 0.068326)
			(type default)
		)
		(layer "F.Cu")
	)
	(gr_arc
		(start 299.073824 -211.694268)
		(mid 299.123815 -211.619452)
		(end 299.141388 -211.5312)
		(stroke
			(width 0.068326)
			(type default)
		)
		(layer "F.Cu")
	)
	(gr_arc
		(start 299.147738 -213.723474)
		(mid 299.055319 -213.25885)
		(end 298.792138 -212.864954)
		(stroke
			(width 0.068326)
			(type default)
		)
		(layer "F.Cu")
	)
	(gr_arc
		(start 299.379894 -33.115758)
		(mid 299.568565 -32.938874)
		(end 299.638212 -32.6898)
		(stroke
			(width 0.068326)
			(type default)
		)
		(layer "F.Cu")
	)
	(gr_line
		(start 299.384466 -24.981154)
		(end 299.384466 -25.33015)
		(stroke
			(width 0.068326)
			(type default)
		)
		(layer "F.Cu")
	)
	(gr_line
		(start 299.384466 -21.18106)
		(end 299.384466 -21.530056)
		(stroke
			(width 0.068326)
			(type default)
		)
		(layer "F.Cu")
	)
	(gr_line
		(start 299.430694 -36.189412)
		(end 299.580554 -36.039806)
		(stroke
			(width 0.068326)
			(type default)
		)
		(layer "F.Cu")
	)
	(gr_arc
		(start 299.446188 -211.5312)
		(mid 299.461469 -211.607656)
		(end 299.504862 -211.672424)
		(stroke
			(width 0.068326)
			(type default)
		)
		(layer "F.Cu")
	)
	(gr_arc
		(start 299.447712 -21.028406)
		(mid 299.40092 -21.098444)
		(end 299.384466 -21.18106)
		(stroke
			(width 0.068326)
			(type default)
		)
		(layer "F.Cu")
	)
	(gr_arc
		(start 299.452792 -224.133664)
		(mid 299.472961 -224.234827)
		(end 299.530262 -224.320608)
		(stroke
			(width 0.068326)
			(type default)
		)
		(layer "F.Cu")
	)
	(gr_line
		(start 299.504862 -211.672424)
		(end 299.808138 -211.975954)
		(stroke
			(width 0.068326)
			(type default)
		)
		(layer "F.Cu")
	)
	(gr_arc
		(start 299.510958 -211.092288)
		(mid 299.463082 -211.163831)
		(end 299.446188 -211.248244)
		(stroke
			(width 0.068326)
			(type default)
		)
		(layer "F.Cu")
	)
	(gr_line
		(start 299.510958 -211.092288)
		(end 299.706538 -210.896454)
		(stroke
			(width 0.068326)
			(type default)
		)
		(layer "F.Cu")
	)
	(gr_arc
		(start 299.570394 -20.977606)
		(mid 299.50399 -20.990786)
		(end 299.447712 -21.028406)
		(stroke
			(width 0.068326)
			(type default)
		)
		(layer "F.Cu")
	)
	(gr_line
		(start 299.570394 -20.977606)
		(end 299.620178 -20.977606)
		(stroke
			(width 0.068326)
			(type default)
		)
		(layer "F.Cu")
	)
	(gr_arc
		(start 299.580554 -36.039806)
		(mid 299.667104 -35.910214)
		(end 299.697394 -35.757358)
		(stroke
			(width 0.068326)
			(type default)
		)
		(layer "F.Cu")
	)
	(gr_arc
		(start 299.697394 -34.77133)
		(mid 299.614906 -34.356456)
		(end 299.379894 -34.004758)
		(stroke
			(width 0.068326)
			(type default)
		)
		(layer "F.Cu")
	)
	(gr_arc
		(start 299.700188 -224.828354)
		(mid 299.656551 -224.560646)
		(end 299.530262 -224.320608)
		(stroke
			(width 0.068326)
			(type default)
		)
		(layer "F.Cu")
	)
	(gr_line
		(start 299.700188 -224.828354)
		(end 299.700188 -225.54438)
		(stroke
			(width 0.068326)
			(type default)
		)
		(layer "F.Cu")
	)
	(gr_arc
		(start 299.72 -24.765)
		(mid 299.49326 -24.78155)
		(end 299.384466 -24.981154)
		(stroke
			(width 0.068326)
			(type default)
		)
		(layer "F.Cu")
	)
	(gr_arc
		(start 299.72 -24.765)
		(mid 299.759986 -24.808796)
		(end 299.80128 -24.85136)
		(stroke
			(width 0.068326)
			(type default)
		)
		(layer "F.Cu")
	)
	(gr_arc
		(start 299.775372 -21.029168)
		(mid 299.701946 -20.990834)
		(end 299.620178 -20.977606)
		(stroke
			(width 0.068326)
			(type default)
		)
		(layer "F.Cu")
	)
	(gr_arc
		(start 299.80128 -21.051266)
		(mid 299.788693 -21.039787)
		(end 299.775372 -21.029168)
		(stroke
			(width 0.068326)
			(type default)
		)
		(layer "F.Cu")
	)
	(gr_arc
		(start 299.803566 -24.853646)
		(mid 299.802427 -24.852499)
		(end 299.80128 -24.85136)
		(stroke
			(width 0.068326)
			(type default)
		)
		(layer "F.Cu")
	)
	(gr_line
		(start 299.803566 -24.853646)
		(end 299.981366 -25.031446)
		(stroke
			(width 0.068326)
			(type default)
		)
		(layer "F.Cu")
	)
	(gr_arc
		(start 299.803566 -21.053552)
		(mid 299.802427 -21.052405)
		(end 299.80128 -21.051266)
		(stroke
			(width 0.068326)
			(type default)
		)
		(layer "F.Cu")
	)
	(gr_line
		(start 299.803566 -21.053552)
		(end 299.981366 -21.231352)
		(stroke
			(width 0.068326)
			(type default)
		)
		(layer "F.Cu")
	)
	(gr_arc
		(start 299.808138 -212.864954)
		(mid 299.545155 -213.258487)
		(end 299.452792 -213.722712)
		(stroke
			(width 0.068326)
			(type default)
		)
		(layer "F.Cu")
	)
	(gr_line
		(start 299.809916 -3.146044)
		(end 306.279042 -9.61517)
		(stroke
			(width 0.060198)
			(type default)
		)
		(layer "F.Cu")
	)
	(gr_arc
		(start 299.943012 -32.6898)
		(mid 300.03377 -32.958007)
		(end 300.268894 -33.115758)
		(stroke
			(width 0.068326)
			(type default)
		)
		(layer "F.Cu")
	)
	(gr_arc
		(start 300.002194 -35.757358)
		(mid 300.037248 -35.933584)
		(end 300.137068 -36.082986)
		(stroke
			(width 0.068326)
			(type default)
		)
		(layer "F.Cu")
	)
	(gr_line
		(start 300.134274 -24.66467)
		(end 300.134528 -24.664924)
		(stroke
			(width 0.068326)
			(type default)
		)
		(layer "F.Cu")
	)
	(gr_line
		(start 300.134274 -23.930102)
		(end 300.134274 -24.66467)
		(stroke
			(width 0.068326)
			(type default)
		)
		(layer "F.Cu")
	)
	(gr_line
		(start 300.134274 -20.130008)
		(end 300.134528 -20.130262)
		(stroke
			(width 0.068326)
			(type default)
		)
		(layer "F.Cu")
	)
	(gr_arc
		(start 300.134528 -24.664924)
		(mid 300.150749 -24.746584)
		(end 300.197012 -24.8158)
		(stroke
			(width 0.068326)
			(type default)
		)
		(layer "F.Cu")
	)
	(gr_arc
		(start 300.134528 -20.86483)
		(mid 300.150769 -20.946479)
		(end 300.197012 -21.015706)
		(stroke
			(width 0.068326)
			(type default)
		)
		(layer "F.Cu")
	)
	(gr_line
		(start 300.134528 -20.130262)
		(end 300.134528 -20.86483)
		(stroke
			(width 0.068326)
			(type default)
		)
		(layer "F.Cu")
	)
	(gr_line
		(start 300.137068 -36.082986)
		(end 300.243494 -36.189412)
		(stroke
			(width 0.068326)
			(type default)
		)
		(layer "F.Cu")
	)
	(gr_arc
		(start 300.268894 -34.004758)
		(mid 300.071501 -34.300177)
		(end 300.002194 -34.648648)
		(stroke
			(width 0.068326)
			(type default)
		)
		(layer "F.Cu")
	)
	(gr_line
		(start 301.60849 -33.984692)
		(end 301.818294 -34.194242)
		(stroke
			(width 0.068326)
			(type default)
		)
		(layer "F.Cu")
	)
	(gr_arc
		(start 301.60849 -33.095692)
		(mid 301.810733 -32.951322)
		(end 301.888144 -32.7152)
		(stroke
			(width 0.068326)
			(type default)
		)
		(layer "F.Cu")
	)
	(gr_line
		(start 301.634398 -24.981154)
		(end 301.634398 -25.33015)
		(stroke
			(width 0.068326)
			(type default)
		)
		(layer "F.Cu")
	)
	(gr_line
		(start 301.634398 -21.18106)
		(end 301.634398 -21.530056)
		(stroke
			(width 0.068326)
			(type default)
		)
		(layer "F.Cu")
	)
	(gr_line
		(start 301.65929 -35.026346)
		(end 301.80915 -34.87674)
		(stroke
			(width 0.068326)
			(type default)
		)
		(layer "F.Cu")
	)
	(gr_arc
		(start 301.697644 -24.8285)
		(mid 301.650843 -24.898536)
		(end 301.634398 -24.981154)
		(stroke
			(width 0.068326)
			(type default)
		)
		(layer "F.Cu")
	)
	(gr_arc
		(start 301.697644 -21.028406)
		(mid 301.650845 -21.098442)
		(end 301.634398 -21.18106)
		(stroke
			(width 0.068326)
			(type default)
		)
		(layer "F.Cu")
	)
	(gr_arc
		(start 301.80915 -34.87674)
		(mid 301.895679 -34.747145)
		(end 301.92599 -34.594292)
		(stroke
			(width 0.068326)
			(type default)
		)
		(layer "F.Cu")
	)
	(gr_arc
		(start 301.820326 -24.7777)
		(mid 301.753936 -24.790902)
		(end 301.697644 -24.8285)
		(stroke
			(width 0.068326)
			(type default)
		)
		(layer "F.Cu")
	)
	(gr_line
		(start 301.820326 -24.7777)
		(end 301.87011 -24.7777)
		(stroke
			(width 0.068326)
			(type default)
		)
		(layer "F.Cu")
	)
	(gr_arc
		(start 301.820326 -20.977606)
		(mid 301.753937 -20.990808)
		(end 301.697644 -21.028406)
		(stroke
			(width 0.068326)
			(type default)
		)
		(layer "F.Cu")
	)
	(gr_line
		(start 301.820326 -20.977606)
		(end 301.87011 -20.977606)
		(stroke
			(width 0.068326)
			(type default)
		)
		(layer "F.Cu")
	)
	(gr_arc
		(start 301.92599 -34.454592)
		(mid 301.898013 -34.313719)
		(end 301.818294 -34.194242)
		(stroke
			(width 0.068326)
			(type default)
		)
		(layer "F.Cu")
	)
	(gr_line
		(start 301.99203 -211.975954)
		(end 302.273716 -211.694268)
		(stroke
			(width 0.068326)
			(type default)
		)
		(layer "F.Cu")
	)
	(gr_arc
		(start 302.051212 -24.85136)
		(mid 301.967858 -24.796845)
		(end 301.87011 -24.7777)
		(stroke
			(width 0.068326)
			(type default)
		)
		(layer "F.Cu")
	)
	(gr_arc
		(start 302.051212 -21.051266)
		(mid 301.967858 -20.99675)
		(end 301.87011 -20.977606)
		(stroke
			(width 0.068326)
			(type default)
		)
		(layer "F.Cu")
	)
	(gr_arc
		(start 302.053498 -24.853646)
		(mid 302.052359 -24.852499)
		(end 302.051212 -24.85136)
		(stroke
			(width 0.068326)
			(type default)
		)
		(layer "F.Cu")
	)
	(gr_line
		(start 302.053498 -24.853646)
		(end 302.231298 -25.031446)
		(stroke
			(width 0.068326)
			(type default)
		)
		(layer "F.Cu")
	)
	(gr_arc
		(start 302.053498 -21.053552)
		(mid 302.052359 -21.052405)
		(end 302.051212 -21.051266)
		(stroke
			(width 0.068326)
			(type default)
		)
		(layer "F.Cu")
	)
	(gr_line
		(start 302.053498 -21.053552)
		(end 302.231298 -21.231352)
		(stroke
			(width 0.068326)
			(type default)
		)
		(layer "F.Cu")
	)
	(gr_line
		(start 302.09363 -210.896454)
		(end 302.24349 -211.046568)
		(stroke
			(width 0.068326)
			(type default)
		)
		(layer "F.Cu")
	)
	(gr_line
		(start 302.100234 -224.828354)
		(end 302.100234 -225.54438)
		(stroke
			(width 0.068326)
			(type default)
		)
		(layer "F.Cu")
	)
	(gr_arc
		(start 302.192944 -32.7152)
		(mid 302.278462 -32.958864)
		(end 302.49749 -33.095692)
		(stroke
			(width 0.068326)
			(type default)
		)
		(layer "F.Cu")
	)
	(gr_arc
		(start 302.23079 -34.594292)
		(mid 302.265844 -34.770518)
		(end 302.365664 -34.91992)
		(stroke
			(width 0.068326)
			(type default)
		)
		(layer "F.Cu")
	)
	(gr_arc
		(start 302.268382 -224.32264)
		(mid 302.143361 -224.561885)
		(end 302.100234 -224.828354)
		(stroke
			(width 0.068326)
			(type default)
		)
		(layer "F.Cu")
	)
	(gr_arc
		(start 302.268382 -224.32264)
		(mid 302.327016 -224.234888)
		(end 302.34763 -224.131378)
		(stroke
			(width 0.068326)
			(type default)
		)
		(layer "F.Cu")
	)
	(gr_arc
		(start 302.273716 -211.694268)
		(mid 302.323707 -211.619452)
		(end 302.34128 -211.5312)
		(stroke
			(width 0.068326)
			(type default)
		)
		(layer "F.Cu")
	)
	(gr_arc
		(start 302.34128 -211.28228)
		(mid 302.315811 -211.154708)
		(end 302.24349 -211.046568)
		(stroke
			(width 0.068326)
			(type default)
		)
		(layer "F.Cu")
	)
	(gr_line
		(start 302.34509 -21.6916)
		(end 302.345344 -21.6916)
		(stroke
			(width 0.068326)
			(type default)
		)
		(layer "F.Cu")
	)
	(gr_line
		(start 302.345344 -21.506688)
		(end 302.345344 -21.6916)
		(stroke
			(width 0.068326)
			(type default)
		)
		(layer "F.Cu")
	)
	(gr_arc
		(start 302.34763 -213.723474)
		(mid 302.255211 -213.25885)
		(end 301.99203 -212.864954)
		(stroke
			(width 0.068326)
			(type default)
		)
		(layer "F.Cu")
	)
	(gr_line
		(start 302.365664 -34.91992)
		(end 302.47209 -35.026346)
		(stroke
			(width 0.068326)
			(type default)
		)
		(layer "F.Cu")
	)
	(gr_arc
		(start 302.374554 -34.107882)
		(mid 302.268183 -34.266939)
		(end 302.23079 -34.454592)
		(stroke
			(width 0.068326)
			(type default)
		)
		(layer "F.Cu")
	)
	(gr_line
		(start 302.374554 -34.107882)
		(end 302.49749 -33.984692)
		(stroke
			(width 0.068326)
			(type default)
		)
		(layer "F.Cu")
	)
	(gr_arc
		(start 302.38446 -24.664924)
		(mid 302.400701 -24.746573)
		(end 302.446944 -24.8158)
		(stroke
			(width 0.068326)
			(type default)
		)
		(layer "F.Cu")
	)
	(gr_line
		(start 302.38446 -23.930102)
		(end 302.38446 -24.664924)
		(stroke
			(width 0.068326)
			(type default)
		)
		(layer "F.Cu")
	)
	(gr_arc
		(start 302.38446 -20.86483)
		(mid 302.384964 -20.881384)
		(end 302.386746 -20.89785)
		(stroke
			(width 0.068326)
			(type default)
		)
		(layer "F.Cu")
	)
	(gr_line
		(start 302.38446 -20.130008)
		(end 302.38446 -20.86483)
		(stroke
			(width 0.068326)
			(type default)
		)
		(layer "F.Cu")
	)
	(gr_arc
		(start 302.386746 -20.89785)
		(mid 302.387239 -20.900393)
		(end 302.387762 -20.90293)
		(stroke
			(width 0.068326)
			(type default)
		)
		(layer "F.Cu")
	)
	(gr_arc
		(start 302.387762 -20.90293)
		(mid 302.408757 -20.963827)
		(end 302.446944 -21.015706)
		(stroke
			(width 0.068326)
			(type default)
		)
		(layer "F.Cu")
	)
	(gr_arc
		(start 302.64608 -211.5312)
		(mid 302.66136 -211.607657)
		(end 302.704754 -211.672424)
		(stroke
			(width 0.068326)
			(type default)
		)
		(layer "F.Cu")
	)
	(gr_line
		(start 302.64989 -21.6916)
		(end 302.650144 -21.6916)
		(stroke
			(width 0.068326)
			(type default)
		)
		(layer "F.Cu")
	)
	(gr_arc
		(start 302.652684 -224.133664)
		(mid 302.672853 -224.234828)
		(end 302.730154 -224.320608)
		(stroke
			(width 0.068326)
			(type default)
		)
		(layer "F.Cu")
	)
	(gr_line
		(start 302.704754 -211.672424)
		(end 303.00803 -211.975954)
		(stroke
			(width 0.068326)
			(type default)
		)
		(layer "F.Cu")
	)
	(gr_arc
		(start 302.734726 -211.067904)
		(mid 302.669055 -211.166266)
		(end 302.64608 -211.28228)
		(stroke
			(width 0.068326)
			(type default)
		)
		(layer "F.Cu")
	)
	(gr_line
		(start 302.734726 -211.067904)
		(end 302.90643 -210.896454)
		(stroke
			(width 0.068326)
			(type default)
		)
		(layer "F.Cu")
	)
	(gr_arc
		(start 302.90008 -224.828354)
		(mid 302.856443 -224.560646)
		(end 302.730154 -224.320608)
		(stroke
			(width 0.068326)
			(type default)
		)
		(layer "F.Cu")
	)
	(gr_line
		(start 302.90008 -224.828354)
		(end 302.90008 -225.54438)
		(stroke
			(width 0.068326)
			(type default)
		)
		(layer "F.Cu")
	)
	(gr_arc
		(start 303.00803 -212.864954)
		(mid 302.745049 -213.258487)
		(end 302.652684 -213.722712)
		(stroke
			(width 0.068326)
			(type default)
		)
		(layer "F.Cu")
	)
	(gr_arc
		(start 303.784 -33.0835)
		(mid 303.987741 -32.901506)
		(end 304.0634 -32.639)
		(stroke
			(width 0.068326)
			(type default)
		)
		(layer "F.Cu")
	)
	(gr_line
		(start 303.8348 -36.284154)
		(end 303.98466 -36.134548)
		(stroke
			(width 0.068326)
			(type default)
		)
		(layer "F.Cu")
	)
	(gr_arc
		(start 303.98466 -36.134548)
		(mid 304.07119 -36.004953)
		(end 304.1015 -35.8521)
		(stroke
			(width 0.068326)
			(type default)
		)
		(layer "F.Cu")
	)
	(gr_arc
		(start 304.1015 -34.739072)
		(mid 304.018993 -34.32421)
		(end 303.784 -33.9725)
		(stroke
			(width 0.068326)
			(type default)
		)
		(layer "F.Cu")
	)
	(gr_arc
		(start 304.3682 -32.639)
		(mid 304.45172 -32.908481)
		(end 304.673 -33.0835)
		(stroke
			(width 0.068326)
			(type default)
		)
		(layer "F.Cu")
	)
	(gr_arc
		(start 304.4063 -35.8521)
		(mid 304.441354 -36.028326)
		(end 304.541174 -36.177728)
		(stroke
			(width 0.068326)
			(type default)
		)
		(layer "F.Cu")
	)
	(gr_line
		(start 304.541174 -36.177728)
		(end 304.6476 -36.284154)
		(stroke
			(width 0.068326)
			(type default)
		)
		(layer "F.Cu")
	)
	(gr_arc
		(start 304.673 -33.9725)
		(mid 304.475607 -34.267919)
		(end 304.4063 -34.61639)
		(stroke
			(width 0.068326)
			(type default)
		)
		(layer "F.Cu")
	)
	(gr_line
		(start 305.762914 -39.80942)
		(end 305.95189 -39.620444)
		(stroke
			(width 0.068326)
			(type default)
		)
		(layer "F.Cu")
	)
	(gr_line
		(start 305.930046 -33.95472)
		(end 306.079398 -34.104326)
		(stroke
			(width 0.068326)
			(type default)
		)
		(layer "F.Cu")
	)
	(gr_arc
		(start 305.930046 -33.06572)
		(mid 306.143456 -32.85346)
		(end 306.221638 -32.5628)
		(stroke
			(width 0.068326)
			(type default)
		)
		(layer "F.Cu")
	)
	(gr_arc
		(start 306.219606 -34.4424)
		(mid 306.183129 -34.259416)
		(end 306.079398 -34.104326)
		(stroke
			(width 0.068326)
			(type default)
		)
		(layer "F.Cu")
	)
	(gr_line
		(start 306.279042 -14.483842)
		(end 306.959 -15.1638)
		(stroke
			(width 0.060198)
			(type default)
		)
		(layer "F.Cu")
	)
	(gr_line
		(start 306.279042 -9.61517)
		(end 306.279042 -14.483842)
		(stroke
			(width 0.060198)
			(type default)
		)
		(layer "F.Cu")
	)
	(gr_line
		(start 306.386738 -39.620444)
		(end 306.575714 -39.80942)
		(stroke
			(width 0.068326)
			(type default)
		)
		(layer "F.Cu")
	)
	(gr_arc
		(start 306.526438 -32.5628)
		(mid 306.604966 -32.853687)
		(end 306.819046 -33.06572)
		(stroke
			(width 0.068326)
			(type default)
		)
		(layer "F.Cu")
	)
	(gr_arc
		(start 306.660804 -34.112708)
		(mid 306.559816 -34.263987)
		(end 306.524406 -34.4424)
		(stroke
			(width 0.068326)
			(type default)
		)
		(layer "F.Cu")
	)
	(gr_line
		(start 306.660804 -34.112708)
		(end 306.819046 -33.95472)
		(stroke
			(width 0.068326)
			(type default)
		)
		(layer "F.Cu")
	)
	(gr_line
		(start 306.959 -18.542)
		(end 308.134512 -19.717512)
		(stroke
			(width 0.060198)
			(type default)
		)
		(layer "F.Cu")
	)
	(gr_line
		(start 306.959 -15.1638)
		(end 306.959 -18.542)
		(stroke
			(width 0.060198)
			(type default)
		)
		(layer "F.Cu")
	)
	(gr_line
		(start 308.037992 -33.03651)
		(end 308.261766 -32.812482)
		(stroke
			(width 0.068326)
			(type default)
		)
		(layer "F.Cu")
	)
	(gr_line
		(start 308.134512 -24.981154)
		(end 308.134512 -25.33015)
		(stroke
			(width 0.068326)
			(type default)
		)
		(layer "F.Cu")
	)
	(gr_line
		(start 308.134512 -19.717512)
		(end 308.134512 -21.530056)
		(stroke
			(width 0.060198)
			(type default)
		)
		(layer "F.Cu")
	)
	(gr_arc
		(start 308.197758 -24.8285)
		(mid 308.15096 -24.898538)
		(end 308.134512 -24.981154)
		(stroke
			(width 0.068326)
			(type default)
		)
		(layer "F.Cu")
	)
	(gr_arc
		(start 308.261766 -32.812482)
		(mid 308.361752 -32.662981)
		(end 308.396894 -32.4866)
		(stroke
			(width 0.068326)
			(type default)
		)
		(layer "F.Cu")
	)
	(gr_arc
		(start 308.32044 -24.7777)
		(mid 308.254051 -24.790906)
		(end 308.197758 -24.8285)
		(stroke
			(width 0.068326)
			(type default)
		)
		(layer "F.Cu")
	)
	(gr_line
		(start 308.32044 -24.7777)
		(end 308.370224 -24.7777)
		(stroke
			(width 0.068326)
			(type default)
		)
		(layer "F.Cu")
	)
	(gr_arc
		(start 308.551326 -24.85136)
		(mid 308.467985 -24.796793)
		(end 308.370224 -24.7777)
		(stroke
			(width 0.068326)
			(type default)
		)
		(layer "F.Cu")
	)
	(gr_arc
		(start 308.553612 -24.853646)
		(mid 308.552473 -24.852499)
		(end 308.551326 -24.85136)
		(stroke
			(width 0.068326)
			(type default)
		)
		(layer "F.Cu")
	)
	(gr_line
		(start 308.553612 -24.853646)
		(end 308.731412 -25.031446)
		(stroke
			(width 0.068326)
			(type default)
		)
		(layer "F.Cu")
	)
	(gr_arc
		(start 308.701694 -32.4866)
		(mid 308.737747 -32.668323)
		(end 308.840632 -32.822388)
		(stroke
			(width 0.068326)
			(type default)
		)
		(layer "F.Cu")
	)
	(gr_line
		(start 308.840632 -32.822388)
		(end 309.055008 -33.03651)
		(stroke
			(width 0.068326)
			(type default)
		)
		(layer "F.Cu")
	)
	(gr_line
		(start 308.88432 -23.930102)
		(end 308.884574 -23.930356)
		(stroke
			(width 0.068326)
			(type default)
		)
		(layer "F.Cu")
	)
	(gr_arc
		(start 308.884574 -24.664924)
		(mid 308.900815 -24.746573)
		(end 308.947058 -24.8158)
		(stroke
			(width 0.068326)
			(type default)
		)
		(layer "F.Cu")
	)
	(gr_line
		(start 308.884574 -23.930356)
		(end 308.884574 -24.664924)
		(stroke
			(width 0.068326)
			(type default)
		)
		(layer "F.Cu")
	)
	(gr_line
		(start 309.992014 -212.864954)
		(end 309.992522 -212.865208)
		(stroke
			(width 0.068326)
			(type default)
		)
		(layer "F.Cu")
	)
	(gr_line
		(start 309.992014 -211.975954)
		(end 309.992268 -211.975954)
		(stroke
			(width 0.068326)
			(type default)
		)
		(layer "F.Cu")
	)
	(gr_line
		(start 309.992268 -211.975954)
		(end 310.273954 -211.694268)
		(stroke
			(width 0.068326)
			(type default)
		)
		(layer "F.Cu")
	)
	(gr_line
		(start 310.093868 -210.896454)
		(end 310.244236 -211.047076)
		(stroke
			(width 0.068326)
			(type default)
		)
		(layer "F.Cu")
	)
	(gr_line
		(start 310.100218 -224.828608)
		(end 310.100218 -225.54438)
		(stroke
			(width 0.068326)
			(type default)
		)
		(layer "F.Cu")
	)
	(gr_line
		(start 310.100218 -224.828608)
		(end 310.100472 -224.828354)
		(stroke
			(width 0.068326)
			(type default)
		)
		(layer "F.Cu")
	)
	(gr_arc
		(start 310.26862 -224.32264)
		(mid 310.143594 -224.561883)
		(end 310.100472 -224.828354)
		(stroke
			(width 0.068326)
			(type default)
		)
		(layer "F.Cu")
	)
	(gr_arc
		(start 310.26862 -224.32264)
		(mid 310.327254 -224.234888)
		(end 310.347868 -224.131378)
		(stroke
			(width 0.068326)
			(type default)
		)
		(layer "F.Cu")
	)
	(gr_arc
		(start 310.273954 -211.694268)
		(mid 310.323945 -211.619452)
		(end 310.341518 -211.5312)
		(stroke
			(width 0.068326)
			(type default)
		)
		(layer "F.Cu")
	)
	(gr_arc
		(start 310.341518 -211.281518)
		(mid 310.316184 -211.154626)
		(end 310.244236 -211.047076)
		(stroke
			(width 0.068326)
			(type default)
		)
		(layer "F.Cu")
	)
	(gr_arc
		(start 310.347868 -213.723474)
		(mid 310.25557 -213.258991)
		(end 309.992522 -212.865208)
		(stroke
			(width 0.068326)
			(type default)
		)
		(layer "F.Cu")
	)
	(gr_line
		(start 310.374792 -34.000186)
		(end 310.584596 -34.209736)
		(stroke
			(width 0.068326)
			(type default)
		)
		(layer "F.Cu")
	)
	(gr_arc
		(start 310.374792 -33.111186)
		(mid 310.567903 -32.909347)
		(end 310.63819 -32.639)
		(stroke
			(width 0.068326)
			(type default)
		)
		(layer "F.Cu")
	)
	(gr_line
		(start 310.384444 -24.981154)
		(end 310.384444 -25.33015)
		(stroke
			(width 0.068326)
			(type default)
		)
		(layer "F.Cu")
	)
	(gr_line
		(start 310.384444 -21.307806)
		(end 310.384444 -21.530056)
		(stroke
			(width 0.068326)
			(type default)
		)
		(layer "F.Cu")
	)
	(gr_line
		(start 310.425592 -35.04184)
		(end 310.575452 -34.892234)
		(stroke
			(width 0.068326)
			(type default)
		)
		(layer "F.Cu")
	)
	(gr_arc
		(start 310.438546 -21.117306)
		(mid 310.398235 -21.20879)
		(end 310.384444 -21.307806)
		(stroke
			(width 0.068326)
			(type default)
		)
		(layer "F.Cu")
	)
	(gr_line
		(start 310.438546 -21.117306)
		(end 310.4642 -21.07565)
		(stroke
			(width 0.068326)
			(type default)
		)
		(layer "F.Cu")
	)
	(gr_arc
		(start 310.44769 -24.8285)
		(mid 310.400879 -24.898533)
		(end 310.384444 -24.981154)
		(stroke
			(width 0.068326)
			(type default)
		)
		(layer "F.Cu")
	)
	(gr_arc
		(start 310.570372 -24.7777)
		(mid 310.503973 -24.790887)
		(end 310.44769 -24.8285)
		(stroke
			(width 0.068326)
			(type default)
		)
		(layer "F.Cu")
	)
	(gr_line
		(start 310.570372 -24.7777)
		(end 310.620156 -24.7777)
		(stroke
			(width 0.068326)
			(type default)
		)
		(layer "F.Cu")
	)
	(gr_arc
		(start 310.575452 -34.892234)
		(mid 310.661979 -34.762638)
		(end 310.692292 -34.609786)
		(stroke
			(width 0.068326)
			(type default)
		)
		(layer "F.Cu")
	)
	(gr_arc
		(start 310.646318 -211.5312)
		(mid 310.661601 -211.607654)
		(end 310.704992 -211.672424)
		(stroke
			(width 0.068326)
			(type default)
		)
		(layer "F.Cu")
	)
	(gr_arc
		(start 310.652922 -224.133664)
		(mid 310.673093 -224.234825)
		(end 310.730392 -224.320608)
		(stroke
			(width 0.068326)
			(type default)
		)
		(layer "F.Cu")
	)
	(gr_arc
		(start 310.685942 -20.985226)
		(mid 310.560355 -20.994322)
		(end 310.4642 -21.07565)
		(stroke
			(width 0.068326)
			(type default)
		)
		(layer "F.Cu")
	)
	(gr_arc
		(start 310.692292 -34.470086)
		(mid 310.664313 -34.329215)
		(end 310.584596 -34.209736)
		(stroke
			(width 0.068326)
			(type default)
		)
		(layer "F.Cu")
	)
	(gr_line
		(start 310.704992 -211.672424)
		(end 311.008014 -211.975446)
		(stroke
			(width 0.068326)
			(type default)
		)
		(layer "F.Cu")
	)
	(gr_arc
		(start 310.734456 -211.068666)
		(mid 310.669217 -211.166329)
		(end 310.646318 -211.281518)
		(stroke
			(width 0.068326)
			(type default)
		)
		(layer "F.Cu")
	)
	(gr_line
		(start 310.734456 -211.068666)
		(end 310.906668 -210.896454)
		(stroke
			(width 0.068326)
			(type default)
		)
		(layer "F.Cu")
	)
	(gr_arc
		(start 310.801258 -24.85136)
		(mid 310.717906 -24.79683)
		(end 310.620156 -24.7777)
		(stroke
			(width 0.068326)
			(type default)
		)
		(layer "F.Cu")
	)
	(gr_arc
		(start 310.803544 -24.853646)
		(mid 310.802405 -24.852499)
		(end 310.801258 -24.85136)
		(stroke
			(width 0.068326)
			(type default)
		)
		(layer "F.Cu")
	)
	(gr_line
		(start 310.803544 -24.853646)
		(end 310.981344 -25.031446)
		(stroke
			(width 0.068326)
			(type default)
		)
		(layer "F.Cu")
	)
	(gr_line
		(start 310.900064 -224.828608)
		(end 310.900064 -225.54438)
		(stroke
			(width 0.068326)
			(type default)
		)
		(layer "F.Cu")
	)
	(gr_line
		(start 310.900064 -224.828608)
		(end 310.900318 -224.828354)
		(stroke
			(width 0.068326)
			(type default)
		)
		(layer "F.Cu")
	)
	(gr_arc
		(start 310.900318 -224.828354)
		(mid 310.856681 -224.560646)
		(end 310.730392 -224.320608)
		(stroke
			(width 0.068326)
			(type default)
		)
		(layer "F.Cu")
	)
	(gr_arc
		(start 310.916066 -21.140674)
		(mid 310.81488 -21.04241)
		(end 310.685942 -20.985226)
		(stroke
			(width 0.068326)
			(type default)
		)
		(layer "F.Cu")
	)
	(gr_line
		(start 310.916066 -21.140674)
		(end 311.054242 -21.332698)
		(stroke
			(width 0.068326)
			(type default)
		)
		(layer "F.Cu")
	)
	(gr_arc
		(start 310.94299 -32.639)
		(mid 311.030769 -32.924444)
		(end 311.263792 -33.111186)
		(stroke
			(width 0.068326)
			(type default)
		)
		(layer "F.Cu")
	)
	(gr_arc
		(start 310.997092 -34.609786)
		(mid 311.032146 -34.786012)
		(end 311.131966 -34.935414)
		(stroke
			(width 0.068326)
			(type default)
		)
		(layer "F.Cu")
	)
	(gr_arc
		(start 311.008014 -212.864954)
		(mid 310.745201 -213.25826)
		(end 310.652922 -213.722204)
		(stroke
			(width 0.068326)
			(type default)
		)
		(layer "F.Cu")
	)
	(gr_line
		(start 311.008014 -211.975446)
		(end 311.008014 -211.975954)
		(stroke
			(width 0.068326)
			(type default)
		)
		(layer "F.Cu")
	)
	(gr_line
		(start 311.131966 -34.935414)
		(end 311.238392 -35.04184)
		(stroke
			(width 0.068326)
			(type default)
		)
		(layer "F.Cu")
	)
	(gr_arc
		(start 311.134506 -24.664924)
		(mid 311.150747 -24.746573)
		(end 311.19699 -24.8158)
		(stroke
			(width 0.068326)
			(type default)
		)
		(layer "F.Cu")
	)
	(gr_line
		(start 311.134506 -23.930102)
		(end 311.134506 -24.664924)
		(stroke
			(width 0.068326)
			(type default)
		)
		(layer "F.Cu")
	)
	(gr_arc
		(start 311.134506 -20.130008)
		(mid 311.122636 -20.462295)
		(end 311.174892 -20.790662)
		(stroke
			(width 0.068326)
			(type default)
		)
		(layer "F.Cu")
	)
	(gr_arc
		(start 311.140856 -34.123376)
		(mid 311.034485 -34.282433)
		(end 310.997092 -34.470086)
		(stroke
			(width 0.068326)
			(type default)
		)
		(layer "F.Cu")
	)
	(gr_line
		(start 311.140856 -34.123376)
		(end 311.263792 -34.000186)
		(stroke
			(width 0.068326)
			(type default)
		)
		(layer "F.Cu")
	)
	(gr_arc
		(start 311.174892 -20.790662)
		(mid 311.187085 -20.83589)
		(end 311.200292 -20.880832)
		(stroke
			(width 0.068326)
			(type default)
		)
		(layer "F.Cu")
	)
	(gr_arc
		(start 311.200292 -20.880832)
		(mid 311.257213 -21.041283)
		(end 311.327038 -21.196554)
		(stroke
			(width 0.068326)
			(type default)
		)
		(layer "F.Cu")
	)
	(gr_arc
		(start 312.625486 -33.111948)
		(mid 312.818792 -32.881157)
		(end 312.888122 -32.5882)
		(stroke
			(width 0.068326)
			(type default)
		)
		(layer "F.Cu")
	)
	(gr_line
		(start 312.634376 -24.981154)
		(end 312.634376 -25.33015)
		(stroke
			(width 0.068326)
			(type default)
		)
		(layer "F.Cu")
	)
	(gr_line
		(start 312.634376 -21.18106)
		(end 312.634376 -21.530056)
		(stroke
			(width 0.068326)
			(type default)
		)
		(layer "F.Cu")
	)
	(gr_line
		(start 312.676286 -36.185602)
		(end 312.826146 -36.035996)
		(stroke
			(width 0.068326)
			(type default)
		)
		(layer "F.Cu")
	)
	(gr_arc
		(start 312.697622 -21.028406)
		(mid 312.650827 -21.098444)
		(end 312.634376 -21.18106)
		(stroke
			(width 0.068326)
			(type default)
		)
		(layer "F.Cu")
	)
	(gr_arc
		(start 312.820304 -20.977606)
		(mid 312.753898 -20.990783)
		(end 312.697622 -21.028406)
		(stroke
			(width 0.068326)
			(type default)
		)
		(layer "F.Cu")
	)
	(gr_line
		(start 312.820304 -20.977606)
		(end 312.870088 -20.977606)
		(stroke
			(width 0.068326)
			(type default)
		)
		(layer "F.Cu")
	)
	(gr_arc
		(start 312.826146 -36.035996)
		(mid 312.912694 -35.906404)
		(end 312.942986 -35.753548)
		(stroke
			(width 0.068326)
			(type default)
		)
		(layer "F.Cu")
	)
	(gr_arc
		(start 312.942986 -34.76752)
		(mid 312.860494 -34.352649)
		(end 312.625486 -34.000948)
		(stroke
			(width 0.068326)
			(type default)
		)
		(layer "F.Cu")
	)
	(gr_arc
		(start 312.9788 -24.7904)
		(mid 312.746716 -24.777641)
		(end 312.634376 -24.981154)
		(stroke
			(width 0.068326)
			(type default)
		)
		(layer "F.Cu")
	)
	(gr_arc
		(start 313.05119 -24.85136)
		(mid 313.016307 -24.819322)
		(end 312.9788 -24.7904)
		(stroke
			(width 0.068326)
			(type default)
		)
		(layer "F.Cu")
	)
	(gr_arc
		(start 313.05119 -21.051266)
		(mid 312.96784 -20.996724)
		(end 312.870088 -20.977606)
		(stroke
			(width 0.068326)
			(type default)
		)
		(layer "F.Cu")
	)
	(gr_arc
		(start 313.053476 -24.853646)
		(mid 313.052337 -24.852499)
		(end 313.05119 -24.85136)
		(stroke
			(width 0.068326)
			(type default)
		)
		(layer "F.Cu")
	)
	(gr_line
		(start 313.053476 -24.853646)
		(end 313.231276 -25.031446)
		(stroke
			(width 0.068326)
			(type default)
		)
		(layer "F.Cu")
	)
	(gr_arc
		(start 313.053476 -21.053552)
		(mid 313.052337 -21.052405)
		(end 313.05119 -21.051266)
		(stroke
			(width 0.068326)
			(type default)
		)
		(layer "F.Cu")
	)
	(gr_line
		(start 313.053476 -21.053552)
		(end 313.231276 -21.231352)
		(stroke
			(width 0.068326)
			(type default)
		)
		(layer "F.Cu")
	)
	(gr_line
		(start 313.19216 -211.975954)
		(end 313.473846 -211.694268)
		(stroke
			(width 0.068326)
			(type default)
		)
		(layer "F.Cu")
	)
	(gr_arc
		(start 313.192922 -32.5882)
		(mid 313.279733 -32.895484)
		(end 313.514486 -33.111948)
		(stroke
			(width 0.068326)
			(type default)
		)
		(layer "F.Cu")
	)
	(gr_arc
		(start 313.247786 -35.753548)
		(mid 313.28284 -35.929774)
		(end 313.38266 -36.079176)
		(stroke
			(width 0.068326)
			(type default)
		)
		(layer "F.Cu")
	)
	(gr_line
		(start 313.29376 -210.896454)
		(end 313.447176 -211.050124)
		(stroke
			(width 0.068326)
			(type default)
		)
		(layer "F.Cu")
	)
	(gr_line
		(start 313.30011 -224.828608)
		(end 313.30011 -225.54438)
		(stroke
			(width 0.068326)
			(type default)
		)
		(layer "F.Cu")
	)
	(gr_line
		(start 313.30011 -224.828608)
		(end 313.300364 -224.828354)
		(stroke
			(width 0.068326)
			(type default)
		)
		(layer "F.Cu")
	)
	(gr_line
		(start 313.38266 -36.079176)
		(end 313.489086 -36.185602)
		(stroke
			(width 0.068326)
			(type default)
		)
		(layer "F.Cu")
	)
	(gr_arc
		(start 313.384438 -24.664924)
		(mid 313.400679 -24.746573)
		(end 313.446922 -24.8158)
		(stroke
			(width 0.068326)
			(type default)
		)
		(layer "F.Cu")
	)
	(gr_line
		(start 313.384438 -23.930102)
		(end 313.384438 -24.664924)
		(stroke
			(width 0.068326)
			(type default)
		)
		(layer "F.Cu")
	)
	(gr_arc
		(start 313.384438 -20.86483)
		(mid 313.400679 -20.946479)
		(end 313.446922 -21.015706)
		(stroke
			(width 0.068326)
			(type default)
		)
		(layer "F.Cu")
	)
	(gr_line
		(start 313.384438 -20.130008)
		(end 313.384438 -20.86483)
		(stroke
			(width 0.068326)
			(type default)
		)
		(layer "F.Cu")
	)
	(gr_arc
		(start 313.468512 -224.32264)
		(mid 313.343487 -224.561884)
		(end 313.300364 -224.828354)
		(stroke
			(width 0.068326)
			(type default)
		)
		(layer "F.Cu")
	)
	(gr_arc
		(start 313.468512 -224.32264)
		(mid 313.527146 -224.234888)
		(end 313.54776 -224.131378)
		(stroke
			(width 0.068326)
			(type default)
		)
		(layer "F.Cu")
	)
	(gr_arc
		(start 313.473846 -211.694268)
		(mid 313.523837 -211.619452)
		(end 313.54141 -211.5312)
		(stroke
			(width 0.068326)
			(type default)
		)
		(layer "F.Cu")
	)
	(gr_arc
		(start 313.514486 -34.000948)
		(mid 313.317093 -34.296367)
		(end 313.247786 -34.644838)
		(stroke
			(width 0.068326)
			(type default)
		)
		(layer "F.Cu")
	)
	(gr_arc
		(start 313.54141 -211.2772)
		(mid 313.516869 -211.154294)
		(end 313.447176 -211.050124)
		(stroke
			(width 0.068326)
			(type default)
		)
		(layer "F.Cu")
	)
	(gr_arc
		(start 313.54776 -213.723474)
		(mid 313.455341 -213.25885)
		(end 313.19216 -212.864954)
		(stroke
			(width 0.068326)
			(type default)
		)
		(layer "F.Cu")
	)
	(gr_arc
		(start 313.84621 -211.5312)
		(mid 313.861492 -211.607655)
		(end 313.904884 -211.672424)
		(stroke
			(width 0.068326)
			(type default)
		)
		(layer "F.Cu")
	)
	(gr_arc
		(start 313.852814 -224.133664)
		(mid 313.872985 -224.234826)
		(end 313.930284 -224.320608)
		(stroke
			(width 0.068326)
			(type default)
		)
		(layer "F.Cu")
	)
	(gr_line
		(start 313.904884 -211.672424)
		(end 314.20816 -211.975954)
		(stroke
			(width 0.068326)
			(type default)
		)
		(layer "F.Cu")
	)
	(gr_arc
		(start 313.939174 -211.063586)
		(mid 313.870317 -211.166728)
		(end 313.84621 -211.288376)
		(stroke
			(width 0.068326)
			(type default)
		)
		(layer "F.Cu")
	)
	(gr_line
		(start 313.939174 -211.063586)
		(end 314.10656 -210.896454)
		(stroke
			(width 0.068326)
			(type default)
		)
		(layer "F.Cu")
	)
	(gr_arc
		(start 314.10021 -224.828354)
		(mid 314.056573 -224.560646)
		(end 313.930284 -224.320608)
		(stroke
			(width 0.068326)
			(type default)
		)
		(layer "F.Cu")
	)
	(gr_line
		(start 314.10021 -224.828354)
		(end 314.10021 -225.54438)
		(stroke
			(width 0.068326)
			(type default)
		)
		(layer "F.Cu")
	)
	(gr_arc
		(start 314.20816 -212.864954)
		(mid 313.945173 -213.258486)
		(end 313.852814 -213.722712)
		(stroke
			(width 0.068326)
			(type default)
		)
		(layer "F.Cu")
	)
	(gr_line
		(start 314.833 -33.9725)
		(end 315.042804 -34.18205)
		(stroke
			(width 0.068326)
			(type default)
		)
		(layer "F.Cu")
	)
	(gr_arc
		(start 314.833 -33.0835)
		(mid 315.038137 -32.858262)
		(end 315.1124 -32.5628)
		(stroke
			(width 0.068326)
			(type default)
		)
		(layer "F.Cu")
	)
	(gr_line
		(start 314.8838 -35.014154)
		(end 315.03366 -34.864548)
		(stroke
			(width 0.068326)
			(type default)
		)
		(layer "F.Cu")
	)
	(gr_arc
		(start 315.03366 -34.864548)
		(mid 315.12019 -34.734953)
		(end 315.1505 -34.5821)
		(stroke
			(width 0.068326)
			(type default)
		)
		(layer "F.Cu")
	)
	(gr_arc
		(start 315.1505 -34.4424)
		(mid 315.122526 -34.301525)
		(end 315.042804 -34.18205)
		(stroke
			(width 0.068326)
			(type default)
		)
		(layer "F.Cu")
	)
	(gr_arc
		(start 315.4172 -32.5628)
		(mid 315.499004 -32.864474)
		(end 315.722 -33.0835)
		(stroke
			(width 0.068326)
			(type default)
		)
		(layer "F.Cu")
	)
	(gr_arc
		(start 315.4553 -34.5821)
		(mid 315.490354 -34.758326)
		(end 315.590174 -34.907728)
		(stroke
			(width 0.068326)
			(type default)
		)
		(layer "F.Cu")
	)
	(gr_line
		(start 315.590174 -34.907728)
		(end 315.6966 -35.014154)
		(stroke
			(width 0.068326)
			(type default)
		)
		(layer "F.Cu")
	)
	(gr_arc
		(start 315.599064 -34.09569)
		(mid 315.492693 -34.254747)
		(end 315.4553 -34.4424)
		(stroke
			(width 0.068326)
			(type default)
		)
		(layer "F.Cu")
	)
	(gr_line
		(start 315.599064 -34.09569)
		(end 315.722 -33.9725)
		(stroke
			(width 0.068326)
			(type default)
		)
		(layer "F.Cu")
	)
	(gr_line
		(start 316.392052 -212.864954)
		(end 316.39256 -212.865208)
		(stroke
			(width 0.068326)
			(type default)
		)
		(layer "F.Cu")
	)
	(gr_line
		(start 316.392052 -211.975954)
		(end 316.392306 -211.975954)
		(stroke
			(width 0.068326)
			(type default)
		)
		(layer "F.Cu")
	)
	(gr_line
		(start 316.392306 -211.975954)
		(end 316.673992 -211.694268)
		(stroke
			(width 0.068326)
			(type default)
		)
		(layer "F.Cu")
	)
	(gr_line
		(start 316.493906 -210.896454)
		(end 316.627002 -211.02955)
		(stroke
			(width 0.068326)
			(type default)
		)
		(layer "F.Cu")
	)
	(gr_line
		(start 316.500002 -224.828862)
		(end 316.500002 -225.54438)
		(stroke
			(width 0.068326)
			(type default)
		)
		(layer "F.Cu")
	)
	(gr_line
		(start 316.500002 -224.828862)
		(end 316.50051 -224.828354)
		(stroke
			(width 0.068326)
			(type default)
		)
		(layer "F.Cu")
	)
	(gr_arc
		(start 316.668658 -224.32264)
		(mid 316.543641 -224.561885)
		(end 316.50051 -224.828354)
		(stroke
			(width 0.068326)
			(type default)
		)
		(layer "F.Cu")
	)
	(gr_arc
		(start 316.668658 -224.32264)
		(mid 316.727292 -224.234888)
		(end 316.747906 -224.131378)
		(stroke
			(width 0.068326)
			(type default)
		)
		(layer "F.Cu")
	)
	(gr_arc
		(start 316.673992 -211.694268)
		(mid 316.723983 -211.619452)
		(end 316.741556 -211.5312)
		(stroke
			(width 0.068326)
			(type default)
		)
		(layer "F.Cu")
	)
	(gr_arc
		(start 316.741556 -211.306156)
		(mid 316.711781 -211.156466)
		(end 316.627002 -211.02955)
		(stroke
			(width 0.068326)
			(type default)
		)
		(layer "F.Cu")
	)
	(gr_arc
		(start 316.747906 -213.723474)
		(mid 316.655608 -213.258991)
		(end 316.39256 -212.865208)
		(stroke
			(width 0.068326)
			(type default)
		)
		(layer "F.Cu")
	)
	(gr_arc
		(start 317.046356 -211.5312)
		(mid 317.061641 -211.607652)
		(end 317.10503 -211.672424)
		(stroke
			(width 0.068326)
			(type default)
		)
		(layer "F.Cu")
	)
	(gr_arc
		(start 317.05296 -224.133664)
		(mid 317.073127 -224.234829)
		(end 317.13043 -224.320608)
		(stroke
			(width 0.068326)
			(type default)
		)
		(layer "F.Cu")
	)
	(gr_line
		(start 317.10503 -211.672424)
		(end 317.408052 -211.975446)
		(stroke
			(width 0.068326)
			(type default)
		)
		(layer "F.Cu")
	)
	(gr_arc
		(start 317.15202 -211.05114)
		(mid 317.07381 -211.168132)
		(end 317.046356 -211.306156)
		(stroke
			(width 0.068326)
			(type default)
		)
		(layer "F.Cu")
	)
	(gr_line
		(start 317.15202 -211.05114)
		(end 317.306706 -210.896454)
		(stroke
			(width 0.068326)
			(type default)
		)
		(layer "F.Cu")
	)
	(gr_line
		(start 317.300102 -224.828608)
		(end 317.300102 -225.54438)
		(stroke
			(width 0.068326)
			(type default)
		)
		(layer "F.Cu")
	)
	(gr_line
		(start 317.300102 -224.828608)
		(end 317.300356 -224.828354)
		(stroke
			(width 0.068326)
			(type default)
		)
		(layer "F.Cu")
	)
	(gr_arc
		(start 317.300356 -224.828354)
		(mid 317.256719 -224.560646)
		(end 317.13043 -224.320608)
		(stroke
			(width 0.068326)
			(type default)
		)
		(layer "F.Cu")
	)
	(gr_arc
		(start 317.408052 -212.864954)
		(mid 317.145252 -213.258264)
		(end 317.05296 -213.722204)
		(stroke
			(width 0.068326)
			(type default)
		)
		(layer "F.Cu")
	)
	(gr_line
		(start 317.408052 -211.975446)
		(end 317.408052 -211.975954)
		(stroke
			(width 0.068326)
			(type default)
		)
		(layer "F.Cu")
	)
	(gr_line
		(start 317.418466 -32.98063)
		(end 317.648844 -32.749998)
		(stroke
			(width 0.068326)
			(type default)
		)
		(layer "F.Cu")
	)
	(gr_arc
		(start 317.648844 -32.749998)
		(mid 317.745248 -32.605858)
		(end 317.779146 -32.4358)
		(stroke
			(width 0.068326)
			(type default)
		)
		(layer "F.Cu")
	)
	(gr_arc
		(start 318.083946 -32.4358)
		(mid 318.117856 -32.605852)
		(end 318.214248 -32.749998)
		(stroke
			(width 0.068326)
			(type default)
		)
		(layer "F.Cu")
	)
	(gr_line
		(start 318.214248 -32.749998)
		(end 318.444626 -32.98063)
		(stroke
			(width 0.068326)
			(type default)
		)
		(layer "F.Cu")
	)
	(gr_line
		(start 319.134236 -13.581126)
		(end 319.13449 -13.58138)
		(stroke
			(width 0.068326)
			(type default)
		)
		(layer "F.Cu")
	)
	(gr_line
		(start 319.13449 -24.981154)
		(end 319.13449 -25.33015)
		(stroke
			(width 0.068326)
			(type default)
		)
		(layer "F.Cu")
	)
	(gr_line
		(start 319.13449 -13.58138)
		(end 319.13449 -13.930122)
		(stroke
			(width 0.068326)
			(type default)
		)
		(layer "F.Cu")
	)
	(gr_arc
		(start 319.197482 -13.428472)
		(mid 319.150684 -13.49851)
		(end 319.134236 -13.581126)
		(stroke
			(width 0.068326)
			(type default)
		)
		(layer "F.Cu")
	)
	(gr_arc
		(start 319.197736 -24.8285)
		(mid 319.150938 -24.898538)
		(end 319.13449 -24.981154)
		(stroke
			(width 0.068326)
			(type default)
		)
		(layer "F.Cu")
	)
	(gr_arc
		(start 319.320164 -13.377672)
		(mid 319.253775 -13.390878)
		(end 319.197482 -13.428472)
		(stroke
			(width 0.068326)
			(type default)
		)
		(layer "F.Cu")
	)
	(gr_line
		(start 319.320164 -13.377672)
		(end 319.369948 -13.377672)
		(stroke
			(width 0.068326)
			(type default)
		)
		(layer "F.Cu")
	)
	(gr_arc
		(start 319.320418 -24.7777)
		(mid 319.254029 -24.790906)
		(end 319.197736 -24.8285)
		(stroke
			(width 0.068326)
			(type default)
		)
		(layer "F.Cu")
	)
	(gr_line
		(start 319.320418 -24.7777)
		(end 319.370202 -24.7777)
		(stroke
			(width 0.068326)
			(type default)
		)
		(layer "F.Cu")
	)
	(gr_arc
		(start 319.55105 -13.451332)
		(mid 319.467709 -13.396765)
		(end 319.369948 -13.377672)
		(stroke
			(width 0.068326)
			(type default)
		)
		(layer "F.Cu")
	)
	(gr_arc
		(start 319.551304 -24.85136)
		(mid 319.467963 -24.796793)
		(end 319.370202 -24.7777)
		(stroke
			(width 0.068326)
			(type default)
		)
		(layer "F.Cu")
	)
	(gr_arc
		(start 319.553336 -13.453618)
		(mid 319.552197 -13.452471)
		(end 319.55105 -13.451332)
		(stroke
			(width 0.068326)
			(type default)
		)
		(layer "F.Cu")
	)
	(gr_arc
		(start 319.55359 -24.853646)
		(mid 319.552451 -24.852499)
		(end 319.551304 -24.85136)
		(stroke
			(width 0.068326)
			(type default)
		)
		(layer "F.Cu")
	)
	(gr_line
		(start 319.55359 -24.853646)
		(end 319.73139 -25.031446)
		(stroke
			(width 0.068326)
			(type default)
		)
		(layer "F.Cu")
	)
	(gr_line
		(start 319.592198 -211.975954)
		(end 319.873884 -211.694268)
		(stroke
			(width 0.068326)
			(type default)
		)
		(layer "F.Cu")
	)
	(gr_arc
		(start 319.670176 -33.062926)
		(mid 319.867213 -32.810343)
		(end 319.937384 -32.497776)
		(stroke
			(width 0.068326)
			(type default)
		)
		(layer "F.Cu")
	)
	(gr_line
		(start 319.693798 -210.896454)
		(end 319.827148 -211.030058)
		(stroke
			(width 0.068326)
			(type default)
		)
		(layer "F.Cu")
	)
	(gr_line
		(start 319.700148 -224.828608)
		(end 319.700148 -225.54438)
		(stroke
			(width 0.068326)
			(type default)
		)
		(layer "F.Cu")
	)
	(gr_line
		(start 319.700148 -224.828608)
		(end 319.700402 -224.828354)
		(stroke
			(width 0.068326)
			(type default)
		)
		(layer "F.Cu")
	)
	(gr_line
		(start 319.710816 -26.85288)
		(end 319.71107 -26.85288)
		(stroke
			(width 0.068326)
			(type default)
		)
		(layer "F.Cu")
	)
	(gr_line
		(start 319.720976 -37.02558)
		(end 319.870836 -36.875974)
		(stroke
			(width 0.068326)
			(type default)
		)
		(layer "F.Cu")
	)
	(gr_arc
		(start 319.86855 -224.32264)
		(mid 319.743534 -224.561886)
		(end 319.700402 -224.828354)
		(stroke
			(width 0.068326)
			(type default)
		)
		(layer "F.Cu")
	)
	(gr_arc
		(start 319.86855 -224.32264)
		(mid 319.927184 -224.234888)
		(end 319.947798 -224.131378)
		(stroke
			(width 0.068326)
			(type default)
		)
		(layer "F.Cu")
	)
	(gr_arc
		(start 319.870836 -36.875974)
		(mid 319.957379 -36.746381)
		(end 319.987676 -36.593526)
		(stroke
			(width 0.068326)
			(type default)
		)
		(layer "F.Cu")
	)
	(gr_arc
		(start 319.873884 -211.694268)
		(mid 319.923875 -211.619452)
		(end 319.941448 -211.5312)
		(stroke
			(width 0.068326)
			(type default)
		)
		(layer "F.Cu")
	)
	(gr_line
		(start 319.884298 -23.930102)
		(end 319.884552 -23.930356)
		(stroke
			(width 0.068326)
			(type default)
		)
		(layer "F.Cu")
	)
	(gr_arc
		(start 319.884298 -13.264896)
		(mid 319.886869 -13.298583)
		(end 319.894712 -13.331444)
		(stroke
			(width 0.068326)
			(type default)
		)
		(layer "F.Cu")
	)
	(gr_line
		(start 319.884298 -12.530074)
		(end 319.884298 -13.264896)
		(stroke
			(width 0.068326)
			(type default)
		)
		(layer "F.Cu")
	)
	(gr_arc
		(start 319.884552 -24.664924)
		(mid 319.900775 -24.746583)
		(end 319.947036 -24.8158)
		(stroke
			(width 0.068326)
			(type default)
		)
		(layer "F.Cu")
	)
	(gr_line
		(start 319.884552 -23.930356)
		(end 319.884552 -24.664924)
		(stroke
			(width 0.068326)
			(type default)
		)
		(layer "F.Cu")
	)
	(gr_arc
		(start 319.894712 -13.331444)
		(mid 319.906255 -13.359572)
		(end 319.921636 -13.3858)
		(stroke
			(width 0.068326)
			(type default)
		)
		(layer "F.Cu")
	)
	(gr_arc
		(start 319.921636 -13.3858)
		(mid 319.933521 -13.401364)
		(end 319.946782 -13.415772)
		(stroke
			(width 0.068326)
			(type default)
		)
		(layer "F.Cu")
	)
	(gr_arc
		(start 319.941448 -211.305648)
		(mid 319.911686 -211.156497)
		(end 319.827148 -211.030058)
		(stroke
			(width 0.068326)
			(type default)
		)
		(layer "F.Cu")
	)
	(gr_arc
		(start 319.947798 -213.723474)
		(mid 319.855379 -213.25885)
		(end 319.592198 -212.864954)
		(stroke
			(width 0.068326)
			(type default)
		)
		(layer "F.Cu")
	)
	(gr_arc
		(start 319.987676 -34.718498)
		(mid 319.905182 -34.303626)
		(end 319.670176 -33.951926)
		(stroke
			(width 0.068326)
			(type default)
		)
		(layer "F.Cu")
	)
	(gr_arc
		(start 320.242184 -32.497776)
		(mid 320.326819 -32.821776)
		(end 320.559176 -33.062926)
		(stroke
			(width 0.068326)
			(type default)
		)
		(layer "F.Cu")
	)
	(gr_arc
		(start 320.246248 -211.5312)
		(mid 320.261532 -211.607653)
		(end 320.304922 -211.672424)
		(stroke
			(width 0.068326)
			(type default)
		)
		(layer "F.Cu")
	)
	(gr_arc
		(start 320.252852 -224.133664)
		(mid 320.273019 -224.234829)
		(end 320.330322 -224.320608)
		(stroke
			(width 0.068326)
			(type default)
		)
		(layer "F.Cu")
	)
	(gr_arc
		(start 320.292476 -36.593526)
		(mid 320.32753 -36.769752)
		(end 320.42735 -36.919154)
		(stroke
			(width 0.068326)
			(type default)
		)
		(layer "F.Cu")
	)
	(gr_line
		(start 320.304922 -211.672424)
		(end 320.608198 -211.975954)
		(stroke
			(width 0.068326)
			(type default)
		)
		(layer "F.Cu")
	)
	(gr_arc
		(start 320.357754 -211.045298)
		(mid 320.275217 -211.168829)
		(end 320.246248 -211.314538)
		(stroke
			(width 0.068326)
			(type default)
		)
		(layer "F.Cu")
	)
	(gr_line
		(start 320.357754 -211.045298)
		(end 320.506598 -210.896454)
		(stroke
			(width 0.068326)
			(type default)
		)
		(layer "F.Cu")
	)
	(gr_line
		(start 320.421 -100.0125)
		(end 320.572384 -100.163884)
		(stroke
			(width 0.060198)
			(type default)
		)
		(layer "F.Cu")
	)
	(gr_line
		(start 320.421 -99.1235)
		(end 320.806064 -98.738436)
		(stroke
			(width 0.060198)
			(type default)
		)
		(layer "F.Cu")
	)
	(gr_line
		(start 320.42735 -36.919154)
		(end 320.533776 -37.02558)
		(stroke
			(width 0.068326)
			(type default)
		)
		(layer "F.Cu")
	)
	(gr_arc
		(start 320.500248 -224.828354)
		(mid 320.456611 -224.560646)
		(end 320.330322 -224.320608)
		(stroke
			(width 0.068326)
			(type default)
		)
		(layer "F.Cu")
	)
	(gr_line
		(start 320.500248 -224.828354)
		(end 320.500248 -225.54438)
		(stroke
			(width 0.068326)
			(type default)
		)
		(layer "F.Cu")
	)
	(gr_arc
		(start 320.559176 -33.951926)
		(mid 320.361783 -34.247345)
		(end 320.292476 -34.595816)
		(stroke
			(width 0.068326)
			(type default)
		)
		(layer "F.Cu")
	)
	(gr_arc
		(start 320.608198 -212.864954)
		(mid 320.345202 -213.258483)
		(end 320.252852 -213.722712)
		(stroke
			(width 0.068326)
			(type default)
		)
		(layer "F.Cu")
	)
	(gr_line
		(start 321.285616 -100.163884)
		(end 321.437 -100.0125)
		(stroke
			(width 0.060198)
			(type default)
		)
		(layer "F.Cu")
	)
	(gr_line
		(start 321.31 -98.9965)
		(end 321.310254 -98.996246)
		(stroke
			(width 0.060198)
			(type default)
		)
		(layer "F.Cu")
	)
	(gr_line
		(start 321.31 -98.9965)
		(end 321.437 -99.1235)
		(stroke
			(width 0.060198)
			(type default)
		)
		(layer "F.Cu")
	)
	(gr_line
		(start 321.384422 -24.981154)
		(end 321.384422 -25.33015)
		(stroke
			(width 0.068326)
			(type default)
		)
		(layer "F.Cu")
	)
	(gr_line
		(start 321.384422 -21.18106)
		(end 321.384422 -21.530056)
		(stroke
			(width 0.068326)
			(type default)
		)
		(layer "F.Cu")
	)
	(gr_arc
		(start 321.447668 -24.8285)
		(mid 321.40087 -24.898538)
		(end 321.384422 -24.981154)
		(stroke
			(width 0.068326)
			(type default)
		)
		(layer "F.Cu")
	)
	(gr_arc
		(start 321.447668 -21.028406)
		(mid 321.40087 -21.098444)
		(end 321.384422 -21.18106)
		(stroke
			(width 0.068326)
			(type default)
		)
		(layer "F.Cu")
	)
	(gr_arc
		(start 321.563238 -33.063688)
		(mid 321.823342 -32.82573)
		(end 321.9196 -32.4866)
		(stroke
			(width 0.068326)
			(type default)
		)
		(layer "F.Cu")
	)
	(gr_arc
		(start 321.57035 -24.7777)
		(mid 321.503961 -24.790906)
		(end 321.447668 -24.8285)
		(stroke
			(width 0.068326)
			(type default)
		)
		(layer "F.Cu")
	)
	(gr_line
		(start 321.57035 -24.7777)
		(end 321.620134 -24.7777)
		(stroke
			(width 0.068326)
			(type default)
		)
		(layer "F.Cu")
	)
	(gr_arc
		(start 321.57035 -20.977606)
		(mid 321.503961 -20.990812)
		(end 321.447668 -21.028406)
		(stroke
			(width 0.068326)
			(type default)
		)
		(layer "F.Cu")
	)
	(gr_line
		(start 321.57035 -20.977606)
		(end 321.620134 -20.977606)
		(stroke
			(width 0.068326)
			(type default)
		)
		(layer "F.Cu")
	)
	(gr_arc
		(start 321.801236 -24.85136)
		(mid 321.717895 -24.796793)
		(end 321.620134 -24.7777)
		(stroke
			(width 0.068326)
			(type default)
		)
		(layer "F.Cu")
	)
	(gr_arc
		(start 321.801236 -21.051266)
		(mid 321.717895 -20.996699)
		(end 321.620134 -20.977606)
		(stroke
			(width 0.068326)
			(type default)
		)
		(layer "F.Cu")
	)
	(gr_arc
		(start 321.803522 -24.853646)
		(mid 321.802383 -24.852499)
		(end 321.801236 -24.85136)
		(stroke
			(width 0.068326)
			(type default)
		)
		(layer "F.Cu")
	)
	(gr_line
		(start 321.803522 -24.853646)
		(end 321.971924 -25.022048)
		(stroke
			(width 0.068326)
			(type default)
		)
		(layer "F.Cu")
	)
	(gr_arc
		(start 321.803522 -21.053552)
		(mid 321.802383 -21.052405)
		(end 321.801236 -21.051266)
		(stroke
			(width 0.068326)
			(type default)
		)
		(layer "F.Cu")
	)
	(gr_line
		(start 321.803522 -21.053552)
		(end 321.981322 -21.231352)
		(stroke
			(width 0.068326)
			(type default)
		)
		(layer "F.Cu")
	)
	(gr_line
		(start 321.91452 -95.885)
		(end 321.91452 -96.666812)
		(stroke
			(width 0.060198)
			(type default)
		)
		(layer "F.Cu")
	)
	(gr_line
		(start 322.134484 -23.930102)
		(end 322.134484 -24.664924)
		(stroke
			(width 0.068326)
			(type default)
		)
		(layer "F.Cu")
	)
	(gr_arc
		(start 322.134484 -20.86483)
		(mid 322.150705 -20.946492)
		(end 322.196968 -21.015706)
		(stroke
			(width 0.068326)
			(type default)
		)
		(layer "F.Cu")
	)
	(gr_line
		(start 322.134484 -20.130008)
		(end 322.134484 -20.86483)
		(stroke
			(width 0.068326)
			(type default)
		)
		(layer "F.Cu")
	)
	(gr_arc
		(start 322.224654 -32.487108)
		(mid 322.321068 -32.825945)
		(end 322.58127 -33.063434)
		(stroke
			(width 0.068326)
			(type default)
		)
		(layer "F.Cu")
	)
	(gr_line
		(start 322.56476 -95.885)
		(end 322.56476 -96.72955)
		(stroke
			(width 0.060198)
			(type default)
		)
		(layer "F.Cu")
	)
	(gr_line
		(start 322.79209 -211.975954)
		(end 323.073776 -211.694268)
		(stroke
			(width 0.068326)
			(type default)
		)
		(layer "F.Cu")
	)
	(gr_line
		(start 322.89369 -210.896454)
		(end 323.047106 -211.050124)
		(stroke
			(width 0.068326)
			(type default)
		)
		(layer "F.Cu")
	)
	(gr_line
		(start 322.90004 -224.828608)
		(end 322.90004 -225.54438)
		(stroke
			(width 0.068326)
			(type default)
		)
		(layer "F.Cu")
	)
	(gr_line
		(start 322.90004 -224.828608)
		(end 322.900294 -224.828354)
		(stroke
			(width 0.068326)
			(type default)
		)
		(layer "F.Cu")
	)
	(gr_arc
		(start 323.068442 -224.32264)
		(mid 322.943427 -224.561886)
		(end 322.900294 -224.828354)
		(stroke
			(width 0.068326)
			(type default)
		)
		(layer "F.Cu")
	)
	(gr_arc
		(start 323.068442 -224.32264)
		(mid 323.127076 -224.234888)
		(end 323.14769 -224.131378)
		(stroke
			(width 0.068326)
			(type default)
		)
		(layer "F.Cu")
	)
	(gr_arc
		(start 323.073776 -211.694268)
		(mid 323.123767 -211.619452)
		(end 323.14134 -211.5312)
		(stroke
			(width 0.068326)
			(type default)
		)
		(layer "F.Cu")
	)
	(gr_arc
		(start 323.14134 -211.2772)
		(mid 323.116799 -211.154294)
		(end 323.047106 -211.050124)
		(stroke
			(width 0.068326)
			(type default)
		)
		(layer "F.Cu")
	)
	(gr_arc
		(start 323.14769 -213.723474)
		(mid 323.055271 -213.25885)
		(end 322.79209 -212.864954)
		(stroke
			(width 0.068326)
			(type default)
		)
		(layer "F.Cu")
	)
	(gr_arc
		(start 323.44614 -211.5312)
		(mid 323.461424 -211.607653)
		(end 323.504814 -211.672424)
		(stroke
			(width 0.068326)
			(type default)
		)
		(layer "F.Cu")
	)
	(gr_arc
		(start 323.452744 -224.133664)
		(mid 323.472911 -224.23483)
		(end 323.530214 -224.320608)
		(stroke
			(width 0.068326)
			(type default)
		)
		(layer "F.Cu")
	)
	(gr_line
		(start 323.504814 -211.672424)
		(end 323.80809 -211.975954)
		(stroke
			(width 0.068326)
			(type default)
		)
		(layer "F.Cu")
	)
	(gr_arc
		(start 323.539104 -211.063586)
		(mid 323.470241 -211.166726)
		(end 323.44614 -211.288376)
		(stroke
			(width 0.068326)
			(type default)
		)
		(layer "F.Cu")
	)
	(gr_line
		(start 323.539104 -211.063586)
		(end 323.70649 -210.896454)
		(stroke
			(width 0.068326)
			(type default)
		)
		(layer "F.Cu")
	)
	(gr_arc
		(start 323.56171 -33.038288)
		(mid 323.75599 -32.764466)
		(end 323.8246 -32.4358)
		(stroke
			(width 0.068326)
			(type default)
		)
		(layer "F.Cu")
	)
	(gr_line
		(start 323.61251 -34.968942)
		(end 323.76237 -34.819336)
		(stroke
			(width 0.068326)
			(type default)
		)
		(layer "F.Cu")
	)
	(gr_line
		(start 323.634354 -24.981154)
		(end 323.634354 -25.33015)
		(stroke
			(width 0.068326)
			(type default)
		)
		(layer "F.Cu")
	)
	(gr_line
		(start 323.634354 -21.18106)
		(end 323.634354 -21.530056)
		(stroke
			(width 0.068326)
			(type default)
		)
		(layer "F.Cu")
	)
	(gr_arc
		(start 323.6976 -24.8285)
		(mid 323.650802 -24.898538)
		(end 323.634354 -24.981154)
		(stroke
			(width 0.068326)
			(type default)
		)
		(layer "F.Cu")
	)
	(gr_arc
		(start 323.6976 -21.028406)
		(mid 323.650802 -21.098444)
		(end 323.634354 -21.18106)
		(stroke
			(width 0.068326)
			(type default)
		)
		(layer "F.Cu")
	)
	(gr_arc
		(start 323.70014 -224.828354)
		(mid 323.656503 -224.560646)
		(end 323.530214 -224.320608)
		(stroke
			(width 0.068326)
			(type default)
		)
		(layer "F.Cu")
	)
	(gr_line
		(start 323.70014 -224.828354)
		(end 323.70014 -225.54438)
		(stroke
			(width 0.068326)
			(type default)
		)
		(layer "F.Cu")
	)
	(gr_arc
		(start 323.76237 -34.819336)
		(mid 323.848894 -34.689739)
		(end 323.87921 -34.536888)
		(stroke
			(width 0.068326)
			(type default)
		)
		(layer "F.Cu")
	)
	(gr_arc
		(start 323.80809 -212.864954)
		(mid 323.545096 -213.258484)
		(end 323.452744 -213.722712)
		(stroke
			(width 0.068326)
			(type default)
		)
		(layer "F.Cu")
	)
	(gr_arc
		(start 323.820282 -24.7777)
		(mid 323.753893 -24.790906)
		(end 323.6976 -24.8285)
		(stroke
			(width 0.068326)
			(type default)
		)
		(layer "F.Cu")
	)
	(gr_line
		(start 323.820282 -24.7777)
		(end 323.870066 -24.7777)
		(stroke
			(width 0.068326)
			(type default)
		)
		(layer "F.Cu")
	)
	(gr_arc
		(start 323.820282 -20.977606)
		(mid 323.753893 -20.990812)
		(end 323.6976 -21.028406)
		(stroke
			(width 0.068326)
			(type default)
		)
		(layer "F.Cu")
	)
	(gr_line
		(start 323.820282 -20.977606)
		(end 323.870066 -20.977606)
		(stroke
			(width 0.068326)
			(type default)
		)
		(layer "F.Cu")
	)
	(gr_arc
		(start 323.87921 -34.397188)
		(mid 323.792393 -34.113633)
		(end 323.56171 -33.927288)
		(stroke
			(width 0.068326)
			(type default)
		)
		(layer "F.Cu")
	)
	(gr_arc
		(start 324.051168 -24.85136)
		(mid 323.967827 -24.796793)
		(end 323.870066 -24.7777)
		(stroke
			(width 0.068326)
			(type default)
		)
		(layer "F.Cu")
	)
	(gr_arc
		(start 324.051168 -21.051266)
		(mid 323.967827 -20.996699)
		(end 323.870066 -20.977606)
		(stroke
			(width 0.068326)
			(type default)
		)
		(layer "F.Cu")
	)
	(gr_arc
		(start 324.053454 -24.853646)
		(mid 324.052315 -24.852499)
		(end 324.051168 -24.85136)
		(stroke
			(width 0.068326)
			(type default)
		)
		(layer "F.Cu")
	)
	(gr_line
		(start 324.053454 -24.853646)
		(end 324.231254 -25.031446)
		(stroke
			(width 0.068326)
			(type default)
		)
		(layer "F.Cu")
	)
	(gr_arc
		(start 324.053454 -21.053552)
		(mid 324.052315 -21.052405)
		(end 324.051168 -21.051266)
		(stroke
			(width 0.068326)
			(type default)
		)
		(layer "F.Cu")
	)
	(gr_line
		(start 324.053454 -21.053552)
		(end 324.231254 -21.231352)
		(stroke
			(width 0.068326)
			(type default)
		)
		(layer "F.Cu")
	)
	(gr_arc
		(start 324.1294 -32.4358)
		(mid 324.214728 -32.777215)
		(end 324.45071 -33.038288)
		(stroke
			(width 0.068326)
			(type default)
		)
		(layer "F.Cu")
	)
	(gr_arc
		(start 324.18401 -34.536888)
		(mid 324.219064 -34.713114)
		(end 324.318884 -34.862516)
		(stroke
			(width 0.068326)
			(type default)
		)
		(layer "F.Cu")
	)
	(gr_line
		(start 324.318884 -34.862516)
		(end 324.42531 -34.968942)
		(stroke
			(width 0.068326)
			(type default)
		)
		(layer "F.Cu")
	)
	(gr_arc
		(start 324.384416 -24.664924)
		(mid 324.400637 -24.746585)
		(end 324.4469 -24.8158)
		(stroke
			(width 0.068326)
			(type default)
		)
		(layer "F.Cu")
	)
	(gr_line
		(start 324.384416 -23.930102)
		(end 324.384416 -24.664924)
		(stroke
			(width 0.068326)
			(type default)
		)
		(layer "F.Cu")
	)
	(gr_arc
		(start 324.384416 -20.86483)
		(mid 324.400639 -20.94649)
		(end 324.4469 -21.015706)
		(stroke
			(width 0.068326)
			(type default)
		)
		(layer "F.Cu")
	)
	(gr_line
		(start 324.384416 -20.130008)
		(end 324.384416 -20.86483)
		(stroke
			(width 0.068326)
			(type default)
		)
		(layer "F.Cu")
	)
	(gr_arc
		(start 324.45071 -33.927288)
		(mid 324.255353 -34.12704)
		(end 324.18401 -34.397188)
		(stroke
			(width 0.068326)
			(type default)
		)
		(layer "F.Cu")
	)
	(gr_arc
		(start 325.918322 -33.01492)
		(mid 326.124884 -32.776729)
		(end 326.199246 -32.470344)
		(stroke
			(width 0.068326)
			(type default)
		)
		(layer "F.Cu")
	)
	(gr_line
		(start 325.969122 -35.961574)
		(end 326.118982 -35.811968)
		(stroke
			(width 0.068326)
			(type default)
		)
		(layer "F.Cu")
	)
	(gr_line
		(start 325.991982 -211.975954)
		(end 326.273668 -211.694268)
		(stroke
			(width 0.068326)
			(type default)
		)
		(layer "F.Cu")
	)
	(gr_line
		(start 326.093582 -210.896454)
		(end 326.246998 -211.050124)
		(stroke
			(width 0.068326)
			(type default)
		)
		(layer "F.Cu")
	)
	(gr_line
		(start 326.100186 -224.828354)
		(end 326.100186 -225.54438)
		(stroke
			(width 0.068326)
			(type default)
		)
		(layer "F.Cu")
	)
	(gr_arc
		(start 326.118982 -35.811968)
		(mid 326.205514 -35.682372)
		(end 326.235822 -35.52952)
		(stroke
			(width 0.068326)
			(type default)
		)
		(layer "F.Cu")
	)
	(gr_arc
		(start 326.235822 -34.670492)
		(mid 326.153323 -34.255625)
		(end 325.918322 -33.90392)
		(stroke
			(width 0.068326)
			(type default)
		)
		(layer "F.Cu")
	)
	(gr_arc
		(start 326.268334 -224.32264)
		(mid 326.143306 -224.561883)
		(end 326.100186 -224.828354)
		(stroke
			(width 0.068326)
			(type default)
		)
		(layer "F.Cu")
	)
	(gr_arc
		(start 326.268334 -224.32264)
		(mid 326.326968 -224.234888)
		(end 326.347582 -224.131378)
		(stroke
			(width 0.068326)
			(type default)
		)
		(layer "F.Cu")
	)
	(gr_arc
		(start 326.273668 -211.694268)
		(mid 326.323659 -211.619452)
		(end 326.341232 -211.5312)
		(stroke
			(width 0.068326)
			(type default)
		)
		(layer "F.Cu")
	)
	(gr_arc
		(start 326.347582 -213.723474)
		(mid 326.255163 -213.25885)
		(end 325.991982 -212.864954)
		(stroke
			(width 0.068326)
			(type default)
		)
		(layer "F.Cu")
	)
	(gr_arc
		(start 326.504046 -32.470344)
		(mid 326.584987 -32.782004)
		(end 326.807322 -33.01492)
		(stroke
			(width 0.068326)
			(type default)
		)
		(layer "F.Cu")
	)
	(gr_arc
		(start 326.540622 -35.52952)
		(mid 326.575676 -35.705746)
		(end 326.675496 -35.855148)
		(stroke
			(width 0.068326)
			(type default)
		)
		(layer "F.Cu")
	)
	(gr_arc
		(start 326.646032 -211.5312)
		(mid 326.661315 -211.607654)
		(end 326.704706 -211.672424)
		(stroke
			(width 0.068326)
			(type default)
		)
		(layer "F.Cu")
	)
	(gr_arc
		(start 326.652636 -224.133664)
		(mid 326.672808 -224.234825)
		(end 326.730106 -224.320608)
		(stroke
			(width 0.068326)
			(type default)
		)
		(layer "F.Cu")
	)
	(gr_line
		(start 326.675496 -35.855148)
		(end 326.781922 -35.961574)
		(stroke
			(width 0.068326)
			(type default)
		)
		(layer "F.Cu")
	)
	(gr_line
		(start 326.704706 -211.672424)
		(end 327.007982 -211.975954)
		(stroke
			(width 0.068326)
			(type default)
		)
		(layer "F.Cu")
	)
	(gr_arc
		(start 326.721724 -211.080858)
		(mid 326.665665 -211.164895)
		(end 326.646032 -211.263992)
		(stroke
			(width 0.068326)
			(type default)
		)
		(layer "F.Cu")
	)
	(gr_line
		(start 326.721724 -211.080858)
		(end 326.906382 -210.896454)
		(stroke
			(width 0.068326)
			(type default)
		)
		(layer "F.Cu")
	)
	(gr_arc
		(start 326.807322 -33.90392)
		(mid 326.609929 -34.199339)
		(end 326.540622 -34.54781)
		(stroke
			(width 0.068326)
			(type default)
		)
		(layer "F.Cu")
	)
	(gr_arc
		(start 326.900032 -224.828354)
		(mid 326.856395 -224.560646)
		(end 326.730106 -224.320608)
		(stroke
			(width 0.068326)
			(type default)
		)
		(layer "F.Cu")
	)
	(gr_line
		(start 326.900032 -224.828354)
		(end 326.900032 -225.54438)
		(stroke
			(width 0.068326)
			(type default)
		)
		(layer "F.Cu")
	)
	(gr_arc
		(start 327.007982 -212.864954)
		(mid 326.74499 -213.258484)
		(end 326.652636 -213.722712)
		(stroke
			(width 0.068326)
			(type default)
		)
		(layer "F.Cu")
	)
	(gr_line
		(start 327.7997 -165.4302)
		(end 328.402696 -164.826442)
		(stroke
			(width 0.060198)
			(type default)
		)
		(layer "F.Cu")
	)
	(gr_line
		(start 328.324718 -33.877758)
		(end 328.534522 -34.087308)
		(stroke
			(width 0.068326)
			(type default)
		)
		(layer "F.Cu")
	)
	(gr_arc
		(start 328.324718 -32.988758)
		(mid 328.530562 -32.724669)
		(end 328.603864 -32.397954)
		(stroke
			(width 0.068326)
			(type default)
		)
		(layer "F.Cu")
	)
	(gr_line
		(start 328.375518 -34.919412)
		(end 328.525378 -34.769806)
		(stroke
			(width 0.068326)
			(type default)
		)
		(layer "F.Cu")
	)
	(gr_arc
		(start 328.525378 -34.769806)
		(mid 328.611923 -34.640213)
		(end 328.642218 -34.487358)
		(stroke
			(width 0.068326)
			(type default)
		)
		(layer "F.Cu")
	)
	(gr_arc
		(start 328.642218 -34.347658)
		(mid 328.614264 -34.20677)
		(end 328.534522 -34.087308)
		(stroke
			(width 0.068326)
			(type default)
		)
		(layer "F.Cu")
	)
	(gr_line
		(start 328.90841 -164.79901)
		(end 329.5396 -165.4302)
		(stroke
			(width 0.060198)
			(type default)
		)
		(layer "F.Cu")
	)
	(gr_arc
		(start 328.908664 -32.397954)
		(mid 328.98944 -32.730403)
		(end 329.213718 -32.988758)
		(stroke
			(width 0.068326)
			(type default)
		)
		(layer "F.Cu")
	)
	(gr_arc
		(start 328.947018 -34.487358)
		(mid 328.982072 -34.663584)
		(end 329.081892 -34.812986)
		(stroke
			(width 0.068326)
			(type default)
		)
		(layer "F.Cu")
	)
	(gr_line
		(start 329.081892 -34.812986)
		(end 329.188318 -34.919412)
		(stroke
			(width 0.068326)
			(type default)
		)
		(layer "F.Cu")
	)
	(gr_arc
		(start 329.090782 -34.000948)
		(mid 328.984411 -34.160005)
		(end 328.947018 -34.347658)
		(stroke
			(width 0.068326)
			(type default)
		)
		(layer "F.Cu")
	)
	(gr_line
		(start 329.090782 -34.000948)
		(end 329.213718 -33.877758)
		(stroke
			(width 0.068326)
			(type default)
		)
		(layer "F.Cu")
	)
	(gr_line
		(start 330.61275 -183.532018)
		(end 330.740512 -183.65978)
		(stroke
			(width 0.060198)
			(type default)
		)
		(layer "F.Cu")
	)
	(gr_line
		(start 330.61275 -183.532018)
		(end 330.858368 -183.2864)
		(stroke
			(width 0.060198)
			(type default)
		)
		(layer "F.Cu")
	)
	(gr_line
		(start 330.740512 -183.65978)
		(end 330.740512 -184.433718)
		(stroke
			(width 0.060198)
			(type default)
		)
		(layer "F.Cu")
	)
	(gr_line
		(start 330.858368 -183.2864)
		(end 331.241146 -183.2864)
		(stroke
			(width 0.060198)
			(type default)
		)
		(layer "F.Cu")
	)
	(gr_line
		(start 331.241146 -183.2864)
		(end 331.57287 -182.954676)
		(stroke
			(width 0.060198)
			(type default)
		)
		(layer "F.Cu")
	)
	(gr_line
		(start 331.756512 -183.609488)
		(end 331.756512 -184.433718)
		(stroke
			(width 0.060198)
			(type default)
		)
		(layer "F.Cu")
	)
	(gr_line
		(start 331.756512 -183.609488)
		(end 331.8764 -183.4896)
		(stroke
			(width 0.060198)
			(type default)
		)
		(layer "F.Cu")
	)
	(gr_line
		(start 331.8764 -183.489346)
		(end 331.8764 -183.4896)
		(stroke
			(width 0.060198)
			(type default)
		)
		(layer "F.Cu")
	)
	(gr_line
		(start 331.8764 -183.489346)
		(end 331.882242 -183.489346)
		(stroke
			(width 0.060198)
			(type default)
		)
		(layer "F.Cu")
	)
	(gr_line
		(start 331.882242 -183.489346)
		(end 332.284324 -183.087264)
		(stroke
			(width 0.060198)
			(type default)
		)
		(layer "F.Cu")
	)
	(gr_line
		(start 332.259432 -181.601618)
		(end 332.259432 -182.268114)
		(stroke
			(width 0.060198)
			(type default)
		)
		(layer "F.Cu")
	)
	(gr_line
		(start 332.284324 -182.9562)
		(end 332.284324 -183.087264)
		(stroke
			(width 0.060198)
			(type default)
		)
		(layer "F.Cu")
	)
	(gr_line
		(start 332.39202 -212.864954)
		(end 332.392528 -212.865208)
		(stroke
			(width 0.068326)
			(type default)
		)
		(layer "F.Cu")
	)
	(gr_line
		(start 332.39202 -211.975954)
		(end 332.392274 -211.975954)
		(stroke
			(width 0.068326)
			(type default)
		)
		(layer "F.Cu")
	)
	(gr_line
		(start 332.392274 -211.975954)
		(end 332.67396 -211.694268)
		(stroke
			(width 0.068326)
			(type default)
		)
		(layer "F.Cu")
	)
	(gr_line
		(start 332.453996 -182.786528)
		(end 332.674214 -182.786528)
		(stroke
			(width 0.060198)
			(type default)
		)
		(layer "F.Cu")
	)
	(gr_line
		(start 332.493874 -210.896454)
		(end 332.62951 -211.03209)
		(stroke
			(width 0.068326)
			(type default)
		)
		(layer "F.Cu")
	)
	(gr_line
		(start 332.500224 -224.828608)
		(end 332.500224 -225.54438)
		(stroke
			(width 0.068326)
			(type default)
		)
		(layer "F.Cu")
	)
	(gr_line
		(start 332.500224 -224.828608)
		(end 332.500478 -224.828354)
		(stroke
			(width 0.068326)
			(type default)
		)
		(layer "F.Cu")
	)
	(gr_arc
		(start 332.668626 -224.32264)
		(mid 332.543599 -224.561883)
		(end 332.500478 -224.828354)
		(stroke
			(width 0.068326)
			(type default)
		)
		(layer "F.Cu")
	)
	(gr_arc
		(start 332.668626 -224.32264)
		(mid 332.72726 -224.234888)
		(end 332.747874 -224.131378)
		(stroke
			(width 0.068326)
			(type default)
		)
		(layer "F.Cu")
	)
	(gr_arc
		(start 332.67396 -211.694268)
		(mid 332.723951 -211.619452)
		(end 332.741524 -211.5312)
		(stroke
			(width 0.068326)
			(type default)
		)
		(layer "F.Cu")
	)
	(gr_line
		(start 332.674214 -182.786528)
		(end 332.909672 -182.55107)
		(stroke
			(width 0.060198)
			(type default)
		)
		(layer "F.Cu")
	)
	(gr_arc
		(start 332.741524 -211.3026)
		(mid 332.712406 -211.156214)
		(end 332.62951 -211.03209)
		(stroke
			(width 0.068326)
			(type default)
		)
		(layer "F.Cu")
	)
	(gr_arc
		(start 332.747874 -213.723474)
		(mid 332.655576 -213.258991)
		(end 332.392528 -212.865208)
		(stroke
			(width 0.068326)
			(type default)
		)
		(layer "F.Cu")
	)
	(gr_line
		(start 332.909672 -181.601618)
		(end 332.909672 -182.55107)
		(stroke
			(width 0.060198)
			(type default)
		)
		(layer "F.Cu")
	)
	(gr_arc
		(start 333.046324 -211.5312)
		(mid 333.061607 -211.607654)
		(end 333.104998 -211.672424)
		(stroke
			(width 0.068326)
			(type default)
		)
		(layer "F.Cu")
	)
	(gr_arc
		(start 333.052928 -224.133664)
		(mid 333.0731 -224.234825)
		(end 333.130398 -224.320608)
		(stroke
			(width 0.068326)
			(type default)
		)
		(layer "F.Cu")
	)
	(gr_line
		(start 333.104998 -211.672424)
		(end 333.40802 -211.975446)
		(stroke
			(width 0.068326)
			(type default)
		)
		(layer "F.Cu")
	)
	(gr_arc
		(start 333.158338 -211.045044)
		(mid 333.075495 -211.16891)
		(end 333.046324 -211.315046)
		(stroke
			(width 0.068326)
			(type default)
		)
		(layer "F.Cu")
	)
	(gr_line
		(start 333.158338 -211.045044)
		(end 333.306674 -210.896454)
		(stroke
			(width 0.068326)
			(type default)
		)
		(layer "F.Cu")
	)
	(gr_line
		(start 333.30007 -224.828608)
		(end 333.30007 -225.54438)
		(stroke
			(width 0.068326)
			(type default)
		)
		(layer "F.Cu")
	)
	(gr_line
		(start 333.30007 -224.828608)
		(end 333.300324 -224.828354)
		(stroke
			(width 0.068326)
			(type default)
		)
		(layer "F.Cu")
	)
	(gr_arc
		(start 333.300324 -224.828354)
		(mid 333.256687 -224.560646)
		(end 333.130398 -224.320608)
		(stroke
			(width 0.068326)
			(type default)
		)
		(layer "F.Cu")
	)
	(gr_arc
		(start 333.40802 -212.864954)
		(mid 333.145205 -213.25826)
		(end 333.052928 -213.722204)
		(stroke
			(width 0.068326)
			(type default)
		)
		(layer "F.Cu")
	)
	(gr_line
		(start 333.40802 -211.975446)
		(end 333.40802 -211.975954)
		(stroke
			(width 0.068326)
			(type default)
		)
		(layer "F.Cu")
	)
	(gr_line
		(start 335.592166 -211.975954)
		(end 335.873852 -211.694268)
		(stroke
			(width 0.068326)
			(type default)
		)
		(layer "F.Cu")
	)
	(gr_line
		(start 335.693766 -210.896454)
		(end 335.865216 -211.067904)
		(stroke
			(width 0.068326)
			(type default)
		)
		(layer "F.Cu")
	)
	(gr_line
		(start 335.700116 -224.828608)
		(end 335.700116 -225.54438)
		(stroke
			(width 0.068326)
			(type default)
		)
		(layer "F.Cu")
	)
	(gr_line
		(start 335.700116 -224.828608)
		(end 335.70037 -224.828354)
		(stroke
			(width 0.068326)
			(type default)
		)
		(layer "F.Cu")
	)
	(gr_arc
		(start 335.868518 -224.32264)
		(mid 335.743492 -224.561883)
		(end 335.70037 -224.828354)
		(stroke
			(width 0.068326)
			(type default)
		)
		(layer "F.Cu")
	)
	(gr_arc
		(start 335.868518 -224.32264)
		(mid 335.927152 -224.234888)
		(end 335.947766 -224.131378)
		(stroke
			(width 0.068326)
			(type default)
		)
		(layer "F.Cu")
	)
	(gr_arc
		(start 335.873852 -211.694268)
		(mid 335.923843 -211.619452)
		(end 335.941416 -211.5312)
		(stroke
			(width 0.068326)
			(type default)
		)
		(layer "F.Cu")
	)
	(gr_arc
		(start 335.947766 -213.723474)
		(mid 335.855347 -213.25885)
		(end 335.592166 -212.864954)
		(stroke
			(width 0.068326)
			(type default)
		)
		(layer "F.Cu")
	)
	(gr_arc
		(start 336.246216 -211.5312)
		(mid 336.261498 -211.607655)
		(end 336.30489 -211.672424)
		(stroke
			(width 0.068326)
			(type default)
		)
		(layer "F.Cu")
	)
	(gr_arc
		(start 336.25282 -224.133664)
		(mid 336.272991 -224.234826)
		(end 336.33029 -224.320608)
		(stroke
			(width 0.068326)
			(type default)
		)
		(layer "F.Cu")
	)
	(gr_line
		(start 336.30489 -211.672424)
		(end 336.608166 -211.975954)
		(stroke
			(width 0.068326)
			(type default)
		)
		(layer "F.Cu")
	)
	(gr_arc
		(start 336.312002 -211.091018)
		(mid 336.263325 -211.163849)
		(end 336.246216 -211.249768)
		(stroke
			(width 0.068326)
			(type default)
		)
		(layer "F.Cu")
	)
	(gr_line
		(start 336.312002 -211.091018)
		(end 336.506566 -210.896454)
		(stroke
			(width 0.068326)
			(type default)
		)
		(layer "F.Cu")
	)
	(gr_arc
		(start 336.500216 -224.828354)
		(mid 336.456579 -224.560646)
		(end 336.33029 -224.320608)
		(stroke
			(width 0.068326)
			(type default)
		)
		(layer "F.Cu")
	)
	(gr_line
		(start 336.500216 -224.828354)
		(end 336.500216 -225.54438)
		(stroke
			(width 0.068326)
			(type default)
		)
		(layer "F.Cu")
	)
	(gr_arc
		(start 336.608166 -212.864954)
		(mid 336.345177 -213.258485)
		(end 336.25282 -213.722712)
		(stroke
			(width 0.068326)
			(type default)
		)
		(layer "F.Cu")
	)
	(gr_line
		(start 338.792058 -211.975954)
		(end 339.073744 -211.694268)
		(stroke
			(width 0.068326)
			(type default)
		)
		(layer "F.Cu")
	)
	(gr_line
		(start 338.893658 -210.896454)
		(end 339.003132 -211.005674)
		(stroke
			(width 0.068326)
			(type default)
		)
		(layer "F.Cu")
	)
	(gr_line
		(start 338.900008 -224.828608)
		(end 338.900008 -225.54438)
		(stroke
			(width 0.068326)
			(type default)
		)
		(layer "F.Cu")
	)
	(gr_line
		(start 338.900008 -224.828608)
		(end 338.900262 -224.828354)
		(stroke
			(width 0.068326)
			(type default)
		)
		(layer "F.Cu")
	)
	(gr_arc
		(start 339.06841 -224.32264)
		(mid 338.943385 -224.561884)
		(end 338.900262 -224.828354)
		(stroke
			(width 0.068326)
			(type default)
		)
		(layer "F.Cu")
	)
	(gr_arc
		(start 339.06841 -224.32264)
		(mid 339.127044 -224.234888)
		(end 339.147658 -224.131378)
		(stroke
			(width 0.068326)
			(type default)
		)
		(layer "F.Cu")
	)
	(gr_arc
		(start 339.073744 -211.694268)
		(mid 339.123735 -211.619452)
		(end 339.141308 -211.5312)
		(stroke
			(width 0.068326)
			(type default)
		)
		(layer "F.Cu")
	)
	(gr_arc
		(start 339.141308 -211.339684)
		(mid 339.105448 -211.158933)
		(end 339.003132 -211.005674)
		(stroke
			(width 0.068326)
			(type default)
		)
		(layer "F.Cu")
	)
	(gr_arc
		(start 339.147658 -213.723474)
		(mid 339.055239 -213.25885)
		(end 338.792058 -212.864954)
		(stroke
			(width 0.068326)
			(type default)
		)
		(layer "F.Cu")
	)
	(gr_arc
		(start 339.446108 -211.5312)
		(mid 339.46139 -211.607655)
		(end 339.504782 -211.672424)
		(stroke
			(width 0.068326)
			(type default)
		)
		(layer "F.Cu")
	)
	(gr_arc
		(start 339.452712 -224.133664)
		(mid 339.472883 -224.234826)
		(end 339.530182 -224.320608)
		(stroke
			(width 0.068326)
			(type default)
		)
		(layer "F.Cu")
	)
	(gr_line
		(start 339.504782 -211.672424)
		(end 339.808058 -211.975954)
		(stroke
			(width 0.068326)
			(type default)
		)
		(layer "F.Cu")
	)
	(gr_arc
		(start 339.575394 -211.027518)
		(mid 339.47972 -211.170748)
		(end 339.446108 -211.339684)
		(stroke
			(width 0.068326)
			(type default)
		)
		(layer "F.Cu")
	)
	(gr_line
		(start 339.575394 -211.027518)
		(end 339.706458 -210.896454)
		(stroke
			(width 0.068326)
			(type default)
		)
		(layer "F.Cu")
	)
	(gr_arc
		(start 339.700108 -224.828354)
		(mid 339.656471 -224.560646)
		(end 339.530182 -224.320608)
		(stroke
			(width 0.068326)
			(type default)
		)
		(layer "F.Cu")
	)
	(gr_line
		(start 339.700108 -224.828354)
		(end 339.700108 -225.54438)
		(stroke
			(width 0.068326)
			(type default)
		)
		(layer "F.Cu")
	)
	(gr_arc
		(start 339.808058 -212.864954)
		(mid 339.545071 -213.258486)
		(end 339.452712 -213.722712)
		(stroke
			(width 0.068326)
			(type default)
		)
		(layer "F.Cu")
	)
	(gr_line
		(start 341.99195 -211.975954)
		(end 342.230456 -211.737702)
		(stroke
			(width 0.068326)
			(type default)
		)
		(layer "F.Cu")
	)
	(gr_line
		(start 342.09355 -210.896454)
		(end 342.246966 -211.050124)
		(stroke
			(width 0.068326)
			(type default)
		)
		(layer "F.Cu")
	)
	(gr_line
		(start 342.100154 -224.828354)
		(end 342.100154 -225.54438)
		(stroke
			(width 0.068326)
			(type default)
		)
		(layer "F.Cu")
	)
	(gr_arc
		(start 342.230456 -211.737702)
		(mid 342.312445 -211.614858)
		(end 342.3412 -211.469986)
		(stroke
			(width 0.068326)
			(type default)
		)
		(layer "F.Cu")
	)
	(gr_arc
		(start 342.268302 -224.32264)
		(mid 342.143278 -224.561884)
		(end 342.100154 -224.828354)
		(stroke
			(width 0.068326)
			(type default)
		)
		(layer "F.Cu")
	)
	(gr_arc
		(start 342.268302 -224.32264)
		(mid 342.326936 -224.234888)
		(end 342.34755 -224.131378)
		(stroke
			(width 0.068326)
			(type default)
		)
		(layer "F.Cu")
	)
	(gr_arc
		(start 342.3412 -211.2772)
		(mid 342.316659 -211.154294)
		(end 342.246966 -211.050124)
		(stroke
			(width 0.068326)
			(type default)
		)
		(layer "F.Cu")
	)
	(gr_arc
		(start 342.34755 -213.723474)
		(mid 342.255131 -213.25885)
		(end 341.99195 -212.864954)
		(stroke
			(width 0.068326)
			(type default)
		)
		(layer "F.Cu")
	)
	(gr_arc
		(start 342.646 -211.469732)
		(mid 342.672559 -211.60296)
		(end 342.748108 -211.715858)
		(stroke
			(width 0.068326)
			(type default)
		)
		(layer "F.Cu")
	)
	(gr_arc
		(start 342.652604 -224.133664)
		(mid 342.672774 -224.234826)
		(end 342.730074 -224.320608)
		(stroke
			(width 0.068326)
			(type default)
		)
		(layer "F.Cu")
	)
	(gr_arc
		(start 342.73109 -211.071714)
		(mid 342.668122 -211.165999)
		(end 342.646 -211.2772)
		(stroke
			(width 0.068326)
			(type default)
		)
		(layer "F.Cu")
	)
	(gr_line
		(start 342.73109 -211.071714)
		(end 342.90635 -210.896454)
		(stroke
			(width 0.068326)
			(type default)
		)
		(layer "F.Cu")
	)
	(gr_line
		(start 342.748108 -211.715858)
		(end 343.00795 -211.975954)
		(stroke
			(width 0.068326)
			(type default)
		)
		(layer "F.Cu")
	)
	(gr_arc
		(start 342.9 -224.828354)
		(mid 342.856363 -224.560646)
		(end 342.730074 -224.320608)
		(stroke
			(width 0.068326)
			(type default)
		)
		(layer "F.Cu")
	)
	(gr_line
		(start 342.9 -224.828354)
		(end 342.9 -225.54438)
		(stroke
			(width 0.068326)
			(type default)
		)
		(layer "F.Cu")
	)
	(gr_arc
		(start 343.00795 -212.864954)
		(mid 342.744965 -213.258486)
		(end 342.652604 -213.722712)
		(stroke
			(width 0.068326)
			(type default)
		)
		(layer "F.Cu")
	)
	(gr_line
		(start 12.73556 -124.6505)
		(end 12.74826 -124.6378)
		(stroke
			(width 0.060198)
			(type default)
		)
		(layer "B.Cu")
	)
	(gr_line
		(start 12.73556 -124.6505)
		(end 13.202412 -125.117352)
		(stroke
			(width 0.060198)
			(type default)
		)
		(layer "B.Cu")
	)
	(gr_line
		(start 12.74826 -124.6378)
		(end 13.6398 -124.6378)
		(stroke
			(width 0.060198)
			(type default)
		)
		(layer "B.Cu")
	)
	(gr_line
		(start 13.202412 -125.508512)
		(end 13.6144 -125.9205)
		(stroke
			(width 0.060198)
			(type default)
		)
		(layer "B.Cu")
	)
	(gr_line
		(start 13.202412 -125.117352)
		(end 13.202412 -125.508512)
		(stroke
			(width 0.060198)
			(type default)
		)
		(layer "B.Cu")
	)
	(gr_line
		(start 13.6398 -124.6378)
		(end 13.884656 -124.882656)
		(stroke
			(width 0.060198)
			(type default)
		)
		(layer "B.Cu")
	)
	(gr_line
		(start 13.884656 -124.882656)
		(end 15.633954 -124.882656)
		(stroke
			(width 0.060198)
			(type default)
		)
		(layer "B.Cu")
	)
	(gr_line
		(start 15.4686 -125.760988)
		(end 15.635478 -125.59411)
		(stroke
			(width 0.060198)
			(type default)
		)
		(layer "B.Cu")
	)
	(gr_line
		(start 19.804634 -125.34646)
		(end 19.956018 -125.497844)
		(stroke
			(width 0.060198)
			(type default)
		)
		(layer "B.Cu")
	)
	(gr_line
		(start 19.804634 -124.633228)
		(end 19.956018 -124.481844)
		(stroke
			(width 0.060198)
			(type default)
		)
		(layer "B.Cu")
	)
	(gr_line
		(start 20.845018 -125.497844)
		(end 20.996402 -125.34646)
		(stroke
			(width 0.060198)
			(type default)
		)
		(layer "B.Cu")
	)
	(gr_line
		(start 20.845018 -124.481844)
		(end 20.996402 -124.633228)
		(stroke
			(width 0.060198)
			(type default)
		)
		(layer "B.Cu")
	)
	(gr_line
		(start 23.330662 -125.239272)
		(end 23.372064 -125.239272)
		(stroke
			(width 0.060198)
			(type default)
		)
		(layer "B.Cu")
	)
	(gr_line
		(start 23.832312 -124.989844)
		(end 23.873714 -124.989844)
		(stroke
			(width 0.060198)
			(type default)
		)
		(layer "B.Cu")
	)
	(gr_line
		(start 28.4099 -185.9026)
		(end 28.561284 -185.751216)
		(stroke
			(width 0.060198)
			(type default)
		)
		(layer "B.Cu")
	)
	(gr_line
		(start 28.4099 -184.8866)
		(end 28.561284 -185.037984)
		(stroke
			(width 0.060198)
			(type default)
		)
		(layer "B.Cu")
	)
	(gr_line
		(start 28.423362 -128.257554)
		(end 28.431998 -128.26619)
		(stroke
			(width 0.060198)
			(type default)
		)
		(layer "B.Cu")
	)
	(gr_line
		(start 28.431998 -128.26619)
		(end 28.450032 -128.284224)
		(stroke
			(width 0.0508)
			(type default)
		)
		(layer "B.Cu")
	)
	(gr_line
		(start 28.450032 -128.284224)
		(end 28.657804 -128.284224)
		(stroke
			(width 0.0508)
			(type default)
		)
		(layer "B.Cu")
	)
	(gr_line
		(start 28.90393 -128.028446)
		(end 28.92171 -128.046226)
		(stroke
			(width 0.0508)
			(type default)
		)
		(layer "B.Cu")
	)
	(gr_line
		(start 28.92171 -128.257554)
		(end 28.930346 -128.26619)
		(stroke
			(width 0.0508)
			(type default)
		)
		(layer "B.Cu")
	)
	(gr_line
		(start 28.92171 -128.046226)
		(end 28.92171 -128.253998)
		(stroke
			(width 0.0508)
			(type default)
		)
		(layer "B.Cu")
	)
	(gr_line
		(start 31.704788 -128.084834)
		(end 31.84271 -128.222756)
		(stroke
			(width 0.0508)
			(type default)
		)
		(layer "B.Cu")
	)
	(gr_line
		(start 31.84271 -128.222756)
		(end 31.84271 -128.389634)
		(stroke
			(width 0.0508)
			(type default)
		)
		(layer "B.Cu")
	)
	(gr_line
		(start 32.132016 -128.391412)
		(end 32.43834 -128.085088)
		(stroke
			(width 0.0508)
			(type default)
		)
		(layer "B.Cu")
	)
	(gr_line
		(start 32.43834 -128.085088)
		(end 32.505142 -128.085088)
		(stroke
			(width 0.0508)
			(type default)
		)
		(layer "B.Cu")
	)
	(gr_line
		(start 34.967926 -152.77973)
		(end 35.01263 -152.735026)
		(stroke
			(width 0.068326)
			(type default)
		)
		(layer "B.Cu")
	)
	(gr_line
		(start 35.447478 -152.735026)
		(end 35.492182 -152.77973)
		(stroke
			(width 0.068326)
			(type default)
		)
		(layer "B.Cu")
	)
	(gr_line
		(start 35.492182 -152.77973)
		(end 35.767772 -152.77973)
		(stroke
			(width 0.068326)
			(type default)
		)
		(layer "B.Cu")
	)
	(gr_line
		(start 36.602416 -185.751216)
		(end 36.6776 -185.8264)
		(stroke
			(width 0.060198)
			(type default)
		)
		(layer "B.Cu")
	)
	(gr_line
		(start 36.602416 -185.037984)
		(end 36.6776 -184.9628)
		(stroke
			(width 0.060198)
			(type default)
		)
		(layer "B.Cu")
	)
	(gr_line
		(start 37.452554 -139.582144)
		(end 37.729414 -139.859004)
		(stroke
			(width 0.068326)
			(type default)
		)
		(layer "B.Cu")
	)
	(gr_line
		(start 40.64 -201.9935)
		(end 40.791384 -202.144884)
		(stroke
			(width 0.060198)
			(type default)
		)
		(layer "B.Cu")
	)
	(gr_line
		(start 40.64 -201.1045)
		(end 40.791384 -200.953116)
		(stroke
			(width 0.060198)
			(type default)
		)
		(layer "B.Cu")
	)
	(gr_line
		(start 40.7416 -208.28)
		(end 40.816784 -208.204816)
		(stroke
			(width 0.060198)
			(type default)
		)
		(layer "B.Cu")
	)
	(gr_line
		(start 40.7416 -195.834)
		(end 40.816784 -195.909184)
		(stroke
			(width 0.060198)
			(type default)
		)
		(layer "B.Cu")
	)
	(gr_line
		(start 41.504616 -202.144884)
		(end 41.656 -201.9935)
		(stroke
			(width 0.060198)
			(type default)
		)
		(layer "B.Cu")
	)
	(gr_line
		(start 41.504616 -200.953116)
		(end 41.656 -201.1045)
		(stroke
			(width 0.060198)
			(type default)
		)
		(layer "B.Cu")
	)
	(gr_line
		(start 41.530016 -208.204816)
		(end 41.6052 -208.28)
		(stroke
			(width 0.060198)
			(type default)
		)
		(layer "B.Cu")
	)
	(gr_line
		(start 41.530016 -195.909184)
		(end 41.6052 -195.834)
		(stroke
			(width 0.060198)
			(type default)
		)
		(layer "B.Cu")
	)
	(gr_line
		(start 42.186098 -77.3049)
		(end 42.360596 -77.479398)
		(stroke
			(width 0.060198)
			(type default)
		)
		(layer "B.Cu")
	)
	(gr_line
		(start 42.4942 -187.8457)
		(end 42.645584 -187.997084)
		(stroke
			(width 0.060198)
			(type default)
		)
		(layer "B.Cu")
	)
	(gr_line
		(start 42.4942 -186.9567)
		(end 42.645584 -186.805316)
		(stroke
			(width 0.060198)
			(type default)
		)
		(layer "B.Cu")
	)
	(gr_line
		(start 42.5704 -194.2846)
		(end 42.645584 -194.209416)
		(stroke
			(width 0.060198)
			(type default)
		)
		(layer "B.Cu")
	)
	(gr_line
		(start 42.5704 -181.8386)
		(end 42.645584 -181.913784)
		(stroke
			(width 0.060198)
			(type default)
		)
		(layer "B.Cu")
	)
	(gr_line
		(start 42.96537 -122.7455)
		(end 43.006518 -122.786648)
		(stroke
			(width 0.060198)
			(type default)
		)
		(layer "B.Cu")
	)
	(gr_line
		(start 43.073574 -77.479398)
		(end 43.195748 -77.357224)
		(stroke
			(width 0.060198)
			(type default)
		)
		(layer "B.Cu")
	)
	(gr_line
		(start 43.174666 -122.955304)
		(end 43.215306 -122.996198)
		(stroke
			(width 0.060198)
			(type default)
		)
		(layer "B.Cu")
	)
	(gr_line
		(start 43.215306 -122.996198)
		(end 43.21556 -122.996452)
		(stroke
			(width 0.060198)
			(type default)
		)
		(layer "B.Cu")
	)
	(gr_line
		(start 43.358816 -194.209416)
		(end 43.434 -194.2846)
		(stroke
			(width 0.060198)
			(type default)
		)
		(layer "B.Cu")
	)
	(gr_line
		(start 43.358816 -187.997084)
		(end 43.5102 -187.8457)
		(stroke
			(width 0.060198)
			(type default)
		)
		(layer "B.Cu")
	)
	(gr_line
		(start 43.358816 -186.805316)
		(end 43.5102 -186.9567)
		(stroke
			(width 0.060198)
			(type default)
		)
		(layer "B.Cu")
	)
	(gr_line
		(start 43.358816 -181.913784)
		(end 43.434 -181.8386)
		(stroke
			(width 0.060198)
			(type default)
		)
		(layer "B.Cu")
	)
	(gr_line
		(start 43.418252 -122.998992)
		(end 43.70451 -123.284996)
		(stroke
			(width 0.060198)
			(type default)
		)
		(layer "B.Cu")
	)
	(gr_line
		(start 43.418252 -122.771916)
		(end 43.705018 -122.48515)
		(stroke
			(width 0.060198)
			(type default)
		)
		(layer "B.Cu")
	)
	(gr_line
		(start 43.64355 -82.11566)
		(end 43.64355 -82.232754)
		(stroke
			(width 0.060198)
			(type default)
		)
		(layer "B.Cu")
	)
	(gr_line
		(start 43.70451 -126.485142)
		(end 44.095162 -126.09449)
		(stroke
			(width 0.060198)
			(type default)
		)
		(layer "B.Cu")
	)
	(gr_line
		(start 43.745404 -121.067068)
		(end 43.745658 -121.26087)
		(stroke
			(width 0.060198)
			(type default)
		)
		(layer "B.Cu")
	)
	(gr_line
		(start 43.745404 -121.067068)
		(end 43.766486 -121.045986)
		(stroke
			(width 0.060198)
			(type default)
		)
		(layer "B.Cu")
	)
	(gr_line
		(start 43.766486 -121.557542)
		(end 43.902376 -121.421652)
		(stroke
			(width 0.060198)
			(type default)
		)
		(layer "B.Cu")
	)
	(gr_line
		(start 43.766486 -121.045986)
		(end 43.902376 -120.910096)
		(stroke
			(width 0.060198)
			(type default)
		)
		(layer "B.Cu")
	)
	(gr_line
		(start 43.905678 -121.421652)
		(end 44.100496 -121.421652)
		(stroke
			(width 0.060198)
			(type default)
		)
		(layer "B.Cu")
	)
	(gr_line
		(start 43.96867 -81.61401)
		(end 43.96867 -81.731104)
		(stroke
			(width 0.060198)
			(type default)
		)
		(layer "B.Cu")
	)
	(gr_line
		(start 44.069 -220.3704)
		(end 44.144184 -220.445584)
		(stroke
			(width 0.060198)
			(type default)
		)
		(layer "B.Cu")
	)
	(gr_line
		(start 44.095162 -126.09449)
		(end 45.010578 -126.09449)
		(stroke
			(width 0.060198)
			(type default)
		)
		(layer "B.Cu")
	)
	(gr_line
		(start 44.100496 -121.421652)
		(end 44.121578 -121.40057)
		(stroke
			(width 0.060198)
			(type default)
		)
		(layer "B.Cu")
	)
	(gr_line
		(start 44.124118 -122.904504)
		(end 44.50461 -123.284996)
		(stroke
			(width 0.0508)
			(type default)
		)
		(layer "B.Cu")
	)
	(gr_line
		(start 44.124118 -122.25401)
		(end 44.124118 -122.904504)
		(stroke
			(width 0.0508)
			(type default)
		)
		(layer "B.Cu")
	)
	(gr_line
		(start 44.124118 -122.25401)
		(end 44.215812 -122.162316)
		(stroke
			(width 0.0508)
			(type default)
		)
		(layer "B.Cu")
	)
	(gr_line
		(start 44.50461 -128.885188)
		(end 44.677584 -128.712214)
		(stroke
			(width 0.068326)
			(type default)
		)
		(layer "B.Cu")
	)
	(gr_line
		(start 44.50461 -127.284988)
		(end 44.674028 -127.284988)
		(stroke
			(width 0.060198)
			(type default)
		)
		(layer "B.Cu")
	)
	(gr_line
		(start 44.504864 -124.084842)
		(end 44.92371 -123.665996)
		(stroke
			(width 0.0508)
			(type default)
		)
		(layer "B.Cu")
	)
	(gr_line
		(start 44.505118 -122.164094)
		(end 44.505118 -122.48515)
		(stroke
			(width 0.0508)
			(type default)
		)
		(layer "B.Cu")
	)
	(gr_line
		(start 44.674028 -127.284988)
		(end 45.06468 -127.67564)
		(stroke
			(width 0.060198)
			(type default)
		)
		(layer "B.Cu")
	)
	(gr_line
		(start 44.677584 -128.712214)
		(end 44.688506 -128.701038)
		(stroke
			(width 0.068326)
			(type default)
		)
		(layer "B.Cu")
	)
	(gr_line
		(start 44.857416 -220.445584)
		(end 44.9326 -220.3704)
		(stroke
			(width 0.060198)
			(type default)
		)
		(layer "B.Cu")
	)
	(gr_line
		(start 44.92371 -123.127008)
		(end 44.92371 -123.665996)
		(stroke
			(width 0.0508)
			(type default)
		)
		(layer "B.Cu")
	)
	(gr_line
		(start 44.92371 -123.127008)
		(end 45.236384 -122.814334)
		(stroke
			(width 0.0508)
			(type default)
		)
		(layer "B.Cu")
	)
	(gr_line
		(start 45.014896 -126.09449)
		(end 45.594524 -126.09449)
		(stroke
			(width 0.060198)
			(type default)
		)
		(layer "B.Cu")
	)
	(gr_line
		(start 45.06468 -127.67564)
		(end 45.619416 -127.67564)
		(stroke
			(width 0.060198)
			(type default)
		)
		(layer "B.Cu")
	)
	(gr_arc
		(start 45.212 -128.484376)
		(mid 44.928701 -128.540634)
		(end 44.688506 -128.701038)
		(stroke
			(width 0.068326)
			(type default)
		)
		(layer "B.Cu")
	)
	(gr_line
		(start 45.212 -128.484376)
		(end 45.229272 -128.484376)
		(stroke
			(width 0.068326)
			(type default)
		)
		(layer "B.Cu")
	)
	(gr_line
		(start 45.300138 -224.199958)
		(end 45.300138 -225.92538)
		(stroke
			(width 0.060198)
			(type default)
		)
		(layer "B.Cu")
	)
	(gr_line
		(start 45.300138 -224.199958)
		(end 45.343572 -224.156524)
		(stroke
			(width 0.060198)
			(type default)
		)
		(layer "B.Cu")
	)
	(gr_line
		(start 45.30471 -127.284988)
		(end 45.415708 -127.17399)
		(stroke
			(width 0.060198)
			(type default)
		)
		(layer "B.Cu")
	)
	(gr_line
		(start 45.30471 -125.685042)
		(end 45.396912 -125.59284)
		(stroke
			(width 0.060198)
			(type default)
		)
		(layer "B.Cu")
	)
	(gr_line
		(start 45.30471 -124.885196)
		(end 46.001432 -124.885196)
		(stroke
			(width 0.060198)
			(type default)
		)
		(layer "B.Cu")
	)
	(gr_line
		(start 45.30471 -123.837192)
		(end 45.30471 -124.085096)
		(stroke
			(width 0.060198)
			(type default)
		)
		(layer "B.Cu")
	)
	(gr_line
		(start 45.30471 -123.837192)
		(end 45.714158 -123.427744)
		(stroke
			(width 0.060198)
			(type default)
		)
		(layer "B.Cu")
	)
	(gr_line
		(start 45.30471 -123.284996)
		(end 45.442124 -123.147582)
		(stroke
			(width 0.0508)
			(type default)
		)
		(layer "B.Cu")
	)
	(gr_arc
		(start 45.386752 -128.825498)
		(mid 45.343407 -128.852149)
		(end 45.30471 -128.885188)
		(stroke
			(width 0.068326)
			(type default)
		)
		(layer "B.Cu")
	)
	(gr_line
		(start 45.399452 -125.5903)
		(end 45.46854 -125.521212)
		(stroke
			(width 0.060198)
			(type default)
		)
		(layer "B.Cu")
	)
	(gr_line
		(start 45.442124 -123.017534)
		(end 45.442124 -123.147582)
		(stroke
			(width 0.0508)
			(type default)
		)
		(layer "B.Cu")
	)
	(gr_line
		(start 45.46854 -125.521212)
		(end 46.022006 -125.521212)
		(stroke
			(width 0.060198)
			(type default)
		)
		(layer "B.Cu")
	)
	(gr_arc
		(start 45.536612 -128.789176)
		(mid 45.459514 -128.798388)
		(end 45.386752 -128.825498)
		(stroke
			(width 0.068326)
			(type default)
		)
		(layer "B.Cu")
	)
	(gr_line
		(start 45.598842 -126.09449)
		(end 46.454568 -126.09449)
		(stroke
			(width 0.060198)
			(type default)
		)
		(layer "B.Cu")
	)
	(gr_line
		(start 45.61586 -127.17399)
		(end 45.626528 -127.17399)
		(stroke
			(width 0.060198)
			(type default)
		)
		(layer "B.Cu")
	)
	(gr_line
		(start 45.714158 -123.062746)
		(end 45.714158 -123.427744)
		(stroke
			(width 0.060198)
			(type default)
		)
		(layer "B.Cu")
	)
	(gr_line
		(start 45.714158 -123.062746)
		(end 46.10862 -122.668284)
		(stroke
			(width 0.060198)
			(type default)
		)
		(layer "B.Cu")
	)
	(gr_line
		(start 45.949108 -128.791716)
		(end 46.102016 -128.944624)
		(stroke
			(width 0.068326)
			(type default)
		)
		(layer "B.Cu")
	)
	(gr_line
		(start 46.003972 -124.885196)
		(end 46.19498 -124.885196)
		(stroke
			(width 0.060198)
			(type default)
		)
		(layer "B.Cu")
	)
	(gr_line
		(start 46.05655 -224.156524)
		(end 46.099984 -224.199958)
		(stroke
			(width 0.060198)
			(type default)
		)
		(layer "B.Cu")
	)
	(gr_line
		(start 46.099984 -224.199958)
		(end 46.099984 -225.92538)
		(stroke
			(width 0.060198)
			(type default)
		)
		(layer "B.Cu")
	)
	(gr_line
		(start 46.102016 -128.944624)
		(end 46.511972 -128.944624)
		(stroke
			(width 0.068326)
			(type default)
		)
		(layer "B.Cu")
	)
	(gr_line
		(start 46.104556 -124.085096)
		(end 46.193202 -124.173742)
		(stroke
			(width 0.060198)
			(type default)
		)
		(layer "B.Cu")
	)
	(gr_line
		(start 46.104556 -123.005596)
		(end 46.104556 -123.284996)
		(stroke
			(width 0.060198)
			(type default)
		)
		(layer "B.Cu")
	)
	(gr_line
		(start 46.104556 -123.005596)
		(end 46.217332 -122.89282)
		(stroke
			(width 0.060198)
			(type default)
		)
		(layer "B.Cu")
	)
	(gr_line
		(start 46.11751 -127.392684)
		(end 46.128178 -127.392684)
		(stroke
			(width 0.060198)
			(type default)
		)
		(layer "B.Cu")
	)
	(gr_line
		(start 46.253908 -128.484376)
		(end 46.36008 -128.484376)
		(stroke
			(width 0.068326)
			(type default)
		)
		(layer "B.Cu")
	)
	(gr_line
		(start 46.454568 -126.09449)
		(end 46.523656 -126.025402)
		(stroke
			(width 0.060198)
			(type default)
		)
		(layer "B.Cu")
	)
	(gr_line
		(start 46.505622 -124.486162)
		(end 46.69663 -124.486162)
		(stroke
			(width 0.060198)
			(type default)
		)
		(layer "B.Cu")
	)
	(gr_line
		(start 46.511972 -128.944624)
		(end 46.66488 -128.791716)
		(stroke
			(width 0.068326)
			(type default)
		)
		(layer "B.Cu")
	)
	(gr_line
		(start 46.539912 -121.208546)
		(end 46.742858 -121.208546)
		(stroke
			(width 0.0508)
			(type default)
		)
		(layer "B.Cu")
	)
	(gr_line
		(start 46.717712 -121.005346)
		(end 46.772322 -120.950736)
		(stroke
			(width 0.0508)
			(type default)
		)
		(layer "B.Cu")
	)
	(gr_line
		(start 46.742858 -121.208546)
		(end 46.772322 -121.23801)
		(stroke
			(width 0.0508)
			(type default)
		)
		(layer "B.Cu")
	)
	(gr_line
		(start 46.7741 -121.239788)
		(end 46.89221 -121.357898)
		(stroke
			(width 0.0508)
			(type default)
		)
		(layer "B.Cu")
	)
	(gr_line
		(start 46.7741 -120.948958)
		(end 46.86681 -120.856248)
		(stroke
			(width 0.0508)
			(type default)
		)
		(layer "B.Cu")
	)
	(gr_line
		(start 46.86681 -120.856248)
		(end 46.89221 -120.856248)
		(stroke
			(width 0.0508)
			(type default)
		)
		(layer "B.Cu")
	)
	(gr_line
		(start 46.89221 -120.856248)
		(end 47.095156 -120.856248)
		(stroke
			(width 0.060198)
			(type default)
		)
		(layer "B.Cu")
	)
	(gr_line
		(start 47.079916 -128.791716)
		(end 47.232824 -128.944624)
		(stroke
			(width 0.068326)
			(type default)
		)
		(layer "B.Cu")
	)
	(gr_line
		(start 47.232824 -128.944624)
		(end 47.64278 -128.944624)
		(stroke
			(width 0.068326)
			(type default)
		)
		(layer "B.Cu")
	)
	(gr_line
		(start 47.384716 -128.484376)
		(end 47.490888 -128.484376)
		(stroke
			(width 0.068326)
			(type default)
		)
		(layer "B.Cu")
	)
	(gr_line
		(start 47.64278 -128.944624)
		(end 47.795688 -128.791716)
		(stroke
			(width 0.068326)
			(type default)
		)
		(layer "B.Cu")
	)
	(gr_line
		(start 47.6504 -106.1085)
		(end 48.1711 -106.6292)
		(stroke
			(width 0.060198)
			(type default)
		)
		(layer "B.Cu")
	)
	(gr_line
		(start 47.6504 -105.19664)
		(end 47.6504 -106.1085)
		(stroke
			(width 0.060198)
			(type default)
		)
		(layer "B.Cu")
	)
	(gr_line
		(start 47.700184 -225.170746)
		(end 47.700184 -225.92538)
		(stroke
			(width 0.068326)
			(type default)
		)
		(layer "B.Cu")
	)
	(gr_arc
		(start 47.840138 -224.832926)
		(mid 47.736575 -224.987919)
		(end 47.700184 -225.170746)
		(stroke
			(width 0.068326)
			(type default)
		)
		(layer "B.Cu")
	)
	(gr_line
		(start 47.840138 -224.832926)
		(end 47.890938 -224.782126)
		(stroke
			(width 0.068326)
			(type default)
		)
		(layer "B.Cu")
	)
	(gr_arc
		(start 47.890938 -224.782126)
		(mid 47.933042 -224.719074)
		(end 47.947834 -224.644712)
		(stroke
			(width 0.068326)
			(type default)
		)
		(layer "B.Cu")
	)
	(gr_line
		(start 47.94758 -223.139)
		(end 47.94758 -223.139508)
		(stroke
			(width 0.068326)
			(type default)
		)
		(layer "B.Cu")
	)
	(gr_line
		(start 48.102774 -114.654076)
		(end 48.297084 -114.459766)
		(stroke
			(width 0.060198)
			(type default)
		)
		(layer "B.Cu")
	)
	(gr_line
		(start 48.1584 -113.5761)
		(end 48.309784 -113.727484)
		(stroke
			(width 0.060198)
			(type default)
		)
		(layer "B.Cu")
	)
	(gr_line
		(start 48.1711 -116.477288)
		(end 48.322484 -116.628672)
		(stroke
			(width 0.060198)
			(type default)
		)
		(layer "B.Cu")
	)
	(gr_line
		(start 48.1711 -106.1085)
		(end 48.1711 -106.6292)
		(stroke
			(width 0.060198)
			(type default)
		)
		(layer "B.Cu")
	)
	(gr_line
		(start 48.1711 -106.1085)
		(end 48.50765 -105.77195)
		(stroke
			(width 0.060198)
			(type default)
		)
		(layer "B.Cu")
	)
	(gr_line
		(start 48.207676 -222.834708)
		(end 48.20793 -222.834708)
		(stroke
			(width 0.068326)
			(type default)
		)
		(layer "B.Cu")
	)
	(gr_arc
		(start 48.252634 -224.62998)
		(mid 48.272703 -224.730875)
		(end 48.32985 -224.816416)
		(stroke
			(width 0.068326)
			(type default)
		)
		(layer "B.Cu")
	)
	(gr_arc
		(start 48.50003 -225.227388)
		(mid 48.455835 -225.004969)
		(end 48.32985 -224.816416)
		(stroke
			(width 0.068326)
			(type default)
		)
		(layer "B.Cu")
	)
	(gr_line
		(start 48.50003 -225.227388)
		(end 48.50003 -225.92538)
		(stroke
			(width 0.068326)
			(type default)
		)
		(layer "B.Cu")
	)
	(gr_line
		(start 48.50765 -103.65105)
		(end 48.50765 -105.77195)
		(stroke
			(width 0.060198)
			(type default)
		)
		(layer "B.Cu")
	)
	(gr_line
		(start 48.50765 -103.65105)
		(end 48.798734 -103.359966)
		(stroke
			(width 0.060198)
			(type default)
		)
		(layer "B.Cu")
	)
	(gr_line
		(start 48.617886 -121.265188)
		(end 48.617886 -121.32437)
		(stroke
			(width 0.0508)
			(type default)
		)
		(layer "B.Cu")
	)
	(gr_line
		(start 48.617886 -121.11355)
		(end 48.617886 -121.262648)
		(stroke
			(width 0.0508)
			(type default)
		)
		(layer "B.Cu")
	)
	(gr_line
		(start 48.617886 -121.11355)
		(end 48.635666 -121.09577)
		(stroke
			(width 0.0508)
			(type default)
		)
		(layer "B.Cu")
	)
	(gr_line
		(start 48.635666 -121.594118)
		(end 48.761396 -121.468388)
		(stroke
			(width 0.0508)
			(type default)
		)
		(layer "B.Cu")
	)
	(gr_line
		(start 48.635666 -121.09577)
		(end 48.761396 -120.97004)
		(stroke
			(width 0.060198)
			(type default)
		)
		(layer "B.Cu")
	)
	(gr_line
		(start 48.736504 -129.493518)
		(end 49.026318 -129.783586)
		(stroke
			(width 0.068326)
			(type default)
		)
		(layer "B.Cu")
	)
	(gr_line
		(start 48.736504 -129.27711)
		(end 48.736504 -129.493518)
		(stroke
			(width 0.068326)
			(type default)
		)
		(layer "B.Cu")
	)
	(gr_line
		(start 48.761396 -121.468388)
		(end 48.821086 -121.468388)
		(stroke
			(width 0.0508)
			(type default)
		)
		(layer "B.Cu")
	)
	(gr_line
		(start 48.823626 -121.468388)
		(end 48.972724 -121.468388)
		(stroke
			(width 0.0508)
			(type default)
		)
		(layer "B.Cu")
	)
	(gr_line
		(start 48.972724 -121.468388)
		(end 48.990504 -121.450608)
		(stroke
			(width 0.0508)
			(type default)
		)
		(layer "B.Cu")
	)
	(gr_line
		(start 49.0093 -102.72649)
		(end 49.126394 -102.843584)
		(stroke
			(width 0.060198)
			(type default)
		)
		(layer "B.Cu")
	)
	(gr_line
		(start 49.0093 -102.4382)
		(end 49.0093 -102.72649)
		(stroke
			(width 0.060198)
			(type default)
		)
		(layer "B.Cu")
	)
	(gr_line
		(start 49.0093 -102.4382)
		(end 49.8602 -102.4382)
		(stroke
			(width 0.060198)
			(type default)
		)
		(layer "B.Cu")
	)
	(gr_line
		(start 49.010062 -114.459766)
		(end 49.204372 -114.654076)
		(stroke
			(width 0.060198)
			(type default)
		)
		(layer "B.Cu")
	)
	(gr_line
		(start 49.023016 -113.727484)
		(end 49.1744 -113.5761)
		(stroke
			(width 0.060198)
			(type default)
		)
		(layer "B.Cu")
	)
	(gr_line
		(start 49.026318 -129.783586)
		(end 49.24298 -129.783586)
		(stroke
			(width 0.068326)
			(type default)
		)
		(layer "B.Cu")
	)
	(gr_line
		(start 49.035716 -116.628672)
		(end 49.1871 -116.477288)
		(stroke
			(width 0.060198)
			(type default)
		)
		(layer "B.Cu")
	)
	(gr_line
		(start 49.038002 -122.190256)
		(end 49.050448 -122.17781)
		(stroke
			(width 0.060198)
			(type default)
		)
		(layer "B.Cu")
	)
	(gr_line
		(start 49.050448 -121.97969)
		(end 49.050448 -122.17781)
		(stroke
			(width 0.060198)
			(type default)
		)
		(layer "B.Cu")
	)
	(gr_line
		(start 49.050448 -121.97969)
		(end 49.07153 -121.958608)
		(stroke
			(width 0.060198)
			(type default)
		)
		(layer "B.Cu")
	)
	(gr_line
		(start 49.085246 -122.460512)
		(end 49.279302 -122.460512)
		(stroke
			(width 0.060198)
			(type default)
		)
		(layer "B.Cu")
	)
	(gr_line
		(start 49.169574 -129.275586)
		(end 49.244504 -129.350516)
		(stroke
			(width 0.068326)
			(type default)
		)
		(layer "B.Cu")
	)
	(gr_line
		(start 49.195482 -102.912672)
		(end 49.30775 -103.02494)
		(stroke
			(width 0.060198)
			(type default)
		)
		(layer "B.Cu")
	)
	(gr_line
		(start 49.279302 -122.460512)
		(end 49.549558 -122.190256)
		(stroke
			(width 0.060198)
			(type default)
		)
		(layer "B.Cu")
	)
	(gr_line
		(start 49.511966 -103.359966)
		(end 49.53 -103.378)
		(stroke
			(width 0.060198)
			(type default)
		)
		(layer "B.Cu")
	)
	(gr_line
		(start 49.53 -103.378)
		(end 49.53 -103.89616)
		(stroke
			(width 0.060198)
			(type default)
		)
		(layer "B.Cu")
	)
	(gr_line
		(start 49.549558 -122.190256)
		(end 49.562004 -122.17781)
		(stroke
			(width 0.060198)
			(type default)
		)
		(layer "B.Cu")
	)
	(gr_line
		(start 49.697894 -111.342424)
		(end 50.060352 -111.704882)
		(stroke
			(width 0.060198)
			(type default)
		)
		(layer "B.Cu")
	)
	(gr_line
		(start 49.697894 -110.10138)
		(end 49.697894 -111.342424)
		(stroke
			(width 0.060198)
			(type default)
		)
		(layer "B.Cu")
	)
	(gr_line
		(start 49.697894 -110.10138)
		(end 50.219102 -109.580172)
		(stroke
			(width 0.060198)
			(type default)
		)
		(layer "B.Cu")
	)
	(gr_line
		(start 49.8602 -102.4382)
		(end 50.038 -102.616)
		(stroke
			(width 0.060198)
			(type default)
		)
		(layer "B.Cu")
	)
	(gr_line
		(start 49.981104 -209.753962)
		(end 49.981612 -209.753962)
		(stroke
			(width 0.068326)
			(type default)
		)
		(layer "B.Cu")
	)
	(gr_line
		(start 50.060352 -111.704882)
		(end 52.192682 -111.704882)
		(stroke
			(width 0.060198)
			(type default)
		)
		(layer "B.Cu")
	)
	(gr_line
		(start 50.099976 -224.713546)
		(end 50.099976 -225.92538)
		(stroke
			(width 0.068326)
			(type default)
		)
		(layer "B.Cu")
	)
	(gr_line
		(start 50.14468 -208.712054)
		(end 50.285142 -208.852516)
		(stroke
			(width 0.068326)
			(type default)
		)
		(layer "B.Cu")
	)
	(gr_line
		(start 50.172874 -114.601498)
		(end 50.367184 -114.407188)
		(stroke
			(width 0.060198)
			(type default)
		)
		(layer "B.Cu")
	)
	(gr_line
		(start 50.2158 -116.35359)
		(end 50.367184 -116.504974)
		(stroke
			(width 0.060198)
			(type default)
		)
		(layer "B.Cu")
	)
	(gr_line
		(start 50.219102 -109.580172)
		(end 51.736244 -108.06303)
		(stroke
			(width 0.060198)
			(type default)
		)
		(layer "B.Cu")
	)
	(gr_arc
		(start 50.23993 -224.375726)
		(mid 50.13635 -224.530713)
		(end 50.099976 -224.713546)
		(stroke
			(width 0.068326)
			(type default)
		)
		(layer "B.Cu")
	)
	(gr_line
		(start 50.23993 -224.375726)
		(end 50.29073 -224.324926)
		(stroke
			(width 0.068326)
			(type default)
		)
		(layer "B.Cu")
	)
	(gr_line
		(start 50.2412 -113.6015)
		(end 50.392584 -113.752884)
		(stroke
			(width 0.060198)
			(type default)
		)
		(layer "B.Cu")
	)
	(gr_arc
		(start 50.29073 -224.324926)
		(mid 50.332856 -224.26188)
		(end 50.347626 -224.187512)
		(stroke
			(width 0.068326)
			(type default)
		)
		(layer "B.Cu")
	)
	(gr_arc
		(start 50.347372 -222.01886)
		(mid 50.281364 -221.687014)
		(end 50.093372 -221.405704)
		(stroke
			(width 0.068326)
			(type default)
		)
		(layer "B.Cu")
	)
	(gr_arc
		(start 50.417476 -130.541776)
		(mid 50.43596 -130.634701)
		(end 50.488596 -130.71348)
		(stroke
			(width 0.068326)
			(type default)
		)
		(layer "B.Cu")
	)
	(gr_arc
		(start 50.417476 -130.297682)
		(mid 50.342684 -130.138254)
		(end 50.17897 -130.0734)
		(stroke
			(width 0.068326)
			(type default)
		)
		(layer "B.Cu")
	)
	(gr_line
		(start 50.417476 -130.297682)
		(end 50.417476 -130.541776)
		(stroke
			(width 0.068326)
			(type default)
		)
		(layer "B.Cu")
	)
	(gr_arc
		(start 50.418746 -209.175604)
		(mid 50.384043 -209.000788)
		(end 50.285142 -208.852516)
		(stroke
			(width 0.068326)
			(type default)
		)
		(layer "B.Cu")
	)
	(gr_line
		(start 50.48631 -129.7686)
		(end 51.0921 -129.7686)
		(stroke
			(width 0.068326)
			(type default)
		)
		(layer "B.Cu")
	)
	(gr_arc
		(start 50.488596 -130.71348)
		(mid 50.567374 -130.766118)
		(end 50.6603 -130.7846)
		(stroke
			(width 0.068326)
			(type default)
		)
		(layer "B.Cu")
	)
	(gr_arc
		(start 50.652426 -224.17278)
		(mid 50.672493 -224.273675)
		(end 50.729642 -224.359216)
		(stroke
			(width 0.068326)
			(type default)
		)
		(layer "B.Cu")
	)
	(gr_line
		(start 50.6603 -130.7846)
		(end 51.0921 -130.7846)
		(stroke
			(width 0.068326)
			(type default)
		)
		(layer "B.Cu")
	)
	(gr_line
		(start 50.673 -196.0245)
		(end 50.824384 -196.175884)
		(stroke
			(width 0.060198)
			(type default)
		)
		(layer "B.Cu")
	)
	(gr_line
		(start 50.673 -195.1355)
		(end 50.824384 -194.984116)
		(stroke
			(width 0.060198)
			(type default)
		)
		(layer "B.Cu")
	)
	(gr_line
		(start 50.673 -181.9275)
		(end 50.824384 -182.078884)
		(stroke
			(width 0.060198)
			(type default)
		)
		(layer "B.Cu")
	)
	(gr_line
		(start 50.673 -181.0385)
		(end 50.824384 -180.887116)
		(stroke
			(width 0.060198)
			(type default)
		)
		(layer "B.Cu")
	)
	(gr_arc
		(start 50.710846 -221.60103)
		(mid 50.667584 -221.665695)
		(end 50.652426 -221.742)
		(stroke
			(width 0.068326)
			(type default)
		)
		(layer "B.Cu")
	)
	(gr_line
		(start 50.710846 -221.60103)
		(end 50.906172 -221.405704)
		(stroke
			(width 0.068326)
			(type default)
		)
		(layer "B.Cu")
	)
	(gr_line
		(start 50.7746 -202.311)
		(end 50.849784 -202.235816)
		(stroke
			(width 0.060198)
			(type default)
		)
		(layer "B.Cu")
	)
	(gr_line
		(start 50.7746 -189.908434)
		(end 50.824384 -189.958218)
		(stroke
			(width 0.060198)
			(type default)
		)
		(layer "B.Cu")
	)
	(gr_line
		(start 50.7746 -189.865)
		(end 50.7746 -189.908434)
		(stroke
			(width 0.060198)
			(type default)
		)
		(layer "B.Cu")
	)
	(gr_line
		(start 50.7746 -188.214)
		(end 50.849784 -188.138816)
		(stroke
			(width 0.060198)
			(type default)
		)
		(layer "B.Cu")
	)
	(gr_line
		(start 50.7746 -175.811434)
		(end 50.824384 -175.861218)
		(stroke
			(width 0.060198)
			(type default)
		)
		(layer "B.Cu")
	)
	(gr_line
		(start 50.7746 -175.768)
		(end 50.7746 -175.811434)
		(stroke
			(width 0.060198)
			(type default)
		)
		(layer "B.Cu")
	)
	(gr_arc
		(start 50.863754 -208.80578)
		(mid 50.760191 -208.960773)
		(end 50.7238 -209.1436)
		(stroke
			(width 0.068326)
			(type default)
		)
		(layer "B.Cu")
	)
	(gr_line
		(start 50.863754 -208.80578)
		(end 50.95748 -208.712054)
		(stroke
			(width 0.068326)
			(type default)
		)
		(layer "B.Cu")
	)
	(gr_arc
		(start 50.899822 -224.770188)
		(mid 50.855584 -224.547791)
		(end 50.729642 -224.359216)
		(stroke
			(width 0.068326)
			(type default)
		)
		(layer "B.Cu")
	)
	(gr_line
		(start 50.899822 -224.770188)
		(end 50.900076 -224.770442)
		(stroke
			(width 0.068326)
			(type default)
		)
		(layer "B.Cu")
	)
	(gr_line
		(start 50.900076 -224.770442)
		(end 50.900076 -225.92538)
		(stroke
			(width 0.068326)
			(type default)
		)
		(layer "B.Cu")
	)
	(gr_line
		(start 50.940716 -128.575816)
		(end 51.0921 -128.7272)
		(stroke
			(width 0.060198)
			(type default)
		)
		(layer "B.Cu")
	)
	(gr_line
		(start 50.940716 -127.862584)
		(end 51.0921 -127.7112)
		(stroke
			(width 0.060198)
			(type default)
		)
		(layer "B.Cu")
	)
	(gr_line
		(start 51.080162 -114.407188)
		(end 51.274472 -114.601498)
		(stroke
			(width 0.060198)
			(type default)
		)
		(layer "B.Cu")
	)
	(gr_line
		(start 51.080416 -116.504974)
		(end 51.2318 -116.35359)
		(stroke
			(width 0.060198)
			(type default)
		)
		(layer "B.Cu")
	)
	(gr_line
		(start 51.105816 -113.752884)
		(end 51.2572 -113.6015)
		(stroke
			(width 0.060198)
			(type default)
		)
		(layer "B.Cu")
	)
	(gr_line
		(start 51.537362 -189.958218)
		(end 51.63058 -189.865)
		(stroke
			(width 0.060198)
			(type default)
		)
		(layer "B.Cu")
	)
	(gr_line
		(start 51.537362 -175.861218)
		(end 51.63058 -175.768)
		(stroke
			(width 0.060198)
			(type default)
		)
		(layer "B.Cu")
	)
	(gr_line
		(start 51.537616 -196.175884)
		(end 51.689 -196.0245)
		(stroke
			(width 0.060198)
			(type default)
		)
		(layer "B.Cu")
	)
	(gr_line
		(start 51.537616 -194.984116)
		(end 51.689 -195.1355)
		(stroke
			(width 0.060198)
			(type default)
		)
		(layer "B.Cu")
	)
	(gr_line
		(start 51.537616 -182.078884)
		(end 51.689 -181.9275)
		(stroke
			(width 0.060198)
			(type default)
		)
		(layer "B.Cu")
	)
	(gr_line
		(start 51.537616 -180.887116)
		(end 51.689 -181.0385)
		(stroke
			(width 0.060198)
			(type default)
		)
		(layer "B.Cu")
	)
	(gr_line
		(start 51.563016 -202.235816)
		(end 51.6382 -202.311)
		(stroke
			(width 0.060198)
			(type default)
		)
		(layer "B.Cu")
	)
	(gr_line
		(start 51.563016 -188.138816)
		(end 51.6382 -188.214)
		(stroke
			(width 0.060198)
			(type default)
		)
		(layer "B.Cu")
	)
	(gr_line
		(start 51.63058 -189.865)
		(end 51.6382 -189.865)
		(stroke
			(width 0.060198)
			(type default)
		)
		(layer "B.Cu")
	)
	(gr_line
		(start 51.63058 -175.768)
		(end 51.6382 -175.768)
		(stroke
			(width 0.060198)
			(type default)
		)
		(layer "B.Cu")
	)
	(gr_line
		(start 51.736244 -108.06303)
		(end 52.778152 -108.06303)
		(stroke
			(width 0.060198)
			(type default)
		)
		(layer "B.Cu")
	)
	(gr_line
		(start 51.9811 -130.7846)
		(end 52.16779 -130.598164)
		(stroke
			(width 0.068326)
			(type default)
		)
		(layer "B.Cu")
	)
	(gr_line
		(start 51.9811 -129.7686)
		(end 52.208176 -129.995676)
		(stroke
			(width 0.068326)
			(type default)
		)
		(layer "B.Cu")
	)
	(gr_line
		(start 51.9811 -128.7272)
		(end 52.132484 -128.575816)
		(stroke
			(width 0.060198)
			(type default)
		)
		(layer "B.Cu")
	)
	(gr_line
		(start 51.9811 -127.7112)
		(end 52.132484 -127.862584)
		(stroke
			(width 0.060198)
			(type default)
		)
		(layer "B.Cu")
	)
	(gr_line
		(start 52.192682 -111.704882)
		(end 53.410104 -112.922304)
		(stroke
			(width 0.060198)
			(type default)
		)
		(layer "B.Cu")
	)
	(gr_arc
		(start 52.208176 -129.995676)
		(mid 52.369695 -130.1036)
		(end 52.56022 -130.141472)
		(stroke
			(width 0.068326)
			(type default)
		)
		(layer "B.Cu")
	)
	(gr_line
		(start 52.28336 -82.646774)
		(end 52.47767 -82.452464)
		(stroke
			(width 0.060198)
			(type default)
		)
		(layer "B.Cu")
	)
	(gr_line
		(start 52.343304 -52.454048)
		(end 52.63515 -52.745894)
		(stroke
			(width 0.068326)
			(type default)
		)
		(layer "B.Cu")
	)
	(gr_line
		(start 52.343304 -52.0319)
		(end 52.343304 -52.454048)
		(stroke
			(width 0.068326)
			(type default)
		)
		(layer "B.Cu")
	)
	(gr_line
		(start 52.343304 -50.720752)
		(end 52.343304 -51.1429)
		(stroke
			(width 0.068326)
			(type default)
		)
		(layer "B.Cu")
	)
	(gr_line
		(start 52.343304 -50.720752)
		(end 52.63515 -50.428906)
		(stroke
			(width 0.068326)
			(type default)
		)
		(layer "B.Cu")
	)
	(gr_line
		(start 52.399438 -47.876968)
		(end 52.635404 -48.112934)
		(stroke
			(width 0.068326)
			(type default)
		)
		(layer "B.Cu")
	)
	(gr_arc
		(start 52.534058 -130.446272)
		(mid 52.33582 -130.485796)
		(end 52.16779 -130.598164)
		(stroke
			(width 0.068326)
			(type default)
		)
		(layer "B.Cu")
	)
	(gr_line
		(start 52.778152 -108.06303)
		(end 52.816252 -108.10113)
		(stroke
			(width 0.060198)
			(type default)
		)
		(layer "B.Cu")
	)
	(gr_line
		(start 52.816252 -110.84687)
		(end 53.36413 -110.84687)
		(stroke
			(width 0.060198)
			(type default)
		)
		(layer "B.Cu")
	)
	(gr_line
		(start 52.816252 -110.84687)
		(end 53.37048 -111.401098)
		(stroke
			(width 0.060198)
			(type default)
		)
		(layer "B.Cu")
	)
	(gr_line
		(start 52.816252 -108.10113)
		(end 52.816252 -109.54639)
		(stroke
			(width 0.060198)
			(type default)
		)
		(layer "B.Cu")
	)
	(gr_line
		(start 53.069998 -52.745894)
		(end 53.361844 -52.454048)
		(stroke
			(width 0.068326)
			(type default)
		)
		(layer "B.Cu")
	)
	(gr_line
		(start 53.069998 -50.428906)
		(end 53.361844 -50.720752)
		(stroke
			(width 0.068326)
			(type default)
		)
		(layer "B.Cu")
	)
	(gr_line
		(start 53.069998 -48.112934)
		(end 53.305964 -47.876968)
		(stroke
			(width 0.068326)
			(type default)
		)
		(layer "B.Cu")
	)
	(gr_line
		(start 53.190648 -82.452464)
		(end 53.384958 -82.646774)
		(stroke
			(width 0.060198)
			(type default)
		)
		(layer "B.Cu")
	)
	(gr_line
		(start 53.300122 -224.713546)
		(end 53.300122 -225.92538)
		(stroke
			(width 0.068326)
			(type default)
		)
		(layer "B.Cu")
	)
	(gr_line
		(start 53.350414 -123.097544)
		(end 53.587142 -122.860816)
		(stroke
			(width 0.060198)
			(type default)
		)
		(layer "B.Cu")
	)
	(gr_line
		(start 53.361844 -52.0319)
		(end 53.361844 -52.454048)
		(stroke
			(width 0.068326)
			(type default)
		)
		(layer "B.Cu")
	)
	(gr_line
		(start 53.361844 -50.720752)
		(end 53.361844 -51.1429)
		(stroke
			(width 0.068326)
			(type default)
		)
		(layer "B.Cu")
	)
	(gr_line
		(start 53.36413 -110.84687)
		(end 53.594 -110.617)
		(stroke
			(width 0.060198)
			(type default)
		)
		(layer "B.Cu")
	)
	(gr_line
		(start 53.36921 -111.788956)
		(end 53.565552 -111.985298)
		(stroke
			(width 0.060198)
			(type default)
		)
		(layer "B.Cu")
	)
	(gr_line
		(start 53.36921 -111.402368)
		(end 53.36921 -111.788956)
		(stroke
			(width 0.060198)
			(type default)
		)
		(layer "B.Cu")
	)
	(gr_line
		(start 53.36921 -111.402368)
		(end 53.37048 -111.401098)
		(stroke
			(width 0.060198)
			(type default)
		)
		(layer "B.Cu")
	)
	(gr_line
		(start 53.379624 -121.671842)
		(end 53.531008 -121.823226)
		(stroke
			(width 0.060198)
			(type default)
		)
		(layer "B.Cu")
	)
	(gr_line
		(start 53.379624 -120.95861)
		(end 53.531008 -120.807226)
		(stroke
			(width 0.060198)
			(type default)
		)
		(layer "B.Cu")
	)
	(gr_line
		(start 53.410104 -113.83391)
		(end 53.575458 -113.999264)
		(stroke
			(width 0.060198)
			(type default)
		)
		(layer "B.Cu")
	)
	(gr_line
		(start 53.410104 -112.922304)
		(end 53.410104 -113.83391)
		(stroke
			(width 0.060198)
			(type default)
		)
		(layer "B.Cu")
	)
	(gr_line
		(start 53.4162 -116.2177)
		(end 53.419248 -116.2177)
		(stroke
			(width 0.060198)
			(type default)
		)
		(layer "B.Cu")
	)
	(gr_line
		(start 53.4162 -115.3287)
		(end 53.567584 -115.177316)
		(stroke
			(width 0.060198)
			(type default)
		)
		(layer "B.Cu")
	)
	(gr_line
		(start 53.419248 -116.2177)
		(end 53.569108 -116.36756)
		(stroke
			(width 0.060198)
			(type default)
		)
		(layer "B.Cu")
	)
	(gr_line
		(start 53.435758 -123.725432)
		(end 53.587142 -123.876816)
		(stroke
			(width 0.060198)
			(type default)
		)
		(layer "B.Cu")
	)
	(gr_arc
		(start 53.440076 -224.375726)
		(mid 53.336486 -224.530711)
		(end 53.300122 -224.713546)
		(stroke
			(width 0.068326)
			(type default)
		)
		(layer "B.Cu")
	)
	(gr_line
		(start 53.440076 -224.375726)
		(end 53.490876 -224.324926)
		(stroke
			(width 0.068326)
			(type default)
		)
		(layer "B.Cu")
	)
	(gr_arc
		(start 53.490876 -224.324926)
		(mid 53.533002 -224.26188)
		(end 53.547772 -224.187512)
		(stroke
			(width 0.068326)
			(type default)
		)
		(layer "B.Cu")
	)
	(gr_arc
		(start 53.547518 -222.90786)
		(mid 53.48151 -222.576014)
		(end 53.293518 -222.294704)
		(stroke
			(width 0.068326)
			(type default)
		)
		(layer "B.Cu")
	)
	(gr_line
		(start 53.565552 -111.985298)
		(end 53.565552 -112.22863)
		(stroke
			(width 0.060198)
			(type default)
		)
		(layer "B.Cu")
	)
	(gr_line
		(start 53.594 -109.20603)
		(end 53.594 -110.617)
		(stroke
			(width 0.060198)
			(type default)
		)
		(layer "B.Cu")
	)
	(gr_line
		(start 53.594 -109.20603)
		(end 53.852826 -108.947204)
		(stroke
			(width 0.060198)
			(type default)
		)
		(layer "B.Cu")
	)
	(gr_line
		(start 53.667152 -108.06303)
		(end 54.581552 -108.06303)
		(stroke
			(width 0.060198)
			(type default)
		)
		(layer "B.Cu")
	)
	(gr_arc
		(start 53.852572 -224.17278)
		(mid 53.872636 -224.273678)
		(end 53.929788 -224.359216)
		(stroke
			(width 0.068326)
			(type default)
		)
		(layer "B.Cu")
	)
	(gr_line
		(start 53.852826 -108.947204)
		(end 53.866796 -108.947204)
		(stroke
			(width 0.060198)
			(type default)
		)
		(layer "B.Cu")
	)
	(gr_line
		(start 53.866796 -108.947204)
		(end 53.8988 -108.9152)
		(stroke
			(width 0.060198)
			(type default)
		)
		(layer "B.Cu")
	)
	(gr_arc
		(start 54.099968 -224.770188)
		(mid 54.05573 -224.547791)
		(end 53.929788 -224.359216)
		(stroke
			(width 0.068326)
			(type default)
		)
		(layer "B.Cu")
	)
	(gr_line
		(start 54.099968 -224.770188)
		(end 54.099968 -225.92538)
		(stroke
			(width 0.068326)
			(type default)
		)
		(layer "B.Cu")
	)
	(gr_arc
		(start 54.106318 -222.294704)
		(mid 53.918515 -222.575794)
		(end 53.852572 -222.907352)
		(stroke
			(width 0.068326)
			(type default)
		)
		(layer "B.Cu")
	)
	(gr_line
		(start 54.280816 -115.177316)
		(end 54.4322 -115.3287)
		(stroke
			(width 0.060198)
			(type default)
		)
		(layer "B.Cu")
	)
	(gr_line
		(start 54.28234 -116.36756)
		(end 54.4322 -116.2177)
		(stroke
			(width 0.060198)
			(type default)
		)
		(layer "B.Cu")
	)
	(gr_line
		(start 54.288436 -113.999264)
		(end 54.4449 -113.8428)
		(stroke
			(width 0.060198)
			(type default)
		)
		(layer "B.Cu")
	)
	(gr_line
		(start 54.4449 -113.8428)
		(end 54.7497 -113.538)
		(stroke
			(width 0.060198)
			(type default)
		)
		(layer "B.Cu")
	)
	(gr_line
		(start 54.454552 -112.22863)
		(end 54.695852 -111.98733)
		(stroke
			(width 0.060198)
			(type default)
		)
		(layer "B.Cu")
	)
	(gr_line
		(start 54.454552 -112.22863)
		(end 54.7497 -112.523778)
		(stroke
			(width 0.060198)
			(type default)
		)
		(layer "B.Cu")
	)
	(gr_line
		(start 54.581552 -108.06303)
		(end 55.038752 -108.06303)
		(stroke
			(width 0.060198)
			(type default)
		)
		(layer "B.Cu")
	)
	(gr_line
		(start 54.695852 -110.84687)
		(end 54.695852 -111.98733)
		(stroke
			(width 0.060198)
			(type default)
		)
		(layer "B.Cu")
	)
	(gr_line
		(start 54.7497 -112.523778)
		(end 54.7497 -113.538)
		(stroke
			(width 0.060198)
			(type default)
		)
		(layer "B.Cu")
	)
	(gr_line
		(start 55.038752 -108.06303)
		(end 55.16626 -108.190538)
		(stroke
			(width 0.060198)
			(type default)
		)
		(layer "B.Cu")
	)
	(gr_line
		(start 55.16626 -108.190538)
		(end 55.16626 -108.83519)
		(stroke
			(width 0.060198)
			(type default)
		)
		(layer "B.Cu")
	)
	(gr_line
		(start 55.20055 -128.445768)
		(end 55.363364 -128.445768)
		(stroke
			(width 0.068326)
			(type default)
		)
		(layer "B.Cu")
	)
	(gr_line
		(start 55.50535 -128.735074)
		(end 55.668164 -128.735074)
		(stroke
			(width 0.068326)
			(type default)
		)
		(layer "B.Cu")
	)
	(gr_line
		(start 56.0451 -127.421894)
		(end 56.297322 -127.421894)
		(stroke
			(width 0.060198)
			(type default)
		)
		(layer "B.Cu")
	)
	(gr_line
		(start 56.436768 -118.288816)
		(end 56.588152 -118.4402)
		(stroke
			(width 0.060198)
			(type default)
		)
		(layer "B.Cu")
	)
	(gr_line
		(start 56.436768 -117.575584)
		(end 56.588152 -117.4242)
		(stroke
			(width 0.060198)
			(type default)
		)
		(layer "B.Cu")
	)
	(gr_line
		(start 56.500014 -224.713546)
		(end 56.500014 -225.92538)
		(stroke
			(width 0.068326)
			(type default)
		)
		(layer "B.Cu")
	)
	(gr_line
		(start 56.54675 -126.961646)
		(end 56.634126 -126.961646)
		(stroke
			(width 0.060198)
			(type default)
		)
		(layer "B.Cu")
	)
	(gr_arc
		(start 56.639968 -224.375726)
		(mid 56.53638 -224.530711)
		(end 56.500014 -224.713546)
		(stroke
			(width 0.068326)
			(type default)
		)
		(layer "B.Cu")
	)
	(gr_line
		(start 56.639968 -224.375726)
		(end 56.690768 -224.324926)
		(stroke
			(width 0.068326)
			(type default)
		)
		(layer "B.Cu")
	)
	(gr_arc
		(start 56.690768 -224.324926)
		(mid 56.732894 -224.26188)
		(end 56.747664 -224.187512)
		(stroke
			(width 0.068326)
			(type default)
		)
		(layer "B.Cu")
	)
	(gr_arc
		(start 56.74741 -222.90786)
		(mid 56.681402 -222.576014)
		(end 56.49341 -222.294704)
		(stroke
			(width 0.068326)
			(type default)
		)
		(layer "B.Cu")
	)
	(gr_line
		(start 56.804814 -25.222708)
		(end 57.121806 -25.5397)
		(stroke
			(width 0.060198)
			(type default)
		)
		(layer "B.Cu")
	)
	(gr_arc
		(start 57.052464 -224.17278)
		(mid 57.072528 -224.273679)
		(end 57.12968 -224.359216)
		(stroke
			(width 0.068326)
			(type default)
		)
		(layer "B.Cu")
	)
	(gr_line
		(start 57.121806 -25.5397)
		(end 58.5724 -25.5397)
		(stroke
			(width 0.060198)
			(type default)
		)
		(layer "B.Cu")
	)
	(gr_line
		(start 57.175654 -128.21285)
		(end 57.24525 -128.21285)
		(stroke
			(width 0.060198)
			(type default)
		)
		(layer "B.Cu")
	)
	(gr_line
		(start 57.24525 -128.21285)
		(end 57.4802 -128.4478)
		(stroke
			(width 0.060198)
			(type default)
		)
		(layer "B.Cu")
	)
	(gr_line
		(start 57.26176 -127.585978)
		(end 57.53862 -127.585978)
		(stroke
			(width 0.060198)
			(type default)
		)
		(layer "B.Cu")
	)
	(gr_arc
		(start 57.29986 -224.770188)
		(mid 57.255622 -224.547791)
		(end 57.12968 -224.359216)
		(stroke
			(width 0.068326)
			(type default)
		)
		(layer "B.Cu")
	)
	(gr_line
		(start 57.29986 -224.770188)
		(end 57.300114 -224.770442)
		(stroke
			(width 0.068326)
			(type default)
		)
		(layer "B.Cu")
	)
	(gr_line
		(start 57.300114 -224.770442)
		(end 57.300114 -225.92538)
		(stroke
			(width 0.068326)
			(type default)
		)
		(layer "B.Cu")
	)
	(gr_arc
		(start 57.30621 -222.294704)
		(mid 57.118409 -222.575794)
		(end 57.052464 -222.907352)
		(stroke
			(width 0.068326)
			(type default)
		)
		(layer "B.Cu")
	)
	(gr_line
		(start 57.477152 -118.4402)
		(end 58.556652 -118.4402)
		(stroke
			(width 0.060198)
			(type default)
		)
		(layer "B.Cu")
	)
	(gr_line
		(start 57.477152 -117.4242)
		(end 57.493154 -117.440202)
		(stroke
			(width 0.060198)
			(type default)
		)
		(layer "B.Cu")
	)
	(gr_line
		(start 57.493154 -117.440202)
		(end 58.565288 -117.440202)
		(stroke
			(width 0.060198)
			(type default)
		)
		(layer "B.Cu")
	)
	(gr_line
		(start 58.556652 -118.4402)
		(end 58.565034 -118.431818)
		(stroke
			(width 0.060198)
			(type default)
		)
		(layer "B.Cu")
	)
	(gr_line
		(start 58.565034 -118.431818)
		(end 58.569352 -118.4275)
		(stroke
			(width 0.060198)
			(type default)
		)
		(layer "B.Cu")
	)
	(gr_line
		(start 58.565288 -117.440202)
		(end 59.2582 -116.74729)
		(stroke
			(width 0.060198)
			(type default)
		)
		(layer "B.Cu")
	)
	(gr_line
		(start 58.569352 -118.4275)
		(end 59.7154 -118.4275)
		(stroke
			(width 0.060198)
			(type default)
		)
		(layer "B.Cu")
	)
	(gr_line
		(start 58.5724 -25.5397)
		(end 59.0804 -25.0317)
		(stroke
			(width 0.060198)
			(type default)
		)
		(layer "B.Cu")
	)
	(gr_line
		(start 58.847228 -90.7542)
		(end 58.909458 -90.81643)
		(stroke
			(width 0.068326)
			(type default)
		)
		(layer "B.Cu")
	)
	(gr_line
		(start 59.2582 -115.5192)
		(end 59.2582 -116.74729)
		(stroke
			(width 0.060198)
			(type default)
		)
		(layer "B.Cu")
	)
	(gr_line
		(start 59.2582 -115.5192)
		(end 59.968384 -114.809016)
		(stroke
			(width 0.060198)
			(type default)
		)
		(layer "B.Cu")
	)
	(gr_line
		(start 59.699906 -224.713546)
		(end 59.70016 -224.7138)
		(stroke
			(width 0.068326)
			(type default)
		)
		(layer "B.Cu")
	)
	(gr_line
		(start 59.70016 -224.7138)
		(end 59.70016 -225.92538)
		(stroke
			(width 0.068326)
			(type default)
		)
		(layer "B.Cu")
	)
	(gr_line
		(start 59.7154 -118.4275)
		(end 60.052966 -118.765066)
		(stroke
			(width 0.060198)
			(type default)
		)
		(layer "B.Cu")
	)
	(gr_line
		(start 59.7154 -117.5385)
		(end 60.1853 -117.0686)
		(stroke
			(width 0.060198)
			(type default)
		)
		(layer "B.Cu")
	)
	(gr_arc
		(start 59.83986 -224.375726)
		(mid 59.736274 -224.530712)
		(end 59.699906 -224.713546)
		(stroke
			(width 0.068326)
			(type default)
		)
		(layer "B.Cu")
	)
	(gr_line
		(start 59.83986 -224.375726)
		(end 59.89066 -224.324926)
		(stroke
			(width 0.068326)
			(type default)
		)
		(layer "B.Cu")
	)
	(gr_arc
		(start 59.89066 -224.324926)
		(mid 59.932786 -224.26188)
		(end 59.947556 -224.187512)
		(stroke
			(width 0.068326)
			(type default)
		)
		(layer "B.Cu")
	)
	(gr_arc
		(start 59.947302 -222.90786)
		(mid 59.881294 -222.576014)
		(end 59.693302 -222.294704)
		(stroke
			(width 0.068326)
			(type default)
		)
		(layer "B.Cu")
	)
	(gr_line
		(start 59.968384 -114.809016)
		(end 61.327284 -114.809016)
		(stroke
			(width 0.060198)
			(type default)
		)
		(layer "B.Cu")
	)
	(gr_line
		(start 60.052966 -118.765066)
		(end 60.254896 -118.765066)
		(stroke
			(width 0.060198)
			(type default)
		)
		(layer "B.Cu")
	)
	(gr_line
		(start 60.1853 -117.0686)
		(end 61.17336 -117.0686)
		(stroke
			(width 0.060198)
			(type default)
		)
		(layer "B.Cu")
	)
	(gr_arc
		(start 60.252356 -224.17278)
		(mid 60.272419 -224.273679)
		(end 60.329572 -224.359216)
		(stroke
			(width 0.068326)
			(type default)
		)
		(layer "B.Cu")
	)
	(gr_line
		(start 60.254896 -118.765066)
		(end 60.43803 -118.9482)
		(stroke
			(width 0.060198)
			(type default)
		)
		(layer "B.Cu")
	)
	(gr_line
		(start 60.43803 -118.9482)
		(end 61.17336 -118.9482)
		(stroke
			(width 0.060198)
			(type default)
		)
		(layer "B.Cu")
	)
	(gr_arc
		(start 60.499752 -224.770188)
		(mid 60.455514 -224.547791)
		(end 60.329572 -224.359216)
		(stroke
			(width 0.068326)
			(type default)
		)
		(layer "B.Cu")
	)
	(gr_line
		(start 60.499752 -224.770188)
		(end 60.500006 -224.770442)
		(stroke
			(width 0.068326)
			(type default)
		)
		(layer "B.Cu")
	)
	(gr_line
		(start 60.500006 -224.770442)
		(end 60.500006 -225.92538)
		(stroke
			(width 0.068326)
			(type default)
		)
		(layer "B.Cu")
	)
	(gr_arc
		(start 60.506102 -222.294704)
		(mid 60.318303 -222.575795)
		(end 60.252356 -222.907352)
		(stroke
			(width 0.068326)
			(type default)
		)
		(layer "B.Cu")
	)
	(gr_line
		(start 61.17336 -117.61216)
		(end 61.4934 -117.9322)
		(stroke
			(width 0.060198)
			(type default)
		)
		(layer "B.Cu")
	)
	(gr_line
		(start 61.17336 -117.0686)
		(end 61.17336 -117.61216)
		(stroke
			(width 0.060198)
			(type default)
		)
		(layer "B.Cu")
	)
	(gr_line
		(start 61.327284 -114.809016)
		(end 62.804548 -114.809016)
		(stroke
			(width 0.060198)
			(type default)
		)
		(layer "B.Cu")
	)
	(gr_line
		(start 61.4934 -117.9322)
		(end 62.9412 -117.9322)
		(stroke
			(width 0.060198)
			(type default)
		)
		(layer "B.Cu")
	)
	(gr_line
		(start 62.47384 -118.9482)
		(end 63.4873 -118.9482)
		(stroke
			(width 0.060198)
			(type default)
		)
		(layer "B.Cu")
	)
	(gr_line
		(start 62.47384 -117.0686)
		(end 63.2714 -117.0686)
		(stroke
			(width 0.060198)
			(type default)
		)
		(layer "B.Cu")
	)
	(gr_line
		(start 62.5602 -123.2916)
		(end 62.7126 -123.444)
		(stroke
			(width 0.060198)
			(type default)
		)
		(layer "B.Cu")
	)
	(gr_line
		(start 62.5602 -122.428)
		(end 62.6872 -122.301)
		(stroke
			(width 0.060198)
			(type default)
		)
		(layer "B.Cu")
	)
	(gr_line
		(start 62.5602 -121.5644)
		(end 62.7126 -121.7168)
		(stroke
			(width 0.060198)
			(type default)
		)
		(layer "B.Cu")
	)
	(gr_line
		(start 62.587378 -124.154946)
		(end 63.131446 -124.154946)
		(stroke
			(width 0.060198)
			(type default)
		)
		(layer "B.Cu")
	)
	(gr_line
		(start 62.6872 -122.301)
		(end 63.6905 -122.301)
		(stroke
			(width 0.060198)
			(type default)
		)
		(layer "B.Cu")
	)
	(gr_line
		(start 62.7126 -123.444)
		(end 63.4365 -123.444)
		(stroke
			(width 0.060198)
			(type default)
		)
		(layer "B.Cu")
	)
	(gr_line
		(start 62.7126 -121.7168)
		(end 63.2587 -121.7168)
		(stroke
			(width 0.060198)
			(type default)
		)
		(layer "B.Cu")
	)
	(gr_line
		(start 62.804548 -114.809016)
		(end 63.871856 -115.876324)
		(stroke
			(width 0.060198)
			(type default)
		)
		(layer "B.Cu")
	)
	(gr_line
		(start 62.9412 -117.9322)
		(end 63.119 -118.11)
		(stroke
			(width 0.060198)
			(type default)
		)
		(layer "B.Cu")
	)
	(gr_line
		(start 63.131446 -124.154946)
		(end 63.4365 -124.46)
		(stroke
			(width 0.060198)
			(type default)
		)
		(layer "B.Cu")
	)
	(gr_line
		(start 63.2587 -121.7168)
		(end 63.6905 -121.285)
		(stroke
			(width 0.060198)
			(type default)
		)
		(layer "B.Cu")
	)
	(gr_line
		(start 63.2714 -117.0686)
		(end 63.7921 -117.5893)
		(stroke
			(width 0.060198)
			(type default)
		)
		(layer "B.Cu")
	)
	(gr_line
		(start 63.4873 -118.9482)
		(end 63.9572 -118.4783)
		(stroke
			(width 0.060198)
			(type default)
		)
		(layer "B.Cu")
	)
	(gr_line
		(start 63.49873 -25.071832)
		(end 64.1604 -25.071832)
		(stroke
			(width 0.060198)
			(type default)
		)
		(layer "B.Cu")
	)
	(gr_line
		(start 63.7921 -117.5893)
		(end 63.9572 -117.5893)
		(stroke
			(width 0.060198)
			(type default)
		)
		(layer "B.Cu")
	)
	(gr_line
		(start 63.871856 -116.18976)
		(end 63.9572 -116.275104)
		(stroke
			(width 0.060198)
			(type default)
		)
		(layer "B.Cu")
	)
	(gr_line
		(start 63.871856 -115.876324)
		(end 63.871856 -116.18976)
		(stroke
			(width 0.060198)
			(type default)
		)
		(layer "B.Cu")
	)
	(gr_line
		(start 63.920116 -101.858826)
		(end 64.20993 -102.148894)
		(stroke
			(width 0.068326)
			(type default)
		)
		(layer "B.Cu")
	)
	(gr_line
		(start 63.920116 -101.642418)
		(end 63.920116 -101.858826)
		(stroke
			(width 0.068326)
			(type default)
		)
		(layer "B.Cu")
	)
	(gr_line
		(start 63.9572 -118.4783)
		(end 63.9572 -119.4054)
		(stroke
			(width 0.060198)
			(type default)
		)
		(layer "B.Cu")
	)
	(gr_line
		(start 63.9572 -116.275104)
		(end 63.9572 -117.5893)
		(stroke
			(width 0.060198)
			(type default)
		)
		(layer "B.Cu")
	)
	(gr_line
		(start 64.1604 -25.071832)
		(end 64.8462 -25.757632)
		(stroke
			(width 0.060198)
			(type default)
		)
		(layer "B.Cu")
	)
	(gr_line
		(start 64.20993 -102.148894)
		(end 64.426592 -102.148894)
		(stroke
			(width 0.068326)
			(type default)
		)
		(layer "B.Cu")
	)
	(gr_line
		(start 64.3255 -124.46)
		(end 65.1002 -124.46)
		(stroke
			(width 0.060198)
			(type default)
		)
		(layer "B.Cu")
	)
	(gr_line
		(start 64.3255 -123.444)
		(end 65.1002 -123.444)
		(stroke
			(width 0.060198)
			(type default)
		)
		(layer "B.Cu")
	)
	(gr_line
		(start 64.353186 -101.640894)
		(end 64.428116 -101.715824)
		(stroke
			(width 0.068326)
			(type default)
		)
		(layer "B.Cu")
	)
	(gr_line
		(start 64.719708 -102.658418)
		(end 65.009522 -102.948486)
		(stroke
			(width 0.068326)
			(type default)
		)
		(layer "B.Cu")
	)
	(gr_line
		(start 64.719708 -102.44201)
		(end 64.719708 -102.658418)
		(stroke
			(width 0.068326)
			(type default)
		)
		(layer "B.Cu")
	)
	(gr_line
		(start 64.8462 -25.757632)
		(end 65.509648 -25.757632)
		(stroke
			(width 0.060198)
			(type default)
		)
		(layer "B.Cu")
	)
	(gr_line
		(start 65.009522 -102.948486)
		(end 65.226184 -102.948486)
		(stroke
			(width 0.068326)
			(type default)
		)
		(layer "B.Cu")
	)
	(gr_line
		(start 65.152778 -102.440486)
		(end 65.227708 -102.515416)
		(stroke
			(width 0.068326)
			(type default)
		)
		(layer "B.Cu")
	)
	(gr_line
		(start 65.300098 -224.713546)
		(end 65.300098 -225.92538)
		(stroke
			(width 0.068326)
			(type default)
		)
		(layer "B.Cu")
	)
	(gr_line
		(start 65.330578 -127.679196)
		(end 65.519554 -127.868172)
		(stroke
			(width 0.068326)
			(type default)
		)
		(layer "B.Cu")
	)
	(gr_line
		(start 65.3796 -122.335798)
		(end 65.490598 -122.335798)
		(stroke
			(width 0.060198)
			(type default)
		)
		(layer "B.Cu")
	)
	(gr_line
		(start 65.3796 -121.2342)
		(end 65.47485 -121.2342)
		(stroke
			(width 0.060198)
			(type default)
		)
		(layer "B.Cu")
	)
	(gr_arc
		(start 65.440052 -224.375726)
		(mid 65.336468 -224.530712)
		(end 65.300098 -224.713546)
		(stroke
			(width 0.068326)
			(type default)
		)
		(layer "B.Cu")
	)
	(gr_line
		(start 65.440052 -224.375726)
		(end 65.490852 -224.324926)
		(stroke
			(width 0.068326)
			(type default)
		)
		(layer "B.Cu")
	)
	(gr_line
		(start 65.47485 -121.2342)
		(end 65.677034 -121.436384)
		(stroke
			(width 0.060198)
			(type default)
		)
		(layer "B.Cu")
	)
	(gr_line
		(start 65.490598 -122.335798)
		(end 65.677034 -122.149362)
		(stroke
			(width 0.060198)
			(type default)
		)
		(layer "B.Cu")
	)
	(gr_arc
		(start 65.490852 -224.324926)
		(mid 65.532978 -224.26188)
		(end 65.547748 -224.187512)
		(stroke
			(width 0.068326)
			(type default)
		)
		(layer "B.Cu")
	)
	(gr_line
		(start 65.5193 -103.45801)
		(end 65.809114 -103.748078)
		(stroke
			(width 0.068326)
			(type default)
		)
		(layer "B.Cu")
	)
	(gr_line
		(start 65.5193 -103.241602)
		(end 65.5193 -103.45801)
		(stroke
			(width 0.068326)
			(type default)
		)
		(layer "B.Cu")
	)
	(gr_arc
		(start 65.547494 -222.90786)
		(mid 65.481486 -222.576014)
		(end 65.293494 -222.294704)
		(stroke
			(width 0.068326)
			(type default)
		)
		(layer "B.Cu")
	)
	(gr_line
		(start 65.809114 -103.748078)
		(end 66.025776 -103.748078)
		(stroke
			(width 0.068326)
			(type default)
		)
		(layer "B.Cu")
	)
	(gr_arc
		(start 65.852548 -224.17278)
		(mid 65.872611 -224.273679)
		(end 65.929764 -224.359216)
		(stroke
			(width 0.068326)
			(type default)
		)
		(layer "B.Cu")
	)
	(gr_line
		(start 65.95237 -103.240078)
		(end 66.0273 -103.315008)
		(stroke
			(width 0.068326)
			(type default)
		)
		(layer "B.Cu")
	)
	(gr_line
		(start 65.954402 -127.868172)
		(end 66.143378 -127.679196)
		(stroke
			(width 0.068326)
			(type default)
		)
		(layer "B.Cu")
	)
	(gr_arc
		(start 66.099944 -224.770188)
		(mid 66.055706 -224.547791)
		(end 65.929764 -224.359216)
		(stroke
			(width 0.068326)
			(type default)
		)
		(layer "B.Cu")
	)
	(gr_line
		(start 66.099944 -224.770188)
		(end 66.100198 -224.770442)
		(stroke
			(width 0.068326)
			(type default)
		)
		(layer "B.Cu")
	)
	(gr_line
		(start 66.100198 -224.770442)
		(end 66.100198 -225.92538)
		(stroke
			(width 0.068326)
			(type default)
		)
		(layer "B.Cu")
	)
	(gr_arc
		(start 66.106294 -222.294704)
		(mid 65.918497 -222.575795)
		(end 65.852548 -222.907352)
		(stroke
			(width 0.068326)
			(type default)
		)
		(layer "B.Cu")
	)
	(gr_line
		(start 66.318892 -104.257602)
		(end 66.608706 -104.54767)
		(stroke
			(width 0.068326)
			(type default)
		)
		(layer "B.Cu")
	)
	(gr_line
		(start 66.318892 -104.041194)
		(end 66.318892 -104.257602)
		(stroke
			(width 0.068326)
			(type default)
		)
		(layer "B.Cu")
	)
	(gr_line
		(start 66.342768 -122.175016)
		(end 66.494152 -122.3264)
		(stroke
			(width 0.060198)
			(type default)
		)
		(layer "B.Cu")
	)
	(gr_line
		(start 66.342768 -121.461784)
		(end 66.494152 -121.3104)
		(stroke
			(width 0.060198)
			(type default)
		)
		(layer "B.Cu")
	)
	(gr_line
		(start 66.608706 -104.54767)
		(end 66.825368 -104.54767)
		(stroke
			(width 0.068326)
			(type default)
		)
		(layer "B.Cu")
	)
	(gr_line
		(start 66.751962 -104.03967)
		(end 66.826892 -104.1146)
		(stroke
			(width 0.068326)
			(type default)
		)
		(layer "B.Cu")
	)
	(gr_line
		(start 66.9925 -150.622)
		(end 68.36918 -150.622)
		(stroke
			(width 0.060198)
			(type default)
		)
		(layer "B.Cu")
	)
	(gr_line
		(start 66.9925 -149.479)
		(end 67.84213 -148.62937)
		(stroke
			(width 0.060198)
			(type default)
		)
		(layer "B.Cu")
	)
	(gr_line
		(start 67.383152 -122.3264)
		(end 67.534536 -122.175016)
		(stroke
			(width 0.060198)
			(type default)
		)
		(layer "B.Cu")
	)
	(gr_line
		(start 67.383152 -121.3104)
		(end 67.534536 -121.461784)
		(stroke
			(width 0.060198)
			(type default)
		)
		(layer "B.Cu")
	)
	(gr_line
		(start 67.84213 -148.62937)
		(end 67.95516 -148.62937)
		(stroke
			(width 0.060198)
			(type default)
		)
		(layer "B.Cu")
	)
	(gr_line
		(start 67.95516 -148.62937)
		(end 68.326 -149.00021)
		(stroke
			(width 0.060198)
			(type default)
		)
		(layer "B.Cu")
	)
	(gr_line
		(start 68.326 -149.00021)
		(end 68.326 -149.606)
		(stroke
			(width 0.060198)
			(type default)
		)
		(layer "B.Cu")
	)
	(gr_line
		(start 68.36918 -150.622)
		(end 68.41109 -150.66391)
		(stroke
			(width 0.060198)
			(type default)
		)
		(layer "B.Cu")
	)
	(gr_line
		(start 68.49999 -224.713546)
		(end 68.49999 -225.92538)
		(stroke
			(width 0.068326)
			(type default)
		)
		(layer "B.Cu")
	)
	(gr_arc
		(start 68.639944 -224.375726)
		(mid 68.536361 -224.530713)
		(end 68.49999 -224.713546)
		(stroke
			(width 0.068326)
			(type default)
		)
		(layer "B.Cu")
	)
	(gr_line
		(start 68.639944 -224.375726)
		(end 68.690744 -224.324926)
		(stroke
			(width 0.068326)
			(type default)
		)
		(layer "B.Cu")
	)
	(gr_arc
		(start 68.690744 -224.324926)
		(mid 68.73287 -224.26188)
		(end 68.74764 -224.187512)
		(stroke
			(width 0.068326)
			(type default)
		)
		(layer "B.Cu")
	)
	(gr_arc
		(start 68.747386 -222.90786)
		(mid 68.681378 -222.576014)
		(end 68.493386 -222.294704)
		(stroke
			(width 0.068326)
			(type default)
		)
		(layer "B.Cu")
	)
	(gr_arc
		(start 69.05244 -224.17278)
		(mid 69.072502 -224.27368)
		(end 69.129656 -224.359216)
		(stroke
			(width 0.068326)
			(type default)
		)
		(layer "B.Cu")
	)
	(gr_arc
		(start 69.299836 -224.770188)
		(mid 69.255598 -224.547791)
		(end 69.129656 -224.359216)
		(stroke
			(width 0.068326)
			(type default)
		)
		(layer "B.Cu")
	)
	(gr_line
		(start 69.299836 -224.770188)
		(end 69.30009 -224.770442)
		(stroke
			(width 0.068326)
			(type default)
		)
		(layer "B.Cu")
	)
	(gr_line
		(start 69.30009 -224.770442)
		(end 69.30009 -225.92538)
		(stroke
			(width 0.068326)
			(type default)
		)
		(layer "B.Cu")
	)
	(gr_arc
		(start 69.306186 -222.294704)
		(mid 69.11839 -222.575796)
		(end 69.05244 -222.907352)
		(stroke
			(width 0.068326)
			(type default)
		)
		(layer "B.Cu")
	)
	(gr_line
		(start 71.700136 -224.713546)
		(end 71.700136 -225.92538)
		(stroke
			(width 0.068326)
			(type default)
		)
		(layer "B.Cu")
	)
	(gr_arc
		(start 71.84009 -224.375726)
		(mid 71.736498 -224.53071)
		(end 71.700136 -224.713546)
		(stroke
			(width 0.068326)
			(type default)
		)
		(layer "B.Cu")
	)
	(gr_line
		(start 71.84009 -224.375726)
		(end 71.89089 -224.324926)
		(stroke
			(width 0.068326)
			(type default)
		)
		(layer "B.Cu")
	)
	(gr_arc
		(start 71.89089 -224.324926)
		(mid 71.933016 -224.26188)
		(end 71.947786 -224.187512)
		(stroke
			(width 0.068326)
			(type default)
		)
		(layer "B.Cu")
	)
	(gr_arc
		(start 71.947532 -220.602302)
		(mid 71.884289 -220.284356)
		(end 71.7042 -220.0148)
		(stroke
			(width 0.068326)
			(type default)
		)
		(layer "B.Cu")
	)
	(gr_arc
		(start 72.252586 -224.17278)
		(mid 72.272651 -224.273677)
		(end 72.329802 -224.359216)
		(stroke
			(width 0.068326)
			(type default)
		)
		(layer "B.Cu")
	)
	(gr_arc
		(start 72.499982 -224.770188)
		(mid 72.455744 -224.547791)
		(end 72.329802 -224.359216)
		(stroke
			(width 0.068326)
			(type default)
		)
		(layer "B.Cu")
	)
	(gr_line
		(start 72.499982 -224.770188)
		(end 72.499982 -225.92538)
		(stroke
			(width 0.068326)
			(type default)
		)
		(layer "B.Cu")
	)
	(gr_arc
		(start 72.517 -220.0148)
		(mid 72.321299 -220.30765)
		(end 72.252586 -220.653102)
		(stroke
			(width 0.068326)
			(type default)
		)
		(layer "B.Cu")
	)
	(gr_line
		(start 73.36917 -105.275126)
		(end 73.4314 -105.337356)
		(stroke
			(width 0.068326)
			(type default)
		)
		(layer "B.Cu")
	)
	(gr_line
		(start 76.317348 -116.815616)
		(end 76.339192 -116.81587)
		(stroke
			(width 0.060198)
			(type default)
		)
		(layer "B.Cu")
	)
	(gr_line
		(start 76.339192 -116.81587)
		(end 76.339446 -116.815362)
		(stroke
			(width 0.060198)
			(type default)
		)
		(layer "B.Cu")
	)
	(gr_line
		(start 76.339446 -116.81587)
		(end 76.495148 -116.65966)
		(stroke
			(width 0.060198)
			(type default)
		)
		(layer "B.Cu")
	)
	(gr_line
		(start 76.349098 -117.398038)
		(end 76.49718 -117.54612)
		(stroke
			(width 0.060198)
			(type default)
		)
		(layer "B.Cu")
	)
	(gr_line
		(start 77.290422 -118.401084)
		(end 77.441552 -118.249954)
		(stroke
			(width 0.060198)
			(type default)
		)
		(layer "B.Cu")
	)
	(gr_line
		(start 77.441552 -118.249954)
		(end 77.805788 -118.249954)
		(stroke
			(width 0.060198)
			(type default)
		)
		(layer "B.Cu")
	)
	(gr_line
		(start 77.90688 -118.249954)
		(end 78.06436 -118.249954)
		(stroke
			(width 0.060198)
			(type default)
		)
		(layer "B.Cu")
	)
	(gr_line
		(start 78.100174 -224.713546)
		(end 78.100174 -225.92538)
		(stroke
			(width 0.068326)
			(type default)
		)
		(layer "B.Cu")
	)
	(gr_arc
		(start 78.240128 -224.375726)
		(mid 78.136549 -224.530714)
		(end 78.100174 -224.713546)
		(stroke
			(width 0.068326)
			(type default)
		)
		(layer "B.Cu")
	)
	(gr_line
		(start 78.240128 -224.375726)
		(end 78.290928 -224.324926)
		(stroke
			(width 0.068326)
			(type default)
		)
		(layer "B.Cu")
	)
	(gr_arc
		(start 78.290928 -224.324926)
		(mid 78.333054 -224.26188)
		(end 78.347824 -224.187512)
		(stroke
			(width 0.068326)
			(type default)
		)
		(layer "B.Cu")
	)
	(gr_arc
		(start 78.34757 -220.310964)
		(mid 78.30136 -220.078652)
		(end 78.16977 -219.881704)
		(stroke
			(width 0.068326)
			(type default)
		)
		(layer "B.Cu")
	)
	(gr_arc
		(start 78.652624 -224.17278)
		(mid 78.672691 -224.273675)
		(end 78.72984 -224.359216)
		(stroke
			(width 0.068326)
			(type default)
		)
		(layer "B.Cu")
	)
	(gr_arc
		(start 78.800706 -220.063314)
		(mid 78.69107 -220.227526)
		(end 78.652624 -220.4212)
		(stroke
			(width 0.068326)
			(type default)
		)
		(layer "B.Cu")
	)
	(gr_line
		(start 78.800706 -220.063314)
		(end 78.98257 -219.881704)
		(stroke
			(width 0.068326)
			(type default)
		)
		(layer "B.Cu")
	)
	(gr_line
		(start 78.90002 -224.770696)
		(end 78.90002 -225.92538)
		(stroke
			(width 0.068326)
			(type default)
		)
		(layer "B.Cu")
	)
	(gr_line
		(start 78.90002 -224.770696)
		(end 78.900274 -224.770442)
		(stroke
			(width 0.068326)
			(type default)
		)
		(layer "B.Cu")
	)
	(gr_arc
		(start 78.90002 -224.770188)
		(mid 78.855782 -224.547791)
		(end 78.72984 -224.359216)
		(stroke
			(width 0.068326)
			(type default)
		)
		(layer "B.Cu")
	)
	(gr_line
		(start 78.90002 -224.770188)
		(end 78.900274 -224.770442)
		(stroke
			(width 0.068326)
			(type default)
		)
		(layer "B.Cu")
	)
	(gr_line
		(start 79.121 -139.192)
		(end 79.196184 -139.116816)
		(stroke
			(width 0.060198)
			(type default)
		)
		(layer "B.Cu")
	)
	(gr_line
		(start 79.5274 -95.107252)
		(end 79.602584 -95.032068)
		(stroke
			(width 0.060198)
			(type default)
		)
		(layer "B.Cu")
	)
	(gr_line
		(start 79.5274 -94.243652)
		(end 79.602584 -94.318836)
		(stroke
			(width 0.060198)
			(type default)
		)
		(layer "B.Cu")
	)
	(gr_line
		(start 79.909416 -139.116816)
		(end 79.9846 -139.192)
		(stroke
			(width 0.060198)
			(type default)
		)
		(layer "B.Cu")
	)
	(gr_line
		(start 81.300066 -224.713546)
		(end 81.300066 -225.92538)
		(stroke
			(width 0.068326)
			(type default)
		)
		(layer "B.Cu")
	)
	(gr_line
		(start 81.407 -134.874)
		(end 81.5848 -134.6962)
		(stroke
			(width 0.060198)
			(type default)
		)
		(layer "B.Cu")
	)
	(gr_arc
		(start 81.44002 -224.375726)
		(mid 81.336442 -224.530714)
		(end 81.300066 -224.713546)
		(stroke
			(width 0.068326)
			(type default)
		)
		(layer "B.Cu")
	)
	(gr_line
		(start 81.44002 -224.375726)
		(end 81.49082 -224.324926)
		(stroke
			(width 0.068326)
			(type default)
		)
		(layer "B.Cu")
	)
	(gr_arc
		(start 81.49082 -224.324926)
		(mid 81.532946 -224.26188)
		(end 81.547716 -224.187512)
		(stroke
			(width 0.068326)
			(type default)
		)
		(layer "B.Cu")
	)
	(gr_line
		(start 81.534 -133.858508)
		(end 81.786984 -134.111492)
		(stroke
			(width 0.060198)
			(type default)
		)
		(layer "B.Cu")
	)
	(gr_line
		(start 81.534 -133.858)
		(end 81.534 -133.858508)
		(stroke
			(width 0.060198)
			(type default)
		)
		(layer "B.Cu")
	)
	(gr_arc
		(start 81.547462 -222.90786)
		(mid 81.481454 -222.576014)
		(end 81.293462 -222.294704)
		(stroke
			(width 0.068326)
			(type default)
		)
		(layer "B.Cu")
	)
	(gr_arc
		(start 81.852516 -224.17278)
		(mid 81.872583 -224.273676)
		(end 81.929732 -224.359216)
		(stroke
			(width 0.068326)
			(type default)
		)
		(layer "B.Cu")
	)
	(gr_arc
		(start 82.099912 -224.770188)
		(mid 82.055674 -224.547791)
		(end 81.929732 -224.359216)
		(stroke
			(width 0.068326)
			(type default)
		)
		(layer "B.Cu")
	)
	(gr_line
		(start 82.099912 -224.770188)
		(end 82.100166 -224.770442)
		(stroke
			(width 0.068326)
			(type default)
		)
		(layer "B.Cu")
	)
	(gr_line
		(start 82.100166 -224.770442)
		(end 82.100166 -225.92538)
		(stroke
			(width 0.068326)
			(type default)
		)
		(layer "B.Cu")
	)
	(gr_arc
		(start 82.106262 -222.294704)
		(mid 81.91845 -222.575791)
		(end 81.852516 -222.907352)
		(stroke
			(width 0.068326)
			(type default)
		)
		(layer "B.Cu")
	)
	(gr_line
		(start 84.499958 -224.713546)
		(end 84.499958 -225.92538)
		(stroke
			(width 0.068326)
			(type default)
		)
		(layer "B.Cu")
	)
	(gr_arc
		(start 84.639912 -224.375726)
		(mid 84.536336 -224.530714)
		(end 84.499958 -224.713546)
		(stroke
			(width 0.068326)
			(type default)
		)
		(layer "B.Cu")
	)
	(gr_line
		(start 84.639912 -224.375726)
		(end 84.690712 -224.324926)
		(stroke
			(width 0.068326)
			(type default)
		)
		(layer "B.Cu")
	)
	(gr_arc
		(start 84.690712 -224.324926)
		(mid 84.732838 -224.26188)
		(end 84.747608 -224.187512)
		(stroke
			(width 0.068326)
			(type default)
		)
		(layer "B.Cu")
	)
	(gr_arc
		(start 84.747354 -222.90786)
		(mid 84.681346 -222.576014)
		(end 84.493354 -222.294704)
		(stroke
			(width 0.068326)
			(type default)
		)
		(layer "B.Cu")
	)
	(gr_arc
		(start 85.052408 -224.17278)
		(mid 85.072474 -224.273676)
		(end 85.129624 -224.359216)
		(stroke
			(width 0.068326)
			(type default)
		)
		(layer "B.Cu")
	)
	(gr_arc
		(start 85.299804 -224.770188)
		(mid 85.255566 -224.547791)
		(end 85.129624 -224.359216)
		(stroke
			(width 0.068326)
			(type default)
		)
		(layer "B.Cu")
	)
	(gr_line
		(start 85.299804 -224.770188)
		(end 85.300058 -224.770442)
		(stroke
			(width 0.068326)
			(type default)
		)
		(layer "B.Cu")
	)
	(gr_line
		(start 85.300058 -224.770442)
		(end 85.300058 -225.92538)
		(stroke
			(width 0.068326)
			(type default)
		)
		(layer "B.Cu")
	)
	(gr_arc
		(start 85.306154 -222.294704)
		(mid 85.118344 -222.575792)
		(end 85.052408 -222.907352)
		(stroke
			(width 0.068326)
			(type default)
		)
		(layer "B.Cu")
	)
	(gr_line
		(start 87.700104 -224.713546)
		(end 87.700104 -225.92538)
		(stroke
			(width 0.068326)
			(type default)
		)
		(layer "B.Cu")
	)
	(gr_arc
		(start 87.840058 -224.375726)
		(mid 87.736472 -224.530712)
		(end 87.700104 -224.713546)
		(stroke
			(width 0.068326)
			(type default)
		)
		(layer "B.Cu")
	)
	(gr_line
		(start 87.840058 -224.375726)
		(end 87.890858 -224.324926)
		(stroke
			(width 0.068326)
			(type default)
		)
		(layer "B.Cu")
	)
	(gr_arc
		(start 87.890858 -224.324926)
		(mid 87.932984 -224.26188)
		(end 87.947754 -224.187512)
		(stroke
			(width 0.068326)
			(type default)
		)
		(layer "B.Cu")
	)
	(gr_arc
		(start 87.9475 -222.90786)
		(mid 87.881492 -222.576014)
		(end 87.6935 -222.294704)
		(stroke
			(width 0.068326)
			(type default)
		)
		(layer "B.Cu")
	)
	(gr_arc
		(start 88.252554 -224.17278)
		(mid 88.272617 -224.273679)
		(end 88.32977 -224.359216)
		(stroke
			(width 0.068326)
			(type default)
		)
		(layer "B.Cu")
	)
	(gr_arc
		(start 88.49995 -224.770188)
		(mid 88.455712 -224.547791)
		(end 88.32977 -224.359216)
		(stroke
			(width 0.068326)
			(type default)
		)
		(layer "B.Cu")
	)
	(gr_line
		(start 88.49995 -224.770188)
		(end 88.500204 -224.770442)
		(stroke
			(width 0.068326)
			(type default)
		)
		(layer "B.Cu")
	)
	(gr_line
		(start 88.500204 -224.770442)
		(end 88.500204 -225.92538)
		(stroke
			(width 0.068326)
			(type default)
		)
		(layer "B.Cu")
	)
	(gr_arc
		(start 88.5063 -222.294704)
		(mid 88.318501 -222.575795)
		(end 88.252554 -222.907352)
		(stroke
			(width 0.068326)
			(type default)
		)
		(layer "B.Cu")
	)
	(gr_line
		(start 90.899996 -224.713546)
		(end 90.899996 -225.92538)
		(stroke
			(width 0.068326)
			(type default)
		)
		(layer "B.Cu")
	)
	(gr_arc
		(start 91.03995 -224.375726)
		(mid 90.936366 -224.530712)
		(end 90.899996 -224.713546)
		(stroke
			(width 0.068326)
			(type default)
		)
		(layer "B.Cu")
	)
	(gr_line
		(start 91.03995 -224.375726)
		(end 91.09075 -224.324926)
		(stroke
			(width 0.068326)
			(type default)
		)
		(layer "B.Cu")
	)
	(gr_arc
		(start 91.09075 -224.324926)
		(mid 91.132876 -224.26188)
		(end 91.147646 -224.187512)
		(stroke
			(width 0.068326)
			(type default)
		)
		(layer "B.Cu")
	)
	(gr_arc
		(start 91.147392 -222.90786)
		(mid 91.081384 -222.576014)
		(end 90.893392 -222.294704)
		(stroke
			(width 0.068326)
			(type default)
		)
		(layer "B.Cu")
	)
	(gr_arc
		(start 91.452446 -224.17278)
		(mid 91.472509 -224.27368)
		(end 91.529662 -224.359216)
		(stroke
			(width 0.068326)
			(type default)
		)
		(layer "B.Cu")
	)
	(gr_arc
		(start 91.699842 -224.770188)
		(mid 91.655604 -224.547791)
		(end 91.529662 -224.359216)
		(stroke
			(width 0.068326)
			(type default)
		)
		(layer "B.Cu")
	)
	(gr_line
		(start 91.699842 -224.770188)
		(end 91.700096 -224.770442)
		(stroke
			(width 0.068326)
			(type default)
		)
		(layer "B.Cu")
	)
	(gr_line
		(start 91.700096 -224.770442)
		(end 91.700096 -225.92538)
		(stroke
			(width 0.068326)
			(type default)
		)
		(layer "B.Cu")
	)
	(gr_arc
		(start 91.706192 -222.294704)
		(mid 91.518395 -222.575795)
		(end 91.452446 -222.907352)
		(stroke
			(width 0.068326)
			(type default)
		)
		(layer "B.Cu")
	)
	(gr_arc
		(start 93.599 -184.147968)
		(mid 93.54455 -183.874143)
		(end 93.38945 -183.642)
		(stroke
			(width 0.068326)
			(type default)
		)
		(layer "B.Cu")
	)
	(gr_arc
		(start 93.9038 -184.46877)
		(mid 93.903785 -184.471564)
		(end 93.9038 -184.474358)
		(stroke
			(width 0.068326)
			(type default)
		)
		(layer "B.Cu")
	)
	(gr_line
		(start 94.169484 -188.507624)
		(end 94.174564 -188.535818)
		(stroke
			(width 0.068326)
			(type default)
		)
		(layer "B.Cu")
	)
	(gr_line
		(start 94.174564 -188.535818)
		(end 94.19082 -188.559186)
		(stroke
			(width 0.068326)
			(type default)
		)
		(layer "B.Cu")
	)
	(gr_arc
		(start 94.20225 -183.642)
		(mid 93.981373 -183.972622)
		(end 93.9038 -184.362598)
		(stroke
			(width 0.068326)
			(type default)
		)
		(layer "B.Cu")
	)
	(gr_line
		(start 96.487996 -191.83985)
		(end 96.496886 -191.85255)
		(stroke
			(width 0.068326)
			(type default)
		)
		(layer "B.Cu")
	)
	(gr_line
		(start 96.496886 -191.85255)
		(end 96.509586 -191.86144)
		(stroke
			(width 0.068326)
			(type default)
		)
		(layer "B.Cu")
	)
	(gr_line
		(start 96.500188 -224.713546)
		(end 96.500188 -225.92538)
		(stroke
			(width 0.068326)
			(type default)
		)
		(layer "B.Cu")
	)
	(gr_arc
		(start 96.640142 -224.375726)
		(mid 96.53656 -224.530713)
		(end 96.500188 -224.713546)
		(stroke
			(width 0.068326)
			(type default)
		)
		(layer "B.Cu")
	)
	(gr_line
		(start 96.640142 -224.375726)
		(end 96.690942 -224.324926)
		(stroke
			(width 0.068326)
			(type default)
		)
		(layer "B.Cu")
	)
	(gr_arc
		(start 96.690942 -224.324926)
		(mid 96.733068 -224.26188)
		(end 96.747838 -224.187512)
		(stroke
			(width 0.068326)
			(type default)
		)
		(layer "B.Cu")
	)
	(gr_arc
		(start 96.747584 -222.90786)
		(mid 96.681576 -222.576014)
		(end 96.493584 -222.294704)
		(stroke
			(width 0.068326)
			(type default)
		)
		(layer "B.Cu")
	)
	(gr_arc
		(start 97.052638 -224.17278)
		(mid 97.072706 -224.273674)
		(end 97.129854 -224.359216)
		(stroke
			(width 0.068326)
			(type default)
		)
		(layer "B.Cu")
	)
	(gr_arc
		(start 97.300034 -224.770188)
		(mid 97.255796 -224.547791)
		(end 97.129854 -224.359216)
		(stroke
			(width 0.068326)
			(type default)
		)
		(layer "B.Cu")
	)
	(gr_line
		(start 97.300034 -224.770188)
		(end 97.300034 -225.92538)
		(stroke
			(width 0.068326)
			(type default)
		)
		(layer "B.Cu")
	)
	(gr_arc
		(start 97.306384 -222.294704)
		(mid 97.118589 -222.575796)
		(end 97.052638 -222.907352)
		(stroke
			(width 0.068326)
			(type default)
		)
		(layer "B.Cu")
	)
	(gr_line
		(start 99.70008 -224.713546)
		(end 99.70008 -225.92538)
		(stroke
			(width 0.068326)
			(type default)
		)
		(layer "B.Cu")
	)
	(gr_arc
		(start 99.840034 -224.375726)
		(mid 99.736453 -224.530713)
		(end 99.70008 -224.713546)
		(stroke
			(width 0.068326)
			(type default)
		)
		(layer "B.Cu")
	)
	(gr_line
		(start 99.840034 -224.375726)
		(end 99.890834 -224.324926)
		(stroke
			(width 0.068326)
			(type default)
		)
		(layer "B.Cu")
	)
	(gr_arc
		(start 99.890834 -224.324926)
		(mid 99.93296 -224.26188)
		(end 99.94773 -224.187512)
		(stroke
			(width 0.068326)
			(type default)
		)
		(layer "B.Cu")
	)
	(gr_arc
		(start 99.947476 -222.90786)
		(mid 99.881468 -222.576014)
		(end 99.693476 -222.294704)
		(stroke
			(width 0.068326)
			(type default)
		)
		(layer "B.Cu")
	)
	(gr_arc
		(start 100.25253 -224.17278)
		(mid 100.272598 -224.273675)
		(end 100.329746 -224.359216)
		(stroke
			(width 0.068326)
			(type default)
		)
		(layer "B.Cu")
	)
	(gr_arc
		(start 100.499926 -224.770188)
		(mid 100.455688 -224.547791)
		(end 100.329746 -224.359216)
		(stroke
			(width 0.068326)
			(type default)
		)
		(layer "B.Cu")
	)
	(gr_line
		(start 100.499926 -224.770188)
		(end 100.50018 -224.770442)
		(stroke
			(width 0.068326)
			(type default)
		)
		(layer "B.Cu")
	)
	(gr_line
		(start 100.50018 -224.770442)
		(end 100.50018 -225.92538)
		(stroke
			(width 0.068326)
			(type default)
		)
		(layer "B.Cu")
	)
	(gr_arc
		(start 100.506276 -222.294704)
		(mid 100.318482 -222.575796)
		(end 100.25253 -222.907352)
		(stroke
			(width 0.068326)
			(type default)
		)
		(layer "B.Cu")
	)
	(gr_line
		(start 102.130352 -195.42506)
		(end 102.143052 -195.43395)
		(stroke
			(width 0.068326)
			(type default)
		)
		(layer "B.Cu")
	)
	(gr_line
		(start 102.143052 -195.43395)
		(end 102.151942 -195.44665)
		(stroke
			(width 0.068326)
			(type default)
		)
		(layer "B.Cu")
	)
	(gr_line
		(start 102.899972 -224.713546)
		(end 102.899972 -225.92538)
		(stroke
			(width 0.068326)
			(type default)
		)
		(layer "B.Cu")
	)
	(gr_arc
		(start 103.039926 -224.375726)
		(mid 102.936347 -224.530714)
		(end 102.899972 -224.713546)
		(stroke
			(width 0.068326)
			(type default)
		)
		(layer "B.Cu")
	)
	(gr_line
		(start 103.039926 -224.375726)
		(end 103.090726 -224.324926)
		(stroke
			(width 0.068326)
			(type default)
		)
		(layer "B.Cu")
	)
	(gr_arc
		(start 103.090726 -224.324926)
		(mid 103.132852 -224.26188)
		(end 103.147622 -224.187512)
		(stroke
			(width 0.068326)
			(type default)
		)
		(layer "B.Cu")
	)
	(gr_arc
		(start 103.147368 -222.90786)
		(mid 103.08136 -222.576014)
		(end 102.893368 -222.294704)
		(stroke
			(width 0.068326)
			(type default)
		)
		(layer "B.Cu")
	)
	(gr_arc
		(start 103.452422 -224.17278)
		(mid 103.472489 -224.273675)
		(end 103.529638 -224.359216)
		(stroke
			(width 0.068326)
			(type default)
		)
		(layer "B.Cu")
	)
	(gr_arc
		(start 103.699818 -224.770188)
		(mid 103.65558 -224.547791)
		(end 103.529638 -224.359216)
		(stroke
			(width 0.068326)
			(type default)
		)
		(layer "B.Cu")
	)
	(gr_line
		(start 103.699818 -224.770188)
		(end 103.700072 -224.770442)
		(stroke
			(width 0.068326)
			(type default)
		)
		(layer "B.Cu")
	)
	(gr_line
		(start 103.700072 -224.770442)
		(end 103.700072 -225.92538)
		(stroke
			(width 0.068326)
			(type default)
		)
		(layer "B.Cu")
	)
	(gr_arc
		(start 103.706168 -222.294704)
		(mid 103.518355 -222.575791)
		(end 103.452422 -222.907352)
		(stroke
			(width 0.068326)
			(type default)
		)
		(layer "B.Cu")
	)
	(gr_line
		(start 106.100118 -224.713546)
		(end 106.100118 -225.92538)
		(stroke
			(width 0.068326)
			(type default)
		)
		(layer "B.Cu")
	)
	(gr_arc
		(start 106.240072 -224.375726)
		(mid 106.136483 -224.530711)
		(end 106.100118 -224.713546)
		(stroke
			(width 0.068326)
			(type default)
		)
		(layer "B.Cu")
	)
	(gr_line
		(start 106.240072 -224.375726)
		(end 106.290872 -224.324926)
		(stroke
			(width 0.068326)
			(type default)
		)
		(layer "B.Cu")
	)
	(gr_arc
		(start 106.290872 -224.324926)
		(mid 106.332998 -224.26188)
		(end 106.347768 -224.187512)
		(stroke
			(width 0.068326)
			(type default)
		)
		(layer "B.Cu")
	)
	(gr_arc
		(start 106.347514 -222.90786)
		(mid 106.281506 -222.576014)
		(end 106.093514 -222.294704)
		(stroke
			(width 0.068326)
			(type default)
		)
		(layer "B.Cu")
	)
	(gr_arc
		(start 106.652568 -224.17278)
		(mid 106.672632 -224.273678)
		(end 106.729784 -224.359216)
		(stroke
			(width 0.068326)
			(type default)
		)
		(layer "B.Cu")
	)
	(gr_line
		(start 106.70667 -202.483212)
		(end 107.087162 -203.026772)
		(stroke
			(width 0.068326)
			(type default)
		)
		(layer "B.Cu")
	)
	(gr_arc
		(start 106.899964 -224.770188)
		(mid 106.855726 -224.547791)
		(end 106.729784 -224.359216)
		(stroke
			(width 0.068326)
			(type default)
		)
		(layer "B.Cu")
	)
	(gr_line
		(start 106.899964 -224.770188)
		(end 106.899964 -225.92538)
		(stroke
			(width 0.068326)
			(type default)
		)
		(layer "B.Cu")
	)
	(gr_arc
		(start 106.906314 -222.294704)
		(mid 106.718512 -222.575794)
		(end 106.652568 -222.907352)
		(stroke
			(width 0.068326)
			(type default)
		)
		(layer "B.Cu")
	)
	(gr_line
		(start 106.93781 -202.277472)
		(end 107.16514 -202.317604)
		(stroke
			(width 0.068326)
			(type default)
		)
		(layer "B.Cu")
	)
	(gr_line
		(start 107.16514 -202.317604)
		(end 107.40009 -202.653392)
		(stroke
			(width 0.068326)
			(type default)
		)
		(layer "B.Cu")
	)
	(gr_line
		(start 107.359958 -202.880468)
		(end 107.40009 -202.653392)
		(stroke
			(width 0.068326)
			(type default)
		)
		(layer "B.Cu")
	)
	(gr_line
		(start 107.367324 -203.426568)
		(end 107.7468 -203.968604)
		(stroke
			(width 0.068326)
			(type default)
		)
		(layer "B.Cu")
	)
	(gr_line
		(start 107.597956 -203.22032)
		(end 107.825286 -203.260452)
		(stroke
			(width 0.068326)
			(type default)
		)
		(layer "B.Cu")
	)
	(gr_line
		(start 107.825286 -203.260452)
		(end 108.06049 -203.59624)
		(stroke
			(width 0.068326)
			(type default)
		)
		(layer "B.Cu")
	)
	(gr_line
		(start 108.020104 -203.823316)
		(end 108.06049 -203.59624)
		(stroke
			(width 0.068326)
			(type default)
		)
		(layer "B.Cu")
	)
	(gr_line
		(start 108.02874 -204.370686)
		(end 108.406692 -204.91069)
		(stroke
			(width 0.068326)
			(type default)
		)
		(layer "B.Cu")
	)
	(gr_line
		(start 108.258102 -204.163168)
		(end 108.485432 -204.2033)
		(stroke
			(width 0.068326)
			(type default)
		)
		(layer "B.Cu")
	)
	(gr_line
		(start 108.485432 -204.2033)
		(end 108.720636 -204.539088)
		(stroke
			(width 0.068326)
			(type default)
		)
		(layer "B.Cu")
	)
	(gr_line
		(start 108.68025 -204.766164)
		(end 108.720636 -204.539088)
		(stroke
			(width 0.068326)
			(type default)
		)
		(layer "B.Cu")
	)
	(gr_line
		(start 110.10011 -225.170746)
		(end 110.10011 -225.92538)
		(stroke
			(width 0.068326)
			(type default)
		)
		(layer "B.Cu")
	)
	(gr_arc
		(start 110.240064 -224.832926)
		(mid 110.136501 -224.987919)
		(end 110.10011 -225.170746)
		(stroke
			(width 0.068326)
			(type default)
		)
		(layer "B.Cu")
	)
	(gr_line
		(start 110.240064 -224.832926)
		(end 110.290864 -224.782126)
		(stroke
			(width 0.068326)
			(type default)
		)
		(layer "B.Cu")
	)
	(gr_arc
		(start 110.290864 -224.782126)
		(mid 110.332962 -224.719072)
		(end 110.34776 -224.644712)
		(stroke
			(width 0.068326)
			(type default)
		)
		(layer "B.Cu")
	)
	(gr_line
		(start 110.317026 -207.10779)
		(end 110.333282 -207.131158)
		(stroke
			(width 0.068326)
			(type default)
		)
		(layer "B.Cu")
	)
	(gr_line
		(start 110.333282 -207.131158)
		(end 110.338362 -207.159352)
		(stroke
			(width 0.068326)
			(type default)
		)
		(layer "B.Cu")
	)
	(gr_arc
		(start 110.65256 -224.62998)
		(mid 110.672623 -224.730879)
		(end 110.729776 -224.816416)
		(stroke
			(width 0.068326)
			(type default)
		)
		(layer "B.Cu")
	)
	(gr_arc
		(start 110.7821 -220.053408)
		(mid 110.811794 -220.009014)
		(end 110.822232 -219.956634)
		(stroke
			(width 0.068326)
			(type default)
		)
		(layer "B.Cu")
	)
	(gr_line
		(start 110.822232 -219.106496)
		(end 110.822232 -219.28455)
		(stroke
			(width 0.068326)
			(type default)
		)
		(layer "B.Cu")
	)
	(gr_arc
		(start 110.899956 -225.227388)
		(mid 110.855718 -225.004991)
		(end 110.729776 -224.816416)
		(stroke
			(width 0.068326)
			(type default)
		)
		(layer "B.Cu")
	)
	(gr_line
		(start 110.899956 -225.227388)
		(end 110.899956 -225.92538)
		(stroke
			(width 0.068326)
			(type default)
		)
		(layer "B.Cu")
	)
	(gr_line
		(start 111.02467 -220.24213)
		(end 111.089948 -220.176852)
		(stroke
			(width 0.068326)
			(type default)
		)
		(layer "B.Cu")
	)
	(gr_arc
		(start 111.089948 -220.176852)
		(mid 111.117381 -220.135701)
		(end 111.127032 -220.08719)
		(stroke
			(width 0.068326)
			(type default)
		)
		(layer "B.Cu")
	)
	(gr_line
		(start 111.126778 -218.801696)
		(end 111.126778 -218.97975)
		(stroke
			(width 0.068326)
			(type default)
		)
		(layer "B.Cu")
	)
	(gr_line
		(start 116.3066 -206.5274)
		(end 116.381784 -206.452216)
		(stroke
			(width 0.060198)
			(type default)
		)
		(layer "B.Cu")
	)
	(gr_line
		(start 117.095016 -206.452216)
		(end 117.1702 -206.5274)
		(stroke
			(width 0.060198)
			(type default)
		)
		(layer "B.Cu")
	)
	(gr_line
		(start 120.9548 -96.6343)
		(end 121.106184 -96.785684)
		(stroke
			(width 0.060198)
			(type default)
		)
		(layer "B.Cu")
	)
	(gr_line
		(start 120.9548 -95.7453)
		(end 121.106184 -95.593916)
		(stroke
			(width 0.060198)
			(type default)
		)
		(layer "B.Cu")
	)
	(gr_line
		(start 121.038874 -103.023924)
		(end 121.169684 -102.893114)
		(stroke
			(width 0.060198)
			(type default)
		)
		(layer "B.Cu")
	)
	(gr_line
		(start 121.0564 -90.3732)
		(end 121.131584 -90.448384)
		(stroke
			(width 0.060198)
			(type default)
		)
		(layer "B.Cu")
	)
	(gr_line
		(start 121.819416 -96.785684)
		(end 121.9708 -96.6343)
		(stroke
			(width 0.060198)
			(type default)
		)
		(layer "B.Cu")
	)
	(gr_line
		(start 121.819416 -95.593916)
		(end 121.9708 -95.7453)
		(stroke
			(width 0.060198)
			(type default)
		)
		(layer "B.Cu")
	)
	(gr_line
		(start 121.844816 -90.448384)
		(end 121.92 -90.3732)
		(stroke
			(width 0.060198)
			(type default)
		)
		(layer "B.Cu")
	)
	(gr_line
		(start 121.882662 -102.893114)
		(end 122.013472 -103.023924)
		(stroke
			(width 0.060198)
			(type default)
		)
		(layer "B.Cu")
	)
	(gr_line
		(start 123.928124 -210.160362)
		(end 124.079508 -210.311746)
		(stroke
			(width 0.060198)
			(type default)
		)
		(layer "B.Cu")
	)
	(gr_line
		(start 124.79274 -210.311746)
		(end 124.944124 -210.160362)
		(stroke
			(width 0.060198)
			(type default)
		)
		(layer "B.Cu")
	)
	(gr_line
		(start 125.080014 -36.340542)
		(end 125.080268 -36.340542)
		(stroke
			(width 0.060198)
			(type default)
		)
		(layer "B.Cu")
	)
	(gr_line
		(start 125.288802 -35.8394)
		(end 125.581918 -35.8394)
		(stroke
			(width 0.060198)
			(type default)
		)
		(layer "B.Cu")
	)
	(gr_line
		(start 128.661668 -36.342828)
		(end 128.80594 -36.4871)
		(stroke
			(width 0.060198)
			(type default)
		)
		(layer "B.Cu")
	)
	(gr_line
		(start 128.661668 -35.629596)
		(end 129.783332 -34.507932)
		(stroke
			(width 0.060198)
			(type default)
		)
		(layer "B.Cu")
	)
	(gr_line
		(start 128.80594 -36.4871)
		(end 129.717546 -36.4871)
		(stroke
			(width 0.060198)
			(type default)
		)
		(layer "B.Cu")
	)
	(gr_line
		(start 129.717546 -36.4871)
		(end 129.8956 -36.309046)
		(stroke
			(width 0.060198)
			(type default)
		)
		(layer "B.Cu")
	)
	(gr_line
		(start 129.783332 -31.740348)
		(end 129.783332 -34.507932)
		(stroke
			(width 0.060198)
			(type default)
		)
		(layer "B.Cu")
	)
	(gr_line
		(start 129.783332 -31.740348)
		(end 130.50393 -31.01975)
		(stroke
			(width 0.060198)
			(type default)
		)
		(layer "B.Cu")
	)
	(gr_line
		(start 129.8956 -35.586416)
		(end 129.8956 -36.309046)
		(stroke
			(width 0.060198)
			(type default)
		)
		(layer "B.Cu")
	)
	(gr_line
		(start 129.8956 -35.586416)
		(end 131.492244 -33.99028)
		(stroke
			(width 0.060198)
			(type default)
		)
		(layer "B.Cu")
	)
	(gr_line
		(start 130.50393 -29.715206)
		(end 130.50393 -31.01975)
		(stroke
			(width 0.060198)
			(type default)
		)
		(layer "B.Cu")
	)
	(gr_line
		(start 130.50393 -29.715206)
		(end 130.9751 -29.244036)
		(stroke
			(width 0.060198)
			(type default)
		)
		(layer "B.Cu")
	)
	(gr_line
		(start 130.9751 -24.087836)
		(end 130.9751 -29.244036)
		(stroke
			(width 0.060198)
			(type default)
		)
		(layer "B.Cu")
	)
	(gr_line
		(start 130.9751 -24.087836)
		(end 133.134354 -21.928582)
		(stroke
			(width 0.060198)
			(type default)
		)
		(layer "B.Cu")
	)
	(gr_line
		(start 131.492244 -33.99028)
		(end 131.52628 -33.99028)
		(stroke
			(width 0.060198)
			(type default)
		)
		(layer "B.Cu")
	)
	(gr_line
		(start 131.52628 -33.99028)
		(end 132.54228 -33.99028)
		(stroke
			(width 0.060198)
			(type default)
		)
		(layer "B.Cu")
	)
	(gr_line
		(start 132.63245 -12.932664)
		(end 132.638546 -12.935966)
		(stroke
			(width 0.068326)
			(type default)
		)
		(layer "B.Cu")
	)
	(gr_line
		(start 133.134354 -21.530056)
		(end 133.134354 -21.928582)
		(stroke
			(width 0.060198)
			(type default)
		)
		(layer "B.Cu")
	)
	(gr_line
		(start 133.134354 -13.930122)
		(end 133.37286 -13.485368)
		(stroke
			(width 0.068326)
			(type default)
		)
		(layer "B.Cu")
	)
	(gr_arc
		(start 133.37286 -13.485368)
		(mid 133.383189 -13.381364)
		(end 133.31698 -13.300456)
		(stroke
			(width 0.068326)
			(type default)
		)
		(layer "B.Cu")
	)
	(gr_arc
		(start 133.46049 -13.031216)
		(mid 133.564412 -13.041605)
		(end 133.645402 -12.97559)
		(stroke
			(width 0.068326)
			(type default)
		)
		(layer "B.Cu")
	)
	(gr_line
		(start 133.559804 -6.458204)
		(end 133.634734 -6.383274)
		(stroke
			(width 0.068326)
			(type default)
		)
		(layer "B.Cu")
	)
	(gr_line
		(start 133.561328 -6.891274)
		(end 133.777736 -6.891274)
		(stroke
			(width 0.068326)
			(type default)
		)
		(layer "B.Cu")
	)
	(gr_line
		(start 133.645402 -12.97559)
		(end 133.884416 -12.530074)
		(stroke
			(width 0.068326)
			(type default)
		)
		(layer "B.Cu")
	)
	(gr_line
		(start 133.777736 -6.891274)
		(end 134.067804 -6.60146)
		(stroke
			(width 0.068326)
			(type default)
		)
		(layer "B.Cu")
	)
	(gr_line
		(start 134.067804 -6.384798)
		(end 134.067804 -6.60146)
		(stroke
			(width 0.068326)
			(type default)
		)
		(layer "B.Cu")
	)
	(gr_line
		(start 134.359396 -5.658612)
		(end 134.434326 -5.583682)
		(stroke
			(width 0.068326)
			(type default)
		)
		(layer "B.Cu")
	)
	(gr_line
		(start 134.36092 -6.091682)
		(end 134.577328 -6.091682)
		(stroke
			(width 0.068326)
			(type default)
		)
		(layer "B.Cu")
	)
	(gr_line
		(start 134.577328 -6.091682)
		(end 134.867396 -5.801868)
		(stroke
			(width 0.068326)
			(type default)
		)
		(layer "B.Cu")
	)
	(gr_line
		(start 134.867396 -5.585206)
		(end 134.867396 -5.801868)
		(stroke
			(width 0.068326)
			(type default)
		)
		(layer "B.Cu")
	)
	(gr_line
		(start 136.900158 -224.713546)
		(end 136.900158 -225.92538)
		(stroke
			(width 0.068326)
			(type default)
		)
		(layer "B.Cu")
	)
	(gr_line
		(start 137.0076 -96.718374)
		(end 137.307574 -96.4184)
		(stroke
			(width 0.060198)
			(type default)
		)
		(layer "B.Cu")
	)
	(gr_arc
		(start 137.040112 -224.375726)
		(mid 136.936536 -224.530714)
		(end 136.900158 -224.713546)
		(stroke
			(width 0.068326)
			(type default)
		)
		(layer "B.Cu")
	)
	(gr_line
		(start 137.040112 -224.375726)
		(end 137.090912 -224.324926)
		(stroke
			(width 0.068326)
			(type default)
		)
		(layer "B.Cu")
	)
	(gr_arc
		(start 137.090912 -224.324926)
		(mid 137.133038 -224.26188)
		(end 137.147808 -224.187512)
		(stroke
			(width 0.068326)
			(type default)
		)
		(layer "B.Cu")
	)
	(gr_arc
		(start 137.147554 -222.90786)
		(mid 137.081546 -222.576014)
		(end 136.893554 -222.294704)
		(stroke
			(width 0.068326)
			(type default)
		)
		(layer "B.Cu")
	)
	(gr_line
		(start 137.307574 -96.026478)
		(end 137.307574 -96.4184)
		(stroke
			(width 0.060198)
			(type default)
		)
		(layer "B.Cu")
	)
	(gr_arc
		(start 137.452608 -224.17278)
		(mid 137.472674 -224.273676)
		(end 137.529824 -224.359216)
		(stroke
			(width 0.068326)
			(type default)
		)
		(layer "B.Cu")
	)
	(gr_line
		(start 137.575798 -66.86296)
		(end 137.770108 -67.05727)
		(stroke
			(width 0.060198)
			(type default)
		)
		(layer "B.Cu")
	)
	(gr_arc
		(start 137.700004 -224.770188)
		(mid 137.655766 -224.547791)
		(end 137.529824 -224.359216)
		(stroke
			(width 0.068326)
			(type default)
		)
		(layer "B.Cu")
	)
	(gr_line
		(start 137.700004 -224.770188)
		(end 137.700004 -225.92538)
		(stroke
			(width 0.068326)
			(type default)
		)
		(layer "B.Cu")
	)
	(gr_arc
		(start 137.706354 -222.294704)
		(mid 137.518544 -222.575792)
		(end 137.452608 -222.907352)
		(stroke
			(width 0.068326)
			(type default)
		)
		(layer "B.Cu")
	)
	(gr_line
		(start 138.483086 -67.05727)
		(end 138.677396 -66.86296)
		(stroke
			(width 0.060198)
			(type default)
		)
		(layer "B.Cu")
	)
	(gr_line
		(start 140.10005 -224.7138)
		(end 140.10005 -225.92538)
		(stroke
			(width 0.068326)
			(type default)
		)
		(layer "B.Cu")
	)
	(gr_line
		(start 140.10005 -224.7138)
		(end 140.100304 -224.713546)
		(stroke
			(width 0.068326)
			(type default)
		)
		(layer "B.Cu")
	)
	(gr_arc
		(start 140.240258 -224.375726)
		(mid 140.136672 -224.530712)
		(end 140.100304 -224.713546)
		(stroke
			(width 0.068326)
			(type default)
		)
		(layer "B.Cu")
	)
	(gr_line
		(start 140.240258 -224.375726)
		(end 140.291058 -224.324926)
		(stroke
			(width 0.068326)
			(type default)
		)
		(layer "B.Cu")
	)
	(gr_arc
		(start 140.291058 -224.324926)
		(mid 140.333184 -224.26188)
		(end 140.347954 -224.187512)
		(stroke
			(width 0.068326)
			(type default)
		)
		(layer "B.Cu")
	)
	(gr_arc
		(start 140.3477 -222.90786)
		(mid 140.281692 -222.576014)
		(end 140.0937 -222.294704)
		(stroke
			(width 0.068326)
			(type default)
		)
		(layer "B.Cu")
	)
	(gr_arc
		(start 140.652754 -224.17278)
		(mid 140.672817 -224.273679)
		(end 140.72997 -224.359216)
		(stroke
			(width 0.068326)
			(type default)
		)
		(layer "B.Cu")
	)
	(gr_arc
		(start 140.90015 -224.770188)
		(mid 140.855912 -224.547791)
		(end 140.72997 -224.359216)
		(stroke
			(width 0.068326)
			(type default)
		)
		(layer "B.Cu")
	)
	(gr_line
		(start 140.90015 -224.770188)
		(end 140.90015 -225.92538)
		(stroke
			(width 0.068326)
			(type default)
		)
		(layer "B.Cu")
	)
	(gr_arc
		(start 140.9065 -222.294704)
		(mid 140.718701 -222.575795)
		(end 140.652754 -222.907352)
		(stroke
			(width 0.068326)
			(type default)
		)
		(layer "B.Cu")
	)
	(gr_line
		(start 142.113 -26.985468)
		(end 144.22501 -29.097478)
		(stroke
			(width 0.060198)
			(type default)
		)
		(layer "B.Cu")
	)
	(gr_line
		(start 142.113 -24.248872)
		(end 142.113 -26.985468)
		(stroke
			(width 0.060198)
			(type default)
		)
		(layer "B.Cu")
	)
	(gr_line
		(start 142.113 -24.248872)
		(end 143.736822 -22.62505)
		(stroke
			(width 0.060198)
			(type default)
		)
		(layer "B.Cu")
	)
	(gr_line
		(start 143.300196 -224.713546)
		(end 143.300196 -225.92538)
		(stroke
			(width 0.068326)
			(type default)
		)
		(layer "B.Cu")
	)
	(gr_line
		(start 143.432022 -36.318444)
		(end 143.432022 -36.53155)
		(stroke
			(width 0.060198)
			(type default)
		)
		(layer "B.Cu")
	)
	(gr_line
		(start 143.432022 -36.039044)
		(end 143.432022 -36.315904)
		(stroke
			(width 0.060198)
			(type default)
		)
		(layer "B.Cu")
	)
	(gr_line
		(start 143.432022 -36.039044)
		(end 143.55826 -35.912806)
		(stroke
			(width 0.060198)
			(type default)
		)
		(layer "B.Cu")
	)
	(gr_arc
		(start 143.44015 -224.375726)
		(mid 143.336566 -224.530712)
		(end 143.300196 -224.713546)
		(stroke
			(width 0.068326)
			(type default)
		)
		(layer "B.Cu")
	)
	(gr_line
		(start 143.44015 -224.375726)
		(end 143.49095 -224.324926)
		(stroke
			(width 0.068326)
			(type default)
		)
		(layer "B.Cu")
	)
	(gr_arc
		(start 143.49095 -224.324926)
		(mid 143.533076 -224.26188)
		(end 143.547846 -224.187512)
		(stroke
			(width 0.068326)
			(type default)
		)
		(layer "B.Cu")
	)
	(gr_arc
		(start 143.547592 -222.90786)
		(mid 143.481584 -222.576014)
		(end 143.293592 -222.294704)
		(stroke
			(width 0.068326)
			(type default)
		)
		(layer "B.Cu")
	)
	(gr_line
		(start 143.55826 -35.66668)
		(end 143.55826 -35.912806)
		(stroke
			(width 0.060198)
			(type default)
		)
		(layer "B.Cu")
	)
	(gr_line
		(start 143.55826 -35.66668)
		(end 144.22501 -34.99993)
		(stroke
			(width 0.060198)
			(type default)
		)
		(layer "B.Cu")
	)
	(gr_line
		(start 143.736822 -22.62505)
		(end 143.740886 -22.62505)
		(stroke
			(width 0.060198)
			(type default)
		)
		(layer "B.Cu")
	)
	(gr_line
		(start 143.740886 -22.62505)
		(end 144.134332 -22.231604)
		(stroke
			(width 0.060198)
			(type default)
		)
		(layer "B.Cu")
	)
	(gr_arc
		(start 143.852646 -224.17278)
		(mid 143.872709 -224.27368)
		(end 143.929862 -224.359216)
		(stroke
			(width 0.068326)
			(type default)
		)
		(layer "B.Cu")
	)
	(gr_line
		(start 143.853154 -36.820094)
		(end 143.933672 -36.820094)
		(stroke
			(width 0.060198)
			(type default)
		)
		(layer "B.Cu")
	)
	(gr_line
		(start 143.936212 -36.820094)
		(end 144.205706 -36.820094)
		(stroke
			(width 0.060198)
			(type default)
		)
		(layer "B.Cu")
	)
	(gr_arc
		(start 144.100042 -224.770188)
		(mid 144.055804 -224.547791)
		(end 143.929862 -224.359216)
		(stroke
			(width 0.068326)
			(type default)
		)
		(layer "B.Cu")
	)
	(gr_line
		(start 144.100042 -224.770188)
		(end 144.100042 -225.92538)
		(stroke
			(width 0.068326)
			(type default)
		)
		(layer "B.Cu")
	)
	(gr_arc
		(start 144.106392 -222.294704)
		(mid 143.918595 -222.575795)
		(end 143.852646 -222.907352)
		(stroke
			(width 0.068326)
			(type default)
		)
		(layer "B.Cu")
	)
	(gr_line
		(start 144.134332 -21.530056)
		(end 144.134332 -22.231604)
		(stroke
			(width 0.060198)
			(type default)
		)
		(layer "B.Cu")
	)
	(gr_line
		(start 144.205706 -36.820094)
		(end 144.365726 -36.660074)
		(stroke
			(width 0.060198)
			(type default)
		)
		(layer "B.Cu")
	)
	(gr_line
		(start 144.22501 -29.097478)
		(end 144.22501 -34.99993)
		(stroke
			(width 0.060198)
			(type default)
		)
		(layer "B.Cu")
	)
	(gr_line
		(start 144.365726 -36.103814)
		(end 144.365726 -36.660074)
		(stroke
			(width 0.060198)
			(type default)
		)
		(layer "B.Cu")
	)
	(gr_line
		(start 144.365726 -36.103814)
		(end 145.30197 -35.16757)
		(stroke
			(width 0.060198)
			(type default)
		)
		(layer "B.Cu")
	)
	(gr_line
		(start 145.30197 -34.56178)
		(end 145.30197 -35.16757)
		(stroke
			(width 0.060198)
			(type default)
		)
		(layer "B.Cu")
	)
	(gr_line
		(start 145.30197 -34.56178)
		(end 145.88363 -33.98012)
		(stroke
			(width 0.060198)
			(type default)
		)
		(layer "B.Cu")
	)
	(gr_line
		(start 145.88363 -33.98012)
		(end 146.930618 -33.98012)
		(stroke
			(width 0.060198)
			(type default)
		)
		(layer "B.Cu")
	)
	(gr_line
		(start 146.500088 -224.7138)
		(end 146.500088 -225.92538)
		(stroke
			(width 0.068326)
			(type default)
		)
		(layer "B.Cu")
	)
	(gr_line
		(start 146.500088 -224.7138)
		(end 146.500342 -224.713546)
		(stroke
			(width 0.068326)
			(type default)
		)
		(layer "B.Cu")
	)
	(gr_arc
		(start 146.640296 -224.375726)
		(mid 146.536723 -224.530715)
		(end 146.500342 -224.713546)
		(stroke
			(width 0.068326)
			(type default)
		)
		(layer "B.Cu")
	)
	(gr_line
		(start 146.640296 -224.375726)
		(end 146.691096 -224.324926)
		(stroke
			(width 0.068326)
			(type default)
		)
		(layer "B.Cu")
	)
	(gr_arc
		(start 146.691096 -224.324926)
		(mid 146.733222 -224.26188)
		(end 146.747992 -224.187512)
		(stroke
			(width 0.068326)
			(type default)
		)
		(layer "B.Cu")
	)
	(gr_arc
		(start 146.747738 -222.90786)
		(mid 146.68173 -222.576014)
		(end 146.493738 -222.294704)
		(stroke
			(width 0.068326)
			(type default)
		)
		(layer "B.Cu")
	)
	(gr_arc
		(start 147.052792 -224.17278)
		(mid 147.072857 -224.273677)
		(end 147.130008 -224.359216)
		(stroke
			(width 0.068326)
			(type default)
		)
		(layer "B.Cu")
	)
	(gr_arc
		(start 147.300188 -224.770188)
		(mid 147.25595 -224.547791)
		(end 147.130008 -224.359216)
		(stroke
			(width 0.068326)
			(type default)
		)
		(layer "B.Cu")
	)
	(gr_line
		(start 147.300188 -224.770188)
		(end 147.300188 -225.92538)
		(stroke
			(width 0.068326)
			(type default)
		)
		(layer "B.Cu")
	)
	(gr_arc
		(start 147.306538 -222.294704)
		(mid 147.118731 -222.575793)
		(end 147.052792 -222.907352)
		(stroke
			(width 0.068326)
			(type default)
		)
		(layer "B.Cu")
	)
	(gr_line
		(start 149.700234 -224.713546)
		(end 149.700234 -225.92538)
		(stroke
			(width 0.068326)
			(type default)
		)
		(layer "B.Cu")
	)
	(gr_arc
		(start 149.840188 -224.375726)
		(mid 149.736596 -224.53071)
		(end 149.700234 -224.713546)
		(stroke
			(width 0.068326)
			(type default)
		)
		(layer "B.Cu")
	)
	(gr_line
		(start 149.840188 -224.375726)
		(end 149.890988 -224.324926)
		(stroke
			(width 0.068326)
			(type default)
		)
		(layer "B.Cu")
	)
	(gr_arc
		(start 149.890988 -224.324926)
		(mid 149.933114 -224.26188)
		(end 149.947884 -224.187512)
		(stroke
			(width 0.068326)
			(type default)
		)
		(layer "B.Cu")
	)
	(gr_arc
		(start 149.94763 -222.90786)
		(mid 149.881622 -222.576014)
		(end 149.69363 -222.294704)
		(stroke
			(width 0.068326)
			(type default)
		)
		(layer "B.Cu")
	)
	(gr_arc
		(start 150.252684 -224.17278)
		(mid 150.272749 -224.273677)
		(end 150.3299 -224.359216)
		(stroke
			(width 0.068326)
			(type default)
		)
		(layer "B.Cu")
	)
	(gr_arc
		(start 150.50008 -224.770188)
		(mid 150.455842 -224.547791)
		(end 150.3299 -224.359216)
		(stroke
			(width 0.068326)
			(type default)
		)
		(layer "B.Cu")
	)
	(gr_line
		(start 150.50008 -224.770188)
		(end 150.50008 -225.92538)
		(stroke
			(width 0.068326)
			(type default)
		)
		(layer "B.Cu")
	)
	(gr_arc
		(start 150.50643 -222.294704)
		(mid 150.318625 -222.575793)
		(end 150.252684 -222.907352)
		(stroke
			(width 0.068326)
			(type default)
		)
		(layer "B.Cu")
	)
	(gr_line
		(start 152.900126 -224.7138)
		(end 152.900126 -225.92538)
		(stroke
			(width 0.068326)
			(type default)
		)
		(layer "B.Cu")
	)
	(gr_line
		(start 152.900126 -224.7138)
		(end 152.90038 -224.713546)
		(stroke
			(width 0.068326)
			(type default)
		)
		(layer "B.Cu")
	)
	(gr_arc
		(start 153.040334 -224.375726)
		(mid 152.936753 -224.530713)
		(end 152.90038 -224.713546)
		(stroke
			(width 0.068326)
			(type default)
		)
		(layer "B.Cu")
	)
	(gr_line
		(start 153.040334 -224.375726)
		(end 153.091134 -224.324926)
		(stroke
			(width 0.068326)
			(type default)
		)
		(layer "B.Cu")
	)
	(gr_arc
		(start 153.091134 -224.324926)
		(mid 153.13326 -224.26188)
		(end 153.14803 -224.187512)
		(stroke
			(width 0.068326)
			(type default)
		)
		(layer "B.Cu")
	)
	(gr_arc
		(start 153.147776 -222.90786)
		(mid 153.081768 -222.576014)
		(end 152.893776 -222.294704)
		(stroke
			(width 0.068326)
			(type default)
		)
		(layer "B.Cu")
	)
	(gr_arc
		(start 153.45283 -224.17278)
		(mid 153.472898 -224.273675)
		(end 153.530046 -224.359216)
		(stroke
			(width 0.068326)
			(type default)
		)
		(layer "B.Cu")
	)
	(gr_line
		(start 153.4922 -27.72156)
		(end 154.776932 -29.006292)
		(stroke
			(width 0.060198)
			(type default)
		)
		(layer "B.Cu")
	)
	(gr_line
		(start 153.4922 -24.003)
		(end 153.4922 -27.72156)
		(stroke
			(width 0.060198)
			(type default)
		)
		(layer "B.Cu")
	)
	(gr_line
		(start 153.4922 -24.003)
		(end 155.134564 -22.360636)
		(stroke
			(width 0.060198)
			(type default)
		)
		(layer "B.Cu")
	)
	(gr_arc
		(start 153.700226 -224.770188)
		(mid 153.655988 -224.547791)
		(end 153.530046 -224.359216)
		(stroke
			(width 0.068326)
			(type default)
		)
		(layer "B.Cu")
	)
	(gr_line
		(start 153.700226 -224.770188)
		(end 153.700226 -225.92538)
		(stroke
			(width 0.068326)
			(type default)
		)
		(layer "B.Cu")
	)
	(gr_arc
		(start 153.706576 -222.294704)
		(mid 153.518782 -222.575796)
		(end 153.45283 -222.907352)
		(stroke
			(width 0.068326)
			(type default)
		)
		(layer "B.Cu")
	)
	(gr_line
		(start 154.259534 -11.426444)
		(end 154.259534 -11.532616)
		(stroke
			(width 0.068326)
			(type default)
		)
		(layer "B.Cu")
	)
	(gr_line
		(start 154.259534 -10.295636)
		(end 154.259534 -10.401808)
		(stroke
			(width 0.068326)
			(type default)
		)
		(layer "B.Cu")
	)
	(gr_line
		(start 154.384248 -37.876734)
		(end 154.65806 -38.150546)
		(stroke
			(width 0.060198)
			(type default)
		)
		(layer "B.Cu")
	)
	(gr_line
		(start 154.384248 -37.876734)
		(end 154.667458 -37.593524)
		(stroke
			(width 0.060198)
			(type default)
		)
		(layer "B.Cu")
	)
	(gr_line
		(start 154.566874 -11.837416)
		(end 154.719782 -11.684508)
		(stroke
			(width 0.068326)
			(type default)
		)
		(layer "B.Cu")
	)
	(gr_line
		(start 154.566874 -11.121644)
		(end 154.719782 -11.274552)
		(stroke
			(width 0.068326)
			(type default)
		)
		(layer "B.Cu")
	)
	(gr_line
		(start 154.566874 -10.706608)
		(end 154.719782 -10.5537)
		(stroke
			(width 0.068326)
			(type default)
		)
		(layer "B.Cu")
	)
	(gr_line
		(start 154.566874 -9.990836)
		(end 154.719782 -10.143744)
		(stroke
			(width 0.068326)
			(type default)
		)
		(layer "B.Cu")
	)
	(gr_line
		(start 154.694128 -12.966954)
		(end 154.69997 -12.970002)
		(stroke
			(width 0.068326)
			(type default)
		)
		(layer "B.Cu")
	)
	(gr_line
		(start 154.716988 -36.494212)
		(end 154.958542 -36.252658)
		(stroke
			(width 0.060198)
			(type default)
		)
		(layer "B.Cu")
	)
	(gr_line
		(start 154.719782 -11.274552)
		(end 154.719782 -11.684508)
		(stroke
			(width 0.068326)
			(type default)
		)
		(layer "B.Cu")
	)
	(gr_line
		(start 154.719782 -10.143744)
		(end 154.719782 -10.5537)
		(stroke
			(width 0.068326)
			(type default)
		)
		(layer "B.Cu")
	)
	(gr_line
		(start 154.776932 -32.130238)
		(end 154.958542 -32.311848)
		(stroke
			(width 0.060198)
			(type default)
		)
		(layer "B.Cu")
	)
	(gr_line
		(start 154.776932 -29.006292)
		(end 154.776932 -32.130238)
		(stroke
			(width 0.060198)
			(type default)
		)
		(layer "B.Cu")
	)
	(gr_line
		(start 154.958542 -32.311848)
		(end 154.958542 -36.252658)
		(stroke
			(width 0.060198)
			(type default)
		)
		(layer "B.Cu")
	)
	(gr_line
		(start 155.134564 -21.530056)
		(end 155.134564 -22.360636)
		(stroke
			(width 0.060198)
			(type default)
		)
		(layer "B.Cu")
	)
	(gr_line
		(start 155.134564 -13.930122)
		(end 155.372816 -13.485114)
		(stroke
			(width 0.068326)
			(type default)
		)
		(layer "B.Cu")
	)
	(gr_line
		(start 155.221178 -36.773358)
		(end 156.605986 -35.38855)
		(stroke
			(width 0.060198)
			(type default)
		)
		(layer "B.Cu")
	)
	(gr_line
		(start 155.371038 -38.150546)
		(end 155.654248 -37.867336)
		(stroke
			(width 0.060198)
			(type default)
		)
		(layer "B.Cu")
	)
	(gr_arc
		(start 155.372816 -13.485114)
		(mid 155.383204 -13.380883)
		(end 155.316682 -13.299948)
		(stroke
			(width 0.068326)
			(type default)
		)
		(layer "B.Cu")
	)
	(gr_line
		(start 155.380436 -37.593524)
		(end 155.654248 -37.867336)
		(stroke
			(width 0.060198)
			(type default)
		)
		(layer "B.Cu")
	)
	(gr_arc
		(start 155.461208 -13.031216)
		(mid 155.565237 -13.041573)
		(end 155.64612 -12.975336)
		(stroke
			(width 0.068326)
			(type default)
		)
		(layer "B.Cu")
	)
	(gr_line
		(start 155.64612 -12.975336)
		(end 155.884372 -12.530074)
		(stroke
			(width 0.068326)
			(type default)
		)
		(layer "B.Cu")
	)
	(gr_line
		(start 156.100018 -224.7138)
		(end 156.100018 -225.92538)
		(stroke
			(width 0.068326)
			(type default)
		)
		(layer "B.Cu")
	)
	(gr_line
		(start 156.100018 -224.7138)
		(end 156.100272 -224.713546)
		(stroke
			(width 0.068326)
			(type default)
		)
		(layer "B.Cu")
	)
	(gr_arc
		(start 156.240226 -224.375726)
		(mid 156.136647 -224.530714)
		(end 156.100272 -224.713546)
		(stroke
			(width 0.068326)
			(type default)
		)
		(layer "B.Cu")
	)
	(gr_line
		(start 156.240226 -224.375726)
		(end 156.291026 -224.324926)
		(stroke
			(width 0.068326)
			(type default)
		)
		(layer "B.Cu")
	)
	(gr_arc
		(start 156.291026 -224.324926)
		(mid 156.333152 -224.26188)
		(end 156.347922 -224.187512)
		(stroke
			(width 0.068326)
			(type default)
		)
		(layer "B.Cu")
	)
	(gr_arc
		(start 156.347668 -222.90786)
		(mid 156.28166 -222.576014)
		(end 156.093668 -222.294704)
		(stroke
			(width 0.068326)
			(type default)
		)
		(layer "B.Cu")
	)
	(gr_line
		(start 156.470604 -34.476436)
		(end 156.605986 -34.611818)
		(stroke
			(width 0.060198)
			(type default)
		)
		(layer "B.Cu")
	)
	(gr_line
		(start 156.470604 -34.036508)
		(end 156.470604 -34.476436)
		(stroke
			(width 0.060198)
			(type default)
		)
		(layer "B.Cu")
	)
	(gr_line
		(start 156.470604 -34.036508)
		(end 157.49016 -34.036508)
		(stroke
			(width 0.060198)
			(type default)
		)
		(layer "B.Cu")
	)
	(gr_line
		(start 156.605986 -34.611818)
		(end 156.605986 -35.38855)
		(stroke
			(width 0.060198)
			(type default)
		)
		(layer "B.Cu")
	)
	(gr_arc
		(start 156.652722 -224.17278)
		(mid 156.672789 -224.273675)
		(end 156.729938 -224.359216)
		(stroke
			(width 0.068326)
			(type default)
		)
		(layer "B.Cu")
	)
	(gr_arc
		(start 156.693108 -222.508064)
		(mid 156.663219 -222.552817)
		(end 156.652722 -222.6056)
		(stroke
			(width 0.068326)
			(type default)
		)
		(layer "B.Cu")
	)
	(gr_line
		(start 156.693108 -222.508064)
		(end 156.906468 -222.294704)
		(stroke
			(width 0.068326)
			(type default)
		)
		(layer "B.Cu")
	)
	(gr_arc
		(start 156.900118 -224.770188)
		(mid 156.85588 -224.547791)
		(end 156.729938 -224.359216)
		(stroke
			(width 0.068326)
			(type default)
		)
		(layer "B.Cu")
	)
	(gr_line
		(start 156.900118 -224.770188)
		(end 156.900118 -225.92538)
		(stroke
			(width 0.068326)
			(type default)
		)
		(layer "B.Cu")
	)
	(gr_line
		(start 157.49016 -34.036508)
		(end 157.492192 -34.034476)
		(stroke
			(width 0.060198)
			(type default)
		)
		(layer "B.Cu")
	)
	(gr_line
		(start 159.300164 -224.713546)
		(end 159.300164 -225.92538)
		(stroke
			(width 0.068326)
			(type default)
		)
		(layer "B.Cu")
	)
	(gr_arc
		(start 159.440118 -224.375726)
		(mid 159.336541 -224.530714)
		(end 159.300164 -224.713546)
		(stroke
			(width 0.068326)
			(type default)
		)
		(layer "B.Cu")
	)
	(gr_line
		(start 159.440118 -224.375726)
		(end 159.490918 -224.324926)
		(stroke
			(width 0.068326)
			(type default)
		)
		(layer "B.Cu")
	)
	(gr_arc
		(start 159.490918 -224.324926)
		(mid 159.533044 -224.26188)
		(end 159.547814 -224.187512)
		(stroke
			(width 0.068326)
			(type default)
		)
		(layer "B.Cu")
	)
	(gr_arc
		(start 159.54756 -222.90786)
		(mid 159.481552 -222.576014)
		(end 159.29356 -222.294704)
		(stroke
			(width 0.068326)
			(type default)
		)
		(layer "B.Cu")
	)
	(gr_arc
		(start 159.852614 -224.17278)
		(mid 159.872681 -224.273676)
		(end 159.92983 -224.359216)
		(stroke
			(width 0.068326)
			(type default)
		)
		(layer "B.Cu")
	)
	(gr_arc
		(start 160.10001 -224.770188)
		(mid 160.055772 -224.547791)
		(end 159.92983 -224.359216)
		(stroke
			(width 0.068326)
			(type default)
		)
		(layer "B.Cu")
	)
	(gr_line
		(start 160.10001 -224.770188)
		(end 160.10001 -225.92538)
		(stroke
			(width 0.068326)
			(type default)
		)
		(layer "B.Cu")
	)
	(gr_arc
		(start 160.10636 -222.294704)
		(mid 159.918549 -222.575792)
		(end 159.852614 -222.907352)
		(stroke
			(width 0.068326)
			(type default)
		)
		(layer "B.Cu")
	)
	(gr_line
		(start 162.80765 -33.42767)
		(end 163.48329 -34.10331)
		(stroke
			(width 0.060198)
			(type default)
		)
		(layer "B.Cu")
	)
	(gr_line
		(start 162.80765 -32.512)
		(end 162.80765 -33.42767)
		(stroke
			(width 0.060198)
			(type default)
		)
		(layer "B.Cu")
	)
	(gr_line
		(start 162.80765 -32.512)
		(end 163.453572 -31.866078)
		(stroke
			(width 0.060198)
			(type default)
		)
		(layer "B.Cu")
	)
	(gr_line
		(start 163.453572 -31.866078)
		(end 164.659818 -30.659832)
		(stroke
			(width 0.060198)
			(type default)
		)
		(layer "B.Cu")
	)
	(gr_line
		(start 163.48329 -36.176966)
		(end 163.626546 -36.320222)
		(stroke
			(width 0.060198)
			(type default)
		)
		(layer "B.Cu")
	)
	(gr_line
		(start 163.48329 -34.10331)
		(end 163.48329 -36.176966)
		(stroke
			(width 0.060198)
			(type default)
		)
		(layer "B.Cu")
	)
	(gr_line
		(start 164.659818 -23.00478)
		(end 164.659818 -30.659832)
		(stroke
			(width 0.060198)
			(type default)
		)
		(layer "B.Cu")
	)
	(gr_line
		(start 164.659818 -23.00478)
		(end 166.134542 -21.530056)
		(stroke
			(width 0.060198)
			(type default)
		)
		(layer "B.Cu")
	)
	(gr_line
		(start 164.900102 -224.7138)
		(end 164.900102 -225.92538)
		(stroke
			(width 0.068326)
			(type default)
		)
		(layer "B.Cu")
	)
	(gr_line
		(start 164.900102 -224.7138)
		(end 164.900356 -224.713546)
		(stroke
			(width 0.068326)
			(type default)
		)
		(layer "B.Cu")
	)
	(gr_arc
		(start 165.04031 -224.375726)
		(mid 164.936734 -224.530715)
		(end 164.900356 -224.713546)
		(stroke
			(width 0.068326)
			(type default)
		)
		(layer "B.Cu")
	)
	(gr_line
		(start 165.04031 -224.375726)
		(end 165.09111 -224.324926)
		(stroke
			(width 0.068326)
			(type default)
		)
		(layer "B.Cu")
	)
	(gr_arc
		(start 165.09111 -224.324926)
		(mid 165.133236 -224.26188)
		(end 165.148006 -224.187512)
		(stroke
			(width 0.068326)
			(type default)
		)
		(layer "B.Cu")
	)
	(gr_arc
		(start 165.147752 -222.90786)
		(mid 165.081744 -222.576014)
		(end 164.893752 -222.294704)
		(stroke
			(width 0.068326)
			(type default)
		)
		(layer "B.Cu")
	)
	(gr_arc
		(start 165.452806 -224.17278)
		(mid 165.472872 -224.273676)
		(end 165.530022 -224.359216)
		(stroke
			(width 0.068326)
			(type default)
		)
		(layer "B.Cu")
	)
	(gr_arc
		(start 165.700202 -224.770188)
		(mid 165.655964 -224.547791)
		(end 165.530022 -224.359216)
		(stroke
			(width 0.068326)
			(type default)
		)
		(layer "B.Cu")
	)
	(gr_line
		(start 165.700202 -224.770188)
		(end 165.700202 -225.92538)
		(stroke
			(width 0.068326)
			(type default)
		)
		(layer "B.Cu")
	)
	(gr_arc
		(start 165.706552 -222.294704)
		(mid 165.518742 -222.575792)
		(end 165.452806 -222.907352)
		(stroke
			(width 0.068326)
			(type default)
		)
		(layer "B.Cu")
	)
	(gr_line
		(start 166.243 -35.8902)
		(end 166.243 -36.322)
		(stroke
			(width 0.060198)
			(type default)
		)
		(layer "B.Cu")
	)
	(gr_line
		(start 166.243 -35.8902)
		(end 166.751 -35.3822)
		(stroke
			(width 0.060198)
			(type default)
		)
		(layer "B.Cu")
	)
	(gr_line
		(start 166.751 -35.3822)
		(end 167.513 -34.6202)
		(stroke
			(width 0.060198)
			(type default)
		)
		(layer "B.Cu")
	)
	(gr_line
		(start 167.513 -33.9725)
		(end 167.513 -34.6202)
		(stroke
			(width 0.060198)
			(type default)
		)
		(layer "B.Cu")
	)
	(gr_line
		(start 168.099994 -224.7138)
		(end 168.099994 -225.92538)
		(stroke
			(width 0.068326)
			(type default)
		)
		(layer "B.Cu")
	)
	(gr_line
		(start 168.099994 -224.7138)
		(end 168.100248 -224.713546)
		(stroke
			(width 0.068326)
			(type default)
		)
		(layer "B.Cu")
	)
	(gr_arc
		(start 168.240202 -224.375726)
		(mid 168.136628 -224.530715)
		(end 168.100248 -224.713546)
		(stroke
			(width 0.068326)
			(type default)
		)
		(layer "B.Cu")
	)
	(gr_line
		(start 168.240202 -224.375726)
		(end 168.291002 -224.324926)
		(stroke
			(width 0.068326)
			(type default)
		)
		(layer "B.Cu")
	)
	(gr_arc
		(start 168.291002 -224.324926)
		(mid 168.333128 -224.26188)
		(end 168.347898 -224.187512)
		(stroke
			(width 0.068326)
			(type default)
		)
		(layer "B.Cu")
	)
	(gr_arc
		(start 168.347644 -222.90786)
		(mid 168.281636 -222.576014)
		(end 168.093644 -222.294704)
		(stroke
			(width 0.068326)
			(type default)
		)
		(layer "B.Cu")
	)
	(gr_arc
		(start 168.652698 -224.17278)
		(mid 168.672764 -224.273677)
		(end 168.729914 -224.359216)
		(stroke
			(width 0.068326)
			(type default)
		)
		(layer "B.Cu")
	)
	(gr_arc
		(start 168.900094 -224.770188)
		(mid 168.855856 -224.547791)
		(end 168.729914 -224.359216)
		(stroke
			(width 0.068326)
			(type default)
		)
		(layer "B.Cu")
	)
	(gr_line
		(start 168.900094 -224.770188)
		(end 168.900094 -225.92538)
		(stroke
			(width 0.068326)
			(type default)
		)
		(layer "B.Cu")
	)
	(gr_arc
		(start 168.906444 -222.294704)
		(mid 168.718636 -222.575793)
		(end 168.652698 -222.907352)
		(stroke
			(width 0.068326)
			(type default)
		)
		(layer "B.Cu")
	)
	(gr_line
		(start 171.30014 -224.7138)
		(end 171.30014 -225.92538)
		(stroke
			(width 0.068326)
			(type default)
		)
		(layer "B.Cu")
	)
	(gr_line
		(start 171.30014 -224.7138)
		(end 171.300394 -224.713546)
		(stroke
			(width 0.068326)
			(type default)
		)
		(layer "B.Cu")
	)
	(gr_arc
		(start 171.440348 -224.375726)
		(mid 171.336764 -224.530712)
		(end 171.300394 -224.713546)
		(stroke
			(width 0.068326)
			(type default)
		)
		(layer "B.Cu")
	)
	(gr_line
		(start 171.440348 -224.375726)
		(end 171.491148 -224.324926)
		(stroke
			(width 0.068326)
			(type default)
		)
		(layer "B.Cu")
	)
	(gr_arc
		(start 171.491148 -224.324926)
		(mid 171.533274 -224.26188)
		(end 171.548044 -224.187512)
		(stroke
			(width 0.068326)
			(type default)
		)
		(layer "B.Cu")
	)
	(gr_arc
		(start 171.54779 -222.90786)
		(mid 171.481782 -222.576014)
		(end 171.29379 -222.294704)
		(stroke
			(width 0.068326)
			(type default)
		)
		(layer "B.Cu")
	)
	(gr_arc
		(start 171.852844 -224.17278)
		(mid 171.872907 -224.27368)
		(end 171.93006 -224.359216)
		(stroke
			(width 0.068326)
			(type default)
		)
		(layer "B.Cu")
	)
	(gr_line
		(start 171.94276 -4.928362)
		(end 172.095668 -5.08127)
		(stroke
			(width 0.068326)
			(type default)
		)
		(layer "B.Cu")
	)
	(gr_line
		(start 172.095668 -5.08127)
		(end 172.505624 -5.08127)
		(stroke
			(width 0.068326)
			(type default)
		)
		(layer "B.Cu")
	)
	(gr_arc
		(start 172.10024 -224.770188)
		(mid 172.056002 -224.547791)
		(end 171.93006 -224.359216)
		(stroke
			(width 0.068326)
			(type default)
		)
		(layer "B.Cu")
	)
	(gr_line
		(start 172.10024 -224.770188)
		(end 172.10024 -225.92538)
		(stroke
			(width 0.068326)
			(type default)
		)
		(layer "B.Cu")
	)
	(gr_arc
		(start 172.10659 -222.294704)
		(mid 171.918793 -222.575796)
		(end 171.852844 -222.907352)
		(stroke
			(width 0.068326)
			(type default)
		)
		(layer "B.Cu")
	)
	(gr_line
		(start 172.24756 -4.621022)
		(end 172.353732 -4.621022)
		(stroke
			(width 0.068326)
			(type default)
		)
		(layer "B.Cu")
	)
	(gr_line
		(start 172.505624 -5.08127)
		(end 172.658532 -4.928362)
		(stroke
			(width 0.068326)
			(type default)
		)
		(layer "B.Cu")
	)
	(gr_line
		(start 173.073568 -4.928362)
		(end 173.226476 -5.08127)
		(stroke
			(width 0.068326)
			(type default)
		)
		(layer "B.Cu")
	)
	(gr_line
		(start 173.226476 -5.08127)
		(end 173.636432 -5.08127)
		(stroke
			(width 0.068326)
			(type default)
		)
		(layer "B.Cu")
	)
	(gr_line
		(start 173.378368 -4.621022)
		(end 173.48454 -4.621022)
		(stroke
			(width 0.068326)
			(type default)
		)
		(layer "B.Cu")
	)
	(gr_line
		(start 173.636432 -5.08127)
		(end 173.78934 -4.928362)
		(stroke
			(width 0.068326)
			(type default)
		)
		(layer "B.Cu")
	)
	(gr_line
		(start 174.204376 -4.928362)
		(end 174.357284 -5.08127)
		(stroke
			(width 0.068326)
			(type default)
		)
		(layer "B.Cu")
	)
	(gr_line
		(start 174.357284 -5.08127)
		(end 174.76724 -5.08127)
		(stroke
			(width 0.068326)
			(type default)
		)
		(layer "B.Cu")
	)
	(gr_line
		(start 174.500032 -224.7138)
		(end 174.500032 -225.92538)
		(stroke
			(width 0.068326)
			(type default)
		)
		(layer "B.Cu")
	)
	(gr_line
		(start 174.500032 -224.7138)
		(end 174.500286 -224.713546)
		(stroke
			(width 0.068326)
			(type default)
		)
		(layer "B.Cu")
	)
	(gr_line
		(start 174.509176 -4.621022)
		(end 174.615348 -4.621022)
		(stroke
			(width 0.068326)
			(type default)
		)
		(layer "B.Cu")
	)
	(gr_arc
		(start 174.64024 -224.375726)
		(mid 174.536658 -224.530713)
		(end 174.500286 -224.713546)
		(stroke
			(width 0.068326)
			(type default)
		)
		(layer "B.Cu")
	)
	(gr_line
		(start 174.64024 -224.375726)
		(end 174.69104 -224.324926)
		(stroke
			(width 0.068326)
			(type default)
		)
		(layer "B.Cu")
	)
	(gr_arc
		(start 174.69104 -224.324926)
		(mid 174.733166 -224.26188)
		(end 174.747936 -224.187512)
		(stroke
			(width 0.068326)
			(type default)
		)
		(layer "B.Cu")
	)
	(gr_arc
		(start 174.747682 -222.90786)
		(mid 174.681674 -222.576014)
		(end 174.493682 -222.294704)
		(stroke
			(width 0.068326)
			(type default)
		)
		(layer "B.Cu")
	)
	(gr_line
		(start 174.76724 -5.08127)
		(end 174.920148 -4.928362)
		(stroke
			(width 0.068326)
			(type default)
		)
		(layer "B.Cu")
	)
	(gr_arc
		(start 175.052736 -224.17278)
		(mid 175.072804 -224.273675)
		(end 175.129952 -224.359216)
		(stroke
			(width 0.068326)
			(type default)
		)
		(layer "B.Cu")
	)
	(gr_arc
		(start 175.300132 -224.770188)
		(mid 175.255894 -224.547791)
		(end 175.129952 -224.359216)
		(stroke
			(width 0.068326)
			(type default)
		)
		(layer "B.Cu")
	)
	(gr_line
		(start 175.300132 -224.770188)
		(end 175.300132 -225.92538)
		(stroke
			(width 0.068326)
			(type default)
		)
		(layer "B.Cu")
	)
	(gr_arc
		(start 175.306482 -222.294704)
		(mid 175.118687 -222.575796)
		(end 175.052736 -222.907352)
		(stroke
			(width 0.068326)
			(type default)
		)
		(layer "B.Cu")
	)
	(gr_line
		(start 175.335184 -4.928362)
		(end 175.488092 -5.08127)
		(stroke
			(width 0.068326)
			(type default)
		)
		(layer "B.Cu")
	)
	(gr_line
		(start 175.488092 -5.08127)
		(end 175.898048 -5.08127)
		(stroke
			(width 0.068326)
			(type default)
		)
		(layer "B.Cu")
	)
	(gr_line
		(start 175.639984 -4.621022)
		(end 175.746156 -4.621022)
		(stroke
			(width 0.068326)
			(type default)
		)
		(layer "B.Cu")
	)
	(gr_line
		(start 175.898048 -5.08127)
		(end 176.050956 -4.928362)
		(stroke
			(width 0.068326)
			(type default)
		)
		(layer "B.Cu")
	)
	(gr_line
		(start 176.805336 -9.906508)
		(end 177.09515 -10.196576)
		(stroke
			(width 0.068326)
			(type default)
		)
		(layer "B.Cu")
	)
	(gr_line
		(start 176.805336 -9.6901)
		(end 176.805336 -9.906508)
		(stroke
			(width 0.068326)
			(type default)
		)
		(layer "B.Cu")
	)
	(gr_line
		(start 177.09515 -10.196576)
		(end 177.311812 -10.196576)
		(stroke
			(width 0.068326)
			(type default)
		)
		(layer "B.Cu")
	)
	(gr_line
		(start 177.238406 -9.688576)
		(end 177.313336 -9.763506)
		(stroke
			(width 0.068326)
			(type default)
		)
		(layer "B.Cu")
	)
	(gr_line
		(start 177.5968 -220.6752)
		(end 177.768504 -220.846904)
		(stroke
			(width 0.068326)
			(type default)
		)
		(layer "B.Cu")
	)
	(gr_line
		(start 177.604928 -10.7061)
		(end 177.894742 -10.996168)
		(stroke
			(width 0.068326)
			(type default)
		)
		(layer "B.Cu")
	)
	(gr_line
		(start 177.604928 -10.489692)
		(end 177.604928 -10.7061)
		(stroke
			(width 0.068326)
			(type default)
		)
		(layer "B.Cu")
	)
	(gr_line
		(start 177.700178 -224.713546)
		(end 177.700178 -225.92538)
		(stroke
			(width 0.068326)
			(type default)
		)
		(layer "B.Cu")
	)
	(gr_arc
		(start 177.840132 -224.375726)
		(mid 177.736552 -224.530713)
		(end 177.700178 -224.713546)
		(stroke
			(width 0.068326)
			(type default)
		)
		(layer "B.Cu")
	)
	(gr_line
		(start 177.840132 -224.375726)
		(end 177.890932 -224.324926)
		(stroke
			(width 0.068326)
			(type default)
		)
		(layer "B.Cu")
	)
	(gr_arc
		(start 177.890932 -224.324926)
		(mid 177.933058 -224.26188)
		(end 177.947828 -224.187512)
		(stroke
			(width 0.068326)
			(type default)
		)
		(layer "B.Cu")
	)
	(gr_line
		(start 177.894742 -10.996168)
		(end 178.111404 -10.996168)
		(stroke
			(width 0.068326)
			(type default)
		)
		(layer "B.Cu")
	)
	(gr_arc
		(start 177.947574 -221.279212)
		(mid 177.901036 -221.045248)
		(end 177.768504 -220.846904)
		(stroke
			(width 0.068326)
			(type default)
		)
		(layer "B.Cu")
	)
	(gr_line
		(start 178.037998 -10.488168)
		(end 178.112928 -10.563098)
		(stroke
			(width 0.068326)
			(type default)
		)
		(layer "B.Cu")
	)
	(gr_arc
		(start 178.252628 -224.17278)
		(mid 178.272696 -224.273675)
		(end 178.329844 -224.359216)
		(stroke
			(width 0.068326)
			(type default)
		)
		(layer "B.Cu")
	)
	(gr_line
		(start 178.40452 -11.505692)
		(end 178.694334 -11.79576)
		(stroke
			(width 0.068326)
			(type default)
		)
		(layer "B.Cu")
	)
	(gr_line
		(start 178.40452 -11.289284)
		(end 178.40452 -11.505692)
		(stroke
			(width 0.068326)
			(type default)
		)
		(layer "B.Cu")
	)
	(gr_arc
		(start 178.4096 -220.6752)
		(mid 178.293419 -220.849072)
		(end 178.252628 -221.054168)
		(stroke
			(width 0.068326)
			(type default)
		)
		(layer "B.Cu")
	)
	(gr_arc
		(start 178.500024 -224.770188)
		(mid 178.455786 -224.547791)
		(end 178.329844 -224.359216)
		(stroke
			(width 0.068326)
			(type default)
		)
		(layer "B.Cu")
	)
	(gr_line
		(start 178.500024 -224.770188)
		(end 178.500024 -225.92538)
		(stroke
			(width 0.068326)
			(type default)
		)
		(layer "B.Cu")
	)
	(gr_line
		(start 178.694334 -11.79576)
		(end 178.910996 -11.79576)
		(stroke
			(width 0.068326)
			(type default)
		)
		(layer "B.Cu")
	)
	(gr_line
		(start 178.83759 -11.28776)
		(end 178.91252 -11.36269)
		(stroke
			(width 0.068326)
			(type default)
		)
		(layer "B.Cu")
	)
	(gr_line
		(start 179.204112 -12.305284)
		(end 179.493926 -12.595352)
		(stroke
			(width 0.068326)
			(type default)
		)
		(layer "B.Cu")
	)
	(gr_line
		(start 179.204112 -12.088876)
		(end 179.204112 -12.305284)
		(stroke
			(width 0.068326)
			(type default)
		)
		(layer "B.Cu")
	)
	(gr_line
		(start 179.493926 -12.595352)
		(end 179.710588 -12.595352)
		(stroke
			(width 0.068326)
			(type default)
		)
		(layer "B.Cu")
	)
	(gr_line
		(start 179.637182 -12.087352)
		(end 179.712112 -12.162282)
		(stroke
			(width 0.068326)
			(type default)
		)
		(layer "B.Cu")
	)
	(gr_arc
		(start 180.8861 -6.824472)
		(mid 181.330101 -6.736125)
		(end 181.70652 -6.48462)
		(stroke
			(width 0.068326)
			(type default)
		)
		(layer "B.Cu")
	)
	(gr_line
		(start 181.327044 -13.209524)
		(end 181.63032 -13.5128)
		(stroke
			(width 0.068326)
			(type default)
		)
		(layer "B.Cu")
	)
	(gr_line
		(start 181.327044 -12.774676)
		(end 181.63032 -12.4714)
		(stroke
			(width 0.068326)
			(type default)
		)
		(layer "B.Cu")
	)
	(gr_arc
		(start 181.472332 -7.324598)
		(mid 181.255793 -7.180004)
		(end 181.0004 -7.129272)
		(stroke
			(width 0.068326)
			(type default)
		)
		(layer "B.Cu")
	)
	(gr_line
		(start 181.472332 -7.324598)
		(end 181.69128 -7.5438)
		(stroke
			(width 0.068326)
			(type default)
		)
		(layer "B.Cu")
	)
	(gr_line
		(start 182.51932 -13.5128)
		(end 182.889652 -13.142722)
		(stroke
			(width 0.068326)
			(type default)
		)
		(layer "B.Cu")
	)
	(gr_line
		(start 182.51932 -12.4714)
		(end 182.740046 -12.691872)
		(stroke
			(width 0.068326)
			(type default)
		)
		(layer "B.Cu")
	)
	(gr_arc
		(start 182.58536 -6.47446)
		(mid 182.846524 -6.769805)
		(end 183.225186 -6.87959)
		(stroke
			(width 0.068326)
			(type default)
		)
		(layer "B.Cu")
	)
	(gr_arc
		(start 182.740046 -12.691872)
		(mid 182.818935 -12.744639)
		(end 182.912004 -12.763246)
		(stroke
			(width 0.068326)
			(type default)
		)
		(layer "B.Cu")
	)
	(gr_line
		(start 182.912004 -12.763246)
		(end 183.068722 -12.763246)
		(stroke
			(width 0.068326)
			(type default)
		)
		(layer "B.Cu")
	)
	(gr_arc
		(start 183.068976 -13.0683)
		(mid 182.971912 -13.08767)
		(end 182.889652 -13.142722)
		(stroke
			(width 0.068326)
			(type default)
		)
		(layer "B.Cu")
	)
	(gr_line
		(start 183.63057 -8.40613)
		(end 183.819546 -8.217154)
		(stroke
			(width 0.068326)
			(type default)
		)
		(layer "B.Cu")
	)
	(gr_line
		(start 184.254394 -8.217154)
		(end 184.44337 -8.40613)
		(stroke
			(width 0.068326)
			(type default)
		)
		(layer "B.Cu")
	)
	(gr_line
		(start 184.36971 -12.320778)
		(end 184.558686 -12.509754)
		(stroke
			(width 0.068326)
			(type default)
		)
		(layer "B.Cu")
	)
	(gr_line
		(start 184.36971 -11.88593)
		(end 184.558686 -11.696954)
		(stroke
			(width 0.068326)
			(type default)
		)
		(layer "B.Cu")
	)
	(gr_line
		(start 185.700162 -224.713546)
		(end 185.700162 -225.92538)
		(stroke
			(width 0.068326)
			(type default)
		)
		(layer "B.Cu")
	)
	(gr_arc
		(start 185.840116 -224.375726)
		(mid 185.736539 -224.530714)
		(end 185.700162 -224.713546)
		(stroke
			(width 0.068326)
			(type default)
		)
		(layer "B.Cu")
	)
	(gr_line
		(start 185.840116 -224.375726)
		(end 185.890916 -224.324926)
		(stroke
			(width 0.068326)
			(type default)
		)
		(layer "B.Cu")
	)
	(gr_arc
		(start 185.890916 -224.324926)
		(mid 185.933042 -224.26188)
		(end 185.947812 -224.187512)
		(stroke
			(width 0.068326)
			(type default)
		)
		(layer "B.Cu")
	)
	(gr_arc
		(start 185.947558 -222.90786)
		(mid 185.88155 -222.576014)
		(end 185.693558 -222.294704)
		(stroke
			(width 0.068326)
			(type default)
		)
		(layer "B.Cu")
	)
	(gr_arc
		(start 186.252612 -224.17278)
		(mid 186.272679 -224.273676)
		(end 186.329828 -224.359216)
		(stroke
			(width 0.068326)
			(type default)
		)
		(layer "B.Cu")
	)
	(gr_arc
		(start 186.500008 -224.770188)
		(mid 186.45577 -224.547791)
		(end 186.329828 -224.359216)
		(stroke
			(width 0.068326)
			(type default)
		)
		(layer "B.Cu")
	)
	(gr_line
		(start 186.500008 -224.770188)
		(end 186.500008 -225.92538)
		(stroke
			(width 0.068326)
			(type default)
		)
		(layer "B.Cu")
	)
	(gr_arc
		(start 186.506358 -222.294704)
		(mid 186.318547 -222.575792)
		(end 186.252612 -222.907352)
		(stroke
			(width 0.068326)
			(type default)
		)
		(layer "B.Cu")
	)
	(gr_line
		(start 188.900054 -224.7138)
		(end 188.900054 -225.92538)
		(stroke
			(width 0.068326)
			(type default)
		)
		(layer "B.Cu")
	)
	(gr_line
		(start 188.900054 -224.7138)
		(end 188.900308 -224.713546)
		(stroke
			(width 0.068326)
			(type default)
		)
		(layer "B.Cu")
	)
	(gr_arc
		(start 189.040262 -224.375726)
		(mid 188.936675 -224.530712)
		(end 188.900308 -224.713546)
		(stroke
			(width 0.068326)
			(type default)
		)
		(layer "B.Cu")
	)
	(gr_line
		(start 189.040262 -224.375726)
		(end 189.091062 -224.324926)
		(stroke
			(width 0.068326)
			(type default)
		)
		(layer "B.Cu")
	)
	(gr_arc
		(start 189.091062 -224.324926)
		(mid 189.133188 -224.26188)
		(end 189.147958 -224.187512)
		(stroke
			(width 0.068326)
			(type default)
		)
		(layer "B.Cu")
	)
	(gr_arc
		(start 189.147704 -222.90786)
		(mid 189.081696 -222.576014)
		(end 188.893704 -222.294704)
		(stroke
			(width 0.068326)
			(type default)
		)
		(layer "B.Cu")
	)
	(gr_arc
		(start 189.452758 -224.17278)
		(mid 189.472821 -224.273679)
		(end 189.529974 -224.359216)
		(stroke
			(width 0.068326)
			(type default)
		)
		(layer "B.Cu")
	)
	(gr_arc
		(start 189.700154 -224.770188)
		(mid 189.655916 -224.547791)
		(end 189.529974 -224.359216)
		(stroke
			(width 0.068326)
			(type default)
		)
		(layer "B.Cu")
	)
	(gr_line
		(start 189.700154 -224.770188)
		(end 189.700154 -225.92538)
		(stroke
			(width 0.068326)
			(type default)
		)
		(layer "B.Cu")
	)
	(gr_arc
		(start 189.706504 -222.294704)
		(mid 189.518704 -222.575795)
		(end 189.452758 -222.907352)
		(stroke
			(width 0.068326)
			(type default)
		)
		(layer "B.Cu")
	)
	(gr_line
		(start 192.1002 -224.713546)
		(end 192.1002 -225.92538)
		(stroke
			(width 0.068326)
			(type default)
		)
		(layer "B.Cu")
	)
	(gr_arc
		(start 192.240154 -224.375726)
		(mid 192.136569 -224.530712)
		(end 192.1002 -224.713546)
		(stroke
			(width 0.068326)
			(type default)
		)
		(layer "B.Cu")
	)
	(gr_line
		(start 192.240154 -224.375726)
		(end 192.290954 -224.324926)
		(stroke
			(width 0.068326)
			(type default)
		)
		(layer "B.Cu")
	)
	(gr_arc
		(start 192.290954 -224.324926)
		(mid 192.33308 -224.26188)
		(end 192.34785 -224.187512)
		(stroke
			(width 0.068326)
			(type default)
		)
		(layer "B.Cu")
	)
	(gr_arc
		(start 192.347596 -222.90786)
		(mid 192.281588 -222.576014)
		(end 192.093596 -222.294704)
		(stroke
			(width 0.068326)
			(type default)
		)
		(layer "B.Cu")
	)
	(gr_arc
		(start 192.65265 -224.17278)
		(mid 192.672713 -224.273679)
		(end 192.729866 -224.359216)
		(stroke
			(width 0.068326)
			(type default)
		)
		(layer "B.Cu")
	)
	(gr_arc
		(start 192.900046 -224.770188)
		(mid 192.855808 -224.547791)
		(end 192.729866 -224.359216)
		(stroke
			(width 0.068326)
			(type default)
		)
		(layer "B.Cu")
	)
	(gr_line
		(start 192.900046 -224.770188)
		(end 192.900046 -225.92538)
		(stroke
			(width 0.068326)
			(type default)
		)
		(layer "B.Cu")
	)
	(gr_arc
		(start 192.906396 -222.294704)
		(mid 192.718598 -222.575795)
		(end 192.65265 -222.907352)
		(stroke
			(width 0.068326)
			(type default)
		)
		(layer "B.Cu")
	)
	(gr_line
		(start 193.355468 -42.987468)
		(end 193.549778 -42.793158)
		(stroke
			(width 0.060198)
			(type default)
		)
		(layer "B.Cu")
	)
	(gr_line
		(start 194.262756 -42.793158)
		(end 194.457066 -42.987468)
		(stroke
			(width 0.060198)
			(type default)
		)
		(layer "B.Cu")
	)
	(gr_line
		(start 195.300092 -224.7138)
		(end 195.300092 -225.92538)
		(stroke
			(width 0.068326)
			(type default)
		)
		(layer "B.Cu")
	)
	(gr_line
		(start 195.300092 -224.7138)
		(end 195.300346 -224.713546)
		(stroke
			(width 0.068326)
			(type default)
		)
		(layer "B.Cu")
	)
	(gr_arc
		(start 195.4403 -224.375726)
		(mid 195.336727 -224.530715)
		(end 195.300346 -224.713546)
		(stroke
			(width 0.068326)
			(type default)
		)
		(layer "B.Cu")
	)
	(gr_line
		(start 195.4403 -224.375726)
		(end 195.4911 -224.324926)
		(stroke
			(width 0.068326)
			(type default)
		)
		(layer "B.Cu")
	)
	(gr_arc
		(start 195.4911 -224.324926)
		(mid 195.533226 -224.26188)
		(end 195.547996 -224.187512)
		(stroke
			(width 0.068326)
			(type default)
		)
		(layer "B.Cu")
	)
	(gr_arc
		(start 195.547742 -222.90786)
		(mid 195.481734 -222.576014)
		(end 195.293742 -222.294704)
		(stroke
			(width 0.068326)
			(type default)
		)
		(layer "B.Cu")
	)
	(gr_arc
		(start 195.852796 -224.17278)
		(mid 195.872862 -224.273677)
		(end 195.930012 -224.359216)
		(stroke
			(width 0.068326)
			(type default)
		)
		(layer "B.Cu")
	)
	(gr_arc
		(start 196.100192 -224.770188)
		(mid 196.055954 -224.547791)
		(end 195.930012 -224.359216)
		(stroke
			(width 0.068326)
			(type default)
		)
		(layer "B.Cu")
	)
	(gr_line
		(start 196.100192 -224.770188)
		(end 196.100192 -225.92538)
		(stroke
			(width 0.068326)
			(type default)
		)
		(layer "B.Cu")
	)
	(gr_arc
		(start 196.106542 -222.294704)
		(mid 195.918734 -222.575793)
		(end 195.852796 -222.907352)
		(stroke
			(width 0.068326)
			(type default)
		)
		(layer "B.Cu")
	)
	(gr_line
		(start 198.500238 -224.713546)
		(end 198.500238 -225.92538)
		(stroke
			(width 0.068326)
			(type default)
		)
		(layer "B.Cu")
	)
	(gr_arc
		(start 198.640192 -224.375726)
		(mid 198.536599 -224.53071)
		(end 198.500238 -224.713546)
		(stroke
			(width 0.068326)
			(type default)
		)
		(layer "B.Cu")
	)
	(gr_line
		(start 198.640192 -224.375726)
		(end 198.690992 -224.324926)
		(stroke
			(width 0.068326)
			(type default)
		)
		(layer "B.Cu")
	)
	(gr_arc
		(start 198.690992 -224.324926)
		(mid 198.733118 -224.26188)
		(end 198.747888 -224.187512)
		(stroke
			(width 0.068326)
			(type default)
		)
		(layer "B.Cu")
	)
	(gr_arc
		(start 198.747634 -222.90786)
		(mid 198.681626 -222.576014)
		(end 198.493634 -222.294704)
		(stroke
			(width 0.068326)
			(type default)
		)
		(layer "B.Cu")
	)
	(gr_arc
		(start 199.052688 -224.17278)
		(mid 199.072753 -224.273677)
		(end 199.129904 -224.359216)
		(stroke
			(width 0.068326)
			(type default)
		)
		(layer "B.Cu")
	)
	(gr_arc
		(start 199.300084 -224.770188)
		(mid 199.255846 -224.547791)
		(end 199.129904 -224.359216)
		(stroke
			(width 0.068326)
			(type default)
		)
		(layer "B.Cu")
	)
	(gr_line
		(start 199.300084 -224.770188)
		(end 199.300084 -225.92538)
		(stroke
			(width 0.068326)
			(type default)
		)
		(layer "B.Cu")
	)
	(gr_arc
		(start 199.306434 -222.294704)
		(mid 199.118628 -222.575793)
		(end 199.052688 -222.907352)
		(stroke
			(width 0.068326)
			(type default)
		)
		(layer "B.Cu")
	)
	(gr_line
		(start 201.70013 -224.7138)
		(end 201.70013 -225.92538)
		(stroke
			(width 0.068326)
			(type default)
		)
		(layer "B.Cu")
	)
	(gr_line
		(start 201.70013 -224.7138)
		(end 201.700384 -224.713546)
		(stroke
			(width 0.068326)
			(type default)
		)
		(layer "B.Cu")
	)
	(gr_arc
		(start 201.840338 -224.375726)
		(mid 201.736757 -224.530713)
		(end 201.700384 -224.713546)
		(stroke
			(width 0.068326)
			(type default)
		)
		(layer "B.Cu")
	)
	(gr_line
		(start 201.840338 -224.375726)
		(end 201.891138 -224.324926)
		(stroke
			(width 0.068326)
			(type default)
		)
		(layer "B.Cu")
	)
	(gr_arc
		(start 201.891138 -224.324926)
		(mid 201.933264 -224.26188)
		(end 201.948034 -224.187512)
		(stroke
			(width 0.068326)
			(type default)
		)
		(layer "B.Cu")
	)
	(gr_arc
		(start 201.94778 -222.90786)
		(mid 201.881772 -222.576014)
		(end 201.69378 -222.294704)
		(stroke
			(width 0.068326)
			(type default)
		)
		(layer "B.Cu")
	)
	(gr_arc
		(start 202.252834 -224.17278)
		(mid 202.272902 -224.273675)
		(end 202.33005 -224.359216)
		(stroke
			(width 0.068326)
			(type default)
		)
		(layer "B.Cu")
	)
	(gr_arc
		(start 202.50023 -224.770188)
		(mid 202.455992 -224.547791)
		(end 202.33005 -224.359216)
		(stroke
			(width 0.068326)
			(type default)
		)
		(layer "B.Cu")
	)
	(gr_line
		(start 202.50023 -224.770188)
		(end 202.50023 -225.92538)
		(stroke
			(width 0.068326)
			(type default)
		)
		(layer "B.Cu")
	)
	(gr_arc
		(start 202.50658 -222.294704)
		(mid 202.318785 -222.575796)
		(end 202.252834 -222.907352)
		(stroke
			(width 0.068326)
			(type default)
		)
		(layer "B.Cu")
	)
	(gr_arc
		(start 202.946 -49.784)
		(mid 203.133937 -49.502804)
		(end 203.2 -49.171098)
		(stroke
			(width 0.068326)
			(type default)
		)
		(layer "B.Cu")
	)
	(gr_arc
		(start 203.5048 -49.170844)
		(mid 203.570814 -49.502689)
		(end 203.7588 -49.784)
		(stroke
			(width 0.068326)
			(type default)
		)
		(layer "B.Cu")
	)
	(gr_line
		(start 204.900022 -224.7138)
		(end 204.900022 -225.92538)
		(stroke
			(width 0.068326)
			(type default)
		)
		(layer "B.Cu")
	)
	(gr_line
		(start 204.900022 -224.7138)
		(end 204.900276 -224.713546)
		(stroke
			(width 0.068326)
			(type default)
		)
		(layer "B.Cu")
	)
	(gr_arc
		(start 205.04023 -224.375726)
		(mid 204.93665 -224.530713)
		(end 204.900276 -224.713546)
		(stroke
			(width 0.068326)
			(type default)
		)
		(layer "B.Cu")
	)
	(gr_line
		(start 205.04023 -224.375726)
		(end 205.09103 -224.324926)
		(stroke
			(width 0.068326)
			(type default)
		)
		(layer "B.Cu")
	)
	(gr_arc
		(start 205.09103 -224.324926)
		(mid 205.133156 -224.26188)
		(end 205.147926 -224.187512)
		(stroke
			(width 0.068326)
			(type default)
		)
		(layer "B.Cu")
	)
	(gr_arc
		(start 205.147672 -222.90786)
		(mid 205.081664 -222.576014)
		(end 204.893672 -222.294704)
		(stroke
			(width 0.068326)
			(type default)
		)
		(layer "B.Cu")
	)
	(gr_arc
		(start 205.452726 -224.17278)
		(mid 205.472793 -224.273675)
		(end 205.529942 -224.359216)
		(stroke
			(width 0.068326)
			(type default)
		)
		(layer "B.Cu")
	)
	(gr_arc
		(start 205.700122 -224.770188)
		(mid 205.655884 -224.547791)
		(end 205.529942 -224.359216)
		(stroke
			(width 0.068326)
			(type default)
		)
		(layer "B.Cu")
	)
	(gr_line
		(start 205.700122 -224.770188)
		(end 205.700122 -225.92538)
		(stroke
			(width 0.068326)
			(type default)
		)
		(layer "B.Cu")
	)
	(gr_arc
		(start 205.706472 -222.294704)
		(mid 205.518679 -222.575797)
		(end 205.452726 -222.907352)
		(stroke
			(width 0.068326)
			(type default)
		)
		(layer "B.Cu")
	)
	(gr_line
		(start 206.20863 -46.248574)
		(end 206.234284 -46.222666)
		(stroke
			(width 0.068326)
			(type default)
		)
		(layer "B.Cu")
	)
	(gr_line
		(start 206.234284 -46.222666)
		(end 206.270352 -46.211236)
		(stroke
			(width 0.068326)
			(type default)
		)
		(layer "B.Cu")
	)
	(gr_arc
		(start 206.368396 -46.517306)
		(mid 206.378156 -46.50973)
		(end 206.387192 -46.501304)
		(stroke
			(width 0.068326)
			(type default)
		)
		(layer "B.Cu")
	)
	(gr_line
		(start 207.080612 -25.032462)
		(end 207.274922 -25.226772)
		(stroke
			(width 0.060198)
			(type default)
		)
		(layer "B.Cu")
	)
	(gr_line
		(start 207.080612 -24.319484)
		(end 207.274922 -24.125174)
		(stroke
			(width 0.060198)
			(type default)
		)
		(layer "B.Cu")
	)
	(gr_line
		(start 209.9437 -45.049186)
		(end 209.95132 -45.0469)
		(stroke
			(width 0.068326)
			(type default)
		)
		(layer "B.Cu")
	)
	(gr_arc
		(start 210.382866 -45.0469)
		(mid 210.651002 -44.967421)
		(end 210.8327 -44.7548)
		(stroke
			(width 0.068326)
			(type default)
		)
		(layer "B.Cu")
	)
	(gr_arc
		(start 210.8327 -45.6438)
		(mid 210.651042 -45.431135)
		(end 210.382866 -45.3517)
		(stroke
			(width 0.068326)
			(type default)
		)
		(layer "B.Cu")
	)
	(gr_line
		(start 211.30006 -224.7138)
		(end 211.30006 -225.92538)
		(stroke
			(width 0.068326)
			(type default)
		)
		(layer "B.Cu")
	)
	(gr_line
		(start 211.30006 -224.7138)
		(end 211.300314 -224.713546)
		(stroke
			(width 0.068326)
			(type default)
		)
		(layer "B.Cu")
	)
	(gr_arc
		(start 211.440268 -224.375726)
		(mid 211.33668 -224.530711)
		(end 211.300314 -224.713546)
		(stroke
			(width 0.068326)
			(type default)
		)
		(layer "B.Cu")
	)
	(gr_line
		(start 211.440268 -224.375726)
		(end 211.491068 -224.324926)
		(stroke
			(width 0.068326)
			(type default)
		)
		(layer "B.Cu")
	)
	(gr_arc
		(start 211.491068 -224.324926)
		(mid 211.533194 -224.26188)
		(end 211.547964 -224.187512)
		(stroke
			(width 0.068326)
			(type default)
		)
		(layer "B.Cu")
	)
	(gr_arc
		(start 211.54771 -222.90786)
		(mid 211.481702 -222.576014)
		(end 211.29371 -222.294704)
		(stroke
			(width 0.068326)
			(type default)
		)
		(layer "B.Cu")
	)
	(gr_arc
		(start 211.7217 -44.7548)
		(mid 212.059305 -44.980381)
		(end 212.457538 -45.0596)
		(stroke
			(width 0.068326)
			(type default)
		)
		(layer "B.Cu")
	)
	(gr_arc
		(start 211.852764 -224.17278)
		(mid 211.872828 -224.273679)
		(end 211.92998 -224.359216)
		(stroke
			(width 0.068326)
			(type default)
		)
		(layer "B.Cu")
	)
	(gr_arc
		(start 212.10016 -224.770188)
		(mid 212.055922 -224.547791)
		(end 211.92998 -224.359216)
		(stroke
			(width 0.068326)
			(type default)
		)
		(layer "B.Cu")
	)
	(gr_line
		(start 212.10016 -224.770188)
		(end 212.10016 -225.92538)
		(stroke
			(width 0.068326)
			(type default)
		)
		(layer "B.Cu")
	)
	(gr_arc
		(start 212.10651 -222.294704)
		(mid 211.918709 -222.575794)
		(end 211.852764 -222.907352)
		(stroke
			(width 0.068326)
			(type default)
		)
		(layer "B.Cu")
	)
	(gr_arc
		(start 212.396324 -45.3644)
		(mid 212.031235 -45.437021)
		(end 211.7217 -45.6438)
		(stroke
			(width 0.068326)
			(type default)
		)
		(layer "B.Cu")
	)
	(gr_line
		(start 213.292436 -45.241972)
		(end 213.29269 -45.242226)
		(stroke
			(width 0.068326)
			(type default)
		)
		(layer "B.Cu")
	)
	(gr_line
		(start 214.500206 -224.713546)
		(end 214.500206 -225.92538)
		(stroke
			(width 0.068326)
			(type default)
		)
		(layer "B.Cu")
	)
	(gr_arc
		(start 214.64016 -224.375726)
		(mid 214.536574 -224.530712)
		(end 214.500206 -224.713546)
		(stroke
			(width 0.068326)
			(type default)
		)
		(layer "B.Cu")
	)
	(gr_line
		(start 214.64016 -224.375726)
		(end 214.69096 -224.324926)
		(stroke
			(width 0.068326)
			(type default)
		)
		(layer "B.Cu")
	)
	(gr_arc
		(start 214.69096 -224.324926)
		(mid 214.733086 -224.26188)
		(end 214.747856 -224.187512)
		(stroke
			(width 0.068326)
			(type default)
		)
		(layer "B.Cu")
	)
	(gr_arc
		(start 214.747602 -222.90786)
		(mid 214.681594 -222.576014)
		(end 214.493602 -222.294704)
		(stroke
			(width 0.068326)
			(type default)
		)
		(layer "B.Cu")
	)
	(gr_arc
		(start 215.052656 -224.17278)
		(mid 215.072719 -224.273679)
		(end 215.129872 -224.359216)
		(stroke
			(width 0.068326)
			(type default)
		)
		(layer "B.Cu")
	)
	(gr_arc
		(start 215.300052 -224.770188)
		(mid 215.255814 -224.547791)
		(end 215.129872 -224.359216)
		(stroke
			(width 0.068326)
			(type default)
		)
		(layer "B.Cu")
	)
	(gr_line
		(start 215.300052 -224.770188)
		(end 215.300052 -225.92538)
		(stroke
			(width 0.068326)
			(type default)
		)
		(layer "B.Cu")
	)
	(gr_arc
		(start 215.306402 -222.294704)
		(mid 215.118603 -222.575795)
		(end 215.052656 -222.907352)
		(stroke
			(width 0.068326)
			(type default)
		)
		(layer "B.Cu")
	)
	(gr_line
		(start 219.6592 -179.7558)
		(end 219.734384 -179.680616)
		(stroke
			(width 0.060198)
			(type default)
		)
		(layer "B.Cu")
	)
	(gr_line
		(start 220.447616 -179.680616)
		(end 220.5228 -179.7558)
		(stroke
			(width 0.060198)
			(type default)
		)
		(layer "B.Cu")
	)
	(gr_line
		(start 223.242378 -45.085)
		(end 223.267778 -45.085)
		(stroke
			(width 0.0508)
			(type default)
		)
		(layer "B.Cu")
	)
	(gr_line
		(start 223.242378 -44.7802)
		(end 223.267778 -44.7802)
		(stroke
			(width 0.0508)
			(type default)
		)
		(layer "B.Cu")
	)
	(gr_line
		(start 223.267778 -45.085)
		(end 223.274636 -45.078142)
		(stroke
			(width 0.0508)
			(type default)
		)
		(layer "B.Cu")
	)
	(gr_line
		(start 223.267778 -44.7802)
		(end 223.274636 -44.787058)
		(stroke
			(width 0.0508)
			(type default)
		)
		(layer "B.Cu")
	)
	(gr_line
		(start 223.276414 -45.076364)
		(end 223.318578 -45.0342)
		(stroke
			(width 0.0508)
			(type default)
		)
		(layer "B.Cu")
	)
	(gr_line
		(start 223.276414 -44.788836)
		(end 223.318578 -44.831)
		(stroke
			(width 0.0508)
			(type default)
		)
		(layer "B.Cu")
	)
	(gr_line
		(start 226.100132 -45.500036)
		(end 226.402646 -45.500036)
		(stroke
			(width 0.0508)
			(type default)
		)
		(layer "B.Cu")
	)
	(gr_arc
		(start 226.402646 -45.500036)
		(mid 226.403154 -45.500037)
		(end 226.403662 -45.500036)
		(stroke
			(width 0.0508)
			(type default)
		)
		(layer "B.Cu")
	)
	(gr_line
		(start 226.403662 -45.500036)
		(end 226.47783 -45.499782)
		(stroke
			(width 0.0508)
			(type default)
		)
		(layer "B.Cu")
	)
	(gr_arc
		(start 226.567492 -45.745146)
		(mid 226.600932 -45.593856)
		(end 226.47783 -45.499782)
		(stroke
			(width 0.0508)
			(type default)
		)
		(layer "B.Cu")
	)
	(gr_line
		(start 226.856798 -45.743368)
		(end 227.10013 -45.500036)
		(stroke
			(width 0.0508)
			(type default)
		)
		(layer "B.Cu")
	)
	(gr_line
		(start 235.6104 -37.01034)
		(end 236.100112 -37.500052)
		(stroke
			(width 0.068326)
			(type default)
		)
		(layer "B.Cu")
	)
	(gr_line
		(start 235.6104 -36.8046)
		(end 235.6104 -37.01034)
		(stroke
			(width 0.068326)
			(type default)
		)
		(layer "B.Cu")
	)
	(gr_line
		(start 244.132862 -29.249878)
		(end 244.238272 -29.355288)
		(stroke
			(width 0.0508)
			(type default)
		)
		(layer "B.Cu")
	)
	(gr_line
		(start 244.132862 -29.224478)
		(end 244.132862 -29.249878)
		(stroke
			(width 0.0508)
			(type default)
		)
		(layer "B.Cu")
	)
	(gr_line
		(start 244.132862 -29.046932)
		(end 244.132862 -29.224478)
		(stroke
			(width 0.060198)
			(type default)
		)
		(layer "B.Cu")
	)
	(gr_line
		(start 244.24005 -29.357066)
		(end 244.28196 -29.398976)
		(stroke
			(width 0.0508)
			(type default)
		)
		(layer "B.Cu")
	)
	(gr_line
		(start 244.48516 -29.39923)
		(end 244.48516 -29.576776)
		(stroke
			(width 0.0508)
			(type default)
		)
		(layer "B.Cu")
	)
	(gr_line
		(start 244.48516 -29.39923)
		(end 244.527324 -29.357066)
		(stroke
			(width 0.0508)
			(type default)
		)
		(layer "B.Cu")
	)
	(gr_line
		(start 244.529102 -29.355288)
		(end 244.634512 -29.249878)
		(stroke
			(width 0.0508)
			(type default)
		)
		(layer "B.Cu")
	)
	(gr_line
		(start 244.634512 -29.224478)
		(end 244.634512 -29.249878)
		(stroke
			(width 0.0508)
			(type default)
		)
		(layer "B.Cu")
	)
	(gr_line
		(start 244.79504 -38.789356)
		(end 245.09984 -39.094156)
		(stroke
			(width 0.0508)
			(type default)
		)
		(layer "B.Cu")
	)
	(gr_line
		(start 244.796818 -38.50005)
		(end 245.09984 -38.50005)
		(stroke
			(width 0.0508)
			(type default)
		)
		(layer "B.Cu")
	)
	(gr_line
		(start 245.09984 -39.094156)
		(end 245.09984 -39.500048)
		(stroke
			(width 0.0508)
			(type default)
		)
		(layer "B.Cu")
	)
	(gr_line
		(start 245.445534 -25.902158)
		(end 245.684802 -25.663398)
		(stroke
			(width 0.060198)
			(type default)
		)
		(layer "B.Cu")
	)
	(gr_line
		(start 245.564152 -26.406348)
		(end 245.684802 -26.526998)
		(stroke
			(width 0.060198)
			(type default)
		)
		(layer "B.Cu")
	)
	(gr_line
		(start 245.684802 -26.526998)
		(end 245.684802 -26.67)
		(stroke
			(width 0.060198)
			(type default)
		)
		(layer "B.Cu")
	)
	(gr_line
		(start 245.684802 -25.4)
		(end 245.684802 -25.663398)
		(stroke
			(width 0.060198)
			(type default)
		)
		(layer "B.Cu")
	)
	(gr_line
		(start 246.012462 -29.141166)
		(end 246.117872 -29.246576)
		(stroke
			(width 0.0508)
			(type default)
		)
		(layer "B.Cu")
	)
	(gr_line
		(start 246.012462 -29.115766)
		(end 246.012462 -29.141166)
		(stroke
			(width 0.0508)
			(type default)
		)
		(layer "B.Cu")
	)
	(gr_line
		(start 246.012462 -28.93822)
		(end 246.012462 -29.115766)
		(stroke
			(width 0.060198)
			(type default)
		)
		(layer "B.Cu")
	)
	(gr_line
		(start 246.11965 -29.248354)
		(end 246.16156 -29.290264)
		(stroke
			(width 0.0508)
			(type default)
		)
		(layer "B.Cu")
	)
	(gr_line
		(start 246.36476 -29.290518)
		(end 246.36476 -29.468064)
		(stroke
			(width 0.0508)
			(type default)
		)
		(layer "B.Cu")
	)
	(gr_line
		(start 246.36476 -29.290518)
		(end 246.406924 -29.248354)
		(stroke
			(width 0.0508)
			(type default)
		)
		(layer "B.Cu")
	)
	(gr_line
		(start 246.408702 -29.246576)
		(end 246.514112 -29.141166)
		(stroke
			(width 0.0508)
			(type default)
		)
		(layer "B.Cu")
	)
	(gr_line
		(start 246.493538 -33.89376)
		(end 247.099836 -34.500058)
		(stroke
			(width 0.0508)
			(type default)
		)
		(layer "B.Cu")
	)
	(gr_line
		(start 246.493538 -33.302702)
		(end 246.493538 -33.89376)
		(stroke
			(width 0.0508)
			(type default)
		)
		(layer "B.Cu")
	)
	(gr_line
		(start 246.514112 -29.115766)
		(end 246.514112 -29.141166)
		(stroke
			(width 0.0508)
			(type default)
		)
		(layer "B.Cu")
	)
	(gr_line
		(start 246.699278 -33.099502)
		(end 247.099836 -33.50006)
		(stroke
			(width 0.0508)
			(type default)
		)
		(layer "B.Cu")
	)
	(gr_line
		(start 247.599962 -39.99992)
		(end 248.099834 -39.500048)
		(stroke
			(width 0.060198)
			(type default)
		)
		(layer "B.Cu")
	)
	(gr_line
		(start 247.599962 -35.999928)
		(end 248.099834 -35.500056)
		(stroke
			(width 0.060198)
			(type default)
		)
		(layer "B.Cu")
	)
	(gr_line
		(start 247.63603 -26.416)
		(end 247.651016 -26.430986)
		(stroke
			(width 0.060198)
			(type default)
		)
		(layer "B.Cu")
	)
	(gr_line
		(start 247.63603 -25.703022)
		(end 247.651016 -25.688036)
		(stroke
			(width 0.060198)
			(type default)
		)
		(layer "B.Cu")
	)
	(gr_line
		(start 247.651016 -26.430986)
		(end 247.651016 -26.694638)
		(stroke
			(width 0.060198)
			(type default)
		)
		(layer "B.Cu")
	)
	(gr_line
		(start 247.651016 -25.424638)
		(end 247.651016 -25.688036)
		(stroke
			(width 0.060198)
			(type default)
		)
		(layer "B.Cu")
	)
	(gr_line
		(start 248.256806 -28.679648)
		(end 248.362216 -28.785058)
		(stroke
			(width 0.0508)
			(type default)
		)
		(layer "B.Cu")
	)
	(gr_line
		(start 248.256806 -28.654248)
		(end 248.256806 -28.679648)
		(stroke
			(width 0.0508)
			(type default)
		)
		(layer "B.Cu")
	)
	(gr_line
		(start 248.256806 -28.476448)
		(end 248.256806 -28.654248)
		(stroke
			(width 0.060198)
			(type default)
		)
		(layer "B.Cu")
	)
	(gr_line
		(start 248.363994 -28.786836)
		(end 248.405904 -28.828746)
		(stroke
			(width 0.0508)
			(type default)
		)
		(layer "B.Cu")
	)
	(gr_line
		(start 248.493534 -36.479734)
		(end 249.099832 -37.086032)
		(stroke
			(width 0.0508)
			(type default)
		)
		(layer "B.Cu")
	)
	(gr_line
		(start 248.493534 -36.302696)
		(end 248.493534 -36.479734)
		(stroke
			(width 0.0508)
			(type default)
		)
		(layer "B.Cu")
	)
	(gr_line
		(start 248.493534 -30.336744)
		(end 248.493534 -30.367986)
		(stroke
			(width 0.0508)
			(type default)
		)
		(layer "B.Cu")
	)
	(gr_line
		(start 248.609104 -30.133544)
		(end 248.609104 -30.164786)
		(stroke
			(width 0.0508)
			(type default)
		)
		(layer "B.Cu")
	)
	(gr_line
		(start 248.609104 -28.829)
		(end 248.609104 -29.0068)
		(stroke
			(width 0.0508)
			(type default)
		)
		(layer "B.Cu")
	)
	(gr_line
		(start 248.609104 -28.829)
		(end 248.651268 -28.786836)
		(stroke
			(width 0.0508)
			(type default)
		)
		(layer "B.Cu")
	)
	(gr_line
		(start 248.653046 -28.785058)
		(end 248.758456 -28.679648)
		(stroke
			(width 0.0508)
			(type default)
		)
		(layer "B.Cu")
	)
	(gr_line
		(start 248.699274 -36.099496)
		(end 249.099832 -36.500054)
		(stroke
			(width 0.0508)
			(type default)
		)
		(layer "B.Cu")
	)
	(gr_line
		(start 248.758456 -28.654248)
		(end 248.758456 -28.679648)
		(stroke
			(width 0.0508)
			(type default)
		)
		(layer "B.Cu")
	)
	(gr_line
		(start 249.099832 -37.086032)
		(end 249.099832 -37.500052)
		(stroke
			(width 0.0508)
			(type default)
		)
		(layer "B.Cu")
	)
	(gr_line
		(start 249.413014 -26.391362)
		(end 249.428 -26.406348)
		(stroke
			(width 0.060198)
			(type default)
		)
		(layer "B.Cu")
	)
	(gr_line
		(start 249.413014 -25.678384)
		(end 249.428 -25.663398)
		(stroke
			(width 0.060198)
			(type default)
		)
		(layer "B.Cu")
	)
	(gr_line
		(start 249.428 -26.406348)
		(end 249.428 -26.67)
		(stroke
			(width 0.060198)
			(type default)
		)
		(layer "B.Cu")
	)
	(gr_line
		(start 249.428 -25.4)
		(end 249.428 -25.663398)
		(stroke
			(width 0.060198)
			(type default)
		)
		(layer "B.Cu")
	)
	(gr_line
		(start 249.96902 -29.553154)
		(end 250.07443 -29.658564)
		(stroke
			(width 0.0508)
			(type default)
		)
		(layer "B.Cu")
	)
	(gr_line
		(start 249.96902 -29.527754)
		(end 249.96902 -29.553154)
		(stroke
			(width 0.0508)
			(type default)
		)
		(layer "B.Cu")
	)
	(gr_line
		(start 249.96902 -29.350208)
		(end 249.96902 -29.527754)
		(stroke
			(width 0.060198)
			(type default)
		)
		(layer "B.Cu")
	)
	(gr_line
		(start 250.076208 -29.660342)
		(end 250.118118 -29.702252)
		(stroke
			(width 0.0508)
			(type default)
		)
		(layer "B.Cu")
	)
	(gr_line
		(start 250.09983 -38.50005)
		(end 250.69673 -37.90315)
		(stroke
			(width 0.0508)
			(type default)
		)
		(layer "B.Cu")
	)
	(gr_line
		(start 250.09983 -33.50006)
		(end 250.49099 -33.1089)
		(stroke
			(width 0.0508)
			(type default)
		)
		(layer "B.Cu")
	)
	(gr_line
		(start 250.292362 -5.840222)
		(end 250.402852 -5.950712)
		(stroke
			(width 0.060198)
			(type default)
		)
		(layer "B.Cu")
	)
	(gr_line
		(start 250.321318 -29.702506)
		(end 250.321318 -29.877004)
		(stroke
			(width 0.0508)
			(type default)
		)
		(layer "B.Cu")
	)
	(gr_line
		(start 250.321318 -29.702506)
		(end 250.363482 -29.660342)
		(stroke
			(width 0.0508)
			(type default)
		)
		(layer "B.Cu")
	)
	(gr_line
		(start 250.337066 -6.729476)
		(end 250.402852 -6.66369)
		(stroke
			(width 0.060198)
			(type default)
		)
		(layer "B.Cu")
	)
	(gr_line
		(start 250.36526 -29.658564)
		(end 250.47067 -29.553154)
		(stroke
			(width 0.0508)
			(type default)
		)
		(layer "B.Cu")
	)
	(gr_line
		(start 250.47067 -29.527754)
		(end 250.47067 -29.553154)
		(stroke
			(width 0.0508)
			(type default)
		)
		(layer "B.Cu")
	)
	(gr_line
		(start 250.584208 -26.5557)
		(end 250.735592 -26.707084)
		(stroke
			(width 0.060198)
			(type default)
		)
		(layer "B.Cu")
	)
	(gr_line
		(start 250.69673 -37.90315)
		(end 251.254006 -37.90315)
		(stroke
			(width 0.0508)
			(type default)
		)
		(layer "B.Cu")
	)
	(gr_line
		(start 250.69673 -35.83813)
		(end 250.964954 -36.106354)
		(stroke
			(width 0.0508)
			(type default)
		)
		(layer "B.Cu")
	)
	(gr_line
		(start 250.69673 -33.3121)
		(end 250.69673 -35.83813)
		(stroke
			(width 0.0508)
			(type default)
		)
		(layer "B.Cu")
	)
	(gr_line
		(start 250.964954 -36.106354)
		(end 251.26315 -36.106354)
		(stroke
			(width 0.0508)
			(type default)
		)
		(layer "B.Cu")
	)
	(gr_line
		(start 251.099828 -35.500056)
		(end 251.255276 -35.500056)
		(stroke
			(width 0.0508)
			(type default)
		)
		(layer "B.Cu")
	)
	(gr_line
		(start 251.099828 -34.500058)
		(end 251.6632 -35.06343)
		(stroke
			(width 0.0508)
			(type default)
		)
		(layer "B.Cu")
	)
	(gr_line
		(start 251.254006 -37.90315)
		(end 251.7902 -37.366956)
		(stroke
			(width 0.0508)
			(type default)
		)
		(layer "B.Cu")
	)
	(gr_line
		(start 251.255276 -35.500056)
		(end 251.373894 -35.618674)
		(stroke
			(width 0.0508)
			(type default)
		)
		(layer "B.Cu")
	)
	(gr_line
		(start 251.26315 -36.106354)
		(end 251.7902 -36.633404)
		(stroke
			(width 0.0508)
			(type default)
		)
		(layer "B.Cu")
	)
	(gr_line
		(start 251.448824 -26.707084)
		(end 251.600208 -26.5557)
		(stroke
			(width 0.060198)
			(type default)
		)
		(layer "B.Cu")
	)
	(gr_line
		(start 251.6632 -35.06343)
		(end 251.6632 -35.616896)
		(stroke
			(width 0.0508)
			(type default)
		)
		(layer "B.Cu")
	)
	(gr_line
		(start 251.7902 -37.0332)
		(end 251.7902 -37.366956)
		(stroke
			(width 0.0508)
			(type default)
		)
		(layer "B.Cu")
	)
	(gr_line
		(start 251.7902 -36.633404)
		(end 251.7902 -37.0332)
		(stroke
			(width 0.0508)
			(type default)
		)
		(layer "B.Cu")
	)
	(gr_line
		(start 252.63729 -6.526784)
		(end 252.717046 -6.526784)
		(stroke
			(width 0.060198)
			(type default)
		)
		(layer "B.Cu")
	)
	(gr_line
		(start 252.833632 -29.649166)
		(end 252.833632 -29.708348)
		(stroke
			(width 0.0508)
			(type default)
		)
		(layer "B.Cu")
	)
	(gr_line
		(start 252.833632 -29.497528)
		(end 252.833632 -29.646626)
		(stroke
			(width 0.0508)
			(type default)
		)
		(layer "B.Cu")
	)
	(gr_line
		(start 252.833632 -29.497528)
		(end 252.851412 -29.479748)
		(stroke
			(width 0.0508)
			(type default)
		)
		(layer "B.Cu")
	)
	(gr_line
		(start 252.851412 -29.978096)
		(end 252.977142 -29.852366)
		(stroke
			(width 0.0508)
			(type default)
		)
		(layer "B.Cu")
	)
	(gr_line
		(start 252.851412 -29.479748)
		(end 252.977142 -29.354018)
		(stroke
			(width 0.060198)
			(type default)
		)
		(layer "B.Cu")
	)
	(gr_line
		(start 252.977142 -29.852366)
		(end 253.036832 -29.852366)
		(stroke
			(width 0.0508)
			(type default)
		)
		(layer "B.Cu")
	)
	(gr_line
		(start 253.039372 -29.852366)
		(end 253.18847 -29.852366)
		(stroke
			(width 0.0508)
			(type default)
		)
		(layer "B.Cu")
	)
	(gr_line
		(start 253.13894 -6.239002)
		(end 253.218696 -6.239002)
		(stroke
			(width 0.060198)
			(type default)
		)
		(layer "B.Cu")
	)
	(gr_line
		(start 253.18847 -29.852366)
		(end 253.20625 -29.834586)
		(stroke
			(width 0.0508)
			(type default)
		)
		(layer "B.Cu")
	)
	(gr_line
		(start 253.746 -26.9748)
		(end 253.910084 -27.138884)
		(stroke
			(width 0.060198)
			(type default)
		)
		(layer "B.Cu")
	)
	(gr_line
		(start 253.746 -26.5557)
		(end 253.746 -26.9748)
		(stroke
			(width 0.060198)
			(type default)
		)
		(layer "B.Cu")
	)
	(gr_line
		(start 254.623062 -27.138884)
		(end 254.7874 -26.974546)
		(stroke
			(width 0.060198)
			(type default)
		)
		(layer "B.Cu")
	)
	(gr_line
		(start 254.7874 -26.5557)
		(end 254.7874 -26.974546)
		(stroke
			(width 0.060198)
			(type default)
		)
		(layer "B.Cu")
	)
	(gr_line
		(start 254.909828 -6.860286)
		(end 255.061212 -7.01167)
		(stroke
			(width 0.060198)
			(type default)
		)
		(layer "B.Cu")
	)
	(gr_line
		(start 254.909828 -6.147054)
		(end 255.061212 -5.99567)
		(stroke
			(width 0.060198)
			(type default)
		)
		(layer "B.Cu")
	)
	(gr_line
		(start 255.950212 -7.01167)
		(end 256.101596 -6.860286)
		(stroke
			(width 0.060198)
			(type default)
		)
		(layer "B.Cu")
	)
	(gr_line
		(start 255.950212 -5.99567)
		(end 256.101596 -6.147054)
		(stroke
			(width 0.060198)
			(type default)
		)
		(layer "B.Cu")
	)
	(gr_line
		(start 257.455162 -7.2517)
		(end 257.830066 -7.2517)
		(stroke
			(width 0.060198)
			(type default)
		)
		(layer "B.Cu")
	)
	(gr_line
		(start 257.5179 -6.60146)
		(end 257.830066 -6.60146)
		(stroke
			(width 0.060198)
			(type default)
		)
		(layer "B.Cu")
	)
	(gr_line
		(start 262.90016 -224.713546)
		(end 262.90016 -225.92538)
		(stroke
			(width 0.068326)
			(type default)
		)
		(layer "B.Cu")
	)
	(gr_arc
		(start 263.040114 -224.375726)
		(mid 262.936538 -224.530714)
		(end 262.90016 -224.713546)
		(stroke
			(width 0.068326)
			(type default)
		)
		(layer "B.Cu")
	)
	(gr_line
		(start 263.040114 -224.375726)
		(end 263.090914 -224.324926)
		(stroke
			(width 0.068326)
			(type default)
		)
		(layer "B.Cu")
	)
	(gr_arc
		(start 263.090914 -224.324926)
		(mid 263.13304 -224.26188)
		(end 263.14781 -224.187512)
		(stroke
			(width 0.068326)
			(type default)
		)
		(layer "B.Cu")
	)
	(gr_arc
		(start 263.147556 -222.90786)
		(mid 263.081548 -222.576014)
		(end 262.893556 -222.294704)
		(stroke
			(width 0.068326)
			(type default)
		)
		(layer "B.Cu")
	)
	(gr_arc
		(start 263.45261 -224.17278)
		(mid 263.472676 -224.273676)
		(end 263.529826 -224.359216)
		(stroke
			(width 0.068326)
			(type default)
		)
		(layer "B.Cu")
	)
	(gr_arc
		(start 263.700006 -224.770188)
		(mid 263.655768 -224.547791)
		(end 263.529826 -224.359216)
		(stroke
			(width 0.068326)
			(type default)
		)
		(layer "B.Cu")
	)
	(gr_line
		(start 263.700006 -224.770188)
		(end 263.700006 -225.92538)
		(stroke
			(width 0.068326)
			(type default)
		)
		(layer "B.Cu")
	)
	(gr_arc
		(start 263.706356 -222.294704)
		(mid 263.518545 -222.575792)
		(end 263.45261 -222.907352)
		(stroke
			(width 0.068326)
			(type default)
		)
		(layer "B.Cu")
	)
	(gr_line
		(start 266.100052 -224.7138)
		(end 266.100052 -225.92538)
		(stroke
			(width 0.068326)
			(type default)
		)
		(layer "B.Cu")
	)
	(gr_line
		(start 266.100052 -224.7138)
		(end 266.100306 -224.713546)
		(stroke
			(width 0.068326)
			(type default)
		)
		(layer "B.Cu")
	)
	(gr_arc
		(start 266.24026 -224.375726)
		(mid 266.136674 -224.530712)
		(end 266.100306 -224.713546)
		(stroke
			(width 0.068326)
			(type default)
		)
		(layer "B.Cu")
	)
	(gr_line
		(start 266.24026 -224.375726)
		(end 266.29106 -224.324926)
		(stroke
			(width 0.068326)
			(type default)
		)
		(layer "B.Cu")
	)
	(gr_arc
		(start 266.29106 -224.324926)
		(mid 266.333186 -224.26188)
		(end 266.347956 -224.187512)
		(stroke
			(width 0.068326)
			(type default)
		)
		(layer "B.Cu")
	)
	(gr_arc
		(start 266.347702 -222.90786)
		(mid 266.281694 -222.576014)
		(end 266.093702 -222.294704)
		(stroke
			(width 0.068326)
			(type default)
		)
		(layer "B.Cu")
	)
	(gr_arc
		(start 266.652756 -224.17278)
		(mid 266.672819 -224.273679)
		(end 266.729972 -224.359216)
		(stroke
			(width 0.068326)
			(type default)
		)
		(layer "B.Cu")
	)
	(gr_arc
		(start 266.900152 -224.770188)
		(mid 266.855914 -224.547791)
		(end 266.729972 -224.359216)
		(stroke
			(width 0.068326)
			(type default)
		)
		(layer "B.Cu")
	)
	(gr_line
		(start 266.900152 -224.770188)
		(end 266.900152 -225.92538)
		(stroke
			(width 0.068326)
			(type default)
		)
		(layer "B.Cu")
	)
	(gr_arc
		(start 266.906502 -222.294704)
		(mid 266.718703 -222.575795)
		(end 266.652756 -222.907352)
		(stroke
			(width 0.068326)
			(type default)
		)
		(layer "B.Cu")
	)
	(gr_line
		(start 268.413738 -18.097754)
		(end 268.705584 -18.3896)
		(stroke
			(width 0.068326)
			(type default)
		)
		(layer "B.Cu")
	)
	(gr_line
		(start 268.413738 -17.662906)
		(end 268.705584 -17.37106)
		(stroke
			(width 0.068326)
			(type default)
		)
		(layer "B.Cu")
	)
	(gr_line
		(start 269.5448 -6.118352)
		(end 269.733776 -5.929376)
		(stroke
			(width 0.068326)
			(type default)
		)
		(layer "B.Cu")
	)
	(gr_line
		(start 269.5448 -5.305552)
		(end 269.733776 -5.494528)
		(stroke
			(width 0.068326)
			(type default)
		)
		(layer "B.Cu")
	)
	(gr_line
		(start 269.580868 -17.384776)
		(end 270.016732 -17.384776)
		(stroke
			(width 0.068326)
			(type default)
		)
		(layer "B.Cu")
	)
	(gr_line
		(start 269.594584 -18.3896)
		(end 270.016732 -18.3896)
		(stroke
			(width 0.068326)
			(type default)
		)
		(layer "B.Cu")
	)
	(gr_line
		(start 269.759176 1.059942)
		(end 269.836138 0.98298)
		(stroke
			(width 0.060198)
			(type default)
		)
		(layer "B.Cu")
	)
	(gr_line
		(start 270.016732 -18.3896)
		(end 270.30172 -18.104612)
		(stroke
			(width 0.068326)
			(type default)
		)
		(layer "B.Cu")
	)
	(gr_line
		(start 270.016732 -17.384776)
		(end 270.30172 -17.669764)
		(stroke
			(width 0.068326)
			(type default)
		)
		(layer "B.Cu")
	)
	(gr_line
		(start 270.282924 -5.932424)
		(end 270.5735 -6.223)
		(stroke
			(width 0.068326)
			(type default)
		)
		(layer "B.Cu")
	)
	(gr_line
		(start 270.282924 -5.497576)
		(end 270.5735 -5.207)
		(stroke
			(width 0.068326)
			(type default)
		)
		(layer "B.Cu")
	)
	(gr_line
		(start 270.54937 0.98298)
		(end 270.66748 1.10109)
		(stroke
			(width 0.060198)
			(type default)
		)
		(layer "B.Cu")
	)
	(gr_line
		(start 270.6878 -9.166352)
		(end 270.876776 -8.977376)
		(stroke
			(width 0.068326)
			(type default)
		)
		(layer "B.Cu")
	)
	(gr_line
		(start 270.6878 -8.353552)
		(end 270.876776 -8.542528)
		(stroke
			(width 0.068326)
			(type default)
		)
		(layer "B.Cu")
	)
	(gr_line
		(start 271.214596 -2.432812)
		(end 271.315434 -2.533904)
		(stroke
			(width 0.060198)
			(type default)
		)
		(layer "B.Cu")
	)
	(gr_line
		(start 271.425924 -8.980424)
		(end 271.7165 -9.271)
		(stroke
			(width 0.068326)
			(type default)
		)
		(layer "B.Cu")
	)
	(gr_line
		(start 271.425924 -8.545576)
		(end 271.7165 -8.255)
		(stroke
			(width 0.068326)
			(type default)
		)
		(layer "B.Cu")
	)
	(gr_line
		(start 271.4625 -6.223)
		(end 271.753076 -5.932424)
		(stroke
			(width 0.068326)
			(type default)
		)
		(layer "B.Cu")
	)
	(gr_line
		(start 271.4625 -5.207)
		(end 271.753076 -5.497576)
		(stroke
			(width 0.068326)
			(type default)
		)
		(layer "B.Cu")
	)
	(gr_line
		(start 271.539716 -2.0447)
		(end 271.7038 -2.0447)
		(stroke
			(width 0.060198)
			(type default)
		)
		(layer "B.Cu")
	)
	(gr_line
		(start 271.7038 -2.0447)
		(end 271.7038 -2.209292)
		(stroke
			(width 0.060198)
			(type default)
		)
		(layer "B.Cu")
	)
	(gr_line
		(start 272.317972 -3.537712)
		(end 272.431256 -3.65125)
		(stroke
			(width 0.060198)
			(type default)
		)
		(layer "B.Cu")
	)
	(gr_line
		(start 272.50009 -224.7138)
		(end 272.50009 -225.92538)
		(stroke
			(width 0.068326)
			(type default)
		)
		(layer "B.Cu")
	)
	(gr_line
		(start 272.50009 -224.7138)
		(end 272.500344 -224.713546)
		(stroke
			(width 0.068326)
			(type default)
		)
		(layer "B.Cu")
	)
	(gr_line
		(start 272.6055 -9.271)
		(end 272.896076 -8.980424)
		(stroke
			(width 0.068326)
			(type default)
		)
		(layer "B.Cu")
	)
	(gr_line
		(start 272.6055 -8.255)
		(end 272.896076 -8.545576)
		(stroke
			(width 0.068326)
			(type default)
		)
		(layer "B.Cu")
	)
	(gr_arc
		(start 272.640298 -224.375726)
		(mid 272.536725 -224.530715)
		(end 272.500344 -224.713546)
		(stroke
			(width 0.068326)
			(type default)
		)
		(layer "B.Cu")
	)
	(gr_line
		(start 272.640298 -224.375726)
		(end 272.691098 -224.324926)
		(stroke
			(width 0.068326)
			(type default)
		)
		(layer "B.Cu")
	)
	(gr_arc
		(start 272.691098 -224.324926)
		(mid 272.733224 -224.26188)
		(end 272.747994 -224.187512)
		(stroke
			(width 0.068326)
			(type default)
		)
		(layer "B.Cu")
	)
	(gr_arc
		(start 272.74774 -222.90786)
		(mid 272.681732 -222.576014)
		(end 272.49374 -222.294704)
		(stroke
			(width 0.068326)
			(type default)
		)
		(layer "B.Cu")
	)
	(gr_arc
		(start 273.052794 -224.17278)
		(mid 273.07286 -224.273677)
		(end 273.13001 -224.359216)
		(stroke
			(width 0.068326)
			(type default)
		)
		(layer "B.Cu")
	)
	(gr_arc
		(start 273.30019 -224.770188)
		(mid 273.255952 -224.547791)
		(end 273.13001 -224.359216)
		(stroke
			(width 0.068326)
			(type default)
		)
		(layer "B.Cu")
	)
	(gr_line
		(start 273.30019 -224.770188)
		(end 273.30019 -225.92538)
		(stroke
			(width 0.068326)
			(type default)
		)
		(layer "B.Cu")
	)
	(gr_arc
		(start 273.30654 -222.294704)
		(mid 273.118733 -222.575793)
		(end 273.052794 -222.907352)
		(stroke
			(width 0.068326)
			(type default)
		)
		(layer "B.Cu")
	)
	(gr_line
		(start 273.33829 -3.65125)
		(end 274.314666 -3.65125)
		(stroke
			(width 0.060198)
			(type default)
		)
		(layer "B.Cu")
	)
	(gr_line
		(start 274.314666 -3.65125)
		(end 274.85721 -3.108706)
		(stroke
			(width 0.060198)
			(type default)
		)
		(layer "B.Cu")
	)
	(gr_line
		(start 274.85721 -3.108706)
		(end 280.273506 -3.108706)
		(stroke
			(width 0.060198)
			(type default)
		)
		(layer "B.Cu")
	)
	(gr_line
		(start 275.700236 -224.713546)
		(end 275.700236 -225.92538)
		(stroke
			(width 0.068326)
			(type default)
		)
		(layer "B.Cu")
	)
	(gr_arc
		(start 275.84019 -224.375726)
		(mid 275.736598 -224.53071)
		(end 275.700236 -224.713546)
		(stroke
			(width 0.068326)
			(type default)
		)
		(layer "B.Cu")
	)
	(gr_line
		(start 275.84019 -224.375726)
		(end 275.89099 -224.324926)
		(stroke
			(width 0.068326)
			(type default)
		)
		(layer "B.Cu")
	)
	(gr_arc
		(start 275.89099 -224.324926)
		(mid 275.933116 -224.26188)
		(end 275.947886 -224.187512)
		(stroke
			(width 0.068326)
			(type default)
		)
		(layer "B.Cu")
	)
	(gr_arc
		(start 275.947632 -222.90786)
		(mid 275.881624 -222.576014)
		(end 275.693632 -222.294704)
		(stroke
			(width 0.068326)
			(type default)
		)
		(layer "B.Cu")
	)
	(gr_arc
		(start 276.252686 -224.17278)
		(mid 276.272751 -224.273677)
		(end 276.329902 -224.359216)
		(stroke
			(width 0.068326)
			(type default)
		)
		(layer "B.Cu")
	)
	(gr_arc
		(start 276.500082 -224.770188)
		(mid 276.455844 -224.547791)
		(end 276.329902 -224.359216)
		(stroke
			(width 0.068326)
			(type default)
		)
		(layer "B.Cu")
	)
	(gr_line
		(start 276.500082 -224.770188)
		(end 276.500082 -225.92538)
		(stroke
			(width 0.068326)
			(type default)
		)
		(layer "B.Cu")
	)
	(gr_arc
		(start 276.506432 -222.294704)
		(mid 276.318627 -222.575793)
		(end 276.252686 -222.907352)
		(stroke
			(width 0.068326)
			(type default)
		)
		(layer "B.Cu")
	)
	(gr_line
		(start 278.900128 -224.7138)
		(end 278.900128 -225.92538)
		(stroke
			(width 0.068326)
			(type default)
		)
		(layer "B.Cu")
	)
	(gr_line
		(start 278.900128 -224.7138)
		(end 278.900382 -224.713546)
		(stroke
			(width 0.068326)
			(type default)
		)
		(layer "B.Cu")
	)
	(gr_arc
		(start 279.040336 -224.375726)
		(mid 278.936755 -224.530713)
		(end 278.900382 -224.713546)
		(stroke
			(width 0.068326)
			(type default)
		)
		(layer "B.Cu")
	)
	(gr_line
		(start 279.040336 -224.375726)
		(end 279.091136 -224.324926)
		(stroke
			(width 0.068326)
			(type default)
		)
		(layer "B.Cu")
	)
	(gr_arc
		(start 279.091136 -224.324926)
		(mid 279.133262 -224.26188)
		(end 279.148032 -224.187512)
		(stroke
			(width 0.068326)
			(type default)
		)
		(layer "B.Cu")
	)
	(gr_arc
		(start 279.147778 -222.90786)
		(mid 279.08177 -222.576014)
		(end 278.893778 -222.294704)
		(stroke
			(width 0.068326)
			(type default)
		)
		(layer "B.Cu")
	)
	(gr_arc
		(start 279.452832 -224.17278)
		(mid 279.4729 -224.273675)
		(end 279.530048 -224.359216)
		(stroke
			(width 0.068326)
			(type default)
		)
		(layer "B.Cu")
	)
	(gr_arc
		(start 279.700228 -224.770188)
		(mid 279.65599 -224.547791)
		(end 279.530048 -224.359216)
		(stroke
			(width 0.068326)
			(type default)
		)
		(layer "B.Cu")
	)
	(gr_line
		(start 279.700228 -224.770188)
		(end 279.700228 -225.92538)
		(stroke
			(width 0.068326)
			(type default)
		)
		(layer "B.Cu")
	)
	(gr_arc
		(start 279.706578 -222.294704)
		(mid 279.518784 -222.575796)
		(end 279.452832 -222.907352)
		(stroke
			(width 0.068326)
			(type default)
		)
		(layer "B.Cu")
	)
	(gr_line
		(start 280.250646 -17.9578)
		(end 280.280618 -17.987772)
		(stroke
			(width 0.068326)
			(type default)
		)
		(layer "B.Cu")
	)
	(gr_line
		(start 280.273506 -3.108706)
		(end 281.178 -4.0132)
		(stroke
			(width 0.060198)
			(type default)
		)
		(layer "B.Cu")
	)
	(gr_arc
		(start 280.280618 -17.987772)
		(mid 280.540837 -18.161672)
		(end 280.8478 -18.222722)
		(stroke
			(width 0.068326)
			(type default)
		)
		(layer "B.Cu")
	)
	(gr_arc
		(start 280.82494 -18.527522)
		(mid 280.507382 -18.590688)
		(end 280.2382 -18.7706)
		(stroke
			(width 0.068326)
			(type default)
		)
		(layer "B.Cu")
	)
	(gr_line
		(start 281.178 -4.0132)
		(end 312.1152 -4.0132)
		(stroke
			(width 0.060198)
			(type default)
		)
		(layer "B.Cu")
	)
	(gr_line
		(start 282.10002 -224.7138)
		(end 282.10002 -225.92538)
		(stroke
			(width 0.068326)
			(type default)
		)
		(layer "B.Cu")
	)
	(gr_line
		(start 282.10002 -224.7138)
		(end 282.100274 -224.713546)
		(stroke
			(width 0.068326)
			(type default)
		)
		(layer "B.Cu")
	)
	(gr_arc
		(start 282.240228 -224.375726)
		(mid 282.136649 -224.530714)
		(end 282.100274 -224.713546)
		(stroke
			(width 0.068326)
			(type default)
		)
		(layer "B.Cu")
	)
	(gr_line
		(start 282.240228 -224.375726)
		(end 282.291028 -224.324926)
		(stroke
			(width 0.068326)
			(type default)
		)
		(layer "B.Cu")
	)
	(gr_arc
		(start 282.291028 -224.324926)
		(mid 282.333154 -224.26188)
		(end 282.347924 -224.187512)
		(stroke
			(width 0.068326)
			(type default)
		)
		(layer "B.Cu")
	)
	(gr_arc
		(start 282.34767 -222.90786)
		(mid 282.281662 -222.576014)
		(end 282.09367 -222.294704)
		(stroke
			(width 0.068326)
			(type default)
		)
		(layer "B.Cu")
	)
	(gr_line
		(start 282.439872 -18.301462)
		(end 282.44927 -18.29689)
		(stroke
			(width 0.068326)
			(type default)
		)
		(layer "B.Cu")
	)
	(gr_arc
		(start 282.476956 -20.971764)
		(mid 282.58772 -20.746194)
		(end 282.6258 -20.4978)
		(stroke
			(width 0.068326)
			(type default)
		)
		(layer "B.Cu")
	)
	(gr_line
		(start 282.623768 -24.586692)
		(end 282.776676 -24.7396)
		(stroke
			(width 0.068326)
			(type default)
		)
		(layer "B.Cu")
	)
	(gr_arc
		(start 282.652724 -224.17278)
		(mid 282.672791 -224.273675)
		(end 282.72994 -224.359216)
		(stroke
			(width 0.068326)
			(type default)
		)
		(layer "B.Cu")
	)
	(gr_line
		(start 282.776676 -24.7396)
		(end 283.186632 -24.7396)
		(stroke
			(width 0.068326)
			(type default)
		)
		(layer "B.Cu")
	)
	(gr_arc
		(start 282.90012 -224.770188)
		(mid 282.855882 -224.547791)
		(end 282.72994 -224.359216)
		(stroke
			(width 0.068326)
			(type default)
		)
		(layer "B.Cu")
	)
	(gr_line
		(start 282.90012 -224.770188)
		(end 282.90012 -225.92538)
		(stroke
			(width 0.068326)
			(type default)
		)
		(layer "B.Cu")
	)
	(gr_arc
		(start 282.90647 -222.294704)
		(mid 282.718678 -222.575797)
		(end 282.652724 -222.907352)
		(stroke
			(width 0.068326)
			(type default)
		)
		(layer "B.Cu")
	)
	(gr_line
		(start 282.928568 -24.279352)
		(end 283.03474 -24.279352)
		(stroke
			(width 0.068326)
			(type default)
		)
		(layer "B.Cu")
	)
	(gr_arc
		(start 283.169868 -21.101812)
		(mid 282.913386 -21.129492)
		(end 282.668726 -21.211286)
		(stroke
			(width 0.068326)
			(type default)
		)
		(layer "B.Cu")
	)
	(gr_line
		(start 283.186632 -24.7396)
		(end 283.33954 -24.586692)
		(stroke
			(width 0.068326)
			(type default)
		)
		(layer "B.Cu")
	)
	(gr_line
		(start 283.754576 -24.586692)
		(end 283.907484 -24.7396)
		(stroke
			(width 0.068326)
			(type default)
		)
		(layer "B.Cu")
	)
	(gr_line
		(start 283.907484 -24.7396)
		(end 284.31744 -24.7396)
		(stroke
			(width 0.068326)
			(type default)
		)
		(layer "B.Cu")
	)
	(gr_line
		(start 284.059376 -24.279352)
		(end 284.165548 -24.279352)
		(stroke
			(width 0.068326)
			(type default)
		)
		(layer "B.Cu")
	)
	(gr_line
		(start 284.31744 -24.7396)
		(end 284.470348 -24.586692)
		(stroke
			(width 0.068326)
			(type default)
		)
		(layer "B.Cu")
	)
	(gr_line
		(start 285.300166 -224.713546)
		(end 285.300166 -225.92538)
		(stroke
			(width 0.068326)
			(type default)
		)
		(layer "B.Cu")
	)
	(gr_arc
		(start 285.44012 -224.375726)
		(mid 285.336542 -224.530714)
		(end 285.300166 -224.713546)
		(stroke
			(width 0.068326)
			(type default)
		)
		(layer "B.Cu")
	)
	(gr_line
		(start 285.44012 -224.375726)
		(end 285.49092 -224.324926)
		(stroke
			(width 0.068326)
			(type default)
		)
		(layer "B.Cu")
	)
	(gr_arc
		(start 285.49092 -224.324926)
		(mid 285.533046 -224.26188)
		(end 285.547816 -224.187512)
		(stroke
			(width 0.068326)
			(type default)
		)
		(layer "B.Cu")
	)
	(gr_arc
		(start 285.547562 -222.90786)
		(mid 285.481554 -222.576014)
		(end 285.293562 -222.294704)
		(stroke
			(width 0.068326)
			(type default)
		)
		(layer "B.Cu")
	)
	(gr_arc
		(start 285.852616 -224.17278)
		(mid 285.872683 -224.273676)
		(end 285.929832 -224.359216)
		(stroke
			(width 0.068326)
			(type default)
		)
		(layer "B.Cu")
	)
	(gr_arc
		(start 285.948374 -12.555474)
		(mid 286.421819 -12.744102)
		(end 286.884364 -12.530074)
		(stroke
			(width 0.068326)
			(type default)
		)
		(layer "B.Cu")
	)
	(gr_line
		(start 286.05734 -24.279352)
		(end 286.291782 -24.279352)
		(stroke
			(width 0.068326)
			(type default)
		)
		(layer "B.Cu")
	)
	(gr_arc
		(start 286.100012 -224.770188)
		(mid 286.055774 -224.547791)
		(end 285.929832 -224.359216)
		(stroke
			(width 0.068326)
			(type default)
		)
		(layer "B.Cu")
	)
	(gr_line
		(start 286.100012 -224.770188)
		(end 286.100012 -225.92538)
		(stroke
			(width 0.068326)
			(type default)
		)
		(layer "B.Cu")
	)
	(gr_arc
		(start 286.106362 -222.294704)
		(mid 285.91855 -222.575791)
		(end 285.852616 -222.907352)
		(stroke
			(width 0.068326)
			(type default)
		)
		(layer "B.Cu")
	)
	(gr_arc
		(start 286.134302 -25.33015)
		(mid 286.169621 -24.83994)
		(end 285.75 -24.584152)
		(stroke
			(width 0.068326)
			(type default)
		)
		(layer "B.Cu")
	)
	(gr_arc
		(start 286.134302 -13.930122)
		(mid 286.131267 -13.372467)
		(end 285.8516 -12.889992)
		(stroke
			(width 0.068326)
			(type default)
		)
		(layer "B.Cu")
	)
	(gr_arc
		(start 286.291782 -24.279352)
		(mid 286.635701 -24.18553)
		(end 286.884364 -23.930102)
		(stroke
			(width 0.068326)
			(type default)
		)
		(layer "B.Cu")
	)
	(gr_line
		(start 288.500058 -224.7138)
		(end 288.500058 -225.92538)
		(stroke
			(width 0.068326)
			(type default)
		)
		(layer "B.Cu")
	)
	(gr_line
		(start 288.500058 -224.7138)
		(end 288.500312 -224.713546)
		(stroke
			(width 0.068326)
			(type default)
		)
		(layer "B.Cu")
	)
	(gr_arc
		(start 288.640266 -224.375726)
		(mid 288.536679 -224.530711)
		(end 288.500312 -224.713546)
		(stroke
			(width 0.068326)
			(type default)
		)
		(layer "B.Cu")
	)
	(gr_line
		(start 288.640266 -224.375726)
		(end 288.691066 -224.324926)
		(stroke
			(width 0.068326)
			(type default)
		)
		(layer "B.Cu")
	)
	(gr_arc
		(start 288.691066 -224.324926)
		(mid 288.733192 -224.26188)
		(end 288.747962 -224.187512)
		(stroke
			(width 0.068326)
			(type default)
		)
		(layer "B.Cu")
	)
	(gr_arc
		(start 288.747708 -222.90786)
		(mid 288.6817 -222.576014)
		(end 288.493708 -222.294704)
		(stroke
			(width 0.068326)
			(type default)
		)
		(layer "B.Cu")
	)
	(gr_arc
		(start 289.052762 -224.17278)
		(mid 289.072826 -224.273679)
		(end 289.129978 -224.359216)
		(stroke
			(width 0.068326)
			(type default)
		)
		(layer "B.Cu")
	)
	(gr_arc
		(start 289.300158 -224.770188)
		(mid 289.25592 -224.547791)
		(end 289.129978 -224.359216)
		(stroke
			(width 0.068326)
			(type default)
		)
		(layer "B.Cu")
	)
	(gr_line
		(start 289.300158 -224.770188)
		(end 289.300158 -225.92538)
		(stroke
			(width 0.068326)
			(type default)
		)
		(layer "B.Cu")
	)
	(gr_arc
		(start 289.306508 -222.294704)
		(mid 289.118708 -222.575795)
		(end 289.052762 -222.907352)
		(stroke
			(width 0.068326)
			(type default)
		)
		(layer "B.Cu")
	)
	(gr_line
		(start 290.63442 -13.930122)
		(end 290.95319 -14.248892)
		(stroke
			(width 0.068326)
			(type default)
		)
		(layer "B.Cu")
	)
	(gr_arc
		(start 291.079682 -14.5542)
		(mid 291.046791 -14.388968)
		(end 290.95319 -14.248892)
		(stroke
			(width 0.068326)
			(type default)
		)
		(layer "B.Cu")
	)
	(gr_line
		(start 291.384482 -12.530074)
		(end 291.384482 -14.24686)
		(stroke
			(width 0.068326)
			(type default)
		)
		(layer "B.Cu")
	)
	(gr_line
		(start 291.700204 -224.713546)
		(end 291.700204 -225.92538)
		(stroke
			(width 0.068326)
			(type default)
		)
		(layer "B.Cu")
	)
	(gr_arc
		(start 291.840158 -224.375726)
		(mid 291.736572 -224.530712)
		(end 291.700204 -224.713546)
		(stroke
			(width 0.068326)
			(type default)
		)
		(layer "B.Cu")
	)
	(gr_line
		(start 291.840158 -224.375726)
		(end 291.890958 -224.324926)
		(stroke
			(width 0.068326)
			(type default)
		)
		(layer "B.Cu")
	)
	(gr_arc
		(start 291.890958 -224.324926)
		(mid 291.933084 -224.26188)
		(end 291.947854 -224.187512)
		(stroke
			(width 0.068326)
			(type default)
		)
		(layer "B.Cu")
	)
	(gr_arc
		(start 291.9476 -222.90786)
		(mid 291.881592 -222.576014)
		(end 291.6936 -222.294704)
		(stroke
			(width 0.068326)
			(type default)
		)
		(layer "B.Cu")
	)
	(gr_arc
		(start 292.252654 -224.17278)
		(mid 292.272717 -224.273679)
		(end 292.32987 -224.359216)
		(stroke
			(width 0.068326)
			(type default)
		)
		(layer "B.Cu")
	)
	(gr_arc
		(start 292.50005 -224.770188)
		(mid 292.455812 -224.547791)
		(end 292.32987 -224.359216)
		(stroke
			(width 0.068326)
			(type default)
		)
		(layer "B.Cu")
	)
	(gr_line
		(start 292.50005 -224.770188)
		(end 292.50005 -225.92538)
		(stroke
			(width 0.068326)
			(type default)
		)
		(layer "B.Cu")
	)
	(gr_arc
		(start 292.5064 -222.294704)
		(mid 292.318601 -222.575795)
		(end 292.252654 -222.907352)
		(stroke
			(width 0.068326)
			(type default)
		)
		(layer "B.Cu")
	)
	(gr_line
		(start 294.900096 -224.7138)
		(end 294.900096 -225.92538)
		(stroke
			(width 0.068326)
			(type default)
		)
		(layer "B.Cu")
	)
	(gr_line
		(start 294.900096 -224.7138)
		(end 294.90035 -224.713546)
		(stroke
			(width 0.068326)
			(type default)
		)
		(layer "B.Cu")
	)
	(gr_arc
		(start 295.040304 -224.375726)
		(mid 294.93673 -224.530715)
		(end 294.90035 -224.713546)
		(stroke
			(width 0.068326)
			(type default)
		)
		(layer "B.Cu")
	)
	(gr_line
		(start 295.040304 -224.375726)
		(end 295.091104 -224.324926)
		(stroke
			(width 0.068326)
			(type default)
		)
		(layer "B.Cu")
	)
	(gr_arc
		(start 295.091104 -224.324926)
		(mid 295.13323 -224.26188)
		(end 295.148 -224.187512)
		(stroke
			(width 0.068326)
			(type default)
		)
		(layer "B.Cu")
	)
	(gr_arc
		(start 295.147746 -222.90786)
		(mid 295.081738 -222.576014)
		(end 294.893746 -222.294704)
		(stroke
			(width 0.068326)
			(type default)
		)
		(layer "B.Cu")
	)
	(gr_arc
		(start 295.4528 -224.17278)
		(mid 295.472866 -224.273677)
		(end 295.530016 -224.359216)
		(stroke
			(width 0.068326)
			(type default)
		)
		(layer "B.Cu")
	)
	(gr_arc
		(start 295.700196 -224.770188)
		(mid 295.655958 -224.547791)
		(end 295.530016 -224.359216)
		(stroke
			(width 0.068326)
			(type default)
		)
		(layer "B.Cu")
	)
	(gr_line
		(start 295.700196 -224.770188)
		(end 295.700196 -225.92538)
		(stroke
			(width 0.068326)
			(type default)
		)
		(layer "B.Cu")
	)
	(gr_arc
		(start 295.706546 -222.294704)
		(mid 295.518738 -222.575792)
		(end 295.4528 -222.907352)
		(stroke
			(width 0.068326)
			(type default)
		)
		(layer "B.Cu")
	)
	(gr_line
		(start 299.296836 -13.518896)
		(end 299.384466 -13.930122)
		(stroke
			(width 0.068326)
			(type default)
		)
		(layer "B.Cu")
	)
	(gr_arc
		(start 299.51934 -13.17625)
		(mid 299.337056 -13.30145)
		(end 299.296836 -13.518896)
		(stroke
			(width 0.068326)
			(type default)
		)
		(layer "B.Cu")
	)
	(gr_line
		(start 299.51934 -13.17625)
		(end 299.519594 -13.17625)
		(stroke
			(width 0.068326)
			(type default)
		)
		(layer "B.Cu")
	)
	(gr_arc
		(start 299.86224 -13.3985)
		(mid 299.736946 -13.216416)
		(end 299.519594 -13.17625)
		(stroke
			(width 0.068326)
			(type default)
		)
		(layer "B.Cu")
	)
	(gr_line
		(start 299.86224 -13.3985)
		(end 299.929804 -13.716508)
		(stroke
			(width 0.068326)
			(type default)
		)
		(layer "B.Cu")
	)
	(gr_arc
		(start 300.134274 -12.754864)
		(mid 300.157822 -13.206389)
		(end 300.228254 -13.653008)
		(stroke
			(width 0.068326)
			(type default)
		)
		(layer "B.Cu")
	)
	(gr_line
		(start 300.134274 -12.530074)
		(end 300.134274 -12.754864)
		(stroke
			(width 0.068326)
			(type default)
		)
		(layer "B.Cu")
	)
	(gr_line
		(start 300.500034 -224.7138)
		(end 300.500034 -225.92538)
		(stroke
			(width 0.068326)
			(type default)
		)
		(layer "B.Cu")
	)
	(gr_line
		(start 300.500034 -224.7138)
		(end 300.500288 -224.713546)
		(stroke
			(width 0.068326)
			(type default)
		)
		(layer "B.Cu")
	)
	(gr_arc
		(start 300.640242 -224.375726)
		(mid 300.53666 -224.530713)
		(end 300.500288 -224.713546)
		(stroke
			(width 0.068326)
			(type default)
		)
		(layer "B.Cu")
	)
	(gr_line
		(start 300.640242 -224.375726)
		(end 300.691042 -224.324926)
		(stroke
			(width 0.068326)
			(type default)
		)
		(layer "B.Cu")
	)
	(gr_arc
		(start 300.691042 -224.324926)
		(mid 300.733168 -224.26188)
		(end 300.747938 -224.187512)
		(stroke
			(width 0.068326)
			(type default)
		)
		(layer "B.Cu")
	)
	(gr_arc
		(start 300.747684 -222.90786)
		(mid 300.681676 -222.576014)
		(end 300.493684 -222.294704)
		(stroke
			(width 0.068326)
			(type default)
		)
		(layer "B.Cu")
	)
	(gr_arc
		(start 301.052738 -224.17278)
		(mid 301.072806 -224.273674)
		(end 301.129954 -224.359216)
		(stroke
			(width 0.068326)
			(type default)
		)
		(layer "B.Cu")
	)
	(gr_arc
		(start 301.300134 -224.770188)
		(mid 301.255896 -224.547791)
		(end 301.129954 -224.359216)
		(stroke
			(width 0.068326)
			(type default)
		)
		(layer "B.Cu")
	)
	(gr_line
		(start 301.300134 -224.770188)
		(end 301.300134 -225.92538)
		(stroke
			(width 0.068326)
			(type default)
		)
		(layer "B.Cu")
	)
	(gr_arc
		(start 301.306484 -222.294704)
		(mid 301.118689 -222.575796)
		(end 301.052738 -222.907352)
		(stroke
			(width 0.068326)
			(type default)
		)
		(layer "B.Cu")
	)
	(gr_line
		(start 303.70018 -224.713546)
		(end 303.70018 -225.92538)
		(stroke
			(width 0.068326)
			(type default)
		)
		(layer "B.Cu")
	)
	(gr_arc
		(start 303.840134 -224.375726)
		(mid 303.736553 -224.530713)
		(end 303.70018 -224.713546)
		(stroke
			(width 0.068326)
			(type default)
		)
		(layer "B.Cu")
	)
	(gr_line
		(start 303.840134 -224.375726)
		(end 303.890934 -224.324926)
		(stroke
			(width 0.068326)
			(type default)
		)
		(layer "B.Cu")
	)
	(gr_arc
		(start 303.890934 -224.324926)
		(mid 303.93306 -224.26188)
		(end 303.94783 -224.187512)
		(stroke
			(width 0.068326)
			(type default)
		)
		(layer "B.Cu")
	)
	(gr_arc
		(start 303.94783 -220.8276)
		(mid 303.892161 -220.540118)
		(end 303.7332 -220.2942)
		(stroke
			(width 0.068326)
			(type default)
		)
		(layer "B.Cu")
	)
	(gr_arc
		(start 304.25263 -224.17278)
		(mid 304.272698 -224.273675)
		(end 304.329846 -224.359216)
		(stroke
			(width 0.068326)
			(type default)
		)
		(layer "B.Cu")
	)
	(gr_arc
		(start 304.500026 -224.770188)
		(mid 304.455788 -224.547791)
		(end 304.329846 -224.359216)
		(stroke
			(width 0.068326)
			(type default)
		)
		(layer "B.Cu")
	)
	(gr_line
		(start 304.500026 -224.770188)
		(end 304.500026 -225.92538)
		(stroke
			(width 0.068326)
			(type default)
		)
		(layer "B.Cu")
	)
	(gr_arc
		(start 304.546 -220.2688)
		(mid 304.330398 -220.512025)
		(end 304.25263 -220.8276)
		(stroke
			(width 0.068326)
			(type default)
		)
		(layer "B.Cu")
	)
	(gr_arc
		(start 308.015894 -12.667488)
		(mid 308.485125 -12.819973)
		(end 308.88432 -12.530074)
		(stroke
			(width 0.068326)
			(type default)
		)
		(layer "B.Cu")
	)
	(gr_line
		(start 308.017672 -13.100558)
		(end 308.184804 -13.26769)
		(stroke
			(width 0.068326)
			(type default)
		)
		(layer "B.Cu")
	)
	(gr_arc
		(start 308.134512 -13.930122)
		(mid 308.311808 -13.610454)
		(end 308.184804 -13.26769)
		(stroke
			(width 0.068326)
			(type default)
		)
		(layer "B.Cu")
	)
	(gr_line
		(start 311.700164 -224.713546)
		(end 311.700164 -225.92538)
		(stroke
			(width 0.068326)
			(type default)
		)
		(layer "B.Cu")
	)
	(gr_arc
		(start 311.840118 -224.375726)
		(mid 311.736541 -224.530714)
		(end 311.700164 -224.713546)
		(stroke
			(width 0.068326)
			(type default)
		)
		(layer "B.Cu")
	)
	(gr_line
		(start 311.840118 -224.375726)
		(end 311.890918 -224.324926)
		(stroke
			(width 0.068326)
			(type default)
		)
		(layer "B.Cu")
	)
	(gr_arc
		(start 311.890918 -224.324926)
		(mid 311.933044 -224.26188)
		(end 311.947814 -224.187512)
		(stroke
			(width 0.068326)
			(type default)
		)
		(layer "B.Cu")
	)
	(gr_arc
		(start 311.94756 -222.90786)
		(mid 311.881552 -222.576014)
		(end 311.69356 -222.294704)
		(stroke
			(width 0.068326)
			(type default)
		)
		(layer "B.Cu")
	)
	(gr_line
		(start 312.1152 -4.0132)
		(end 317.4492 -9.3472)
		(stroke
			(width 0.060198)
			(type default)
		)
		(layer "B.Cu")
	)
	(gr_arc
		(start 312.252614 -224.17278)
		(mid 312.272681 -224.273676)
		(end 312.32983 -224.359216)
		(stroke
			(width 0.068326)
			(type default)
		)
		(layer "B.Cu")
	)
	(gr_arc
		(start 312.50001 -224.770188)
		(mid 312.455772 -224.547791)
		(end 312.32983 -224.359216)
		(stroke
			(width 0.068326)
			(type default)
		)
		(layer "B.Cu")
	)
	(gr_line
		(start 312.50001 -224.770188)
		(end 312.50001 -225.92538)
		(stroke
			(width 0.068326)
			(type default)
		)
		(layer "B.Cu")
	)
	(gr_arc
		(start 312.50636 -222.294704)
		(mid 312.318549 -222.575792)
		(end 312.252614 -222.907352)
		(stroke
			(width 0.068326)
			(type default)
		)
		(layer "B.Cu")
	)
	(gr_line
		(start 314.900056 -224.7138)
		(end 314.900056 -225.92538)
		(stroke
			(width 0.068326)
			(type default)
		)
		(layer "B.Cu")
	)
	(gr_line
		(start 314.900056 -224.7138)
		(end 314.90031 -224.713546)
		(stroke
			(width 0.068326)
			(type default)
		)
		(layer "B.Cu")
	)
	(gr_arc
		(start 315.040264 -224.375726)
		(mid 314.936677 -224.530712)
		(end 314.90031 -224.713546)
		(stroke
			(width 0.068326)
			(type default)
		)
		(layer "B.Cu")
	)
	(gr_line
		(start 315.040264 -224.375726)
		(end 315.091064 -224.324926)
		(stroke
			(width 0.068326)
			(type default)
		)
		(layer "B.Cu")
	)
	(gr_arc
		(start 315.091064 -224.324926)
		(mid 315.13319 -224.26188)
		(end 315.14796 -224.187512)
		(stroke
			(width 0.068326)
			(type default)
		)
		(layer "B.Cu")
	)
	(gr_arc
		(start 315.147706 -222.90786)
		(mid 315.081698 -222.576014)
		(end 314.893706 -222.294704)
		(stroke
			(width 0.068326)
			(type default)
		)
		(layer "B.Cu")
	)
	(gr_arc
		(start 315.45276 -224.17278)
		(mid 315.472823 -224.273679)
		(end 315.529976 -224.359216)
		(stroke
			(width 0.068326)
			(type default)
		)
		(layer "B.Cu")
	)
	(gr_arc
		(start 315.700156 -224.770188)
		(mid 315.655918 -224.547791)
		(end 315.529976 -224.359216)
		(stroke
			(width 0.068326)
			(type default)
		)
		(layer "B.Cu")
	)
	(gr_line
		(start 315.700156 -224.770188)
		(end 315.700156 -225.92538)
		(stroke
			(width 0.068326)
			(type default)
		)
		(layer "B.Cu")
	)
	(gr_arc
		(start 315.706506 -222.294704)
		(mid 315.518706 -222.575795)
		(end 315.45276 -222.907352)
		(stroke
			(width 0.068326)
			(type default)
		)
		(layer "B.Cu")
	)
	(gr_line
		(start 317.4492 -18.1102)
		(end 319.13449 -19.79549)
		(stroke
			(width 0.060198)
			(type default)
		)
		(layer "B.Cu")
	)
	(gr_line
		(start 317.4492 -9.3472)
		(end 317.4492 -18.1102)
		(stroke
			(width 0.060198)
			(type default)
		)
		(layer "B.Cu")
	)
	(gr_line
		(start 318.100202 -224.713546)
		(end 318.100202 -225.92538)
		(stroke
			(width 0.068326)
			(type default)
		)
		(layer "B.Cu")
	)
	(gr_arc
		(start 318.240156 -224.375726)
		(mid 318.136571 -224.530712)
		(end 318.100202 -224.713546)
		(stroke
			(width 0.068326)
			(type default)
		)
		(layer "B.Cu")
	)
	(gr_line
		(start 318.240156 -224.375726)
		(end 318.290956 -224.324926)
		(stroke
			(width 0.068326)
			(type default)
		)
		(layer "B.Cu")
	)
	(gr_arc
		(start 318.290956 -224.324926)
		(mid 318.333082 -224.26188)
		(end 318.347852 -224.187512)
		(stroke
			(width 0.068326)
			(type default)
		)
		(layer "B.Cu")
	)
	(gr_arc
		(start 318.347598 -222.90786)
		(mid 318.28159 -222.576014)
		(end 318.093598 -222.294704)
		(stroke
			(width 0.068326)
			(type default)
		)
		(layer "B.Cu")
	)
	(gr_arc
		(start 318.652652 -224.17278)
		(mid 318.672715 -224.273679)
		(end 318.729868 -224.359216)
		(stroke
			(width 0.068326)
			(type default)
		)
		(layer "B.Cu")
	)
	(gr_arc
		(start 318.900048 -224.770188)
		(mid 318.85581 -224.547791)
		(end 318.729868 -224.359216)
		(stroke
			(width 0.068326)
			(type default)
		)
		(layer "B.Cu")
	)
	(gr_line
		(start 318.900048 -224.770188)
		(end 318.900048 -225.92538)
		(stroke
			(width 0.068326)
			(type default)
		)
		(layer "B.Cu")
	)
	(gr_arc
		(start 318.906398 -222.294704)
		(mid 318.7186 -222.575795)
		(end 318.652652 -222.907352)
		(stroke
			(width 0.068326)
			(type default)
		)
		(layer "B.Cu")
	)
	(gr_line
		(start 319.13449 -19.79549)
		(end 319.13449 -21.530056)
		(stroke
			(width 0.060198)
			(type default)
		)
		(layer "B.Cu")
	)
	(gr_line
		(start 321.300094 -224.7138)
		(end 321.300094 -225.92538)
		(stroke
			(width 0.068326)
			(type default)
		)
		(layer "B.Cu")
	)
	(gr_line
		(start 321.300094 -224.7138)
		(end 321.300348 -224.713546)
		(stroke
			(width 0.068326)
			(type default)
		)
		(layer "B.Cu")
	)
	(gr_arc
		(start 321.440302 -224.375726)
		(mid 321.336728 -224.530715)
		(end 321.300348 -224.713546)
		(stroke
			(width 0.068326)
			(type default)
		)
		(layer "B.Cu")
	)
	(gr_line
		(start 321.440302 -224.375726)
		(end 321.491102 -224.324926)
		(stroke
			(width 0.068326)
			(type default)
		)
		(layer "B.Cu")
	)
	(gr_arc
		(start 321.491102 -224.324926)
		(mid 321.533228 -224.26188)
		(end 321.547998 -224.187512)
		(stroke
			(width 0.068326)
			(type default)
		)
		(layer "B.Cu")
	)
	(gr_arc
		(start 321.547744 -222.90786)
		(mid 321.481736 -222.576014)
		(end 321.293744 -222.294704)
		(stroke
			(width 0.068326)
			(type default)
		)
		(layer "B.Cu")
	)
	(gr_arc
		(start 321.852798 -224.17278)
		(mid 321.872864 -224.273677)
		(end 321.930014 -224.359216)
		(stroke
			(width 0.068326)
			(type default)
		)
		(layer "B.Cu")
	)
	(gr_arc
		(start 322.100194 -224.770188)
		(mid 322.055956 -224.547791)
		(end 321.930014 -224.359216)
		(stroke
			(width 0.068326)
			(type default)
		)
		(layer "B.Cu")
	)
	(gr_line
		(start 322.100194 -224.770188)
		(end 322.100194 -225.92538)
		(stroke
			(width 0.068326)
			(type default)
		)
		(layer "B.Cu")
	)
	(gr_arc
		(start 322.106544 -222.294704)
		(mid 321.918736 -222.575793)
		(end 321.852798 -222.907352)
		(stroke
			(width 0.068326)
			(type default)
		)
		(layer "B.Cu")
	)
	(gr_line
		(start 324.50024 -224.713546)
		(end 324.50024 -225.92538)
		(stroke
			(width 0.068326)
			(type default)
		)
		(layer "B.Cu")
	)
	(gr_arc
		(start 324.640194 -224.375726)
		(mid 324.536622 -224.530715)
		(end 324.50024 -224.713546)
		(stroke
			(width 0.068326)
			(type default)
		)
		(layer "B.Cu")
	)
	(gr_line
		(start 324.640194 -224.375726)
		(end 324.690994 -224.324926)
		(stroke
			(width 0.068326)
			(type default)
		)
		(layer "B.Cu")
	)
	(gr_arc
		(start 324.690994 -224.324926)
		(mid 324.73312 -224.26188)
		(end 324.74789 -224.187512)
		(stroke
			(width 0.068326)
			(type default)
		)
		(layer "B.Cu")
	)
	(gr_arc
		(start 324.747636 -222.90786)
		(mid 324.681628 -222.576014)
		(end 324.493636 -222.294704)
		(stroke
			(width 0.068326)
			(type default)
		)
		(layer "B.Cu")
	)
	(gr_arc
		(start 325.05269 -224.17278)
		(mid 325.072755 -224.273677)
		(end 325.129906 -224.359216)
		(stroke
			(width 0.068326)
			(type default)
		)
		(layer "B.Cu")
	)
	(gr_arc
		(start 325.300086 -224.770188)
		(mid 325.255848 -224.547791)
		(end 325.129906 -224.359216)
		(stroke
			(width 0.068326)
			(type default)
		)
		(layer "B.Cu")
	)
	(gr_line
		(start 325.300086 -224.770188)
		(end 325.300086 -225.92538)
		(stroke
			(width 0.068326)
			(type default)
		)
		(layer "B.Cu")
	)
	(gr_arc
		(start 325.306436 -222.294704)
		(mid 325.11863 -222.575793)
		(end 325.05269 -222.907352)
		(stroke
			(width 0.068326)
			(type default)
		)
		(layer "B.Cu")
	)
	(gr_line
		(start 327.700132 -224.7138)
		(end 327.700132 -225.92538)
		(stroke
			(width 0.068326)
			(type default)
		)
		(layer "B.Cu")
	)
	(gr_line
		(start 327.700132 -224.7138)
		(end 327.700386 -224.713546)
		(stroke
			(width 0.068326)
			(type default)
		)
		(layer "B.Cu")
	)
	(gr_line
		(start 327.7997 -165.4302)
		(end 328.313034 -164.916866)
		(stroke
			(width 0.060198)
			(type default)
		)
		(layer "B.Cu")
	)
	(gr_arc
		(start 327.84034 -224.375726)
		(mid 327.736758 -224.530713)
		(end 327.700386 -224.713546)
		(stroke
			(width 0.068326)
			(type default)
		)
		(layer "B.Cu")
	)
	(gr_line
		(start 327.84034 -224.375726)
		(end 327.89114 -224.324926)
		(stroke
			(width 0.068326)
			(type default)
		)
		(layer "B.Cu")
	)
	(gr_arc
		(start 327.89114 -224.324926)
		(mid 327.933266 -224.26188)
		(end 327.948036 -224.187512)
		(stroke
			(width 0.068326)
			(type default)
		)
		(layer "B.Cu")
	)
	(gr_arc
		(start 327.947782 -222.90786)
		(mid 327.881774 -222.576014)
		(end 327.693782 -222.294704)
		(stroke
			(width 0.068326)
			(type default)
		)
		(layer "B.Cu")
	)
	(gr_arc
		(start 328.252836 -224.17278)
		(mid 328.272904 -224.273675)
		(end 328.330052 -224.359216)
		(stroke
			(width 0.068326)
			(type default)
		)
		(layer "B.Cu")
	)
	(gr_arc
		(start 328.500232 -224.770188)
		(mid 328.455994 -224.547791)
		(end 328.330052 -224.359216)
		(stroke
			(width 0.068326)
			(type default)
		)
		(layer "B.Cu")
	)
	(gr_line
		(start 328.500232 -224.770188)
		(end 328.500232 -225.92538)
		(stroke
			(width 0.068326)
			(type default)
		)
		(layer "B.Cu")
	)
	(gr_arc
		(start 328.506582 -222.294704)
		(mid 328.318787 -222.575796)
		(end 328.252836 -222.907352)
		(stroke
			(width 0.068326)
			(type default)
		)
		(layer "B.Cu")
	)
	(gr_line
		(start 329.026266 -164.916866)
		(end 329.5396 -165.4302)
		(stroke
			(width 0.060198)
			(type default)
		)
		(layer "B.Cu")
	)
	(gr_line
		(start 330.900024 -224.7138)
		(end 330.900024 -225.92538)
		(stroke
			(width 0.068326)
			(type default)
		)
		(layer "B.Cu")
	)
	(gr_line
		(start 330.900024 -224.7138)
		(end 330.900278 -224.713546)
		(stroke
			(width 0.068326)
			(type default)
		)
		(layer "B.Cu")
	)
	(gr_arc
		(start 331.040232 -224.375726)
		(mid 330.936652 -224.530713)
		(end 330.900278 -224.713546)
		(stroke
			(width 0.068326)
			(type default)
		)
		(layer "B.Cu")
	)
	(gr_line
		(start 331.040232 -224.375726)
		(end 331.091032 -224.324926)
		(stroke
			(width 0.068326)
			(type default)
		)
		(layer "B.Cu")
	)
	(gr_arc
		(start 331.091032 -224.324926)
		(mid 331.133158 -224.26188)
		(end 331.147928 -224.187512)
		(stroke
			(width 0.068326)
			(type default)
		)
		(layer "B.Cu")
	)
	(gr_arc
		(start 331.147674 -222.90786)
		(mid 331.081666 -222.576014)
		(end 330.893674 -222.294704)
		(stroke
			(width 0.068326)
			(type default)
		)
		(layer "B.Cu")
	)
	(gr_arc
		(start 331.452728 -224.17278)
		(mid 331.472796 -224.273675)
		(end 331.529944 -224.359216)
		(stroke
			(width 0.068326)
			(type default)
		)
		(layer "B.Cu")
	)
	(gr_arc
		(start 331.700124 -224.770188)
		(mid 331.655886 -224.547791)
		(end 331.529944 -224.359216)
		(stroke
			(width 0.068326)
			(type default)
		)
		(layer "B.Cu")
	)
	(gr_line
		(start 331.700124 -224.770188)
		(end 331.700124 -225.92538)
		(stroke
			(width 0.068326)
			(type default)
		)
		(layer "B.Cu")
	)
	(gr_arc
		(start 331.706474 -222.294704)
		(mid 331.518681 -222.575796)
		(end 331.452728 -222.907352)
		(stroke
			(width 0.068326)
			(type default)
		)
		(layer "B.Cu")
	)
	(gr_line
		(start 334.10017 -224.713546)
		(end 334.10017 -225.92538)
		(stroke
			(width 0.068326)
			(type default)
		)
		(layer "B.Cu")
	)
	(gr_arc
		(start 334.240124 -224.375726)
		(mid 334.136545 -224.530714)
		(end 334.10017 -224.713546)
		(stroke
			(width 0.068326)
			(type default)
		)
		(layer "B.Cu")
	)
	(gr_line
		(start 334.240124 -224.375726)
		(end 334.290924 -224.324926)
		(stroke
			(width 0.068326)
			(type default)
		)
		(layer "B.Cu")
	)
	(gr_arc
		(start 334.290924 -224.324926)
		(mid 334.33305 -224.26188)
		(end 334.34782 -224.187512)
		(stroke
			(width 0.068326)
			(type default)
		)
		(layer "B.Cu")
	)
	(gr_arc
		(start 334.347566 -222.90786)
		(mid 334.281558 -222.576014)
		(end 334.093566 -222.294704)
		(stroke
			(width 0.068326)
			(type default)
		)
		(layer "B.Cu")
	)
	(gr_arc
		(start 334.65262 -224.17278)
		(mid 334.672687 -224.273675)
		(end 334.729836 -224.359216)
		(stroke
			(width 0.068326)
			(type default)
		)
		(layer "B.Cu")
	)
	(gr_arc
		(start 334.900016 -224.770188)
		(mid 334.855778 -224.547791)
		(end 334.729836 -224.359216)
		(stroke
			(width 0.068326)
			(type default)
		)
		(layer "B.Cu")
	)
	(gr_line
		(start 334.900016 -224.770188)
		(end 334.900016 -225.92538)
		(stroke
			(width 0.068326)
			(type default)
		)
		(layer "B.Cu")
	)
	(gr_arc
		(start 334.906366 -222.294704)
		(mid 334.718553 -222.575791)
		(end 334.65262 -222.907352)
		(stroke
			(width 0.068326)
			(type default)
		)
		(layer "B.Cu")
	)
	(gr_line
		(start 337.300062 -224.7138)
		(end 337.300062 -225.92538)
		(stroke
			(width 0.068326)
			(type default)
		)
		(layer "B.Cu")
	)
	(gr_line
		(start 337.300062 -224.7138)
		(end 337.300316 -224.713546)
		(stroke
			(width 0.068326)
			(type default)
		)
		(layer "B.Cu")
	)
	(gr_arc
		(start 337.44027 -224.375726)
		(mid 337.336682 -224.530711)
		(end 337.300316 -224.713546)
		(stroke
			(width 0.068326)
			(type default)
		)
		(layer "B.Cu")
	)
	(gr_line
		(start 337.44027 -224.375726)
		(end 337.49107 -224.324926)
		(stroke
			(width 0.068326)
			(type default)
		)
		(layer "B.Cu")
	)
	(gr_arc
		(start 337.49107 -224.324926)
		(mid 337.533196 -224.26188)
		(end 337.547966 -224.187512)
		(stroke
			(width 0.068326)
			(type default)
		)
		(layer "B.Cu")
	)
	(gr_arc
		(start 337.547712 -222.90786)
		(mid 337.481704 -222.576014)
		(end 337.293712 -222.294704)
		(stroke
			(width 0.068326)
			(type default)
		)
		(layer "B.Cu")
	)
	(gr_arc
		(start 337.852766 -224.17278)
		(mid 337.87283 -224.273678)
		(end 337.929982 -224.359216)
		(stroke
			(width 0.068326)
			(type default)
		)
		(layer "B.Cu")
	)
	(gr_arc
		(start 338.100162 -224.770188)
		(mid 338.055924 -224.547791)
		(end 337.929982 -224.359216)
		(stroke
			(width 0.068326)
			(type default)
		)
		(layer "B.Cu")
	)
	(gr_line
		(start 338.100162 -224.770188)
		(end 338.100162 -225.92538)
		(stroke
			(width 0.068326)
			(type default)
		)
		(layer "B.Cu")
	)
	(gr_arc
		(start 338.106512 -222.294704)
		(mid 337.918711 -222.575794)
		(end 337.852766 -222.907352)
		(stroke
			(width 0.068326)
			(type default)
		)
		(layer "B.Cu")
	)
	(gr_line
		(start 340.500208 -224.713546)
		(end 340.500208 -225.92538)
		(stroke
			(width 0.068326)
			(type default)
		)
		(layer "B.Cu")
	)
	(gr_arc
		(start 340.640162 -224.375726)
		(mid 340.536575 -224.530712)
		(end 340.500208 -224.713546)
		(stroke
			(width 0.068326)
			(type default)
		)
		(layer "B.Cu")
	)
	(gr_line
		(start 340.640162 -224.375726)
		(end 340.690962 -224.324926)
		(stroke
			(width 0.068326)
			(type default)
		)
		(layer "B.Cu")
	)
	(gr_arc
		(start 340.690962 -224.324926)
		(mid 340.733088 -224.26188)
		(end 340.747858 -224.187512)
		(stroke
			(width 0.068326)
			(type default)
		)
		(layer "B.Cu")
	)
	(gr_arc
		(start 340.747604 -222.90786)
		(mid 340.681596 -222.576014)
		(end 340.493604 -222.294704)
		(stroke
			(width 0.068326)
			(type default)
		)
		(layer "B.Cu")
	)
	(gr_arc
		(start 341.052658 -224.17278)
		(mid 341.072721 -224.273679)
		(end 341.129874 -224.359216)
		(stroke
			(width 0.068326)
			(type default)
		)
		(layer "B.Cu")
	)
	(gr_arc
		(start 341.300054 -224.770188)
		(mid 341.255816 -224.547791)
		(end 341.129874 -224.359216)
		(stroke
			(width 0.068326)
			(type default)
		)
		(layer "B.Cu")
	)
	(gr_line
		(start 341.300054 -224.770188)
		(end 341.300054 -225.92538)
		(stroke
			(width 0.068326)
			(type default)
		)
		(layer "B.Cu")
	)
	(gr_arc
		(start 341.306404 -222.294704)
		(mid 341.118604 -222.575795)
		(end 341.052658 -222.907352)
		(stroke
			(width 0.068326)
			(type default)
		)
		(layer "B.Cu")
	)
	(gr_line
		(start 0 -212.499956)
		(end 0 -28.010104)
		(stroke
			(width 1.524)
			(type default)
		)
		(layer "In1.Cu")
	)
	(gr_arc
		(start 0 -212.499956)
		(mid 0.292895 -213.207058)
		(end 0.999998 -213.499954)
		(stroke
			(width 1.524)
			(type default)
		)
		(layer "In1.Cu")
	)
	(gr_arc
		(start 1.999996 -26.010108)
		(mid 0.585785 -26.595893)
		(end 0 -28.010104)
		(stroke
			(width 1.524)
			(type default)
		)
		(layer "In1.Cu")
	)
	(gr_line
		(start 1.999996 -26.010108)
		(end 49.950116 -26.010108)
		(stroke
			(width 1.524)
			(type default)
		)
		(layer "In1.Cu")
	)
	(gr_line
		(start 5.461 -195.58)
		(end 5.461 -189.738)
		(stroke
			(width 0.381)
			(type default)
		)
		(layer "In1.Cu")
	)
	(gr_line
		(start 5.461 -189.738)
		(end 6.096 -189.103)
		(stroke
			(width 0.381)
			(type default)
		)
		(layer "In1.Cu")
	)
	(gr_line
		(start 5.715 -74.3458)
		(end 5.9944 -74.6252)
		(stroke
			(width 0.381)
			(type default)
		)
		(layer "In1.Cu")
	)
	(gr_line
		(start 5.715 -67.6402)
		(end 5.715 -74.3458)
		(stroke
			(width 0.381)
			(type default)
		)
		(layer "In1.Cu")
	)
	(gr_line
		(start 5.8166 -91.2876)
		(end 5.8166 -82.8548)
		(stroke
			(width 0.381)
			(type default)
		)
		(layer "In1.Cu")
	)
	(gr_line
		(start 5.8166 -82.8548)
		(end 6.223 -82.4484)
		(stroke
			(width 0.381)
			(type default)
		)
		(layer "In1.Cu")
	)
	(gr_line
		(start 5.969 -67.3862)
		(end 5.715 -67.6402)
		(stroke
			(width 0.381)
			(type default)
		)
		(layer "In1.Cu")
	)
	(gr_line
		(start 5.9944 -74.6252)
		(end 9.0424 -74.6252)
		(stroke
			(width 0.381)
			(type default)
		)
		(layer "In1.Cu")
	)
	(gr_line
		(start 6.096 -189.103)
		(end 8.636 -189.103)
		(stroke
			(width 0.381)
			(type default)
		)
		(layer "In1.Cu")
	)
	(gr_line
		(start 6.1976 -91.6686)
		(end 5.8166 -91.2876)
		(stroke
			(width 0.381)
			(type default)
		)
		(layer "In1.Cu")
	)
	(gr_line
		(start 6.223 -82.4484)
		(end 11.557 -82.4484)
		(stroke
			(width 0.381)
			(type default)
		)
		(layer "In1.Cu")
	)
	(gr_line
		(start 7.112 -181.483)
		(end 7.112 -179.197)
		(stroke
			(width 0.381)
			(type default)
		)
		(layer "In1.Cu")
	)
	(gr_line
		(start 7.112 -179.197)
		(end 8.128 -178.181)
		(stroke
			(width 0.381)
			(type default)
		)
		(layer "In1.Cu")
	)
	(gr_line
		(start 7.2898 -91.6686)
		(end 6.1976 -91.6686)
		(stroke
			(width 0.381)
			(type default)
		)
		(layer "In1.Cu")
	)
	(gr_line
		(start 7.747 -182.118)
		(end 7.112 -181.483)
		(stroke
			(width 0.381)
			(type default)
		)
		(layer "In1.Cu")
	)
	(gr_line
		(start 7.8232 -91.1352)
		(end 7.2898 -91.6686)
		(stroke
			(width 0.381)
			(type default)
		)
		(layer "In1.Cu")
	)
	(gr_line
		(start 8.128 -178.181)
		(end 15.24 -178.181)
		(stroke
			(width 0.381)
			(type default)
		)
		(layer "In1.Cu")
	)
	(gr_line
		(start 8.636 -189.103)
		(end 10.033 -187.706)
		(stroke
			(width 0.381)
			(type default)
		)
		(layer "In1.Cu")
	)
	(gr_line
		(start 8.89 -67.3862)
		(end 5.969 -67.3862)
		(stroke
			(width 0.381)
			(type default)
		)
		(layer "In1.Cu")
	)
	(gr_line
		(start 9.017 -199.136)
		(end 5.461 -195.58)
		(stroke
			(width 0.381)
			(type default)
		)
		(layer "In1.Cu")
	)
	(gr_line
		(start 9.0424 -74.6252)
		(end 10.2362 -73.4314)
		(stroke
			(width 0.381)
			(type default)
		)
		(layer "In1.Cu")
	)
	(gr_line
		(start 9.144 -182.118)
		(end 7.747 -182.118)
		(stroke
			(width 0.381)
			(type default)
		)
		(layer "In1.Cu")
	)
	(gr_line
		(start 9.6647 -55.559452)
		(end 10.477246 -55.559452)
		(stroke
			(width 0.2)
			(type default)
		)
		(layer "In1.Cu")
	)
	(gr_arc
		(start 9.6647 -54.538372)
		(mid 9.15416 -55.048912)
		(end 9.6647 -55.559452)
		(stroke
			(width 0.2)
			(type default)
		)
		(layer "In1.Cu")
	)
	(gr_line
		(start 10.033 -187.706)
		(end 11.049 -187.706)
		(stroke
			(width 0.381)
			(type default)
		)
		(layer "In1.Cu")
	)
	(gr_line
		(start 10.2362 -73.4314)
		(end 10.2362 -68.7324)
		(stroke
			(width 0.381)
			(type default)
		)
		(layer "In1.Cu")
	)
	(gr_line
		(start 10.2362 -68.7324)
		(end 8.89 -67.3862)
		(stroke
			(width 0.381)
			(type default)
		)
		(layer "In1.Cu")
	)
	(gr_line
		(start 10.287 -183.261)
		(end 9.144 -182.118)
		(stroke
			(width 0.381)
			(type default)
		)
		(layer "In1.Cu")
	)
	(gr_arc
		(start 10.477246 -55.559452)
		(mid 10.98804 -55.049039)
		(end 10.4775 -54.538372)
		(stroke
			(width 0.2)
			(type default)
		)
		(layer "In1.Cu")
	)
	(gr_line
		(start 10.4775 -54.538372)
		(end 9.6647 -54.538372)
		(stroke
			(width 0.2)
			(type default)
		)
		(layer "In1.Cu")
	)
	(gr_line
		(start 11.049 -187.706)
		(end 11.811 -186.944)
		(stroke
			(width 0.381)
			(type default)
		)
		(layer "In1.Cu")
	)
	(gr_line
		(start 11.2268 -91.1352)
		(end 7.8232 -91.1352)
		(stroke
			(width 0.381)
			(type default)
		)
		(layer "In1.Cu")
	)
	(gr_line
		(start 11.557 -82.4484)
		(end 12.1412 -83.0326)
		(stroke
			(width 0.381)
			(type default)
		)
		(layer "In1.Cu")
	)
	(gr_line
		(start 11.811 -186.944)
		(end 11.811 -185.166)
		(stroke
			(width 0.381)
			(type default)
		)
		(layer "In1.Cu")
	)
	(gr_line
		(start 11.811 -185.166)
		(end 12.446 -184.531)
		(stroke
			(width 0.381)
			(type default)
		)
		(layer "In1.Cu")
	)
	(gr_line
		(start 12.1412 -90.2208)
		(end 11.2268 -91.1352)
		(stroke
			(width 0.381)
			(type default)
		)
		(layer "In1.Cu")
	)
	(gr_line
		(start 12.1412 -83.0326)
		(end 12.1412 -90.2208)
		(stroke
			(width 0.381)
			(type default)
		)
		(layer "In1.Cu")
	)
	(gr_line
		(start 12.192 -183.261)
		(end 10.287 -183.261)
		(stroke
			(width 0.381)
			(type default)
		)
		(layer "In1.Cu")
	)
	(gr_line
		(start 12.446 -184.531)
		(end 12.446 -183.515)
		(stroke
			(width 0.381)
			(type default)
		)
		(layer "In1.Cu")
	)
	(gr_line
		(start 12.446 -183.515)
		(end 12.192 -183.261)
		(stroke
			(width 0.381)
			(type default)
		)
		(layer "In1.Cu")
	)
	(gr_line
		(start 13.5636 -54.340252)
		(end 14.3764 -54.340252)
		(stroke
			(width 0.2)
			(type default)
		)
		(layer "In1.Cu")
	)
	(gr_arc
		(start 13.563854 -53.319172)
		(mid 13.05306 -53.829585)
		(end 13.5636 -54.340252)
		(stroke
			(width 0.2)
			(type default)
		)
		(layer "In1.Cu")
	)
	(gr_arc
		(start 13.66266 -68.451222)
		(mid 14.1732 -68.961762)
		(end 14.68374 -68.451222)
		(stroke
			(width 0.2)
			(type default)
		)
		(layer "In1.Cu")
	)
	(gr_line
		(start 13.66266 -67.638422)
		(end 13.66266 -68.451222)
		(stroke
			(width 0.2)
			(type default)
		)
		(layer "In1.Cu")
	)
	(gr_arc
		(start 14.3764 -54.340252)
		(mid 14.88694 -53.829712)
		(end 14.3764 -53.319172)
		(stroke
			(width 0.2)
			(type default)
		)
		(layer "In1.Cu")
	)
	(gr_line
		(start 14.3764 -53.319172)
		(end 13.563854 -53.319172)
		(stroke
			(width 0.2)
			(type default)
		)
		(layer "In1.Cu")
	)
	(gr_line
		(start 14.605 -184.785)
		(end 14.859 -185.039)
		(stroke
			(width 0.381)
			(type default)
		)
		(layer "In1.Cu")
	)
	(gr_line
		(start 14.605 -183.388)
		(end 14.605 -184.785)
		(stroke
			(width 0.381)
			(type default)
		)
		(layer "In1.Cu")
	)
	(gr_line
		(start 14.68374 -68.451222)
		(end 14.68374 -67.638676)
		(stroke
			(width 0.2)
			(type default)
		)
		(layer "In1.Cu")
	)
	(gr_arc
		(start 14.68374 -67.638676)
		(mid 14.173327 -67.127882)
		(end 13.66266 -67.638422)
		(stroke
			(width 0.2)
			(type default)
		)
		(layer "In1.Cu")
	)
	(gr_line
		(start 14.859 -185.039)
		(end 15.24 -185.039)
		(stroke
			(width 0.381)
			(type default)
		)
		(layer "In1.Cu")
	)
	(gr_line
		(start 15.24 -185.039)
		(end 15.494 -185.293)
		(stroke
			(width 0.381)
			(type default)
		)
		(layer "In1.Cu")
	)
	(gr_line
		(start 15.24 -178.181)
		(end 16.256 -179.197)
		(stroke
			(width 0.381)
			(type default)
		)
		(layer "In1.Cu")
	)
	(gr_line
		(start 15.494 -187.198)
		(end 15.748 -187.452)
		(stroke
			(width 0.381)
			(type default)
		)
		(layer "In1.Cu")
	)
	(gr_line
		(start 15.494 -185.293)
		(end 15.494 -187.198)
		(stroke
			(width 0.381)
			(type default)
		)
		(layer "In1.Cu")
	)
	(gr_arc
		(start 15.66926 -67.03695)
		(mid 16.1798 -67.54749)
		(end 16.69034 -67.03695)
		(stroke
			(width 0.2)
			(type default)
		)
		(layer "In1.Cu")
	)
	(gr_line
		(start 15.66926 -66.22415)
		(end 15.66926 -67.03695)
		(stroke
			(width 0.2)
			(type default)
		)
		(layer "In1.Cu")
	)
	(gr_line
		(start 15.748 -187.452)
		(end 18.415 -187.452)
		(stroke
			(width 0.381)
			(type default)
		)
		(layer "In1.Cu")
	)
	(gr_line
		(start 15.7988 -73.727564)
		(end 16.6116 -73.727564)
		(stroke
			(width 0.2)
			(type default)
		)
		(layer "In1.Cu")
	)
	(gr_arc
		(start 15.799054 -72.706484)
		(mid 15.28826 -73.216897)
		(end 15.7988 -73.727564)
		(stroke
			(width 0.2)
			(type default)
		)
		(layer "In1.Cu")
	)
	(gr_line
		(start 15.8496 -87.65794)
		(end 16.9672 -87.65794)
		(stroke
			(width 0.2)
			(type default)
		)
		(layer "In1.Cu")
	)
	(gr_arc
		(start 15.8496 -86.43366)
		(mid 15.23746 -87.0458)
		(end 15.8496 -87.65794)
		(stroke
			(width 0.2)
			(type default)
		)
		(layer "In1.Cu")
	)
	(gr_line
		(start 16.256 -181.737)
		(end 14.605 -183.388)
		(stroke
			(width 0.381)
			(type default)
		)
		(layer "In1.Cu")
	)
	(gr_line
		(start 16.256 -179.197)
		(end 16.256 -181.737)
		(stroke
			(width 0.381)
			(type default)
		)
		(layer "In1.Cu")
	)
	(gr_arc
		(start 16.6116 -73.727564)
		(mid 17.12214 -73.217024)
		(end 16.6116 -72.706484)
		(stroke
			(width 0.2)
			(type default)
		)
		(layer "In1.Cu")
	)
	(gr_line
		(start 16.6116 -72.706484)
		(end 15.799054 -72.706484)
		(stroke
			(width 0.2)
			(type default)
		)
		(layer "In1.Cu")
	)
	(gr_line
		(start 16.69034 -67.03695)
		(end 16.69034 -66.224404)
		(stroke
			(width 0.2)
			(type default)
		)
		(layer "In1.Cu")
	)
	(gr_arc
		(start 16.69034 -66.224404)
		(mid 16.179927 -65.71361)
		(end 15.66926 -66.22415)
		(stroke
			(width 0.2)
			(type default)
		)
		(layer "In1.Cu")
	)
	(gr_arc
		(start 16.9672 -87.65794)
		(mid 17.57934 -87.0458)
		(end 16.9672 -86.43366)
		(stroke
			(width 0.2)
			(type default)
		)
		(layer "In1.Cu")
	)
	(gr_line
		(start 16.9672 -86.43366)
		(end 15.8496 -86.43366)
		(stroke
			(width 0.2)
			(type default)
		)
		(layer "In1.Cu")
	)
	(gr_line
		(start 18.415 -187.452)
		(end 19.304 -186.563)
		(stroke
			(width 0.381)
			(type default)
		)
		(layer "In1.Cu")
	)
	(gr_line
		(start 18.57375 -73.721214)
		(end 19.38655 -73.721214)
		(stroke
			(width 0.2)
			(type default)
		)
		(layer "In1.Cu")
	)
	(gr_arc
		(start 18.574004 -72.700134)
		(mid 18.06321 -73.210547)
		(end 18.57375 -73.721214)
		(stroke
			(width 0.2)
			(type default)
		)
		(layer "In1.Cu")
	)
	(gr_line
		(start 18.6944 -58.851546)
		(end 19.812 -58.851546)
		(stroke
			(width 0.2)
			(type default)
		)
		(layer "In1.Cu")
	)
	(gr_arc
		(start 18.6944 -57.627266)
		(mid 18.08226 -58.239406)
		(end 18.6944 -58.851546)
		(stroke
			(width 0.2)
			(type default)
		)
		(layer "In1.Cu")
	)
	(gr_line
		(start 18.8468 -55.508652)
		(end 19.659346 -55.508652)
		(stroke
			(width 0.2)
			(type default)
		)
		(layer "In1.Cu")
	)
	(gr_arc
		(start 18.8468 -54.487572)
		(mid 18.33626 -54.998112)
		(end 18.8468 -55.508652)
		(stroke
			(width 0.2)
			(type default)
		)
		(layer "In1.Cu")
	)
	(gr_line
		(start 18.852134 -82.41792)
		(end 19.664934 -82.41792)
		(stroke
			(width 0.2)
			(type default)
		)
		(layer "In1.Cu")
	)
	(gr_arc
		(start 18.852388 -81.39684)
		(mid 18.341594 -81.907253)
		(end 18.852134 -82.41792)
		(stroke
			(width 0.2)
			(type default)
		)
		(layer "In1.Cu")
	)
	(gr_line
		(start 19.304 -186.563)
		(end 23.495 -186.563)
		(stroke
			(width 0.381)
			(type default)
		)
		(layer "In1.Cu")
	)
	(gr_arc
		(start 19.38655 -73.721214)
		(mid 19.89709 -73.210674)
		(end 19.38655 -72.700134)
		(stroke
			(width 0.2)
			(type default)
		)
		(layer "In1.Cu")
	)
	(gr_line
		(start 19.38655 -72.700134)
		(end 18.574004 -72.700134)
		(stroke
			(width 0.2)
			(type default)
		)
		(layer "In1.Cu")
	)
	(gr_arc
		(start 19.659346 -55.508652)
		(mid 20.17014 -54.998239)
		(end 19.6596 -54.487572)
		(stroke
			(width 0.2)
			(type default)
		)
		(layer "In1.Cu")
	)
	(gr_line
		(start 19.6596 -54.487572)
		(end 18.8468 -54.487572)
		(stroke
			(width 0.2)
			(type default)
		)
		(layer "In1.Cu")
	)
	(gr_arc
		(start 19.664934 -82.41792)
		(mid 20.175474 -81.90738)
		(end 19.664934 -81.39684)
		(stroke
			(width 0.2)
			(type default)
		)
		(layer "In1.Cu")
	)
	(gr_line
		(start 19.664934 -81.39684)
		(end 18.852388 -81.39684)
		(stroke
			(width 0.2)
			(type default)
		)
		(layer "In1.Cu")
	)
	(gr_arc
		(start 19.812 -58.851546)
		(mid 20.42414 -58.239406)
		(end 19.812 -57.627266)
		(stroke
			(width 0.2)
			(type default)
		)
		(layer "In1.Cu")
	)
	(gr_line
		(start 19.812 -57.627266)
		(end 18.6944 -57.627266)
		(stroke
			(width 0.2)
			(type default)
		)
		(layer "In1.Cu")
	)
	(gr_arc
		(start 20.3454 -84.4804)
		(mid 20.375158 -84.552242)
		(end 20.447 -84.582)
		(stroke
			(width 0.2)
			(type default)
		)
		(layer "In1.Cu")
	)
	(gr_line
		(start 20.3454 -83.1596)
		(end 20.3454 -84.4804)
		(stroke
			(width 0.2)
			(type default)
		)
		(layer "In1.Cu")
	)
	(gr_line
		(start 20.3962 -87.93734)
		(end 21.209 -87.93734)
		(stroke
			(width 0.2)
			(type default)
		)
		(layer "In1.Cu")
	)
	(gr_arc
		(start 20.396454 -86.91626)
		(mid 19.88566 -87.426673)
		(end 20.3962 -87.93734)
		(stroke
			(width 0.2)
			(type default)
		)
		(layer "In1.Cu")
	)
	(gr_line
		(start 20.447 -84.582)
		(end 21.717 -84.582)
		(stroke
			(width 0.2)
			(type default)
		)
		(layer "In1.Cu")
	)
	(gr_arc
		(start 20.447 -83.058)
		(mid 20.375158 -83.087758)
		(end 20.3454 -83.1596)
		(stroke
			(width 0.2)
			(type default)
		)
		(layer "In1.Cu")
	)
	(gr_arc
		(start 21.209 -87.93734)
		(mid 21.71954 -87.4268)
		(end 21.209 -86.91626)
		(stroke
			(width 0.2)
			(type default)
		)
		(layer "In1.Cu")
	)
	(gr_line
		(start 21.209 -86.91626)
		(end 20.396454 -86.91626)
		(stroke
			(width 0.2)
			(type default)
		)
		(layer "In1.Cu")
	)
	(gr_arc
		(start 21.717 -84.582)
		(mid 21.788842 -84.552242)
		(end 21.8186 -84.4804)
		(stroke
			(width 0.2)
			(type default)
		)
		(layer "In1.Cu")
	)
	(gr_line
		(start 21.717 -83.058)
		(end 20.447 -83.058)
		(stroke
			(width 0.2)
			(type default)
		)
		(layer "In1.Cu")
	)
	(gr_line
		(start 21.8186 -84.4804)
		(end 21.8186 -83.1596)
		(stroke
			(width 0.2)
			(type default)
		)
		(layer "In1.Cu")
	)
	(gr_arc
		(start 21.8186 -83.1596)
		(mid 21.788842 -83.087758)
		(end 21.717 -83.058)
		(stroke
			(width 0.2)
			(type default)
		)
		(layer "In1.Cu")
	)
	(gr_arc
		(start 21.933154 -124.5235)
		(mid 21.970351 -124.613303)
		(end 22.060154 -124.6505)
		(stroke
			(width 0.2)
			(type default)
		)
		(layer "In1.Cu")
	)
	(gr_line
		(start 21.933154 -123.2281)
		(end 21.933154 -124.5235)
		(stroke
			(width 0.2)
			(type default)
		)
		(layer "In1.Cu")
	)
	(gr_line
		(start 22.060154 -124.6505)
		(end 23.380954 -124.6505)
		(stroke
			(width 0.2)
			(type default)
		)
		(layer "In1.Cu")
	)
	(gr_arc
		(start 22.060154 -123.1011)
		(mid 21.970351 -123.138297)
		(end 21.933154 -123.2281)
		(stroke
			(width 0.2)
			(type default)
		)
		(layer "In1.Cu")
	)
	(gr_line
		(start 22.417786 -57.300876)
		(end 23.535386 -57.300876)
		(stroke
			(width 0.2)
			(type default)
		)
		(layer "In1.Cu")
	)
	(gr_arc
		(start 22.417786 -56.076596)
		(mid 21.805646 -56.688736)
		(end 22.417786 -57.300876)
		(stroke
			(width 0.2)
			(type default)
		)
		(layer "In1.Cu")
	)
	(gr_arc
		(start 22.55266 -115.1128)
		(mid 23.1648 -115.72494)
		(end 23.77694 -115.1128)
		(stroke
			(width 0.2)
			(type default)
		)
		(layer "In1.Cu")
	)
	(gr_line
		(start 22.55266 -113.9952)
		(end 22.55266 -115.1128)
		(stroke
			(width 0.2)
			(type default)
		)
		(layer "In1.Cu")
	)
	(gr_line
		(start 22.5552 -54.066694)
		(end 23.368 -54.066694)
		(stroke
			(width 0.2)
			(type default)
		)
		(layer "In1.Cu")
	)
	(gr_arc
		(start 22.555454 -53.045614)
		(mid 22.04466 -53.556027)
		(end 22.5552 -54.066694)
		(stroke
			(width 0.2)
			(type default)
		)
		(layer "In1.Cu")
	)
	(gr_line
		(start 22.733 -199.136)
		(end 9.017 -199.136)
		(stroke
			(width 0.381)
			(type default)
		)
		(layer "In1.Cu")
	)
	(gr_arc
		(start 23.368 -54.066694)
		(mid 23.87854 -53.556154)
		(end 23.368 -53.045614)
		(stroke
			(width 0.2)
			(type default)
		)
		(layer "In1.Cu")
	)
	(gr_line
		(start 23.368 -53.045614)
		(end 22.555454 -53.045614)
		(stroke
			(width 0.2)
			(type default)
		)
		(layer "In1.Cu")
	)
	(gr_arc
		(start 23.380954 -124.6505)
		(mid 23.470757 -124.613303)
		(end 23.507954 -124.5235)
		(stroke
			(width 0.2)
			(type default)
		)
		(layer "In1.Cu")
	)
	(gr_line
		(start 23.380954 -123.1011)
		(end 22.060154 -123.1011)
		(stroke
			(width 0.2)
			(type default)
		)
		(layer "In1.Cu")
	)
	(gr_line
		(start 23.495 -186.563)
		(end 24.638 -187.706)
		(stroke
			(width 0.381)
			(type default)
		)
		(layer "In1.Cu")
	)
	(gr_line
		(start 23.495 -149.5044)
		(end 23.6474 -149.6568)
		(stroke
			(width 0.381)
			(type default)
		)
		(layer "In1.Cu")
	)
	(gr_line
		(start 23.495 -148.971)
		(end 23.495 -149.5044)
		(stroke
			(width 0.381)
			(type default)
		)
		(layer "In1.Cu")
	)
	(gr_line
		(start 23.495 -145.415)
		(end 23.495 -148.971)
		(stroke
			(width 0.381)
			(type default)
		)
		(layer "In1.Cu")
	)
	(gr_line
		(start 23.507954 -124.5235)
		(end 23.507954 -123.2281)
		(stroke
			(width 0.2)
			(type default)
		)
		(layer "In1.Cu")
	)
	(gr_arc
		(start 23.507954 -123.2281)
		(mid 23.470757 -123.138297)
		(end 23.380954 -123.1011)
		(stroke
			(width 0.2)
			(type default)
		)
		(layer "In1.Cu")
	)
	(gr_arc
		(start 23.535386 -57.300876)
		(mid 24.147526 -56.688736)
		(end 23.535386 -56.076596)
		(stroke
			(width 0.2)
			(type default)
		)
		(layer "In1.Cu")
	)
	(gr_line
		(start 23.535386 -56.076596)
		(end 22.417786 -56.076596)
		(stroke
			(width 0.2)
			(type default)
		)
		(layer "In1.Cu")
	)
	(gr_line
		(start 23.6474 -149.6568)
		(end 26.3398 -149.6568)
		(stroke
			(width 0.381)
			(type default)
		)
		(layer "In1.Cu")
	)
	(gr_line
		(start 23.77694 -115.1128)
		(end 23.77694 -113.995454)
		(stroke
			(width 0.2)
			(type default)
		)
		(layer "In1.Cu")
	)
	(gr_arc
		(start 23.77694 -113.995454)
		(mid 23.164927 -113.38306)
		(end 22.55266 -113.9952)
		(stroke
			(width 0.2)
			(type default)
		)
		(layer "In1.Cu")
	)
	(gr_arc
		(start 23.861014 -112.521746)
		(mid 24.473027 -113.13414)
		(end 25.085294 -112.522)
		(stroke
			(width 0.2)
			(type default)
		)
		(layer "In1.Cu")
	)
	(gr_line
		(start 23.861014 -111.4044)
		(end 23.861014 -112.521746)
		(stroke
			(width 0.2)
			(type default)
		)
		(layer "In1.Cu")
	)
	(gr_line
		(start 24.0538 -144.8562)
		(end 23.495 -145.415)
		(stroke
			(width 0.381)
			(type default)
		)
		(layer "In1.Cu")
	)
	(gr_arc
		(start 24.112982 -109.586522)
		(mid 24.143484 -109.66016)
		(end 24.217122 -109.690662)
		(stroke
			(width 0.2)
			(type default)
		)
		(layer "In1.Cu")
	)
	(gr_line
		(start 24.112982 -109.230922)
		(end 24.112982 -109.586522)
		(stroke
			(width 0.2)
			(type default)
		)
		(layer "In1.Cu")
	)
	(gr_arc
		(start 24.113744 -108.56722)
		(mid 24.144246 -108.640858)
		(end 24.217884 -108.67136)
		(stroke
			(width 0.2)
			(type default)
		)
		(layer "In1.Cu")
	)
	(gr_line
		(start 24.113744 -108.21162)
		(end 24.113744 -108.56722)
		(stroke
			(width 0.2)
			(type default)
		)
		(layer "In1.Cu")
	)
	(gr_line
		(start 24.217122 -109.690662)
		(end 24.572722 -109.690662)
		(stroke
			(width 0.2)
			(type default)
		)
		(layer "In1.Cu")
	)
	(gr_arc
		(start 24.217122 -109.126782)
		(mid 24.143484 -109.157284)
		(end 24.112982 -109.230922)
		(stroke
			(width 0.2)
			(type default)
		)
		(layer "In1.Cu")
	)
	(gr_line
		(start 24.217884 -108.67136)
		(end 24.573484 -108.67136)
		(stroke
			(width 0.2)
			(type default)
		)
		(layer "In1.Cu")
	)
	(gr_arc
		(start 24.217884 -108.10748)
		(mid 24.144246 -108.137982)
		(end 24.113744 -108.21162)
		(stroke
			(width 0.2)
			(type default)
		)
		(layer "In1.Cu")
	)
	(gr_arc
		(start 24.4475 -126.188978)
		(mid 24.463123 -126.226695)
		(end 24.50084 -126.242318)
		(stroke
			(width 0.2)
			(type default)
		)
		(layer "In1.Cu")
	)
	(gr_line
		(start 24.4475 -125.934978)
		(end 24.4475 -126.188978)
		(stroke
			(width 0.2)
			(type default)
		)
		(layer "In1.Cu")
	)
	(gr_arc
		(start 24.4475 -125.630178)
		(mid 24.463123 -125.667895)
		(end 24.50084 -125.683518)
		(stroke
			(width 0.2)
			(type default)
		)
		(layer "In1.Cu")
	)
	(gr_line
		(start 24.4475 -125.376178)
		(end 24.4475 -125.630178)
		(stroke
			(width 0.2)
			(type default)
		)
		(layer "In1.Cu")
	)
	(gr_line
		(start 24.50084 -126.242318)
		(end 24.70404 -126.242318)
		(stroke
			(width 0.2)
			(type default)
		)
		(layer "In1.Cu")
	)
	(gr_arc
		(start 24.50084 -125.881638)
		(mid 24.463123 -125.897261)
		(end 24.4475 -125.934978)
		(stroke
			(width 0.2)
			(type default)
		)
		(layer "In1.Cu")
	)
	(gr_line
		(start 24.50084 -125.683518)
		(end 24.70404 -125.683518)
		(stroke
			(width 0.2)
			(type default)
		)
		(layer "In1.Cu")
	)
	(gr_arc
		(start 24.50084 -125.322838)
		(mid 24.463123 -125.338461)
		(end 24.4475 -125.376178)
		(stroke
			(width 0.2)
			(type default)
		)
		(layer "In1.Cu")
	)
	(gr_arc
		(start 24.572722 -109.690662)
		(mid 24.64636 -109.66016)
		(end 24.676862 -109.586522)
		(stroke
			(width 0.2)
			(type default)
		)
		(layer "In1.Cu")
	)
	(gr_line
		(start 24.572722 -109.126782)
		(end 24.217122 -109.126782)
		(stroke
			(width 0.2)
			(type default)
		)
		(layer "In1.Cu")
	)
	(gr_arc
		(start 24.573484 -108.67136)
		(mid 24.647122 -108.640858)
		(end 24.677624 -108.56722)
		(stroke
			(width 0.2)
			(type default)
		)
		(layer "In1.Cu")
	)
	(gr_line
		(start 24.573484 -108.10748)
		(end 24.217884 -108.10748)
		(stroke
			(width 0.2)
			(type default)
		)
		(layer "In1.Cu")
	)
	(gr_line
		(start 24.638 -197.231)
		(end 22.733 -199.136)
		(stroke
			(width 0.381)
			(type default)
		)
		(layer "In1.Cu")
	)
	(gr_line
		(start 24.638 -189.865)
		(end 24.638 -197.231)
		(stroke
			(width 0.381)
			(type default)
		)
		(layer "In1.Cu")
	)
	(gr_line
		(start 24.638 -187.706)
		(end 24.638 -189.865)
		(stroke
			(width 0.381)
			(type default)
		)
		(layer "In1.Cu")
	)
	(gr_line
		(start 24.676862 -109.586522)
		(end 24.676862 -109.230922)
		(stroke
			(width 0.2)
			(type default)
		)
		(layer "In1.Cu")
	)
	(gr_arc
		(start 24.676862 -109.230922)
		(mid 24.64636 -109.157284)
		(end 24.572722 -109.126782)
		(stroke
			(width 0.2)
			(type default)
		)
		(layer "In1.Cu")
	)
	(gr_line
		(start 24.677624 -108.56722)
		(end 24.677624 -108.21162)
		(stroke
			(width 0.2)
			(type default)
		)
		(layer "In1.Cu")
	)
	(gr_arc
		(start 24.677624 -108.21162)
		(mid 24.647122 -108.137982)
		(end 24.573484 -108.10748)
		(stroke
			(width 0.2)
			(type default)
		)
		(layer "In1.Cu")
	)
	(gr_arc
		(start 24.70404 -126.242318)
		(mid 24.741757 -126.226695)
		(end 24.75738 -126.188978)
		(stroke
			(width 0.2)
			(type default)
		)
		(layer "In1.Cu")
	)
	(gr_line
		(start 24.70404 -125.881638)
		(end 24.50084 -125.881638)
		(stroke
			(width 0.2)
			(type default)
		)
		(layer "In1.Cu")
	)
	(gr_arc
		(start 24.70404 -125.683518)
		(mid 24.741757 -125.667895)
		(end 24.75738 -125.630178)
		(stroke
			(width 0.2)
			(type default)
		)
		(layer "In1.Cu")
	)
	(gr_line
		(start 24.70404 -125.322838)
		(end 24.50084 -125.322838)
		(stroke
			(width 0.2)
			(type default)
		)
		(layer "In1.Cu")
	)
	(gr_line
		(start 24.75738 -126.188978)
		(end 24.75738 -125.934978)
		(stroke
			(width 0.2)
			(type default)
		)
		(layer "In1.Cu")
	)
	(gr_arc
		(start 24.75738 -125.934978)
		(mid 24.741757 -125.897261)
		(end 24.70404 -125.881638)
		(stroke
			(width 0.2)
			(type default)
		)
		(layer "In1.Cu")
	)
	(gr_line
		(start 24.75738 -125.630178)
		(end 24.75738 -125.376178)
		(stroke
			(width 0.2)
			(type default)
		)
		(layer "In1.Cu")
	)
	(gr_arc
		(start 24.75738 -125.376178)
		(mid 24.741757 -125.338461)
		(end 24.70404 -125.322838)
		(stroke
			(width 0.2)
			(type default)
		)
		(layer "In1.Cu")
	)
	(gr_line
		(start 25.085294 -112.522)
		(end 25.085294 -111.4044)
		(stroke
			(width 0.2)
			(type default)
		)
		(layer "In1.Cu")
	)
	(gr_arc
		(start 25.085294 -111.4044)
		(mid 24.473154 -110.79226)
		(end 23.861014 -111.4044)
		(stroke
			(width 0.2)
			(type default)
		)
		(layer "In1.Cu")
	)
	(gr_arc
		(start 25.137364 -109.58322)
		(mid 25.167866 -109.656858)
		(end 25.241504 -109.68736)
		(stroke
			(width 0.2)
			(type default)
		)
		(layer "In1.Cu")
	)
	(gr_line
		(start 25.137364 -109.22762)
		(end 25.137364 -109.58322)
		(stroke
			(width 0.2)
			(type default)
		)
		(layer "In1.Cu")
	)
	(gr_arc
		(start 25.138126 -108.563918)
		(mid 25.168628 -108.637556)
		(end 25.242266 -108.668058)
		(stroke
			(width 0.2)
			(type default)
		)
		(layer "In1.Cu")
	)
	(gr_line
		(start 25.138126 -108.208318)
		(end 25.138126 -108.563918)
		(stroke
			(width 0.2)
			(type default)
		)
		(layer "In1.Cu")
	)
	(gr_line
		(start 25.241504 -109.68736)
		(end 25.597104 -109.68736)
		(stroke
			(width 0.2)
			(type default)
		)
		(layer "In1.Cu")
	)
	(gr_arc
		(start 25.241504 -109.12348)
		(mid 25.167866 -109.153982)
		(end 25.137364 -109.22762)
		(stroke
			(width 0.2)
			(type default)
		)
		(layer "In1.Cu")
	)
	(gr_line
		(start 25.242266 -108.668058)
		(end 25.597866 -108.668058)
		(stroke
			(width 0.2)
			(type default)
		)
		(layer "In1.Cu")
	)
	(gr_arc
		(start 25.242266 -108.104178)
		(mid 25.168628 -108.13468)
		(end 25.138126 -108.208318)
		(stroke
			(width 0.2)
			(type default)
		)
		(layer "In1.Cu")
	)
	(gr_line
		(start 25.4 -213.499954)
		(end 0.999998 -213.499954)
		(stroke
			(width 1.524)
			(type default)
		)
		(layer "In1.Cu")
	)
	(gr_arc
		(start 25.51684 -143.69796)
		(mid 26.12898 -144.3101)
		(end 26.74112 -143.69796)
		(stroke
			(width 0.2)
			(type default)
		)
		(layer "In1.Cu")
	)
	(gr_line
		(start 25.51684 -142.58036)
		(end 25.51684 -143.69796)
		(stroke
			(width 0.2)
			(type default)
		)
		(layer "In1.Cu")
	)
	(gr_arc
		(start 25.597104 -109.68736)
		(mid 25.670742 -109.656858)
		(end 25.701244 -109.58322)
		(stroke
			(width 0.2)
			(type default)
		)
		(layer "In1.Cu")
	)
	(gr_line
		(start 25.597104 -109.12348)
		(end 25.241504 -109.12348)
		(stroke
			(width 0.2)
			(type default)
		)
		(layer "In1.Cu")
	)
	(gr_arc
		(start 25.597866 -108.668058)
		(mid 25.671504 -108.637556)
		(end 25.702006 -108.563918)
		(stroke
			(width 0.2)
			(type default)
		)
		(layer "In1.Cu")
	)
	(gr_line
		(start 25.597866 -108.104178)
		(end 25.242266 -108.104178)
		(stroke
			(width 0.2)
			(type default)
		)
		(layer "In1.Cu")
	)
	(gr_line
		(start 25.701244 -109.58322)
		(end 25.701244 -109.22762)
		(stroke
			(width 0.2)
			(type default)
		)
		(layer "In1.Cu")
	)
	(gr_arc
		(start 25.701244 -109.22762)
		(mid 25.670742 -109.153982)
		(end 25.597104 -109.12348)
		(stroke
			(width 0.2)
			(type default)
		)
		(layer "In1.Cu")
	)
	(gr_line
		(start 25.702006 -108.563918)
		(end 25.702006 -108.208318)
		(stroke
			(width 0.2)
			(type default)
		)
		(layer "In1.Cu")
	)
	(gr_arc
		(start 25.702006 -108.208318)
		(mid 25.671504 -108.13468)
		(end 25.597866 -108.104178)
		(stroke
			(width 0.2)
			(type default)
		)
		(layer "In1.Cu")
	)
	(gr_line
		(start 25.7302 -144.8562)
		(end 24.0538 -144.8562)
		(stroke
			(width 0.381)
			(type default)
		)
		(layer "In1.Cu")
	)
	(gr_line
		(start 26.123392 -109.521244)
		(end 26.124408 -109.52226)
		(stroke
			(width 0.2)
			(type default)
		)
		(layer "In1.Cu")
	)
	(gr_line
		(start 26.123392 -108.255816)
		(end 26.123392 -109.521244)
		(stroke
			(width 0.2)
			(type default)
		)
		(layer "In1.Cu")
	)
	(gr_arc
		(start 26.124408 -109.52988)
		(mid 26.15491 -109.603518)
		(end 26.228548 -109.63402)
		(stroke
			(width 0.2)
			(type default)
		)
		(layer "In1.Cu")
	)
	(gr_line
		(start 26.124408 -109.52226)
		(end 26.124408 -109.52988)
		(stroke
			(width 0.2)
			(type default)
		)
		(layer "In1.Cu")
	)
	(gr_arc
		(start 26.227532 -108.151676)
		(mid 26.153894 -108.182178)
		(end 26.123392 -108.255816)
		(stroke
			(width 0.2)
			(type default)
		)
		(layer "In1.Cu")
	)
	(gr_line
		(start 26.228548 -109.63402)
		(end 27.549348 -109.63402)
		(stroke
			(width 0.2)
			(type default)
		)
		(layer "In1.Cu")
	)
	(gr_line
		(start 26.3398 -149.6568)
		(end 26.5176 -149.479)
		(stroke
			(width 0.381)
			(type default)
		)
		(layer "In1.Cu")
	)
	(gr_line
		(start 26.5176 -149.479)
		(end 26.5176 -145.6436)
		(stroke
			(width 0.381)
			(type default)
		)
		(layer "In1.Cu")
	)
	(gr_line
		(start 26.5176 -145.6436)
		(end 25.7302 -144.8562)
		(stroke
			(width 0.381)
			(type default)
		)
		(layer "In1.Cu")
	)
	(gr_line
		(start 26.699972 -221.400116)
		(end 26.699972 -214.799926)
		(stroke
			(width 1.524)
			(type default)
		)
		(layer "In1.Cu")
	)
	(gr_arc
		(start 26.699972 -221.400116)
		(mid 26.846532 -221.75362)
		(end 27.200098 -221.899988)
		(stroke
			(width 1.524)
			(type default)
		)
		(layer "In1.Cu")
	)
	(gr_arc
		(start 26.699972 -214.799926)
		(mid 26.319219 -213.880707)
		(end 25.4 -213.499954)
		(stroke
			(width 1.524)
			(type default)
		)
		(layer "In1.Cu")
	)
	(gr_line
		(start 26.74112 -143.69796)
		(end 26.74112 -142.580614)
		(stroke
			(width 0.2)
			(type default)
		)
		(layer "In1.Cu")
	)
	(gr_arc
		(start 26.74112 -142.580614)
		(mid 26.129107 -141.96822)
		(end 25.51684 -142.58036)
		(stroke
			(width 0.2)
			(type default)
		)
		(layer "In1.Cu")
	)
	(gr_arc
		(start 26.9494 -143.8148)
		(mid 26.986597 -143.904603)
		(end 27.0764 -143.9418)
		(stroke
			(width 0.2)
			(type default)
		)
		(layer "In1.Cu")
	)
	(gr_line
		(start 26.9494 -142.4432)
		(end 26.9494 -143.8148)
		(stroke
			(width 0.2)
			(type default)
		)
		(layer "In1.Cu")
	)
	(gr_line
		(start 27.0764 -143.9418)
		(end 28.2956 -143.9418)
		(stroke
			(width 0.2)
			(type default)
		)
		(layer "In1.Cu")
	)
	(gr_arc
		(start 27.0764 -142.3162)
		(mid 26.986597 -142.353397)
		(end 26.9494 -142.4432)
		(stroke
			(width 0.2)
			(type default)
		)
		(layer "In1.Cu")
	)
	(gr_line
		(start 27.548332 -108.151676)
		(end 26.227532 -108.151676)
		(stroke
			(width 0.2)
			(type default)
		)
		(layer "In1.Cu")
	)
	(gr_arc
		(start 27.549348 -109.63402)
		(mid 27.622986 -109.603518)
		(end 27.653488 -109.52988)
		(stroke
			(width 0.2)
			(type default)
		)
		(layer "In1.Cu")
	)
	(gr_line
		(start 27.60853 -106.369612)
		(end 28.398978 -107.16006)
		(stroke
			(width 0.2)
			(type default)
		)
		(layer "In1.Cu")
	)
	(gr_line
		(start 27.610308 -106.367834)
		(end 27.60853 -106.369612)
		(stroke
			(width 0.2)
			(type default)
		)
		(layer "In1.Cu")
	)
	(gr_line
		(start 27.652472 -109.109002)
		(end 27.652472 -108.255816)
		(stroke
			(width 0.2)
			(type default)
		)
		(layer "In1.Cu")
	)
	(gr_arc
		(start 27.652472 -108.255816)
		(mid 27.62197 -108.182178)
		(end 27.548332 -108.151676)
		(stroke
			(width 0.2)
			(type default)
		)
		(layer "In1.Cu")
	)
	(gr_line
		(start 27.653488 -109.52988)
		(end 27.653488 -109.12348)
		(stroke
			(width 0.2)
			(type default)
		)
		(layer "In1.Cu")
	)
	(gr_arc
		(start 27.653488 -109.12348)
		(mid 27.653235 -109.116223)
		(end 27.652472 -109.109002)
		(stroke
			(width 0.2)
			(type default)
		)
		(layer "In1.Cu")
	)
	(gr_line
		(start 27.999944 -221.899988)
		(end 27.200098 -221.899988)
		(stroke
			(width 1.524)
			(type default)
		)
		(layer "In1.Cu")
	)
	(gr_arc
		(start 28.2956 -143.9418)
		(mid 28.385403 -143.904603)
		(end 28.4226 -143.8148)
		(stroke
			(width 0.2)
			(type default)
		)
		(layer "In1.Cu")
	)
	(gr_line
		(start 28.2956 -142.3162)
		(end 27.0764 -142.3162)
		(stroke
			(width 0.2)
			(type default)
		)
		(layer "In1.Cu")
	)
	(gr_line
		(start 28.398978 -107.16006)
		(end 28.400756 -107.158282)
		(stroke
			(width 0.2)
			(type default)
		)
		(layer "In1.Cu")
	)
	(gr_arc
		(start 28.400756 -107.158282)
		(mid 29.266388 -107.158282)
		(end 29.266388 -106.29265)
		(stroke
			(width 0.2)
			(type default)
		)
		(layer "In1.Cu")
	)
	(gr_line
		(start 28.4226 -143.8148)
		(end 28.4226 -142.804134)
		(stroke
			(width 0.2)
			(type default)
		)
		(layer "In1.Cu")
	)
	(gr_arc
		(start 28.4226 -142.804134)
		(mid 28.422625 -142.801467)
		(end 28.4226 -142.7988)
		(stroke
			(width 0.2)
			(type default)
		)
		(layer "In1.Cu")
	)
	(gr_line
		(start 28.4226 -142.7988)
		(end 28.4226 -142.4432)
		(stroke
			(width 0.2)
			(type default)
		)
		(layer "In1.Cu")
	)
	(gr_arc
		(start 28.4226 -142.4432)
		(mid 28.385403 -142.353397)
		(end 28.2956 -142.3162)
		(stroke
			(width 0.2)
			(type default)
		)
		(layer "In1.Cu")
	)
	(gr_arc
		(start 28.47594 -105.502202)
		(mid 27.610308 -105.502202)
		(end 27.610308 -106.367834)
		(stroke
			(width 0.2)
			(type default)
		)
		(layer "In1.Cu")
	)
	(gr_line
		(start 28.477464 -105.500678)
		(end 28.47594 -105.502202)
		(stroke
			(width 0.2)
			(type default)
		)
		(layer "In1.Cu")
	)
	(gr_line
		(start 28.477972 -105.500678)
		(end 28.477464 -105.500678)
		(stroke
			(width 0.2)
			(type default)
		)
		(layer "In1.Cu")
	)
	(gr_line
		(start 28.50007 -228.000052)
		(end 28.50007 -222.400114)
		(stroke
			(width 1.524)
			(type default)
		)
		(layer "In1.Cu")
	)
	(gr_arc
		(start 28.50007 -222.400114)
		(mid 28.353586 -222.046472)
		(end 27.999944 -221.899988)
		(stroke
			(width 1.524)
			(type default)
		)
		(layer "In1.Cu")
	)
	(gr_line
		(start 29.266388 -106.29265)
		(end 29.268166 -106.290872)
		(stroke
			(width 0.2)
			(type default)
		)
		(layer "In1.Cu")
	)
	(gr_line
		(start 29.268166 -106.290872)
		(end 28.477972 -105.500678)
		(stroke
			(width 0.2)
			(type default)
		)
		(layer "In1.Cu")
	)
	(gr_arc
		(start 48.06188 -213.080854)
		(mid 48.099077 -213.170657)
		(end 48.18888 -213.207854)
		(stroke
			(width 0.2)
			(type default)
		)
		(layer "In1.Cu")
	)
	(gr_line
		(start 48.06188 -211.760054)
		(end 48.06188 -213.080854)
		(stroke
			(width 0.2)
			(type default)
		)
		(layer "In1.Cu")
	)
	(gr_line
		(start 48.18888 -213.207854)
		(end 48.59528 -213.207854)
		(stroke
			(width 0.2)
			(type default)
		)
		(layer "In1.Cu")
	)
	(gr_arc
		(start 48.18888 -211.633054)
		(mid 48.099077 -211.670251)
		(end 48.06188 -211.760054)
		(stroke
			(width 0.2)
			(type default)
		)
		(layer "In1.Cu")
	)
	(gr_line
		(start 48.49368 -211.406994)
		(end 49.30648 -211.406994)
		(stroke
			(width 0.2)
			(type default)
		)
		(layer "In1.Cu")
	)
	(gr_arc
		(start 48.493934 -210.385914)
		(mid 47.98314 -210.896327)
		(end 48.49368 -211.406994)
		(stroke
			(width 0.2)
			(type default)
		)
		(layer "In1.Cu")
	)
	(gr_line
		(start 48.59528 -213.207854)
		(end 48.595534 -213.2076)
		(stroke
			(width 0.2)
			(type default)
		)
		(layer "In1.Cu")
	)
	(gr_line
		(start 48.595534 -213.2076)
		(end 49.196752 -213.2076)
		(stroke
			(width 0.2)
			(type default)
		)
		(layer "In1.Cu")
	)
	(gr_arc
		(start 49.196752 -213.2076)
		(mid 49.200814 -213.207795)
		(end 49.20488 -213.207854)
		(stroke
			(width 0.2)
			(type default)
		)
		(layer "In1.Cu")
	)
	(gr_line
		(start 49.20488 -213.207854)
		(end 49.61128 -213.207854)
		(stroke
			(width 0.2)
			(type default)
		)
		(layer "In1.Cu")
	)
	(gr_arc
		(start 49.30648 -211.406994)
		(mid 49.81702 -210.896454)
		(end 49.30648 -210.385914)
		(stroke
			(width 0.2)
			(type default)
		)
		(layer "In1.Cu")
	)
	(gr_line
		(start 49.30648 -210.385914)
		(end 48.493934 -210.385914)
		(stroke
			(width 0.2)
			(type default)
		)
		(layer "In1.Cu")
	)
	(gr_arc
		(start 49.61128 -213.207854)
		(mid 49.701083 -213.170657)
		(end 49.73828 -213.080854)
		(stroke
			(width 0.2)
			(type default)
		)
		(layer "In1.Cu")
	)
	(gr_line
		(start 49.61128 -211.633054)
		(end 48.18888 -211.633054)
		(stroke
			(width 0.2)
			(type default)
		)
		(layer "In1.Cu")
	)
	(gr_line
		(start 49.73828 -213.080854)
		(end 49.73828 -211.760054)
		(stroke
			(width 0.2)
			(type default)
		)
		(layer "In1.Cu")
	)
	(gr_arc
		(start 49.73828 -211.760054)
		(mid 49.701083 -211.670251)
		(end 49.61128 -211.633054)
		(stroke
			(width 0.2)
			(type default)
		)
		(layer "In1.Cu")
	)
	(gr_arc
		(start 49.950116 -26.010108)
		(mid 51.364327 -25.424323)
		(end 51.950112 -24.010112)
		(stroke
			(width 1.524)
			(type default)
		)
		(layer "In1.Cu")
	)
	(gr_line
		(start 50.093372 -221.916244)
		(end 50.905918 -221.916244)
		(stroke
			(width 0.2)
			(type default)
		)
		(layer "In1.Cu")
	)
	(gr_arc
		(start 50.093372 -220.895164)
		(mid 49.582832 -221.405704)
		(end 50.093372 -221.916244)
		(stroke
			(width 0.2)
			(type default)
		)
		(layer "In1.Cu")
	)
	(gr_line
		(start 50.14468 -209.222594)
		(end 50.95748 -209.222594)
		(stroke
			(width 0.2)
			(type default)
		)
		(layer "In1.Cu")
	)
	(gr_arc
		(start 50.144934 -208.201514)
		(mid 49.63414 -208.711927)
		(end 50.14468 -209.222594)
		(stroke
			(width 0.2)
			(type default)
		)
		(layer "In1.Cu")
	)
	(gr_arc
		(start 50.905918 -221.916244)
		(mid 51.416712 -221.405831)
		(end 50.906172 -220.895164)
		(stroke
			(width 0.2)
			(type default)
		)
		(layer "In1.Cu")
	)
	(gr_line
		(start 50.906172 -220.895164)
		(end 50.093372 -220.895164)
		(stroke
			(width 0.2)
			(type default)
		)
		(layer "In1.Cu")
	)
	(gr_arc
		(start 50.95748 -209.222594)
		(mid 51.46802 -208.712054)
		(end 50.95748 -208.201514)
		(stroke
			(width 0.2)
			(type default)
		)
		(layer "In1.Cu")
	)
	(gr_line
		(start 50.95748 -208.201514)
		(end 50.144934 -208.201514)
		(stroke
			(width 0.2)
			(type default)
		)
		(layer "In1.Cu")
	)
	(gr_arc
		(start 51.261772 -213.080854)
		(mid 51.298969 -213.170657)
		(end 51.388772 -213.207854)
		(stroke
			(width 0.2)
			(type default)
		)
		(layer "In1.Cu")
	)
	(gr_line
		(start 51.261772 -211.760054)
		(end 51.261772 -213.080854)
		(stroke
			(width 0.2)
			(type default)
		)
		(layer "In1.Cu")
	)
	(gr_line
		(start 51.388772 -213.207854)
		(end 51.795172 -213.207854)
		(stroke
			(width 0.2)
			(type default)
		)
		(layer "In1.Cu")
	)
	(gr_arc
		(start 51.388772 -211.633054)
		(mid 51.298969 -211.670251)
		(end 51.261772 -211.760054)
		(stroke
			(width 0.2)
			(type default)
		)
		(layer "In1.Cu")
	)
	(gr_line
		(start 51.693572 -211.406994)
		(end 52.506372 -211.406994)
		(stroke
			(width 0.2)
			(type default)
		)
		(layer "In1.Cu")
	)
	(gr_arc
		(start 51.693826 -210.385914)
		(mid 51.183032 -210.896327)
		(end 51.693572 -211.406994)
		(stroke
			(width 0.2)
			(type default)
		)
		(layer "In1.Cu")
	)
	(gr_line
		(start 51.795172 -213.207854)
		(end 51.795426 -213.2076)
		(stroke
			(width 0.2)
			(type default)
		)
		(layer "In1.Cu")
	)
	(gr_line
		(start 51.795426 -213.2076)
		(end 52.396644 -213.2076)
		(stroke
			(width 0.2)
			(type default)
		)
		(layer "In1.Cu")
	)
	(gr_line
		(start 51.950112 -24.010112)
		(end 51.950112 -1.999996)
		(stroke
			(width 1.524)
			(type default)
		)
		(layer "In1.Cu")
	)
	(gr_arc
		(start 52.396644 -213.2076)
		(mid 52.400706 -213.207795)
		(end 52.404772 -213.207854)
		(stroke
			(width 0.2)
			(type default)
		)
		(layer "In1.Cu")
	)
	(gr_line
		(start 52.399438 -48.387508)
		(end 53.305964 -48.387508)
		(stroke
			(width 0.2)
			(type default)
		)
		(layer "In1.Cu")
	)
	(gr_arc
		(start 52.399692 -47.366428)
		(mid 51.888898 -47.876841)
		(end 52.399438 -48.387508)
		(stroke
			(width 0.2)
			(type default)
		)
		(layer "In1.Cu")
	)
	(gr_line
		(start 52.404772 -213.207854)
		(end 52.811172 -213.207854)
		(stroke
			(width 0.2)
			(type default)
		)
		(layer "In1.Cu")
	)
	(gr_arc
		(start 52.506372 -211.406994)
		(mid 53.016912 -210.896454)
		(end 52.506372 -210.385914)
		(stroke
			(width 0.2)
			(type default)
		)
		(layer "In1.Cu")
	)
	(gr_line
		(start 52.506372 -210.385914)
		(end 51.693826 -210.385914)
		(stroke
			(width 0.2)
			(type default)
		)
		(layer "In1.Cu")
	)
	(gr_arc
		(start 52.811172 -213.207854)
		(mid 52.900975 -213.170657)
		(end 52.938172 -213.080854)
		(stroke
			(width 0.2)
			(type default)
		)
		(layer "In1.Cu")
	)
	(gr_line
		(start 52.811172 -211.633054)
		(end 51.388772 -211.633054)
		(stroke
			(width 0.2)
			(type default)
		)
		(layer "In1.Cu")
	)
	(gr_line
		(start 52.938172 -213.080854)
		(end 52.938172 -211.760054)
		(stroke
			(width 0.2)
			(type default)
		)
		(layer "In1.Cu")
	)
	(gr_arc
		(start 52.938172 -211.760054)
		(mid 52.900975 -211.670251)
		(end 52.811172 -211.633054)
		(stroke
			(width 0.2)
			(type default)
		)
		(layer "In1.Cu")
	)
	(gr_arc
		(start 53.0098 -128.70434)
		(mid 53.039558 -128.776182)
		(end 53.1114 -128.80594)
		(stroke
			(width 0.2)
			(type default)
		)
		(layer "In1.Cu")
	)
	(gr_line
		(start 53.0098 -127.3302)
		(end 53.0098 -128.70434)
		(stroke
			(width 0.2)
			(type default)
		)
		(layer "In1.Cu")
	)
	(gr_line
		(start 53.1114 -128.80594)
		(end 54.3306 -128.80594)
		(stroke
			(width 0.2)
			(type default)
		)
		(layer "In1.Cu")
	)
	(gr_arc
		(start 53.1114 -127.2286)
		(mid 53.039558 -127.258358)
		(end 53.0098 -127.3302)
		(stroke
			(width 0.2)
			(type default)
		)
		(layer "In1.Cu")
	)
	(gr_line
		(start 53.293518 -222.805244)
		(end 54.106064 -222.805244)
		(stroke
			(width 0.2)
			(type default)
		)
		(layer "In1.Cu")
	)
	(gr_arc
		(start 53.293518 -221.784164)
		(mid 52.782978 -222.294704)
		(end 53.293518 -222.805244)
		(stroke
			(width 0.2)
			(type default)
		)
		(layer "In1.Cu")
	)
	(gr_arc
		(start 53.305964 -48.387508)
		(mid 53.816504 -47.876968)
		(end 53.305964 -47.366428)
		(stroke
			(width 0.2)
			(type default)
		)
		(layer "In1.Cu")
	)
	(gr_line
		(start 53.305964 -47.366428)
		(end 52.399692 -47.366428)
		(stroke
			(width 0.2)
			(type default)
		)
		(layer "In1.Cu")
	)
	(gr_arc
		(start 53.950108 0)
		(mid 52.535891 -0.585782)
		(end 51.950112 -1.999996)
		(stroke
			(width 1.524)
			(type default)
		)
		(layer "In1.Cu")
	)
	(gr_line
		(start 53.950108 0)
		(end 119.637556 0)
		(stroke
			(width 1.524)
			(type default)
		)
		(layer "In1.Cu")
	)
	(gr_arc
		(start 54.106064 -222.805244)
		(mid 54.616858 -222.294831)
		(end 54.106318 -221.784164)
		(stroke
			(width 0.2)
			(type default)
		)
		(layer "In1.Cu")
	)
	(gr_line
		(start 54.106318 -221.784164)
		(end 53.293518 -221.784164)
		(stroke
			(width 0.2)
			(type default)
		)
		(layer "In1.Cu")
	)
	(gr_arc
		(start 54.3306 -128.80594)
		(mid 54.402442 -128.776182)
		(end 54.4322 -128.70434)
		(stroke
			(width 0.2)
			(type default)
		)
		(layer "In1.Cu")
	)
	(gr_line
		(start 54.3306 -127.2286)
		(end 53.1114 -127.2286)
		(stroke
			(width 0.2)
			(type default)
		)
		(layer "In1.Cu")
	)
	(gr_line
		(start 54.4322 -128.70434)
		(end 54.4322 -127.3302)
		(stroke
			(width 0.2)
			(type default)
		)
		(layer "In1.Cu")
	)
	(gr_arc
		(start 54.4322 -127.3302)
		(mid 54.402442 -127.258358)
		(end 54.3306 -127.2286)
		(stroke
			(width 0.2)
			(type default)
		)
		(layer "In1.Cu")
	)
	(gr_arc
		(start 54.461918 -213.080854)
		(mid 54.499115 -213.170657)
		(end 54.588918 -213.207854)
		(stroke
			(width 0.2)
			(type default)
		)
		(layer "In1.Cu")
	)
	(gr_line
		(start 54.461918 -211.760054)
		(end 54.461918 -213.080854)
		(stroke
			(width 0.2)
			(type default)
		)
		(layer "In1.Cu")
	)
	(gr_line
		(start 54.588918 -213.207854)
		(end 54.995318 -213.207854)
		(stroke
			(width 0.2)
			(type default)
		)
		(layer "In1.Cu")
	)
	(gr_arc
		(start 54.588918 -211.633054)
		(mid 54.499115 -211.670251)
		(end 54.461918 -211.760054)
		(stroke
			(width 0.2)
			(type default)
		)
		(layer "In1.Cu")
	)
	(gr_line
		(start 54.893718 -211.406994)
		(end 55.706264 -211.406994)
		(stroke
			(width 0.2)
			(type default)
		)
		(layer "In1.Cu")
	)
	(gr_arc
		(start 54.893718 -210.385914)
		(mid 54.383178 -210.896454)
		(end 54.893718 -211.406994)
		(stroke
			(width 0.2)
			(type default)
		)
		(layer "In1.Cu")
	)
	(gr_line
		(start 54.995318 -213.207854)
		(end 54.995572 -213.2076)
		(stroke
			(width 0.2)
			(type default)
		)
		(layer "In1.Cu")
	)
	(gr_line
		(start 54.995572 -213.2076)
		(end 55.59679 -213.2076)
		(stroke
			(width 0.2)
			(type default)
		)
		(layer "In1.Cu")
	)
	(gr_arc
		(start 55.59679 -213.2076)
		(mid 55.600852 -213.207795)
		(end 55.604918 -213.207854)
		(stroke
			(width 0.2)
			(type default)
		)
		(layer "In1.Cu")
	)
	(gr_line
		(start 55.604918 -213.207854)
		(end 56.011318 -213.207854)
		(stroke
			(width 0.2)
			(type default)
		)
		(layer "In1.Cu")
	)
	(gr_arc
		(start 55.6387 -86.32825)
		(mid 56.25084 -86.94039)
		(end 56.86298 -86.32825)
		(stroke
			(width 0.2)
			(type default)
		)
		(layer "In1.Cu")
	)
	(gr_line
		(start 55.6387 -85.21065)
		(end 55.6387 -86.32825)
		(stroke
			(width 0.2)
			(type default)
		)
		(layer "In1.Cu")
	)
	(gr_arc
		(start 55.706264 -211.406994)
		(mid 56.217058 -210.896581)
		(end 55.706518 -210.385914)
		(stroke
			(width 0.2)
			(type default)
		)
		(layer "In1.Cu")
	)
	(gr_line
		(start 55.706518 -210.385914)
		(end 54.893718 -210.385914)
		(stroke
			(width 0.2)
			(type default)
		)
		(layer "In1.Cu")
	)
	(gr_arc
		(start 56.011318 -213.207854)
		(mid 56.101121 -213.170657)
		(end 56.138318 -213.080854)
		(stroke
			(width 0.2)
			(type default)
		)
		(layer "In1.Cu")
	)
	(gr_line
		(start 56.011318 -211.633054)
		(end 54.588918 -211.633054)
		(stroke
			(width 0.2)
			(type default)
		)
		(layer "In1.Cu")
	)
	(gr_line
		(start 56.138318 -213.080854)
		(end 56.138318 -211.760054)
		(stroke
			(width 0.2)
			(type default)
		)
		(layer "In1.Cu")
	)
	(gr_arc
		(start 56.138318 -211.760054)
		(mid 56.101121 -211.670251)
		(end 56.011318 -211.633054)
		(stroke
			(width 0.2)
			(type default)
		)
		(layer "In1.Cu")
	)
	(gr_line
		(start 56.49341 -222.805244)
		(end 57.305956 -222.805244)
		(stroke
			(width 0.2)
			(type default)
		)
		(layer "In1.Cu")
	)
	(gr_arc
		(start 56.49341 -221.784164)
		(mid 55.98287 -222.294704)
		(end 56.49341 -222.805244)
		(stroke
			(width 0.2)
			(type default)
		)
		(layer "In1.Cu")
	)
	(gr_line
		(start 56.86298 -86.32825)
		(end 56.86298 -85.210904)
		(stroke
			(width 0.2)
			(type default)
		)
		(layer "In1.Cu")
	)
	(gr_arc
		(start 56.86298 -85.210904)
		(mid 56.250967 -84.59851)
		(end 55.6387 -85.21065)
		(stroke
			(width 0.2)
			(type default)
		)
		(layer "In1.Cu")
	)
	(gr_arc
		(start 57.305956 -222.805244)
		(mid 57.81675 -222.294831)
		(end 57.30621 -221.784164)
		(stroke
			(width 0.2)
			(type default)
		)
		(layer "In1.Cu")
	)
	(gr_line
		(start 57.30621 -221.784164)
		(end 56.49341 -221.784164)
		(stroke
			(width 0.2)
			(type default)
		)
		(layer "In1.Cu")
	)
	(gr_arc
		(start 57.66181 -213.080854)
		(mid 57.699007 -213.170657)
		(end 57.78881 -213.207854)
		(stroke
			(width 0.2)
			(type default)
		)
		(layer "In1.Cu")
	)
	(gr_line
		(start 57.66181 -211.760054)
		(end 57.66181 -213.080854)
		(stroke
			(width 0.2)
			(type default)
		)
		(layer "In1.Cu")
	)
	(gr_line
		(start 57.78881 -213.207854)
		(end 58.19521 -213.207854)
		(stroke
			(width 0.2)
			(type default)
		)
		(layer "In1.Cu")
	)
	(gr_arc
		(start 57.78881 -211.633054)
		(mid 57.699007 -211.670251)
		(end 57.66181 -211.760054)
		(stroke
			(width 0.2)
			(type default)
		)
		(layer "In1.Cu")
	)
	(gr_line
		(start 58.0517 -196.77634)
		(end 58.8645 -196.77634)
		(stroke
			(width 0.2)
			(type default)
		)
		(layer "In1.Cu")
	)
	(gr_arc
		(start 58.051954 -195.75526)
		(mid 57.54116 -196.265673)
		(end 58.0517 -196.77634)
		(stroke
			(width 0.2)
			(type default)
		)
		(layer "In1.Cu")
	)
	(gr_line
		(start 58.09361 -211.406994)
		(end 58.90641 -211.406994)
		(stroke
			(width 0.2)
			(type default)
		)
		(layer "In1.Cu")
	)
	(gr_arc
		(start 58.093864 -210.385914)
		(mid 57.58307 -210.896327)
		(end 58.09361 -211.406994)
		(stroke
			(width 0.2)
			(type default)
		)
		(layer "In1.Cu")
	)
	(gr_line
		(start 58.19521 -213.207854)
		(end 58.195464 -213.2076)
		(stroke
			(width 0.2)
			(type default)
		)
		(layer "In1.Cu")
	)
	(gr_line
		(start 58.195464 -213.2076)
		(end 58.796682 -213.2076)
		(stroke
			(width 0.2)
			(type default)
		)
		(layer "In1.Cu")
	)
	(gr_arc
		(start 58.796682 -213.2076)
		(mid 58.800744 -213.207795)
		(end 58.80481 -213.207854)
		(stroke
			(width 0.2)
			(type default)
		)
		(layer "In1.Cu")
	)
	(gr_line
		(start 58.80481 -213.207854)
		(end 59.21121 -213.207854)
		(stroke
			(width 0.2)
			(type default)
		)
		(layer "In1.Cu")
	)
	(gr_arc
		(start 58.8645 -196.77634)
		(mid 59.37504 -196.2658)
		(end 58.8645 -195.75526)
		(stroke
			(width 0.2)
			(type default)
		)
		(layer "In1.Cu")
	)
	(gr_line
		(start 58.8645 -195.75526)
		(end 58.051954 -195.75526)
		(stroke
			(width 0.2)
			(type default)
		)
		(layer "In1.Cu")
	)
	(gr_arc
		(start 58.90641 -211.406994)
		(mid 59.41695 -210.896454)
		(end 58.90641 -210.385914)
		(stroke
			(width 0.2)
			(type default)
		)
		(layer "In1.Cu")
	)
	(gr_line
		(start 58.90641 -210.385914)
		(end 58.093864 -210.385914)
		(stroke
			(width 0.2)
			(type default)
		)
		(layer "In1.Cu")
	)
	(gr_arc
		(start 59.21121 -213.207854)
		(mid 59.301013 -213.170657)
		(end 59.33821 -213.080854)
		(stroke
			(width 0.2)
			(type default)
		)
		(layer "In1.Cu")
	)
	(gr_line
		(start 59.21121 -211.633054)
		(end 57.78881 -211.633054)
		(stroke
			(width 0.2)
			(type default)
		)
		(layer "In1.Cu")
	)
	(gr_line
		(start 59.33821 -213.080854)
		(end 59.33821 -211.760054)
		(stroke
			(width 0.2)
			(type default)
		)
		(layer "In1.Cu")
	)
	(gr_arc
		(start 59.33821 -211.760054)
		(mid 59.301013 -211.670251)
		(end 59.21121 -211.633054)
		(stroke
			(width 0.2)
			(type default)
		)
		(layer "In1.Cu")
	)
	(gr_line
		(start 59.693302 -222.805244)
		(end 60.505848 -222.805244)
		(stroke
			(width 0.2)
			(type default)
		)
		(layer "In1.Cu")
	)
	(gr_arc
		(start 59.693302 -221.784164)
		(mid 59.182762 -222.294704)
		(end 59.693302 -222.805244)
		(stroke
			(width 0.2)
			(type default)
		)
		(layer "In1.Cu")
	)
	(gr_arc
		(start 60.505848 -222.805244)
		(mid 61.016642 -222.294831)
		(end 60.506102 -221.784164)
		(stroke
			(width 0.2)
			(type default)
		)
		(layer "In1.Cu")
	)
	(gr_line
		(start 60.506102 -221.784164)
		(end 59.693302 -221.784164)
		(stroke
			(width 0.2)
			(type default)
		)
		(layer "In1.Cu")
	)
	(gr_arc
		(start 63.261748 -213.080854)
		(mid 63.298945 -213.170657)
		(end 63.388748 -213.207854)
		(stroke
			(width 0.2)
			(type default)
		)
		(layer "In1.Cu")
	)
	(gr_line
		(start 63.261748 -211.760054)
		(end 63.261748 -213.080854)
		(stroke
			(width 0.2)
			(type default)
		)
		(layer "In1.Cu")
	)
	(gr_line
		(start 63.388748 -213.207854)
		(end 63.795148 -213.207854)
		(stroke
			(width 0.2)
			(type default)
		)
		(layer "In1.Cu")
	)
	(gr_arc
		(start 63.388748 -211.633054)
		(mid 63.298945 -211.670251)
		(end 63.261748 -211.760054)
		(stroke
			(width 0.2)
			(type default)
		)
		(layer "In1.Cu")
	)
	(gr_line
		(start 63.693548 -211.406994)
		(end 64.506348 -211.406994)
		(stroke
			(width 0.2)
			(type default)
		)
		(layer "In1.Cu")
	)
	(gr_arc
		(start 63.693802 -210.385914)
		(mid 63.183008 -210.896327)
		(end 63.693548 -211.406994)
		(stroke
			(width 0.2)
			(type default)
		)
		(layer "In1.Cu")
	)
	(gr_line
		(start 63.795148 -213.207854)
		(end 63.795402 -213.2076)
		(stroke
			(width 0.2)
			(type default)
		)
		(layer "In1.Cu")
	)
	(gr_line
		(start 63.795402 -213.2076)
		(end 64.39662 -213.2076)
		(stroke
			(width 0.2)
			(type default)
		)
		(layer "In1.Cu")
	)
	(gr_arc
		(start 64.39662 -213.2076)
		(mid 64.400682 -213.207795)
		(end 64.404748 -213.207854)
		(stroke
			(width 0.2)
			(type default)
		)
		(layer "In1.Cu")
	)
	(gr_line
		(start 64.404748 -213.207854)
		(end 64.811148 -213.207854)
		(stroke
			(width 0.2)
			(type default)
		)
		(layer "In1.Cu")
	)
	(gr_arc
		(start 64.506348 -211.406994)
		(mid 65.016888 -210.896454)
		(end 64.506348 -210.385914)
		(stroke
			(width 0.2)
			(type default)
		)
		(layer "In1.Cu")
	)
	(gr_line
		(start 64.506348 -210.385914)
		(end 63.693802 -210.385914)
		(stroke
			(width 0.2)
			(type default)
		)
		(layer "In1.Cu")
	)
	(gr_arc
		(start 64.811148 -213.207854)
		(mid 64.900951 -213.170657)
		(end 64.938148 -213.080854)
		(stroke
			(width 0.2)
			(type default)
		)
		(layer "In1.Cu")
	)
	(gr_line
		(start 64.811148 -211.633054)
		(end 63.388748 -211.633054)
		(stroke
			(width 0.2)
			(type default)
		)
		(layer "In1.Cu")
	)
	(gr_line
		(start 64.938148 -213.080854)
		(end 64.938148 -211.760054)
		(stroke
			(width 0.2)
			(type default)
		)
		(layer "In1.Cu")
	)
	(gr_arc
		(start 64.938148 -211.760054)
		(mid 64.900951 -211.670251)
		(end 64.811148 -211.633054)
		(stroke
			(width 0.2)
			(type default)
		)
		(layer "In1.Cu")
	)
	(gr_line
		(start 65.293494 -222.805244)
		(end 66.10604 -222.805244)
		(stroke
			(width 0.2)
			(type default)
		)
		(layer "In1.Cu")
	)
	(gr_arc
		(start 65.293494 -221.784164)
		(mid 64.782954 -222.294704)
		(end 65.293494 -222.805244)
		(stroke
			(width 0.2)
			(type default)
		)
		(layer "In1.Cu")
	)
	(gr_line
		(start 65.330578 -128.189736)
		(end 66.143378 -128.189736)
		(stroke
			(width 0.2)
			(type default)
		)
		(layer "In1.Cu")
	)
	(gr_arc
		(start 65.330832 -127.168656)
		(mid 64.820038 -127.679069)
		(end 65.330578 -128.189736)
		(stroke
			(width 0.2)
			(type default)
		)
		(layer "In1.Cu")
	)
	(gr_arc
		(start 66.10604 -222.805244)
		(mid 66.616834 -222.294831)
		(end 66.106294 -221.784164)
		(stroke
			(width 0.2)
			(type default)
		)
		(layer "In1.Cu")
	)
	(gr_line
		(start 66.106294 -221.784164)
		(end 65.293494 -221.784164)
		(stroke
			(width 0.2)
			(type default)
		)
		(layer "In1.Cu")
	)
	(gr_arc
		(start 66.143378 -128.189736)
		(mid 66.653918 -127.679196)
		(end 66.143378 -127.168656)
		(stroke
			(width 0.2)
			(type default)
		)
		(layer "In1.Cu")
	)
	(gr_line
		(start 66.143378 -127.168656)
		(end 65.330832 -127.168656)
		(stroke
			(width 0.2)
			(type default)
		)
		(layer "In1.Cu")
	)
	(gr_arc
		(start 66.461894 -213.080854)
		(mid 66.499091 -213.170657)
		(end 66.588894 -213.207854)
		(stroke
			(width 0.2)
			(type default)
		)
		(layer "In1.Cu")
	)
	(gr_line
		(start 66.461894 -211.760054)
		(end 66.461894 -213.080854)
		(stroke
			(width 0.2)
			(type default)
		)
		(layer "In1.Cu")
	)
	(gr_line
		(start 66.588894 -213.207854)
		(end 66.995294 -213.207854)
		(stroke
			(width 0.2)
			(type default)
		)
		(layer "In1.Cu")
	)
	(gr_arc
		(start 66.588894 -211.633054)
		(mid 66.499091 -211.670251)
		(end 66.461894 -211.760054)
		(stroke
			(width 0.2)
			(type default)
		)
		(layer "In1.Cu")
	)
	(gr_line
		(start 66.893694 -211.406994)
		(end 67.706494 -211.406994)
		(stroke
			(width 0.2)
			(type default)
		)
		(layer "In1.Cu")
	)
	(gr_arc
		(start 66.893948 -210.385914)
		(mid 66.383154 -210.896327)
		(end 66.893694 -211.406994)
		(stroke
			(width 0.2)
			(type default)
		)
		(layer "In1.Cu")
	)
	(gr_line
		(start 66.995294 -213.207854)
		(end 66.995548 -213.2076)
		(stroke
			(width 0.2)
			(type default)
		)
		(layer "In1.Cu")
	)
	(gr_line
		(start 66.995548 -213.2076)
		(end 67.596766 -213.2076)
		(stroke
			(width 0.2)
			(type default)
		)
		(layer "In1.Cu")
	)
	(gr_arc
		(start 67.596766 -213.2076)
		(mid 67.600828 -213.207795)
		(end 67.604894 -213.207854)
		(stroke
			(width 0.2)
			(type default)
		)
		(layer "In1.Cu")
	)
	(gr_line
		(start 67.604894 -213.207854)
		(end 68.011294 -213.207854)
		(stroke
			(width 0.2)
			(type default)
		)
		(layer "In1.Cu")
	)
	(gr_arc
		(start 67.706494 -211.406994)
		(mid 68.217034 -210.896454)
		(end 67.706494 -210.385914)
		(stroke
			(width 0.2)
			(type default)
		)
		(layer "In1.Cu")
	)
	(gr_line
		(start 67.706494 -210.385914)
		(end 66.893948 -210.385914)
		(stroke
			(width 0.2)
			(type default)
		)
		(layer "In1.Cu")
	)
	(gr_arc
		(start 68.011294 -213.207854)
		(mid 68.101097 -213.170657)
		(end 68.138294 -213.080854)
		(stroke
			(width 0.2)
			(type default)
		)
		(layer "In1.Cu")
	)
	(gr_line
		(start 68.011294 -211.633054)
		(end 66.588894 -211.633054)
		(stroke
			(width 0.2)
			(type default)
		)
		(layer "In1.Cu")
	)
	(gr_line
		(start 68.138294 -213.080854)
		(end 68.138294 -211.760054)
		(stroke
			(width 0.2)
			(type default)
		)
		(layer "In1.Cu")
	)
	(gr_arc
		(start 68.138294 -211.760054)
		(mid 68.101097 -211.670251)
		(end 68.011294 -211.633054)
		(stroke
			(width 0.2)
			(type default)
		)
		(layer "In1.Cu")
	)
	(gr_line
		(start 68.493386 -222.805244)
		(end 69.305932 -222.805244)
		(stroke
			(width 0.2)
			(type default)
		)
		(layer "In1.Cu")
	)
	(gr_arc
		(start 68.493386 -221.784164)
		(mid 67.982846 -222.294704)
		(end 68.493386 -222.805244)
		(stroke
			(width 0.2)
			(type default)
		)
		(layer "In1.Cu")
	)
	(gr_arc
		(start 69.305932 -222.805244)
		(mid 69.816726 -222.294831)
		(end 69.306186 -221.784164)
		(stroke
			(width 0.2)
			(type default)
		)
		(layer "In1.Cu")
	)
	(gr_line
		(start 69.306186 -221.784164)
		(end 68.493386 -221.784164)
		(stroke
			(width 0.2)
			(type default)
		)
		(layer "In1.Cu")
	)
	(gr_arc
		(start 69.661786 -213.080854)
		(mid 69.698983 -213.170657)
		(end 69.788786 -213.207854)
		(stroke
			(width 0.2)
			(type default)
		)
		(layer "In1.Cu")
	)
	(gr_line
		(start 69.661786 -211.760054)
		(end 69.661786 -213.080854)
		(stroke
			(width 0.2)
			(type default)
		)
		(layer "In1.Cu")
	)
	(gr_line
		(start 69.788786 -213.207854)
		(end 70.195186 -213.207854)
		(stroke
			(width 0.2)
			(type default)
		)
		(layer "In1.Cu")
	)
	(gr_arc
		(start 69.788786 -211.633054)
		(mid 69.698983 -211.670251)
		(end 69.661786 -211.760054)
		(stroke
			(width 0.2)
			(type default)
		)
		(layer "In1.Cu")
	)
	(gr_line
		(start 70.093586 -211.406994)
		(end 70.906386 -211.406994)
		(stroke
			(width 0.2)
			(type default)
		)
		(layer "In1.Cu")
	)
	(gr_arc
		(start 70.09384 -210.385914)
		(mid 69.583046 -210.896327)
		(end 70.093586 -211.406994)
		(stroke
			(width 0.2)
			(type default)
		)
		(layer "In1.Cu")
	)
	(gr_line
		(start 70.195186 -213.207854)
		(end 70.19544 -213.2076)
		(stroke
			(width 0.2)
			(type default)
		)
		(layer "In1.Cu")
	)
	(gr_line
		(start 70.19544 -213.2076)
		(end 70.796658 -213.2076)
		(stroke
			(width 0.2)
			(type default)
		)
		(layer "In1.Cu")
	)
	(gr_arc
		(start 70.796658 -213.2076)
		(mid 70.80072 -213.207795)
		(end 70.804786 -213.207854)
		(stroke
			(width 0.2)
			(type default)
		)
		(layer "In1.Cu")
	)
	(gr_line
		(start 70.804786 -213.207854)
		(end 71.211186 -213.207854)
		(stroke
			(width 0.2)
			(type default)
		)
		(layer "In1.Cu")
	)
	(gr_arc
		(start 70.906386 -211.406994)
		(mid 71.416926 -210.896454)
		(end 70.906386 -210.385914)
		(stroke
			(width 0.2)
			(type default)
		)
		(layer "In1.Cu")
	)
	(gr_line
		(start 70.906386 -210.385914)
		(end 70.09384 -210.385914)
		(stroke
			(width 0.2)
			(type default)
		)
		(layer "In1.Cu")
	)
	(gr_arc
		(start 71.211186 -213.207854)
		(mid 71.300989 -213.170657)
		(end 71.338186 -213.080854)
		(stroke
			(width 0.2)
			(type default)
		)
		(layer "In1.Cu")
	)
	(gr_line
		(start 71.211186 -211.633054)
		(end 69.788786 -211.633054)
		(stroke
			(width 0.2)
			(type default)
		)
		(layer "In1.Cu")
	)
	(gr_line
		(start 71.338186 -213.080854)
		(end 71.338186 -211.760054)
		(stroke
			(width 0.2)
			(type default)
		)
		(layer "In1.Cu")
	)
	(gr_arc
		(start 71.338186 -211.760054)
		(mid 71.300989 -211.670251)
		(end 71.211186 -211.633054)
		(stroke
			(width 0.2)
			(type default)
		)
		(layer "In1.Cu")
	)
	(gr_line
		(start 71.7042 -220.52534)
		(end 72.516746 -220.52534)
		(stroke
			(width 0.2)
			(type default)
		)
		(layer "In1.Cu")
	)
	(gr_arc
		(start 71.7042 -219.50426)
		(mid 71.19366 -220.0148)
		(end 71.7042 -220.52534)
		(stroke
			(width 0.2)
			(type default)
		)
		(layer "In1.Cu")
	)
	(gr_arc
		(start 72.516746 -220.52534)
		(mid 73.02754 -220.014927)
		(end 72.517 -219.50426)
		(stroke
			(width 0.2)
			(type default)
		)
		(layer "In1.Cu")
	)
	(gr_line
		(start 72.517 -219.50426)
		(end 71.7042 -219.50426)
		(stroke
			(width 0.2)
			(type default)
		)
		(layer "In1.Cu")
	)
	(gr_line
		(start 74.099928 -228.000052)
		(end 28.50007 -228.000052)
		(stroke
			(width 5.08)
			(type default)
		)
		(layer "In1.Cu")
	)
	(gr_line
		(start 74.099928 -222.600012)
		(end 74.099928 -228.000052)
		(stroke
			(width 1.524)
			(type default)
		)
		(layer "In1.Cu")
	)
	(gr_line
		(start 76.499974 -228.000052)
		(end 76.499974 -222.600012)
		(stroke
			(width 1.524)
			(type default)
		)
		(layer "In1.Cu")
	)
	(gr_arc
		(start 76.499974 -222.600012)
		(mid 75.300078 -221.400116)
		(end 74.099928 -222.600012)
		(stroke
			(width 1.524)
			(type default)
		)
		(layer "In1.Cu")
	)
	(gr_line
		(start 78.16977 -220.392244)
		(end 78.982316 -220.392244)
		(stroke
			(width 0.2)
			(type default)
		)
		(layer "In1.Cu")
	)
	(gr_arc
		(start 78.16977 -219.371164)
		(mid 77.65923 -219.881704)
		(end 78.16977 -220.392244)
		(stroke
			(width 0.2)
			(type default)
		)
		(layer "In1.Cu")
	)
	(gr_arc
		(start 78.982316 -220.392244)
		(mid 79.49311 -219.881831)
		(end 78.98257 -219.371164)
		(stroke
			(width 0.2)
			(type default)
		)
		(layer "In1.Cu")
	)
	(gr_line
		(start 78.98257 -219.371164)
		(end 78.16977 -219.371164)
		(stroke
			(width 0.2)
			(type default)
		)
		(layer "In1.Cu")
	)
	(gr_arc
		(start 79.261716 -213.080854)
		(mid 79.298913 -213.170657)
		(end 79.388716 -213.207854)
		(stroke
			(width 0.2)
			(type default)
		)
		(layer "In1.Cu")
	)
	(gr_line
		(start 79.261716 -211.760054)
		(end 79.261716 -213.080854)
		(stroke
			(width 0.2)
			(type default)
		)
		(layer "In1.Cu")
	)
	(gr_line
		(start 79.388716 -213.207854)
		(end 79.795116 -213.207854)
		(stroke
			(width 0.2)
			(type default)
		)
		(layer "In1.Cu")
	)
	(gr_arc
		(start 79.388716 -211.633054)
		(mid 79.298913 -211.670251)
		(end 79.261716 -211.760054)
		(stroke
			(width 0.2)
			(type default)
		)
		(layer "In1.Cu")
	)
	(gr_line
		(start 79.693516 -211.406994)
		(end 80.506316 -211.406994)
		(stroke
			(width 0.2)
			(type default)
		)
		(layer "In1.Cu")
	)
	(gr_arc
		(start 79.69377 -210.385914)
		(mid 79.182976 -210.896327)
		(end 79.693516 -211.406994)
		(stroke
			(width 0.2)
			(type default)
		)
		(layer "In1.Cu")
	)
	(gr_line
		(start 79.795116 -213.207854)
		(end 79.79537 -213.2076)
		(stroke
			(width 0.2)
			(type default)
		)
		(layer "In1.Cu")
	)
	(gr_line
		(start 79.79537 -213.2076)
		(end 80.396588 -213.2076)
		(stroke
			(width 0.2)
			(type default)
		)
		(layer "In1.Cu")
	)
	(gr_arc
		(start 80.396588 -213.2076)
		(mid 80.40065 -213.207795)
		(end 80.404716 -213.207854)
		(stroke
			(width 0.2)
			(type default)
		)
		(layer "In1.Cu")
	)
	(gr_line
		(start 80.404716 -213.207854)
		(end 80.811116 -213.207854)
		(stroke
			(width 0.2)
			(type default)
		)
		(layer "In1.Cu")
	)
	(gr_arc
		(start 80.506316 -211.406994)
		(mid 81.016856 -210.896454)
		(end 80.506316 -210.385914)
		(stroke
			(width 0.2)
			(type default)
		)
		(layer "In1.Cu")
	)
	(gr_line
		(start 80.506316 -210.385914)
		(end 79.69377 -210.385914)
		(stroke
			(width 0.2)
			(type default)
		)
		(layer "In1.Cu")
	)
	(gr_arc
		(start 80.811116 -213.207854)
		(mid 80.900919 -213.170657)
		(end 80.938116 -213.080854)
		(stroke
			(width 0.2)
			(type default)
		)
		(layer "In1.Cu")
	)
	(gr_line
		(start 80.811116 -211.633054)
		(end 79.388716 -211.633054)
		(stroke
			(width 0.2)
			(type default)
		)
		(layer "In1.Cu")
	)
	(gr_line
		(start 80.938116 -213.080854)
		(end 80.938116 -211.760054)
		(stroke
			(width 0.2)
			(type default)
		)
		(layer "In1.Cu")
	)
	(gr_arc
		(start 80.938116 -211.760054)
		(mid 80.900919 -211.670251)
		(end 80.811116 -211.633054)
		(stroke
			(width 0.2)
			(type default)
		)
		(layer "In1.Cu")
	)
	(gr_line
		(start 81.293462 -222.805244)
		(end 82.106008 -222.805244)
		(stroke
			(width 0.2)
			(type default)
		)
		(layer "In1.Cu")
	)
	(gr_arc
		(start 81.293462 -221.784164)
		(mid 80.782922 -222.294704)
		(end 81.293462 -222.805244)
		(stroke
			(width 0.2)
			(type default)
		)
		(layer "In1.Cu")
	)
	(gr_arc
		(start 82.106008 -222.805244)
		(mid 82.616802 -222.294831)
		(end 82.106262 -221.784164)
		(stroke
			(width 0.2)
			(type default)
		)
		(layer "In1.Cu")
	)
	(gr_line
		(start 82.106262 -221.784164)
		(end 81.293462 -221.784164)
		(stroke
			(width 0.2)
			(type default)
		)
		(layer "In1.Cu")
	)
	(gr_arc
		(start 82.461862 -213.080854)
		(mid 82.499059 -213.170657)
		(end 82.588862 -213.207854)
		(stroke
			(width 0.2)
			(type default)
		)
		(layer "In1.Cu")
	)
	(gr_line
		(start 82.461862 -211.760054)
		(end 82.461862 -213.080854)
		(stroke
			(width 0.2)
			(type default)
		)
		(layer "In1.Cu")
	)
	(gr_line
		(start 82.588862 -213.207854)
		(end 82.995262 -213.207854)
		(stroke
			(width 0.2)
			(type default)
		)
		(layer "In1.Cu")
	)
	(gr_arc
		(start 82.588862 -211.633054)
		(mid 82.499059 -211.670251)
		(end 82.461862 -211.760054)
		(stroke
			(width 0.2)
			(type default)
		)
		(layer "In1.Cu")
	)
	(gr_line
		(start 82.893662 -211.406994)
		(end 83.706462 -211.406994)
		(stroke
			(width 0.2)
			(type default)
		)
		(layer "In1.Cu")
	)
	(gr_arc
		(start 82.893916 -210.385914)
		(mid 82.383122 -210.896327)
		(end 82.893662 -211.406994)
		(stroke
			(width 0.2)
			(type default)
		)
		(layer "In1.Cu")
	)
	(gr_line
		(start 82.995262 -213.207854)
		(end 82.995516 -213.2076)
		(stroke
			(width 0.2)
			(type default)
		)
		(layer "In1.Cu")
	)
	(gr_line
		(start 82.995516 -213.2076)
		(end 83.596734 -213.2076)
		(stroke
			(width 0.2)
			(type default)
		)
		(layer "In1.Cu")
	)
	(gr_arc
		(start 83.596734 -213.2076)
		(mid 83.600796 -213.207795)
		(end 83.604862 -213.207854)
		(stroke
			(width 0.2)
			(type default)
		)
		(layer "In1.Cu")
	)
	(gr_line
		(start 83.604862 -213.207854)
		(end 84.011262 -213.207854)
		(stroke
			(width 0.2)
			(type default)
		)
		(layer "In1.Cu")
	)
	(gr_arc
		(start 83.706462 -211.406994)
		(mid 84.217002 -210.896454)
		(end 83.706462 -210.385914)
		(stroke
			(width 0.2)
			(type default)
		)
		(layer "In1.Cu")
	)
	(gr_line
		(start 83.706462 -210.385914)
		(end 82.893916 -210.385914)
		(stroke
			(width 0.2)
			(type default)
		)
		(layer "In1.Cu")
	)
	(gr_arc
		(start 84.011262 -213.207854)
		(mid 84.101065 -213.170657)
		(end 84.138262 -213.080854)
		(stroke
			(width 0.2)
			(type default)
		)
		(layer "In1.Cu")
	)
	(gr_line
		(start 84.011262 -211.633054)
		(end 82.588862 -211.633054)
		(stroke
			(width 0.2)
			(type default)
		)
		(layer "In1.Cu")
	)
	(gr_line
		(start 84.138262 -213.080854)
		(end 84.138262 -211.760054)
		(stroke
			(width 0.2)
			(type default)
		)
		(layer "In1.Cu")
	)
	(gr_arc
		(start 84.138262 -211.760054)
		(mid 84.101065 -211.670251)
		(end 84.011262 -211.633054)
		(stroke
			(width 0.2)
			(type default)
		)
		(layer "In1.Cu")
	)
	(gr_line
		(start 84.493354 -222.805244)
		(end 85.3059 -222.805244)
		(stroke
			(width 0.2)
			(type default)
		)
		(layer "In1.Cu")
	)
	(gr_arc
		(start 84.493354 -221.784164)
		(mid 83.982814 -222.294704)
		(end 84.493354 -222.805244)
		(stroke
			(width 0.2)
			(type default)
		)
		(layer "In1.Cu")
	)
	(gr_arc
		(start 85.3059 -222.805244)
		(mid 85.816694 -222.294831)
		(end 85.306154 -221.784164)
		(stroke
			(width 0.2)
			(type default)
		)
		(layer "In1.Cu")
	)
	(gr_line
		(start 85.306154 -221.784164)
		(end 84.493354 -221.784164)
		(stroke
			(width 0.2)
			(type default)
		)
		(layer "In1.Cu")
	)
	(gr_arc
		(start 85.661754 -213.080854)
		(mid 85.698951 -213.170657)
		(end 85.788754 -213.207854)
		(stroke
			(width 0.2)
			(type default)
		)
		(layer "In1.Cu")
	)
	(gr_line
		(start 85.661754 -211.760054)
		(end 85.661754 -213.080854)
		(stroke
			(width 0.2)
			(type default)
		)
		(layer "In1.Cu")
	)
	(gr_line
		(start 85.788754 -213.207854)
		(end 86.195154 -213.207854)
		(stroke
			(width 0.2)
			(type default)
		)
		(layer "In1.Cu")
	)
	(gr_arc
		(start 85.788754 -211.633054)
		(mid 85.698951 -211.670251)
		(end 85.661754 -211.760054)
		(stroke
			(width 0.2)
			(type default)
		)
		(layer "In1.Cu")
	)
	(gr_line
		(start 86.093554 -211.406994)
		(end 86.906354 -211.406994)
		(stroke
			(width 0.2)
			(type default)
		)
		(layer "In1.Cu")
	)
	(gr_arc
		(start 86.093808 -210.385914)
		(mid 85.583014 -210.896327)
		(end 86.093554 -211.406994)
		(stroke
			(width 0.2)
			(type default)
		)
		(layer "In1.Cu")
	)
	(gr_line
		(start 86.195154 -213.207854)
		(end 86.195408 -213.2076)
		(stroke
			(width 0.2)
			(type default)
		)
		(layer "In1.Cu")
	)
	(gr_line
		(start 86.195408 -213.2076)
		(end 86.796626 -213.2076)
		(stroke
			(width 0.2)
			(type default)
		)
		(layer "In1.Cu")
	)
	(gr_arc
		(start 86.269068 -77.478382)
		(mid 86.779481 -77.989176)
		(end 87.290148 -77.478636)
		(stroke
			(width 0.2)
			(type default)
		)
		(layer "In1.Cu")
	)
	(gr_line
		(start 86.269068 -76.589636)
		(end 86.269068 -77.478382)
		(stroke
			(width 0.2)
			(type default)
		)
		(layer "In1.Cu")
	)
	(gr_arc
		(start 86.796626 -213.2076)
		(mid 86.800688 -213.207795)
		(end 86.804754 -213.207854)
		(stroke
			(width 0.2)
			(type default)
		)
		(layer "In1.Cu")
	)
	(gr_line
		(start 86.804754 -213.207854)
		(end 87.211154 -213.207854)
		(stroke
			(width 0.2)
			(type default)
		)
		(layer "In1.Cu")
	)
	(gr_arc
		(start 86.906354 -211.406994)
		(mid 87.416894 -210.896454)
		(end 86.906354 -210.385914)
		(stroke
			(width 0.2)
			(type default)
		)
		(layer "In1.Cu")
	)
	(gr_line
		(start 86.906354 -210.385914)
		(end 86.093808 -210.385914)
		(stroke
			(width 0.2)
			(type default)
		)
		(layer "In1.Cu")
	)
	(gr_arc
		(start 87.211154 -213.207854)
		(mid 87.300957 -213.170657)
		(end 87.338154 -213.080854)
		(stroke
			(width 0.2)
			(type default)
		)
		(layer "In1.Cu")
	)
	(gr_line
		(start 87.211154 -211.633054)
		(end 85.788754 -211.633054)
		(stroke
			(width 0.2)
			(type default)
		)
		(layer "In1.Cu")
	)
	(gr_line
		(start 87.290148 -77.478636)
		(end 87.290148 -76.589636)
		(stroke
			(width 0.2)
			(type default)
		)
		(layer "In1.Cu")
	)
	(gr_arc
		(start 87.290148 -76.589636)
		(mid 86.779608 -76.079096)
		(end 86.269068 -76.589636)
		(stroke
			(width 0.2)
			(type default)
		)
		(layer "In1.Cu")
	)
	(gr_line
		(start 87.338154 -213.080854)
		(end 87.338154 -211.760054)
		(stroke
			(width 0.2)
			(type default)
		)
		(layer "In1.Cu")
	)
	(gr_arc
		(start 87.338154 -211.760054)
		(mid 87.300957 -211.670251)
		(end 87.211154 -211.633054)
		(stroke
			(width 0.2)
			(type default)
		)
		(layer "In1.Cu")
	)
	(gr_line
		(start 87.6935 -222.805244)
		(end 88.506046 -222.805244)
		(stroke
			(width 0.2)
			(type default)
		)
		(layer "In1.Cu")
	)
	(gr_arc
		(start 87.6935 -221.784164)
		(mid 87.18296 -222.294704)
		(end 87.6935 -222.805244)
		(stroke
			(width 0.2)
			(type default)
		)
		(layer "In1.Cu")
	)
	(gr_arc
		(start 88.506046 -222.805244)
		(mid 89.01684 -222.294831)
		(end 88.5063 -221.784164)
		(stroke
			(width 0.2)
			(type default)
		)
		(layer "In1.Cu")
	)
	(gr_line
		(start 88.5063 -221.784164)
		(end 87.6935 -221.784164)
		(stroke
			(width 0.2)
			(type default)
		)
		(layer "In1.Cu")
	)
	(gr_arc
		(start 88.8619 -213.080854)
		(mid 88.899097 -213.170657)
		(end 88.9889 -213.207854)
		(stroke
			(width 0.2)
			(type default)
		)
		(layer "In1.Cu")
	)
	(gr_line
		(start 88.8619 -211.760054)
		(end 88.8619 -213.080854)
		(stroke
			(width 0.2)
			(type default)
		)
		(layer "In1.Cu")
	)
	(gr_line
		(start 88.9889 -213.207854)
		(end 89.3953 -213.207854)
		(stroke
			(width 0.2)
			(type default)
		)
		(layer "In1.Cu")
	)
	(gr_arc
		(start 88.9889 -211.633054)
		(mid 88.899097 -211.670251)
		(end 88.8619 -211.760054)
		(stroke
			(width 0.2)
			(type default)
		)
		(layer "In1.Cu")
	)
	(gr_line
		(start 89.2937 -211.406994)
		(end 90.1065 -211.406994)
		(stroke
			(width 0.2)
			(type default)
		)
		(layer "In1.Cu")
	)
	(gr_arc
		(start 89.293954 -210.385914)
		(mid 88.78316 -210.896327)
		(end 89.2937 -211.406994)
		(stroke
			(width 0.2)
			(type default)
		)
		(layer "In1.Cu")
	)
	(gr_line
		(start 89.3953 -213.207854)
		(end 89.395554 -213.2076)
		(stroke
			(width 0.2)
			(type default)
		)
		(layer "In1.Cu")
	)
	(gr_line
		(start 89.395554 -213.2076)
		(end 89.996772 -213.2076)
		(stroke
			(width 0.2)
			(type default)
		)
		(layer "In1.Cu")
	)
	(gr_arc
		(start 89.996772 -213.2076)
		(mid 90.000834 -213.207795)
		(end 90.0049 -213.207854)
		(stroke
			(width 0.2)
			(type default)
		)
		(layer "In1.Cu")
	)
	(gr_line
		(start 90.0049 -213.207854)
		(end 90.4113 -213.207854)
		(stroke
			(width 0.2)
			(type default)
		)
		(layer "In1.Cu")
	)
	(gr_arc
		(start 90.1065 -211.406994)
		(mid 90.61704 -210.896454)
		(end 90.1065 -210.385914)
		(stroke
			(width 0.2)
			(type default)
		)
		(layer "In1.Cu")
	)
	(gr_line
		(start 90.1065 -210.385914)
		(end 89.293954 -210.385914)
		(stroke
			(width 0.2)
			(type default)
		)
		(layer "In1.Cu")
	)
	(gr_arc
		(start 90.4113 -213.207854)
		(mid 90.501103 -213.170657)
		(end 90.5383 -213.080854)
		(stroke
			(width 0.2)
			(type default)
		)
		(layer "In1.Cu")
	)
	(gr_line
		(start 90.4113 -211.633054)
		(end 88.9889 -211.633054)
		(stroke
			(width 0.2)
			(type default)
		)
		(layer "In1.Cu")
	)
	(gr_line
		(start 90.5383 -213.080854)
		(end 90.5383 -211.760054)
		(stroke
			(width 0.2)
			(type default)
		)
		(layer "In1.Cu")
	)
	(gr_arc
		(start 90.5383 -211.760054)
		(mid 90.501103 -211.670251)
		(end 90.4113 -211.633054)
		(stroke
			(width 0.2)
			(type default)
		)
		(layer "In1.Cu")
	)
	(gr_line
		(start 90.893392 -222.805244)
		(end 91.705938 -222.805244)
		(stroke
			(width 0.2)
			(type default)
		)
		(layer "In1.Cu")
	)
	(gr_arc
		(start 90.893392 -221.784164)
		(mid 90.382852 -222.294704)
		(end 90.893392 -222.805244)
		(stroke
			(width 0.2)
			(type default)
		)
		(layer "In1.Cu")
	)
	(gr_line
		(start 91.608402 -185.665364)
		(end 92.18295 -186.240166)
		(stroke
			(width 0.2)
			(type default)
		)
		(layer "In1.Cu")
	)
	(gr_line
		(start 91.61018 -185.663586)
		(end 91.608402 -185.665364)
		(stroke
			(width 0.2)
			(type default)
		)
		(layer "In1.Cu")
	)
	(gr_arc
		(start 91.705938 -222.805244)
		(mid 92.216732 -222.294831)
		(end 91.706192 -221.784164)
		(stroke
			(width 0.2)
			(type default)
		)
		(layer "In1.Cu")
	)
	(gr_line
		(start 91.706192 -221.784164)
		(end 90.893392 -221.784164)
		(stroke
			(width 0.2)
			(type default)
		)
		(layer "In1.Cu")
	)
	(gr_arc
		(start 92.061792 -213.080854)
		(mid 92.098989 -213.170657)
		(end 92.188792 -213.207854)
		(stroke
			(width 0.2)
			(type default)
		)
		(layer "In1.Cu")
	)
	(gr_line
		(start 92.061792 -211.760054)
		(end 92.061792 -213.080854)
		(stroke
			(width 0.2)
			(type default)
		)
		(layer "In1.Cu")
	)
	(gr_line
		(start 92.18295 -186.240166)
		(end 92.183204 -186.240166)
		(stroke
			(width 0.2)
			(type default)
		)
		(layer "In1.Cu")
	)
	(gr_line
		(start 92.183204 -186.240166)
		(end 92.184982 -186.238388)
		(stroke
			(width 0.2)
			(type default)
		)
		(layer "In1.Cu")
	)
	(gr_arc
		(start 92.184982 -186.238388)
		(mid 92.90685 -186.238388)
		(end 92.90685 -185.51652)
		(stroke
			(width 0.2)
			(type default)
		)
		(layer "In1.Cu")
	)
	(gr_line
		(start 92.188792 -213.207854)
		(end 92.595192 -213.207854)
		(stroke
			(width 0.2)
			(type default)
		)
		(layer "In1.Cu")
	)
	(gr_arc
		(start 92.188792 -211.633054)
		(mid 92.098989 -211.670251)
		(end 92.061792 -211.760054)
		(stroke
			(width 0.2)
			(type default)
		)
		(layer "In1.Cu")
	)
	(gr_arc
		(start 92.332048 -184.941718)
		(mid 91.61018 -184.941718)
		(end 91.61018 -185.663586)
		(stroke
			(width 0.2)
			(type default)
		)
		(layer "In1.Cu")
	)
	(gr_line
		(start 92.333826 -184.93994)
		(end 92.332048 -184.941718)
		(stroke
			(width 0.2)
			(type default)
		)
		(layer "In1.Cu")
	)
	(gr_line
		(start 92.493592 -211.406994)
		(end 93.306392 -211.406994)
		(stroke
			(width 0.2)
			(type default)
		)
		(layer "In1.Cu")
	)
	(gr_arc
		(start 92.493846 -210.385914)
		(mid 91.983052 -210.896327)
		(end 92.493592 -211.406994)
		(stroke
			(width 0.2)
			(type default)
		)
		(layer "In1.Cu")
	)
	(gr_line
		(start 92.595192 -213.207854)
		(end 92.595446 -213.2076)
		(stroke
			(width 0.2)
			(type default)
		)
		(layer "In1.Cu")
	)
	(gr_line
		(start 92.595446 -213.2076)
		(end 93.196664 -213.2076)
		(stroke
			(width 0.2)
			(type default)
		)
		(layer "In1.Cu")
	)
	(gr_line
		(start 92.90685 -185.51652)
		(end 92.908628 -185.514742)
		(stroke
			(width 0.2)
			(type default)
		)
		(layer "In1.Cu")
	)
	(gr_line
		(start 92.908628 -185.514742)
		(end 92.333826 -184.93994)
		(stroke
			(width 0.2)
			(type default)
		)
		(layer "In1.Cu")
	)
	(gr_arc
		(start 93.196664 -213.2076)
		(mid 93.200726 -213.207795)
		(end 93.204792 -213.207854)
		(stroke
			(width 0.2)
			(type default)
		)
		(layer "In1.Cu")
	)
	(gr_line
		(start 93.204792 -213.207854)
		(end 93.611192 -213.207854)
		(stroke
			(width 0.2)
			(type default)
		)
		(layer "In1.Cu")
	)
	(gr_arc
		(start 93.306392 -211.406994)
		(mid 93.816932 -210.896454)
		(end 93.306392 -210.385914)
		(stroke
			(width 0.2)
			(type default)
		)
		(layer "In1.Cu")
	)
	(gr_line
		(start 93.306392 -210.385914)
		(end 92.493846 -210.385914)
		(stroke
			(width 0.2)
			(type default)
		)
		(layer "In1.Cu")
	)
	(gr_line
		(start 93.38945 -184.15254)
		(end 94.201996 -184.15254)
		(stroke
			(width 0.2)
			(type default)
		)
		(layer "In1.Cu")
	)
	(gr_arc
		(start 93.38945 -183.13146)
		(mid 92.87891 -183.642)
		(end 93.38945 -184.15254)
		(stroke
			(width 0.2)
			(type default)
		)
		(layer "In1.Cu")
	)
	(gr_arc
		(start 93.611192 -213.207854)
		(mid 93.700995 -213.170657)
		(end 93.738192 -213.080854)
		(stroke
			(width 0.2)
			(type default)
		)
		(layer "In1.Cu")
	)
	(gr_line
		(start 93.611192 -211.633054)
		(end 92.188792 -211.633054)
		(stroke
			(width 0.2)
			(type default)
		)
		(layer "In1.Cu")
	)
	(gr_line
		(start 93.738192 -213.080854)
		(end 93.738192 -211.760054)
		(stroke
			(width 0.2)
			(type default)
		)
		(layer "In1.Cu")
	)
	(gr_arc
		(start 93.738192 -211.760054)
		(mid 93.700995 -211.670251)
		(end 93.611192 -211.633054)
		(stroke
			(width 0.2)
			(type default)
		)
		(layer "In1.Cu")
	)
	(gr_arc
		(start 94.201996 -184.15254)
		(mid 94.71279 -183.642127)
		(end 94.20225 -183.13146)
		(stroke
			(width 0.2)
			(type default)
		)
		(layer "In1.Cu")
	)
	(gr_line
		(start 94.20225 -183.13146)
		(end 93.38945 -183.13146)
		(stroke
			(width 0.2)
			(type default)
		)
		(layer "In1.Cu")
	)
	(gr_line
		(start 96.493584 -222.805244)
		(end 97.30613 -222.805244)
		(stroke
			(width 0.2)
			(type default)
		)
		(layer "In1.Cu")
	)
	(gr_arc
		(start 96.493584 -221.784164)
		(mid 95.983044 -222.294704)
		(end 96.493584 -222.805244)
		(stroke
			(width 0.2)
			(type default)
		)
		(layer "In1.Cu")
	)
	(gr_arc
		(start 97.30613 -222.805244)
		(mid 97.816924 -222.294831)
		(end 97.306384 -221.784164)
		(stroke
			(width 0.2)
			(type default)
		)
		(layer "In1.Cu")
	)
	(gr_line
		(start 97.306384 -221.784164)
		(end 96.493584 -221.784164)
		(stroke
			(width 0.2)
			(type default)
		)
		(layer "In1.Cu")
	)
	(gr_arc
		(start 97.661984 -213.080854)
		(mid 97.699181 -213.170657)
		(end 97.788984 -213.207854)
		(stroke
			(width 0.2)
			(type default)
		)
		(layer "In1.Cu")
	)
	(gr_line
		(start 97.661984 -211.760054)
		(end 97.661984 -213.080854)
		(stroke
			(width 0.2)
			(type default)
		)
		(layer "In1.Cu")
	)
	(gr_line
		(start 97.788984 -213.207854)
		(end 98.195384 -213.207854)
		(stroke
			(width 0.2)
			(type default)
		)
		(layer "In1.Cu")
	)
	(gr_arc
		(start 97.788984 -211.633054)
		(mid 97.699181 -211.670251)
		(end 97.661984 -211.760054)
		(stroke
			(width 0.2)
			(type default)
		)
		(layer "In1.Cu")
	)
	(gr_line
		(start 98.093784 -211.406994)
		(end 98.906584 -211.406994)
		(stroke
			(width 0.2)
			(type default)
		)
		(layer "In1.Cu")
	)
	(gr_arc
		(start 98.094038 -210.385914)
		(mid 97.583244 -210.896327)
		(end 98.093784 -211.406994)
		(stroke
			(width 0.2)
			(type default)
		)
		(layer "In1.Cu")
	)
	(gr_line
		(start 98.195384 -213.207854)
		(end 98.195638 -213.2076)
		(stroke
			(width 0.2)
			(type default)
		)
		(layer "In1.Cu")
	)
	(gr_line
		(start 98.195638 -213.2076)
		(end 98.796856 -213.2076)
		(stroke
			(width 0.2)
			(type default)
		)
		(layer "In1.Cu")
	)
	(gr_arc
		(start 98.796856 -213.2076)
		(mid 98.800918 -213.207795)
		(end 98.804984 -213.207854)
		(stroke
			(width 0.2)
			(type default)
		)
		(layer "In1.Cu")
	)
	(gr_line
		(start 98.804984 -213.207854)
		(end 99.211384 -213.207854)
		(stroke
			(width 0.2)
			(type default)
		)
		(layer "In1.Cu")
	)
	(gr_arc
		(start 98.906584 -211.406994)
		(mid 99.417124 -210.896454)
		(end 98.906584 -210.385914)
		(stroke
			(width 0.2)
			(type default)
		)
		(layer "In1.Cu")
	)
	(gr_line
		(start 98.906584 -210.385914)
		(end 98.094038 -210.385914)
		(stroke
			(width 0.2)
			(type default)
		)
		(layer "In1.Cu")
	)
	(gr_arc
		(start 99.211384 -213.207854)
		(mid 99.301187 -213.170657)
		(end 99.338384 -213.080854)
		(stroke
			(width 0.2)
			(type default)
		)
		(layer "In1.Cu")
	)
	(gr_line
		(start 99.211384 -211.633054)
		(end 97.788984 -211.633054)
		(stroke
			(width 0.2)
			(type default)
		)
		(layer "In1.Cu")
	)
	(gr_line
		(start 99.338384 -213.080854)
		(end 99.338384 -211.760054)
		(stroke
			(width 0.2)
			(type default)
		)
		(layer "In1.Cu")
	)
	(gr_arc
		(start 99.338384 -211.760054)
		(mid 99.301187 -211.670251)
		(end 99.211384 -211.633054)
		(stroke
			(width 0.2)
			(type default)
		)
		(layer "In1.Cu")
	)
	(gr_line
		(start 99.693476 -222.805244)
		(end 100.506022 -222.805244)
		(stroke
			(width 0.2)
			(type default)
		)
		(layer "In1.Cu")
	)
	(gr_arc
		(start 99.693476 -221.784164)
		(mid 99.182936 -222.294704)
		(end 99.693476 -222.805244)
		(stroke
			(width 0.2)
			(type default)
		)
		(layer "In1.Cu")
	)
	(gr_arc
		(start 100.506022 -222.805244)
		(mid 101.016816 -222.294831)
		(end 100.506276 -221.784164)
		(stroke
			(width 0.2)
			(type default)
		)
		(layer "In1.Cu")
	)
	(gr_line
		(start 100.506276 -221.784164)
		(end 99.693476 -221.784164)
		(stroke
			(width 0.2)
			(type default)
		)
		(layer "In1.Cu")
	)
	(gr_arc
		(start 100.861876 -213.080854)
		(mid 100.899073 -213.170657)
		(end 100.988876 -213.207854)
		(stroke
			(width 0.2)
			(type default)
		)
		(layer "In1.Cu")
	)
	(gr_line
		(start 100.861876 -211.760054)
		(end 100.861876 -213.080854)
		(stroke
			(width 0.2)
			(type default)
		)
		(layer "In1.Cu")
	)
	(gr_line
		(start 100.988876 -213.207854)
		(end 101.395276 -213.207854)
		(stroke
			(width 0.2)
			(type default)
		)
		(layer "In1.Cu")
	)
	(gr_arc
		(start 100.988876 -211.633054)
		(mid 100.899073 -211.670251)
		(end 100.861876 -211.760054)
		(stroke
			(width 0.2)
			(type default)
		)
		(layer "In1.Cu")
	)
	(gr_line
		(start 101.293676 -211.406994)
		(end 102.106222 -211.406994)
		(stroke
			(width 0.2)
			(type default)
		)
		(layer "In1.Cu")
	)
	(gr_arc
		(start 101.293676 -210.385914)
		(mid 100.783136 -210.896454)
		(end 101.293676 -211.406994)
		(stroke
			(width 0.2)
			(type default)
		)
		(layer "In1.Cu")
	)
	(gr_line
		(start 101.395276 -213.207854)
		(end 101.39553 -213.2076)
		(stroke
			(width 0.2)
			(type default)
		)
		(layer "In1.Cu")
	)
	(gr_line
		(start 101.39553 -213.2076)
		(end 101.996748 -213.2076)
		(stroke
			(width 0.2)
			(type default)
		)
		(layer "In1.Cu")
	)
	(gr_arc
		(start 101.41966 -39.80561)
		(mid 101.9302 -40.31615)
		(end 102.44074 -39.80561)
		(stroke
			(width 0.2)
			(type default)
		)
		(layer "In1.Cu")
	)
	(gr_line
		(start 101.41966 -38.91661)
		(end 101.41966 -39.80561)
		(stroke
			(width 0.2)
			(type default)
		)
		(layer "In1.Cu")
	)
	(gr_arc
		(start 101.996748 -213.2076)
		(mid 102.00081 -213.207795)
		(end 102.004876 -213.207854)
		(stroke
			(width 0.2)
			(type default)
		)
		(layer "In1.Cu")
	)
	(gr_arc
		(start 102.00386 -37.094414)
		(mid 102.514273 -37.605208)
		(end 103.02494 -37.094668)
		(stroke
			(width 0.2)
			(type default)
		)
		(layer "In1.Cu")
	)
	(gr_line
		(start 102.00386 -36.205668)
		(end 102.00386 -37.094414)
		(stroke
			(width 0.2)
			(type default)
		)
		(layer "In1.Cu")
	)
	(gr_line
		(start 102.004876 -213.207854)
		(end 102.411276 -213.207854)
		(stroke
			(width 0.2)
			(type default)
		)
		(layer "In1.Cu")
	)
	(gr_arc
		(start 102.01402 -82.1182)
		(mid 102.62616 -82.73034)
		(end 103.2383 -82.1182)
		(stroke
			(width 0.2)
			(type default)
		)
		(layer "In1.Cu")
	)
	(gr_line
		(start 102.01402 -81.0006)
		(end 102.01402 -82.1182)
		(stroke
			(width 0.2)
			(type default)
		)
		(layer "In1.Cu")
	)
	(gr_arc
		(start 102.106222 -211.406994)
		(mid 102.617016 -210.896581)
		(end 102.106476 -210.385914)
		(stroke
			(width 0.2)
			(type default)
		)
		(layer "In1.Cu")
	)
	(gr_line
		(start 102.106476 -210.385914)
		(end 101.293676 -210.385914)
		(stroke
			(width 0.2)
			(type default)
		)
		(layer "In1.Cu")
	)
	(gr_arc
		(start 102.411276 -213.207854)
		(mid 102.501079 -213.170657)
		(end 102.538276 -213.080854)
		(stroke
			(width 0.2)
			(type default)
		)
		(layer "In1.Cu")
	)
	(gr_line
		(start 102.411276 -211.633054)
		(end 100.988876 -211.633054)
		(stroke
			(width 0.2)
			(type default)
		)
		(layer "In1.Cu")
	)
	(gr_line
		(start 102.44074 -39.80561)
		(end 102.44074 -38.916864)
		(stroke
			(width 0.2)
			(type default)
		)
		(layer "In1.Cu")
	)
	(gr_arc
		(start 102.44074 -38.916864)
		(mid 101.930327 -38.40607)
		(end 101.41966 -38.91661)
		(stroke
			(width 0.2)
			(type default)
		)
		(layer "In1.Cu")
	)
	(gr_line
		(start 102.538276 -213.080854)
		(end 102.538276 -211.760054)
		(stroke
			(width 0.2)
			(type default)
		)
		(layer "In1.Cu")
	)
	(gr_arc
		(start 102.538276 -211.760054)
		(mid 102.501079 -211.670251)
		(end 102.411276 -211.633054)
		(stroke
			(width 0.2)
			(type default)
		)
		(layer "In1.Cu")
	)
	(gr_line
		(start 102.893368 -222.805244)
		(end 103.705914 -222.805244)
		(stroke
			(width 0.2)
			(type default)
		)
		(layer "In1.Cu")
	)
	(gr_arc
		(start 102.893368 -221.784164)
		(mid 102.382828 -222.294704)
		(end 102.893368 -222.805244)
		(stroke
			(width 0.2)
			(type default)
		)
		(layer "In1.Cu")
	)
	(gr_line
		(start 103.02494 -37.094668)
		(end 103.02494 -36.205668)
		(stroke
			(width 0.2)
			(type default)
		)
		(layer "In1.Cu")
	)
	(gr_arc
		(start 103.02494 -36.205668)
		(mid 102.5144 -35.695128)
		(end 102.00386 -36.205668)
		(stroke
			(width 0.2)
			(type default)
		)
		(layer "In1.Cu")
	)
	(gr_line
		(start 103.2383 -82.1182)
		(end 103.2383 -81.000854)
		(stroke
			(width 0.2)
			(type default)
		)
		(layer "In1.Cu")
	)
	(gr_arc
		(start 103.2383 -81.000854)
		(mid 102.626287 -80.38846)
		(end 102.01402 -81.0006)
		(stroke
			(width 0.2)
			(type default)
		)
		(layer "In1.Cu")
	)
	(gr_arc
		(start 103.705914 -222.805244)
		(mid 104.216708 -222.294831)
		(end 103.706168 -221.784164)
		(stroke
			(width 0.2)
			(type default)
		)
		(layer "In1.Cu")
	)
	(gr_line
		(start 103.706168 -221.784164)
		(end 102.893368 -221.784164)
		(stroke
			(width 0.2)
			(type default)
		)
		(layer "In1.Cu")
	)
	(gr_arc
		(start 104.062022 -213.080854)
		(mid 104.099219 -213.170657)
		(end 104.189022 -213.207854)
		(stroke
			(width 0.2)
			(type default)
		)
		(layer "In1.Cu")
	)
	(gr_line
		(start 104.062022 -211.760054)
		(end 104.062022 -213.080854)
		(stroke
			(width 0.2)
			(type default)
		)
		(layer "In1.Cu")
	)
	(gr_line
		(start 104.189022 -213.207854)
		(end 104.595422 -213.207854)
		(stroke
			(width 0.2)
			(type default)
		)
		(layer "In1.Cu")
	)
	(gr_arc
		(start 104.189022 -211.633054)
		(mid 104.099219 -211.670251)
		(end 104.062022 -211.760054)
		(stroke
			(width 0.2)
			(type default)
		)
		(layer "In1.Cu")
	)
	(gr_line
		(start 104.493822 -211.406994)
		(end 105.306622 -211.406994)
		(stroke
			(width 0.2)
			(type default)
		)
		(layer "In1.Cu")
	)
	(gr_arc
		(start 104.494076 -210.385914)
		(mid 103.983282 -210.896327)
		(end 104.493822 -211.406994)
		(stroke
			(width 0.2)
			(type default)
		)
		(layer "In1.Cu")
	)
	(gr_line
		(start 104.595422 -213.207854)
		(end 104.595676 -213.2076)
		(stroke
			(width 0.2)
			(type default)
		)
		(layer "In1.Cu")
	)
	(gr_line
		(start 104.595676 -213.2076)
		(end 105.196894 -213.2076)
		(stroke
			(width 0.2)
			(type default)
		)
		(layer "In1.Cu")
	)
	(gr_arc
		(start 105.196894 -213.2076)
		(mid 105.200956 -213.207795)
		(end 105.205022 -213.207854)
		(stroke
			(width 0.2)
			(type default)
		)
		(layer "In1.Cu")
	)
	(gr_line
		(start 105.205022 -213.207854)
		(end 105.611422 -213.207854)
		(stroke
			(width 0.2)
			(type default)
		)
		(layer "In1.Cu")
	)
	(gr_arc
		(start 105.306622 -211.406994)
		(mid 105.817162 -210.896454)
		(end 105.306622 -210.385914)
		(stroke
			(width 0.2)
			(type default)
		)
		(layer "In1.Cu")
	)
	(gr_line
		(start 105.306622 -210.385914)
		(end 104.494076 -210.385914)
		(stroke
			(width 0.2)
			(type default)
		)
		(layer "In1.Cu")
	)
	(gr_arc
		(start 105.611422 -213.207854)
		(mid 105.701225 -213.170657)
		(end 105.738422 -213.080854)
		(stroke
			(width 0.2)
			(type default)
		)
		(layer "In1.Cu")
	)
	(gr_line
		(start 105.611422 -211.633054)
		(end 104.189022 -211.633054)
		(stroke
			(width 0.2)
			(type default)
		)
		(layer "In1.Cu")
	)
	(gr_line
		(start 105.738422 -213.080854)
		(end 105.738422 -211.760054)
		(stroke
			(width 0.2)
			(type default)
		)
		(layer "In1.Cu")
	)
	(gr_arc
		(start 105.738422 -211.760054)
		(mid 105.701225 -211.670251)
		(end 105.611422 -211.633054)
		(stroke
			(width 0.2)
			(type default)
		)
		(layer "In1.Cu")
	)
	(gr_line
		(start 106.093514 -222.805244)
		(end 106.90606 -222.805244)
		(stroke
			(width 0.2)
			(type default)
		)
		(layer "In1.Cu")
	)
	(gr_arc
		(start 106.093514 -221.784164)
		(mid 105.582974 -222.294704)
		(end 106.093514 -222.805244)
		(stroke
			(width 0.2)
			(type default)
		)
		(layer "In1.Cu")
	)
	(gr_arc
		(start 106.90606 -222.805244)
		(mid 107.416854 -222.294831)
		(end 106.906314 -221.784164)
		(stroke
			(width 0.2)
			(type default)
		)
		(layer "In1.Cu")
	)
	(gr_line
		(start 106.906314 -221.784164)
		(end 106.093514 -221.784164)
		(stroke
			(width 0.2)
			(type default)
		)
		(layer "In1.Cu")
	)
	(gr_arc
		(start 107.261914 -213.080854)
		(mid 107.299111 -213.170657)
		(end 107.388914 -213.207854)
		(stroke
			(width 0.2)
			(type default)
		)
		(layer "In1.Cu")
	)
	(gr_line
		(start 107.261914 -211.760054)
		(end 107.261914 -213.080854)
		(stroke
			(width 0.2)
			(type default)
		)
		(layer "In1.Cu")
	)
	(gr_line
		(start 107.388914 -213.207854)
		(end 107.795314 -213.207854)
		(stroke
			(width 0.2)
			(type default)
		)
		(layer "In1.Cu")
	)
	(gr_arc
		(start 107.388914 -211.633054)
		(mid 107.299111 -211.670251)
		(end 107.261914 -211.760054)
		(stroke
			(width 0.2)
			(type default)
		)
		(layer "In1.Cu")
	)
	(gr_line
		(start 107.693714 -211.406994)
		(end 108.506514 -211.406994)
		(stroke
			(width 0.2)
			(type default)
		)
		(layer "In1.Cu")
	)
	(gr_arc
		(start 107.693968 -210.385914)
		(mid 107.183174 -210.896327)
		(end 107.693714 -211.406994)
		(stroke
			(width 0.2)
			(type default)
		)
		(layer "In1.Cu")
	)
	(gr_line
		(start 107.795314 -213.207854)
		(end 107.795568 -213.2076)
		(stroke
			(width 0.2)
			(type default)
		)
		(layer "In1.Cu")
	)
	(gr_line
		(start 107.795568 -213.2076)
		(end 108.396786 -213.2076)
		(stroke
			(width 0.2)
			(type default)
		)
		(layer "In1.Cu")
	)
	(gr_arc
		(start 108.396786 -213.2076)
		(mid 108.400848 -213.207795)
		(end 108.404914 -213.207854)
		(stroke
			(width 0.2)
			(type default)
		)
		(layer "In1.Cu")
	)
	(gr_line
		(start 108.404914 -213.207854)
		(end 108.811314 -213.207854)
		(stroke
			(width 0.2)
			(type default)
		)
		(layer "In1.Cu")
	)
	(gr_arc
		(start 108.506514 -211.406994)
		(mid 109.017054 -210.896454)
		(end 108.506514 -210.385914)
		(stroke
			(width 0.2)
			(type default)
		)
		(layer "In1.Cu")
	)
	(gr_line
		(start 108.506514 -210.385914)
		(end 107.693968 -210.385914)
		(stroke
			(width 0.2)
			(type default)
		)
		(layer "In1.Cu")
	)
	(gr_arc
		(start 108.811314 -213.207854)
		(mid 108.901117 -213.170657)
		(end 108.938314 -213.080854)
		(stroke
			(width 0.2)
			(type default)
		)
		(layer "In1.Cu")
	)
	(gr_line
		(start 108.811314 -211.633054)
		(end 107.388914 -211.633054)
		(stroke
			(width 0.2)
			(type default)
		)
		(layer "In1.Cu")
	)
	(gr_line
		(start 108.938314 -213.080854)
		(end 108.938314 -211.760054)
		(stroke
			(width 0.2)
			(type default)
		)
		(layer "In1.Cu")
	)
	(gr_arc
		(start 108.938314 -211.760054)
		(mid 108.901117 -211.670251)
		(end 108.811314 -211.633054)
		(stroke
			(width 0.2)
			(type default)
		)
		(layer "In1.Cu")
	)
	(gr_line
		(start 112.499902 -228.000052)
		(end 76.499974 -228.000052)
		(stroke
			(width 5.08)
			(type default)
		)
		(layer "In1.Cu")
	)
	(gr_line
		(start 112.499902 -222.400114)
		(end 112.499902 -228.000052)
		(stroke
			(width 1.524)
			(type default)
		)
		(layer "In1.Cu")
	)
	(gr_arc
		(start 113.000028 -221.899988)
		(mid 112.646386 -222.046472)
		(end 112.499902 -222.400114)
		(stroke
			(width 1.524)
			(type default)
		)
		(layer "In1.Cu")
	)
	(gr_line
		(start 113.799874 -221.899988)
		(end 113.000028 -221.899988)
		(stroke
			(width 1.524)
			(type default)
		)
		(layer "In1.Cu")
	)
	(gr_arc
		(start 113.799874 -221.899988)
		(mid 114.153489 -221.75366)
		(end 114.3 -221.400116)
		(stroke
			(width 1.524)
			(type default)
		)
		(layer "In1.Cu")
	)
	(gr_line
		(start 114.3 -214.799926)
		(end 114.3 -221.400116)
		(stroke
			(width 1.524)
			(type default)
		)
		(layer "In1.Cu")
	)
	(gr_arc
		(start 115.599972 -213.499954)
		(mid 114.680753 -213.880707)
		(end 114.3 -214.799926)
		(stroke
			(width 1.524)
			(type default)
		)
		(layer "In1.Cu")
	)
	(gr_arc
		(start 119.637556 0)
		(mid 121.051767 0.585785)
		(end 121.637552 1.999996)
		(stroke
			(width 1.524)
			(type default)
		)
		(layer "In1.Cu")
	)
	(gr_line
		(start 121.637552 1.999996)
		(end 121.637552 2.999994)
		(stroke
			(width 1.524)
			(type default)
		)
		(layer "In1.Cu")
	)
	(gr_arc
		(start 123.637548 4.99999)
		(mid 122.223308 4.414221)
		(end 121.637552 2.999994)
		(stroke
			(width 1.524)
			(type default)
		)
		(layer "In1.Cu")
	)
	(gr_line
		(start 123.637548 4.99999)
		(end 330.74991 4.99999)
		(stroke
			(width 1.524)
			(type default)
		)
		(layer "In1.Cu")
	)
	(gr_arc
		(start 126.781052 -34.2011)
		(mid 126.81081 -34.272942)
		(end 126.882652 -34.3027)
		(stroke
			(width 0.2)
			(type default)
		)
		(layer "In1.Cu")
	)
	(gr_line
		(start 126.781052 -32.9819)
		(end 126.781052 -34.2011)
		(stroke
			(width 0.2)
			(type default)
		)
		(layer "In1.Cu")
	)
	(gr_line
		(start 126.882652 -34.3027)
		(end 128.256792 -34.3027)
		(stroke
			(width 0.2)
			(type default)
		)
		(layer "In1.Cu")
	)
	(gr_arc
		(start 126.882652 -32.8803)
		(mid 126.81081 -32.910058)
		(end 126.781052 -32.9819)
		(stroke
			(width 0.2)
			(type default)
		)
		(layer "In1.Cu")
	)
	(gr_arc
		(start 128.256792 -34.3027)
		(mid 128.328634 -34.272942)
		(end 128.358392 -34.2011)
		(stroke
			(width 0.2)
			(type default)
		)
		(layer "In1.Cu")
	)
	(gr_line
		(start 128.256792 -32.8803)
		(end 126.882652 -32.8803)
		(stroke
			(width 0.2)
			(type default)
		)
		(layer "In1.Cu")
	)
	(gr_line
		(start 128.358392 -34.2011)
		(end 128.358392 -32.9819)
		(stroke
			(width 0.2)
			(type default)
		)
		(layer "In1.Cu")
	)
	(gr_arc
		(start 128.358392 -32.9819)
		(mid 128.328634 -32.910058)
		(end 128.256792 -32.8803)
		(stroke
			(width 0.2)
			(type default)
		)
		(layer "In1.Cu")
	)
	(gr_arc
		(start 130.7211 -34.21126)
		(mid 130.758297 -34.301063)
		(end 130.8481 -34.33826)
		(stroke
			(width 0.2)
			(type default)
		)
		(layer "In1.Cu")
	)
	(gr_line
		(start 130.7211 -32.89046)
		(end 130.7211 -34.21126)
		(stroke
			(width 0.2)
			(type default)
		)
		(layer "In1.Cu")
	)
	(gr_line
		(start 130.8481 -34.33826)
		(end 132.1435 -34.33826)
		(stroke
			(width 0.2)
			(type default)
		)
		(layer "In1.Cu")
	)
	(gr_arc
		(start 130.8481 -32.76346)
		(mid 130.758297 -32.800657)
		(end 130.7211 -32.89046)
		(stroke
			(width 0.2)
			(type default)
		)
		(layer "In1.Cu")
	)
	(gr_line
		(start 131.0894 -35.783774)
		(end 131.9022 -35.783774)
		(stroke
			(width 0.2)
			(type default)
		)
		(layer "In1.Cu")
	)
	(gr_arc
		(start 131.089654 -34.762694)
		(mid 130.57886 -35.273107)
		(end 131.0894 -35.783774)
		(stroke
			(width 0.2)
			(type default)
		)
		(layer "In1.Cu")
	)
	(gr_arc
		(start 131.134104 -42.7228)
		(mid 131.746244 -43.33494)
		(end 132.358384 -42.7228)
		(stroke
			(width 0.2)
			(type default)
		)
		(layer "In1.Cu")
	)
	(gr_line
		(start 131.134104 -41.6052)
		(end 131.134104 -42.7228)
		(stroke
			(width 0.2)
			(type default)
		)
		(layer "In1.Cu")
	)
	(gr_line
		(start 131.400042 -213.499954)
		(end 115.599972 -213.499954)
		(stroke
			(width 1.524)
			(type default)
		)
		(layer "In1.Cu")
	)
	(gr_arc
		(start 131.9022 -35.783774)
		(mid 132.41274 -35.273234)
		(end 131.9022 -34.762694)
		(stroke
			(width 0.2)
			(type default)
		)
		(layer "In1.Cu")
	)
	(gr_line
		(start 131.9022 -34.762694)
		(end 131.089654 -34.762694)
		(stroke
			(width 0.2)
			(type default)
		)
		(layer "In1.Cu")
	)
	(gr_arc
		(start 132.1435 -34.33826)
		(mid 132.233303 -34.301063)
		(end 132.2705 -34.21126)
		(stroke
			(width 0.2)
			(type default)
		)
		(layer "In1.Cu")
	)
	(gr_line
		(start 132.1435 -32.76346)
		(end 130.8481 -32.76346)
		(stroke
			(width 0.2)
			(type default)
		)
		(layer "In1.Cu")
	)
	(gr_line
		(start 132.2324 -84.836)
		(end 132.588 -85.1916)
		(stroke
			(width 0.381)
			(type default)
		)
		(layer "In1.Cu")
	)
	(gr_line
		(start 132.2324 -80.7466)
		(end 132.2324 -84.836)
		(stroke
			(width 0.381)
			(type default)
		)
		(layer "In1.Cu")
	)
	(gr_line
		(start 132.2705 -34.21126)
		(end 132.2705 -32.89046)
		(stroke
			(width 0.2)
			(type default)
		)
		(layer "In1.Cu")
	)
	(gr_arc
		(start 132.2705 -32.89046)
		(mid 132.233303 -32.800657)
		(end 132.1435 -32.76346)
		(stroke
			(width 0.2)
			(type default)
		)
		(layer "In1.Cu")
	)
	(gr_line
		(start 132.358384 -42.7228)
		(end 132.358384 -41.605454)
		(stroke
			(width 0.2)
			(type default)
		)
		(layer "In1.Cu")
	)
	(gr_arc
		(start 132.358384 -41.605454)
		(mid 131.746371 -40.99306)
		(end 131.134104 -41.6052)
		(stroke
			(width 0.2)
			(type default)
		)
		(layer "In1.Cu")
	)
	(gr_line
		(start 132.4864 -80.4926)
		(end 132.2324 -80.7466)
		(stroke
			(width 0.381)
			(type default)
		)
		(layer "In1.Cu")
	)
	(gr_line
		(start 132.581396 -25.033732)
		(end 132.58165 -25.033986)
		(stroke
			(width 0.2)
			(type default)
		)
		(layer "In1.Cu")
	)
	(gr_line
		(start 132.581396 -13.633958)
		(end 132.583428 -13.635228)
		(stroke
			(width 0.2)
			(type default)
		)
		(layer "In1.Cu")
	)
	(gr_line
		(start 132.58165 -25.033986)
		(end 132.583682 -25.035002)
		(stroke
			(width 0.2)
			(type default)
		)
		(layer "In1.Cu")
	)
	(gr_arc
		(start 132.583428 -13.635228)
		(mid 132.83946 -14.481048)
		(end 133.68528 -14.225016)
		(stroke
			(width 0.2)
			(type default)
		)
		(layer "In1.Cu")
	)
	(gr_arc
		(start 132.583682 -25.035002)
		(mid 132.839358 -25.880903)
		(end 133.68528 -25.625044)
		(stroke
			(width 0.2)
			(type default)
		)
		(layer "In1.Cu")
	)
	(gr_line
		(start 132.588 -85.1916)
		(end 132.6134 -85.1916)
		(stroke
			(width 0.381)
			(type default)
		)
		(layer "In1.Cu")
	)
	(gr_line
		(start 132.6134 -85.1916)
		(end 136.271 -85.1916)
		(stroke
			(width 0.381)
			(type default)
		)
		(layer "In1.Cu")
	)
	(gr_line
		(start 132.700014 -221.400116)
		(end 132.700014 -214.799926)
		(stroke
			(width 1.524)
			(type default)
		)
		(layer "In1.Cu")
	)
	(gr_arc
		(start 132.700014 -221.400116)
		(mid 132.846428 -221.753573)
		(end 133.199886 -221.899988)
		(stroke
			(width 1.524)
			(type default)
		)
		(layer "In1.Cu")
	)
	(gr_arc
		(start 132.700014 -214.799926)
		(mid 132.319261 -213.880707)
		(end 131.400042 -213.499954)
		(stroke
			(width 1.524)
			(type default)
		)
		(layer "In1.Cu")
	)
	(gr_arc
		(start 132.88264 -34.19856)
		(mid 132.919837 -34.288363)
		(end 133.00964 -34.32556)
		(stroke
			(width 0.2)
			(type default)
		)
		(layer "In1.Cu")
	)
	(gr_line
		(start 132.88264 -32.87776)
		(end 132.88264 -34.19856)
		(stroke
			(width 0.2)
			(type default)
		)
		(layer "In1.Cu")
	)
	(gr_line
		(start 133.00964 -34.32556)
		(end 134.30504 -34.32556)
		(stroke
			(width 0.2)
			(type default)
		)
		(layer "In1.Cu")
	)
	(gr_arc
		(start 133.00964 -32.75076)
		(mid 132.919837 -32.787957)
		(end 132.88264 -32.87776)
		(stroke
			(width 0.2)
			(type default)
		)
		(layer "In1.Cu")
	)
	(gr_line
		(start 133.331458 -23.633938)
		(end 132.581396 -25.033732)
		(stroke
			(width 0.2)
			(type default)
		)
		(layer "In1.Cu")
	)
	(gr_line
		(start 133.331458 -12.23391)
		(end 132.581396 -13.633958)
		(stroke
			(width 0.2)
			(type default)
		)
		(layer "In1.Cu")
	)
	(gr_line
		(start 133.33349 -23.635208)
		(end 133.331458 -23.633938)
		(stroke
			(width 0.2)
			(type default)
		)
		(layer "In1.Cu")
	)
	(gr_line
		(start 133.33349 -12.23518)
		(end 133.331458 -12.23391)
		(stroke
			(width 0.2)
			(type default)
		)
		(layer "In1.Cu")
	)
	(gr_line
		(start 133.68528 -25.625044)
		(end 133.687312 -25.626314)
		(stroke
			(width 0.2)
			(type default)
		)
		(layer "In1.Cu")
	)
	(gr_line
		(start 133.68528 -14.225016)
		(end 133.687312 -14.226286)
		(stroke
			(width 0.2)
			(type default)
		)
		(layer "In1.Cu")
	)
	(gr_line
		(start 133.687312 -25.626314)
		(end 134.437374 -24.226266)
		(stroke
			(width 0.2)
			(type default)
		)
		(layer "In1.Cu")
	)
	(gr_line
		(start 133.687312 -14.226286)
		(end 134.437374 -12.826492)
		(stroke
			(width 0.2)
			(type default)
		)
		(layer "In1.Cu")
	)
	(gr_line
		(start 133.852158 -36.250372)
		(end 134.664704 -36.250372)
		(stroke
			(width 0.2)
			(type default)
		)
		(layer "In1.Cu")
	)
	(gr_arc
		(start 133.852158 -35.229292)
		(mid 133.341618 -35.739832)
		(end 133.852158 -36.250372)
		(stroke
			(width 0.2)
			(type default)
		)
		(layer "In1.Cu")
	)
	(gr_line
		(start 133.999986 -221.899988)
		(end 133.199886 -221.899988)
		(stroke
			(width 1.524)
			(type default)
		)
		(layer "In1.Cu")
	)
	(gr_arc
		(start 134.30504 -34.32556)
		(mid 134.394843 -34.288363)
		(end 134.43204 -34.19856)
		(stroke
			(width 0.2)
			(type default)
		)
		(layer "In1.Cu")
	)
	(gr_line
		(start 134.30504 -32.75076)
		(end 133.00964 -32.75076)
		(stroke
			(width 0.2)
			(type default)
		)
		(layer "In1.Cu")
	)
	(gr_line
		(start 134.43204 -34.19856)
		(end 134.43204 -32.87776)
		(stroke
			(width 0.2)
			(type default)
		)
		(layer "In1.Cu")
	)
	(gr_arc
		(start 134.43204 -32.87776)
		(mid 134.394843 -32.787957)
		(end 134.30504 -32.75076)
		(stroke
			(width 0.2)
			(type default)
		)
		(layer "In1.Cu")
	)
	(gr_arc
		(start 134.435088 -12.825222)
		(mid 134.179412 -11.979321)
		(end 133.33349 -12.23518)
		(stroke
			(width 0.2)
			(type default)
		)
		(layer "In1.Cu")
	)
	(gr_arc
		(start 134.435342 -24.224996)
		(mid 134.17931 -23.379176)
		(end 133.33349 -23.635208)
		(stroke
			(width 0.2)
			(type default)
		)
		(layer "In1.Cu")
	)
	(gr_line
		(start 134.43712 -12.826238)
		(end 134.435088 -12.825222)
		(stroke
			(width 0.2)
			(type default)
		)
		(layer "In1.Cu")
	)
	(gr_line
		(start 134.437374 -24.226266)
		(end 134.435342 -24.224996)
		(stroke
			(width 0.2)
			(type default)
		)
		(layer "In1.Cu")
	)
	(gr_line
		(start 134.437374 -12.826492)
		(end 134.43712 -12.826238)
		(stroke
			(width 0.2)
			(type default)
		)
		(layer "In1.Cu")
	)
	(gr_line
		(start 134.500112 -228.000052)
		(end 134.500112 -222.400114)
		(stroke
			(width 1.524)
			(type default)
		)
		(layer "In1.Cu")
	)
	(gr_arc
		(start 134.500112 -222.400114)
		(mid 134.353628 -222.046472)
		(end 133.999986 -221.899988)
		(stroke
			(width 1.524)
			(type default)
		)
		(layer "In1.Cu")
	)
	(gr_arc
		(start 134.664704 -36.250372)
		(mid 135.175498 -35.739959)
		(end 134.664958 -35.229292)
		(stroke
			(width 0.2)
			(type default)
		)
		(layer "In1.Cu")
	)
	(gr_line
		(start 134.664958 -35.229292)
		(end 133.852158 -35.229292)
		(stroke
			(width 0.2)
			(type default)
		)
		(layer "In1.Cu")
	)
	(gr_line
		(start 134.831582 -17.433544)
		(end 134.831836 -17.433798)
		(stroke
			(width 0.2)
			(type default)
		)
		(layer "In1.Cu")
	)
	(gr_line
		(start 134.831836 -17.433798)
		(end 134.833868 -17.434814)
		(stroke
			(width 0.2)
			(type default)
		)
		(layer "In1.Cu")
	)
	(gr_arc
		(start 134.833614 -13.635228)
		(mid 135.089646 -14.481048)
		(end 135.935466 -14.225016)
		(stroke
			(width 0.2)
			(type default)
		)
		(layer "In1.Cu")
	)
	(gr_arc
		(start 134.833868 -17.434814)
		(mid 135.089544 -18.280715)
		(end 135.935466 -18.024856)
		(stroke
			(width 0.2)
			(type default)
		)
		(layer "In1.Cu")
	)
	(gr_arc
		(start 134.837678 -25.027636)
		(mid 135.085812 -25.879089)
		(end 135.935466 -25.625044)
		(stroke
			(width 0.2)
			(type default)
		)
		(layer "In1.Cu")
	)
	(gr_arc
		(start 134.837678 -21.227542)
		(mid 135.085812 -22.078995)
		(end 135.935466 -21.82495)
		(stroke
			(width 0.2)
			(type default)
		)
		(layer "In1.Cu")
	)
	(gr_arc
		(start 135.03402 -34.20872)
		(mid 135.071217 -34.298523)
		(end 135.16102 -34.33572)
		(stroke
			(width 0.2)
			(type default)
		)
		(layer "In1.Cu")
	)
	(gr_line
		(start 135.03402 -32.88792)
		(end 135.03402 -34.20872)
		(stroke
			(width 0.2)
			(type default)
		)
		(layer "In1.Cu")
	)
	(gr_line
		(start 135.16102 -34.33572)
		(end 136.45642 -34.33572)
		(stroke
			(width 0.2)
			(type default)
		)
		(layer "In1.Cu")
	)
	(gr_arc
		(start 135.16102 -32.76092)
		(mid 135.071217 -32.798117)
		(end 135.03402 -32.88792)
		(stroke
			(width 0.2)
			(type default)
		)
		(layer "In1.Cu")
	)
	(gr_line
		(start 135.58139 -16.034004)
		(end 134.831582 -17.433544)
		(stroke
			(width 0.2)
			(type default)
		)
		(layer "In1.Cu")
	)
	(gr_line
		(start 135.583422 -23.635208)
		(end 134.837678 -25.027636)
		(stroke
			(width 0.2)
			(type default)
		)
		(layer "In1.Cu")
	)
	(gr_line
		(start 135.583422 -19.835114)
		(end 134.837678 -21.227542)
		(stroke
			(width 0.2)
			(type default)
		)
		(layer "In1.Cu")
	)
	(gr_line
		(start 135.583422 -16.035274)
		(end 135.58139 -16.034004)
		(stroke
			(width 0.2)
			(type default)
		)
		(layer "In1.Cu")
	)
	(gr_line
		(start 135.583422 -12.23518)
		(end 134.833614 -13.635228)
		(stroke
			(width 0.2)
			(type default)
		)
		(layer "In1.Cu")
	)
	(gr_line
		(start 135.935466 -25.625044)
		(end 136.685274 -24.224996)
		(stroke
			(width 0.2)
			(type default)
		)
		(layer "In1.Cu")
	)
	(gr_line
		(start 135.935466 -21.82495)
		(end 136.685274 -20.424902)
		(stroke
			(width 0.2)
			(type default)
		)
		(layer "In1.Cu")
	)
	(gr_line
		(start 135.935466 -18.024856)
		(end 135.937498 -18.026126)
		(stroke
			(width 0.2)
			(type default)
		)
		(layer "In1.Cu")
	)
	(gr_line
		(start 135.935466 -14.225016)
		(end 136.68121 -12.832588)
		(stroke
			(width 0.2)
			(type default)
		)
		(layer "In1.Cu")
	)
	(gr_line
		(start 135.937498 -18.026126)
		(end 136.687306 -16.626332)
		(stroke
			(width 0.2)
			(type default)
		)
		(layer "In1.Cu")
	)
	(gr_line
		(start 136.0424 -80.4926)
		(end 132.4864 -80.4926)
		(stroke
			(width 0.381)
			(type default)
		)
		(layer "In1.Cu")
	)
	(gr_line
		(start 136.271 -85.1916)
		(end 136.4488 -85.0138)
		(stroke
			(width 0.381)
			(type default)
		)
		(layer "In1.Cu")
	)
	(gr_line
		(start 136.4488 -85.0138)
		(end 136.4488 -80.899)
		(stroke
			(width 0.381)
			(type default)
		)
		(layer "In1.Cu")
	)
	(gr_line
		(start 136.4488 -80.899)
		(end 136.0424 -80.4926)
		(stroke
			(width 0.381)
			(type default)
		)
		(layer "In1.Cu")
	)
	(gr_arc
		(start 136.45642 -34.33572)
		(mid 136.546223 -34.298523)
		(end 136.58342 -34.20872)
		(stroke
			(width 0.2)
			(type default)
		)
		(layer "In1.Cu")
	)
	(gr_line
		(start 136.45642 -32.76092)
		(end 135.16102 -32.76092)
		(stroke
			(width 0.2)
			(type default)
		)
		(layer "In1.Cu")
	)
	(gr_line
		(start 136.58342 -34.20872)
		(end 136.58342 -32.88792)
		(stroke
			(width 0.2)
			(type default)
		)
		(layer "In1.Cu")
	)
	(gr_arc
		(start 136.58342 -32.88792)
		(mid 136.546223 -32.798117)
		(end 136.45642 -32.76092)
		(stroke
			(width 0.2)
			(type default)
		)
		(layer "In1.Cu")
	)
	(gr_arc
		(start 136.68121 -12.832588)
		(mid 136.433076 -11.981135)
		(end 135.583422 -12.23518)
		(stroke
			(width 0.2)
			(type default)
		)
		(layer "In1.Cu")
	)
	(gr_arc
		(start 136.685274 -24.224996)
		(mid 136.429242 -23.379176)
		(end 135.583422 -23.635208)
		(stroke
			(width 0.2)
			(type default)
		)
		(layer "In1.Cu")
	)
	(gr_arc
		(start 136.685274 -20.424902)
		(mid 136.429242 -19.579082)
		(end 135.583422 -19.835114)
		(stroke
			(width 0.2)
			(type default)
		)
		(layer "In1.Cu")
	)
	(gr_arc
		(start 136.685274 -16.625062)
		(mid 136.429242 -15.779242)
		(end 135.583422 -16.035274)
		(stroke
			(width 0.2)
			(type default)
		)
		(layer "In1.Cu")
	)
	(gr_line
		(start 136.687306 -16.626332)
		(end 136.685274 -16.625062)
		(stroke
			(width 0.2)
			(type default)
		)
		(layer "In1.Cu")
	)
	(gr_line
		(start 136.893554 -222.805244)
		(end 137.7061 -222.805244)
		(stroke
			(width 0.2)
			(type default)
		)
		(layer "In1.Cu")
	)
	(gr_arc
		(start 136.893554 -221.784164)
		(mid 136.383014 -222.294704)
		(end 136.893554 -222.805244)
		(stroke
			(width 0.2)
			(type default)
		)
		(layer "In1.Cu")
	)
	(gr_line
		(start 137.081514 -25.033732)
		(end 137.081768 -25.033986)
		(stroke
			(width 0.2)
			(type default)
		)
		(layer "In1.Cu")
	)
	(gr_line
		(start 137.081514 -21.233638)
		(end 137.081768 -21.233892)
		(stroke
			(width 0.2)
			(type default)
		)
		(layer "In1.Cu")
	)
	(gr_line
		(start 137.081514 -17.433544)
		(end 137.081768 -17.433798)
		(stroke
			(width 0.2)
			(type default)
		)
		(layer "In1.Cu")
	)
	(gr_line
		(start 137.081514 -13.633958)
		(end 137.083546 -13.635228)
		(stroke
			(width 0.2)
			(type default)
		)
		(layer "In1.Cu")
	)
	(gr_line
		(start 137.081768 -25.033986)
		(end 137.0838 -25.035002)
		(stroke
			(width 0.2)
			(type default)
		)
		(layer "In1.Cu")
	)
	(gr_line
		(start 137.081768 -21.233892)
		(end 137.0838 -21.234908)
		(stroke
			(width 0.2)
			(type default)
		)
		(layer "In1.Cu")
	)
	(gr_line
		(start 137.081768 -17.433798)
		(end 137.0838 -17.434814)
		(stroke
			(width 0.2)
			(type default)
		)
		(layer "In1.Cu")
	)
	(gr_arc
		(start 137.083546 -13.635228)
		(mid 137.339578 -14.481048)
		(end 138.185398 -14.225016)
		(stroke
			(width 0.2)
			(type default)
		)
		(layer "In1.Cu")
	)
	(gr_arc
		(start 137.0838 -25.035002)
		(mid 137.339476 -25.880903)
		(end 138.185398 -25.625044)
		(stroke
			(width 0.2)
			(type default)
		)
		(layer "In1.Cu")
	)
	(gr_arc
		(start 137.0838 -21.234908)
		(mid 137.339476 -22.080809)
		(end 138.185398 -21.82495)
		(stroke
			(width 0.2)
			(type default)
		)
		(layer "In1.Cu")
	)
	(gr_arc
		(start 137.0838 -17.434814)
		(mid 137.339324 -18.280634)
		(end 138.185144 -18.02511)
		(stroke
			(width 0.2)
			(type default)
		)
		(layer "In1.Cu")
	)
	(gr_arc
		(start 137.18794 -34.19094)
		(mid 137.225137 -34.280743)
		(end 137.31494 -34.31794)
		(stroke
			(width 0.2)
			(type default)
		)
		(layer "In1.Cu")
	)
	(gr_line
		(start 137.18794 -32.87014)
		(end 137.18794 -34.19094)
		(stroke
			(width 0.2)
			(type default)
		)
		(layer "In1.Cu")
	)
	(gr_line
		(start 137.31494 -34.31794)
		(end 138.61034 -34.31794)
		(stroke
			(width 0.2)
			(type default)
		)
		(layer "In1.Cu")
	)
	(gr_arc
		(start 137.31494 -32.74314)
		(mid 137.225137 -32.780337)
		(end 137.18794 -32.87014)
		(stroke
			(width 0.2)
			(type default)
		)
		(layer "In1.Cu")
	)
	(gr_line
		(start 137.5664 -35.503866)
		(end 138.378946 -35.503866)
		(stroke
			(width 0.2)
			(type default)
		)
		(layer "In1.Cu")
	)
	(gr_arc
		(start 137.5664 -34.482786)
		(mid 137.05586 -34.993326)
		(end 137.5664 -35.503866)
		(stroke
			(width 0.2)
			(type default)
		)
		(layer "In1.Cu")
	)
	(gr_arc
		(start 137.7061 -222.805244)
		(mid 138.216894 -222.294831)
		(end 137.706354 -221.784164)
		(stroke
			(width 0.2)
			(type default)
		)
		(layer "In1.Cu")
	)
	(gr_line
		(start 137.706354 -221.784164)
		(end 136.893554 -221.784164)
		(stroke
			(width 0.2)
			(type default)
		)
		(layer "In1.Cu")
	)
	(gr_line
		(start 137.831576 -23.633938)
		(end 137.081514 -25.033732)
		(stroke
			(width 0.2)
			(type default)
		)
		(layer "In1.Cu")
	)
	(gr_line
		(start 137.831576 -19.833844)
		(end 137.081514 -21.233638)
		(stroke
			(width 0.2)
			(type default)
		)
		(layer "In1.Cu")
	)
	(gr_line
		(start 137.831576 -16.03375)
		(end 137.081514 -17.433544)
		(stroke
			(width 0.2)
			(type default)
		)
		(layer "In1.Cu")
	)
	(gr_line
		(start 137.831576 -12.23391)
		(end 137.081514 -13.633958)
		(stroke
			(width 0.2)
			(type default)
		)
		(layer "In1.Cu")
	)
	(gr_line
		(start 137.833608 -23.635208)
		(end 137.831576 -23.633938)
		(stroke
			(width 0.2)
			(type default)
		)
		(layer "In1.Cu")
	)
	(gr_line
		(start 137.833608 -19.835114)
		(end 137.831576 -19.833844)
		(stroke
			(width 0.2)
			(type default)
		)
		(layer "In1.Cu")
	)
	(gr_line
		(start 137.833608 -12.23518)
		(end 137.831576 -12.23391)
		(stroke
			(width 0.2)
			(type default)
		)
		(layer "In1.Cu")
	)
	(gr_line
		(start 137.833862 -16.03502)
		(end 137.831576 -16.03375)
		(stroke
			(width 0.2)
			(type default)
		)
		(layer "In1.Cu")
	)
	(gr_arc
		(start 138.061954 -213.080854)
		(mid 138.099151 -213.170657)
		(end 138.188954 -213.207854)
		(stroke
			(width 0.2)
			(type default)
		)
		(layer "In1.Cu")
	)
	(gr_line
		(start 138.061954 -211.760054)
		(end 138.061954 -213.080854)
		(stroke
			(width 0.2)
			(type default)
		)
		(layer "In1.Cu")
	)
	(gr_line
		(start 138.185144 -18.02511)
		(end 138.18743 -18.02638)
		(stroke
			(width 0.2)
			(type default)
		)
		(layer "In1.Cu")
	)
	(gr_line
		(start 138.185398 -25.625044)
		(end 138.18743 -25.626314)
		(stroke
			(width 0.2)
			(type default)
		)
		(layer "In1.Cu")
	)
	(gr_line
		(start 138.185398 -21.82495)
		(end 138.18743 -21.82622)
		(stroke
			(width 0.2)
			(type default)
		)
		(layer "In1.Cu")
	)
	(gr_line
		(start 138.185398 -14.225016)
		(end 138.18743 -14.226286)
		(stroke
			(width 0.2)
			(type default)
		)
		(layer "In1.Cu")
	)
	(gr_line
		(start 138.18743 -25.626314)
		(end 138.937492 -24.226266)
		(stroke
			(width 0.2)
			(type default)
		)
		(layer "In1.Cu")
	)
	(gr_line
		(start 138.18743 -21.82622)
		(end 138.937492 -20.426172)
		(stroke
			(width 0.2)
			(type default)
		)
		(layer "In1.Cu")
	)
	(gr_line
		(start 138.18743 -18.02638)
		(end 138.937492 -16.626586)
		(stroke
			(width 0.2)
			(type default)
		)
		(layer "In1.Cu")
	)
	(gr_line
		(start 138.18743 -14.226286)
		(end 138.937492 -12.826492)
		(stroke
			(width 0.2)
			(type default)
		)
		(layer "In1.Cu")
	)
	(gr_line
		(start 138.188954 -213.207854)
		(end 138.595354 -213.207854)
		(stroke
			(width 0.2)
			(type default)
		)
		(layer "In1.Cu")
	)
	(gr_arc
		(start 138.188954 -211.633054)
		(mid 138.099151 -211.670251)
		(end 138.061954 -211.760054)
		(stroke
			(width 0.2)
			(type default)
		)
		(layer "In1.Cu")
	)
	(gr_arc
		(start 138.378946 -35.503866)
		(mid 138.88974 -34.993453)
		(end 138.3792 -34.482786)
		(stroke
			(width 0.2)
			(type default)
		)
		(layer "In1.Cu")
	)
	(gr_line
		(start 138.3792 -34.482786)
		(end 137.5664 -34.482786)
		(stroke
			(width 0.2)
			(type default)
		)
		(layer "In1.Cu")
	)
	(gr_line
		(start 138.493754 -211.406994)
		(end 139.306554 -211.406994)
		(stroke
			(width 0.2)
			(type default)
		)
		(layer "In1.Cu")
	)
	(gr_arc
		(start 138.494008 -210.385914)
		(mid 137.983214 -210.896327)
		(end 138.493754 -211.406994)
		(stroke
			(width 0.2)
			(type default)
		)
		(layer "In1.Cu")
	)
	(gr_line
		(start 138.557 -39.16934)
		(end 139.3698 -39.16934)
		(stroke
			(width 0.2)
			(type default)
		)
		(layer "In1.Cu")
	)
	(gr_arc
		(start 138.557254 -38.14826)
		(mid 138.04646 -38.658673)
		(end 138.557 -39.16934)
		(stroke
			(width 0.2)
			(type default)
		)
		(layer "In1.Cu")
	)
	(gr_line
		(start 138.595354 -213.207854)
		(end 138.595608 -213.2076)
		(stroke
			(width 0.2)
			(type default)
		)
		(layer "In1.Cu")
	)
	(gr_line
		(start 138.595608 -213.2076)
		(end 139.196826 -213.2076)
		(stroke
			(width 0.2)
			(type default)
		)
		(layer "In1.Cu")
	)
	(gr_arc
		(start 138.61034 -34.31794)
		(mid 138.700143 -34.280743)
		(end 138.73734 -34.19094)
		(stroke
			(width 0.2)
			(type default)
		)
		(layer "In1.Cu")
	)
	(gr_line
		(start 138.61034 -32.74314)
		(end 137.31494 -32.74314)
		(stroke
			(width 0.2)
			(type default)
		)
		(layer "In1.Cu")
	)
	(gr_line
		(start 138.73734 -34.19094)
		(end 138.73734 -32.87014)
		(stroke
			(width 0.2)
			(type default)
		)
		(layer "In1.Cu")
	)
	(gr_arc
		(start 138.73734 -32.87014)
		(mid 138.700143 -32.780337)
		(end 138.61034 -32.74314)
		(stroke
			(width 0.2)
			(type default)
		)
		(layer "In1.Cu")
	)
	(gr_arc
		(start 138.935206 -16.625316)
		(mid 138.679682 -15.779496)
		(end 137.833862 -16.03502)
		(stroke
			(width 0.2)
			(type default)
		)
		(layer "In1.Cu")
	)
	(gr_arc
		(start 138.935206 -12.825222)
		(mid 138.67953 -11.979321)
		(end 137.833608 -12.23518)
		(stroke
			(width 0.2)
			(type default)
		)
		(layer "In1.Cu")
	)
	(gr_arc
		(start 138.93546 -24.224996)
		(mid 138.679428 -23.379176)
		(end 137.833608 -23.635208)
		(stroke
			(width 0.2)
			(type default)
		)
		(layer "In1.Cu")
	)
	(gr_arc
		(start 138.93546 -20.424902)
		(mid 138.679428 -19.579082)
		(end 137.833608 -19.835114)
		(stroke
			(width 0.2)
			(type default)
		)
		(layer "In1.Cu")
	)
	(gr_line
		(start 138.937238 -12.826238)
		(end 138.935206 -12.825222)
		(stroke
			(width 0.2)
			(type default)
		)
		(layer "In1.Cu")
	)
	(gr_line
		(start 138.937492 -24.226266)
		(end 138.93546 -24.224996)
		(stroke
			(width 0.2)
			(type default)
		)
		(layer "In1.Cu")
	)
	(gr_line
		(start 138.937492 -20.426172)
		(end 138.93546 -20.424902)
		(stroke
			(width 0.2)
			(type default)
		)
		(layer "In1.Cu")
	)
	(gr_line
		(start 138.937492 -16.626586)
		(end 138.935206 -16.625316)
		(stroke
			(width 0.2)
			(type default)
		)
		(layer "In1.Cu")
	)
	(gr_line
		(start 138.937492 -12.826492)
		(end 138.937238 -12.826238)
		(stroke
			(width 0.2)
			(type default)
		)
		(layer "In1.Cu")
	)
	(gr_arc
		(start 139.196826 -213.2076)
		(mid 139.200888 -213.207795)
		(end 139.204954 -213.207854)
		(stroke
			(width 0.2)
			(type default)
		)
		(layer "In1.Cu")
	)
	(gr_line
		(start 139.204954 -213.207854)
		(end 139.611354 -213.207854)
		(stroke
			(width 0.2)
			(type default)
		)
		(layer "In1.Cu")
	)
	(gr_arc
		(start 139.306554 -211.406994)
		(mid 139.817094 -210.896454)
		(end 139.306554 -210.385914)
		(stroke
			(width 0.2)
			(type default)
		)
		(layer "In1.Cu")
	)
	(gr_line
		(start 139.306554 -210.385914)
		(end 138.494008 -210.385914)
		(stroke
			(width 0.2)
			(type default)
		)
		(layer "In1.Cu")
	)
	(gr_arc
		(start 139.3698 -39.16934)
		(mid 139.88034 -38.6588)
		(end 139.3698 -38.14826)
		(stroke
			(width 0.2)
			(type default)
		)
		(layer "In1.Cu")
	)
	(gr_line
		(start 139.3698 -38.14826)
		(end 138.557254 -38.14826)
		(stroke
			(width 0.2)
			(type default)
		)
		(layer "In1.Cu")
	)
	(gr_arc
		(start 139.611354 -213.207854)
		(mid 139.701157 -213.170657)
		(end 139.738354 -213.080854)
		(stroke
			(width 0.2)
			(type default)
		)
		(layer "In1.Cu")
	)
	(gr_line
		(start 139.611354 -211.633054)
		(end 138.188954 -211.633054)
		(stroke
			(width 0.2)
			(type default)
		)
		(layer "In1.Cu")
	)
	(gr_line
		(start 139.738354 -213.080854)
		(end 139.738354 -211.760054)
		(stroke
			(width 0.2)
			(type default)
		)
		(layer "In1.Cu")
	)
	(gr_arc
		(start 139.738354 -211.760054)
		(mid 139.701157 -211.670251)
		(end 139.611354 -211.633054)
		(stroke
			(width 0.2)
			(type default)
		)
		(layer "In1.Cu")
	)
	(gr_line
		(start 140.0937 -222.805244)
		(end 140.906246 -222.805244)
		(stroke
			(width 0.2)
			(type default)
		)
		(layer "In1.Cu")
	)
	(gr_arc
		(start 140.0937 -221.784164)
		(mid 139.58316 -222.294704)
		(end 140.0937 -222.805244)
		(stroke
			(width 0.2)
			(type default)
		)
		(layer "In1.Cu")
	)
	(gr_arc
		(start 140.906246 -222.805244)
		(mid 141.41704 -222.294831)
		(end 140.9065 -221.784164)
		(stroke
			(width 0.2)
			(type default)
		)
		(layer "In1.Cu")
	)
	(gr_line
		(start 140.9065 -221.784164)
		(end 140.0937 -221.784164)
		(stroke
			(width 0.2)
			(type default)
		)
		(layer "In1.Cu")
	)
	(gr_arc
		(start 141.261846 -213.080854)
		(mid 141.299043 -213.170657)
		(end 141.388846 -213.207854)
		(stroke
			(width 0.2)
			(type default)
		)
		(layer "In1.Cu")
	)
	(gr_line
		(start 141.261846 -211.760054)
		(end 141.261846 -213.080854)
		(stroke
			(width 0.2)
			(type default)
		)
		(layer "In1.Cu")
	)
	(gr_line
		(start 141.388846 -213.207854)
		(end 141.795246 -213.207854)
		(stroke
			(width 0.2)
			(type default)
		)
		(layer "In1.Cu")
	)
	(gr_arc
		(start 141.388846 -211.633054)
		(mid 141.299043 -211.670251)
		(end 141.261846 -211.760054)
		(stroke
			(width 0.2)
			(type default)
		)
		(layer "In1.Cu")
	)
	(gr_line
		(start 141.6939 -211.406994)
		(end 142.5067 -211.406994)
		(stroke
			(width 0.2)
			(type default)
		)
		(layer "In1.Cu")
	)
	(gr_arc
		(start 141.694154 -210.385914)
		(mid 141.18336 -210.896327)
		(end 141.6939 -211.406994)
		(stroke
			(width 0.2)
			(type default)
		)
		(layer "In1.Cu")
	)
	(gr_line
		(start 141.795246 -213.207854)
		(end 141.7955 -213.2076)
		(stroke
			(width 0.2)
			(type default)
		)
		(layer "In1.Cu")
	)
	(gr_line
		(start 141.7955 -213.2076)
		(end 142.396718 -213.2076)
		(stroke
			(width 0.2)
			(type default)
		)
		(layer "In1.Cu")
	)
	(gr_arc
		(start 142.396718 -213.2076)
		(mid 142.40078 -213.207795)
		(end 142.404846 -213.207854)
		(stroke
			(width 0.2)
			(type default)
		)
		(layer "In1.Cu")
	)
	(gr_line
		(start 142.404846 -213.207854)
		(end 142.811246 -213.207854)
		(stroke
			(width 0.2)
			(type default)
		)
		(layer "In1.Cu")
	)
	(gr_arc
		(start 142.5067 -211.406994)
		(mid 143.01724 -210.896454)
		(end 142.5067 -210.385914)
		(stroke
			(width 0.2)
			(type default)
		)
		(layer "In1.Cu")
	)
	(gr_line
		(start 142.5067 -210.385914)
		(end 141.694154 -210.385914)
		(stroke
			(width 0.2)
			(type default)
		)
		(layer "In1.Cu")
	)
	(gr_arc
		(start 142.811246 -213.207854)
		(mid 142.901049 -213.170657)
		(end 142.938246 -213.080854)
		(stroke
			(width 0.2)
			(type default)
		)
		(layer "In1.Cu")
	)
	(gr_line
		(start 142.811246 -211.633054)
		(end 141.388846 -211.633054)
		(stroke
			(width 0.2)
			(type default)
		)
		(layer "In1.Cu")
	)
	(gr_line
		(start 142.938246 -213.080854)
		(end 142.938246 -211.760054)
		(stroke
			(width 0.2)
			(type default)
		)
		(layer "In1.Cu")
	)
	(gr_arc
		(start 142.938246 -211.760054)
		(mid 142.901049 -211.670251)
		(end 142.811246 -211.633054)
		(stroke
			(width 0.2)
			(type default)
		)
		(layer "In1.Cu")
	)
	(gr_line
		(start 143.293592 -222.805244)
		(end 144.106138 -222.805244)
		(stroke
			(width 0.2)
			(type default)
		)
		(layer "In1.Cu")
	)
	(gr_arc
		(start 143.293592 -221.784164)
		(mid 142.783052 -222.294704)
		(end 143.293592 -222.805244)
		(stroke
			(width 0.2)
			(type default)
		)
		(layer "In1.Cu")
	)
	(gr_line
		(start 143.581374 -25.033986)
		(end 143.583406 -25.035256)
		(stroke
			(width 0.2)
			(type default)
		)
		(layer "In1.Cu")
	)
	(gr_line
		(start 143.581374 -13.633704)
		(end 143.581628 -13.633958)
		(stroke
			(width 0.2)
			(type default)
		)
		(layer "In1.Cu")
	)
	(gr_line
		(start 143.581628 -13.633958)
		(end 143.58366 -13.634974)
		(stroke
			(width 0.2)
			(type default)
		)
		(layer "In1.Cu")
	)
	(gr_arc
		(start 143.583406 -25.035256)
		(mid 143.839438 -25.881076)
		(end 144.685258 -25.625044)
		(stroke
			(width 0.2)
			(type default)
		)
		(layer "In1.Cu")
	)
	(gr_arc
		(start 143.58366 -13.634974)
		(mid 143.839336 -14.480875)
		(end 144.685258 -14.225016)
		(stroke
			(width 0.2)
			(type default)
		)
		(layer "In1.Cu")
	)
	(gr_arc
		(start 144.106138 -222.805244)
		(mid 144.616932 -222.294831)
		(end 144.106392 -221.784164)
		(stroke
			(width 0.2)
			(type default)
		)
		(layer "In1.Cu")
	)
	(gr_line
		(start 144.106392 -221.784164)
		(end 143.293592 -221.784164)
		(stroke
			(width 0.2)
			(type default)
		)
		(layer "In1.Cu")
	)
	(gr_line
		(start 144.331436 -23.633938)
		(end 143.581374 -25.033986)
		(stroke
			(width 0.2)
			(type default)
		)
		(layer "In1.Cu")
	)
	(gr_line
		(start 144.331436 -12.23391)
		(end 143.581374 -13.633704)
		(stroke
			(width 0.2)
			(type default)
		)
		(layer "In1.Cu")
	)
	(gr_line
		(start 144.333468 -23.635208)
		(end 144.331436 -23.633938)
		(stroke
			(width 0.2)
			(type default)
		)
		(layer "In1.Cu")
	)
	(gr_line
		(start 144.333468 -12.23518)
		(end 144.331436 -12.23391)
		(stroke
			(width 0.2)
			(type default)
		)
		(layer "In1.Cu")
	)
	(gr_arc
		(start 144.461992 -213.080854)
		(mid 144.499189 -213.170657)
		(end 144.588992 -213.207854)
		(stroke
			(width 0.2)
			(type default)
		)
		(layer "In1.Cu")
	)
	(gr_line
		(start 144.461992 -211.760054)
		(end 144.461992 -213.080854)
		(stroke
			(width 0.2)
			(type default)
		)
		(layer "In1.Cu")
	)
	(gr_line
		(start 144.588992 -213.207854)
		(end 144.995392 -213.207854)
		(stroke
			(width 0.2)
			(type default)
		)
		(layer "In1.Cu")
	)
	(gr_arc
		(start 144.588992 -211.633054)
		(mid 144.499189 -211.670251)
		(end 144.461992 -211.760054)
		(stroke
			(width 0.2)
			(type default)
		)
		(layer "In1.Cu")
	)
	(gr_line
		(start 144.685258 -25.625044)
		(end 144.68729 -25.626314)
		(stroke
			(width 0.2)
			(type default)
		)
		(layer "In1.Cu")
	)
	(gr_line
		(start 144.685258 -14.225016)
		(end 144.68729 -14.226286)
		(stroke
			(width 0.2)
			(type default)
		)
		(layer "In1.Cu")
	)
	(gr_line
		(start 144.68729 -25.626314)
		(end 145.437352 -24.22652)
		(stroke
			(width 0.2)
			(type default)
		)
		(layer "In1.Cu")
	)
	(gr_line
		(start 144.68729 -14.226286)
		(end 145.437352 -12.826238)
		(stroke
			(width 0.2)
			(type default)
		)
		(layer "In1.Cu")
	)
	(gr_line
		(start 144.893792 -211.406994)
		(end 145.706592 -211.406994)
		(stroke
			(width 0.2)
			(type default)
		)
		(layer "In1.Cu")
	)
	(gr_arc
		(start 144.894046 -210.385914)
		(mid 144.383252 -210.896327)
		(end 144.893792 -211.406994)
		(stroke
			(width 0.2)
			(type default)
		)
		(layer "In1.Cu")
	)
	(gr_line
		(start 144.995392 -213.207854)
		(end 144.995646 -213.2076)
		(stroke
			(width 0.2)
			(type default)
		)
		(layer "In1.Cu")
	)
	(gr_line
		(start 144.995646 -213.2076)
		(end 145.596864 -213.2076)
		(stroke
			(width 0.2)
			(type default)
		)
		(layer "In1.Cu")
	)
	(gr_arc
		(start 145.435066 -24.22525)
		(mid 145.17939 -23.379349)
		(end 144.333468 -23.635208)
		(stroke
			(width 0.2)
			(type default)
		)
		(layer "In1.Cu")
	)
	(gr_arc
		(start 145.43532 -12.824968)
		(mid 145.179288 -11.979148)
		(end 144.333468 -12.23518)
		(stroke
			(width 0.2)
			(type default)
		)
		(layer "In1.Cu")
	)
	(gr_line
		(start 145.437098 -24.226266)
		(end 145.435066 -24.22525)
		(stroke
			(width 0.2)
			(type default)
		)
		(layer "In1.Cu")
	)
	(gr_line
		(start 145.437352 -24.22652)
		(end 145.437098 -24.226266)
		(stroke
			(width 0.2)
			(type default)
		)
		(layer "In1.Cu")
	)
	(gr_line
		(start 145.437352 -12.826238)
		(end 145.43532 -12.824968)
		(stroke
			(width 0.2)
			(type default)
		)
		(layer "In1.Cu")
	)
	(gr_arc
		(start 145.542 -34.18332)
		(mid 145.579197 -34.273123)
		(end 145.669 -34.31032)
		(stroke
			(width 0.2)
			(type default)
		)
		(layer "In1.Cu")
	)
	(gr_line
		(start 145.542 -32.86252)
		(end 145.542 -34.18332)
		(stroke
			(width 0.2)
			(type default)
		)
		(layer "In1.Cu")
	)
	(gr_arc
		(start 145.596864 -213.2076)
		(mid 145.600926 -213.207795)
		(end 145.604992 -213.207854)
		(stroke
			(width 0.2)
			(type default)
		)
		(layer "In1.Cu")
	)
	(gr_line
		(start 145.604992 -213.207854)
		(end 146.011392 -213.207854)
		(stroke
			(width 0.2)
			(type default)
		)
		(layer "In1.Cu")
	)
	(gr_line
		(start 145.669 -34.31032)
		(end 146.9644 -34.31032)
		(stroke
			(width 0.2)
			(type default)
		)
		(layer "In1.Cu")
	)
	(gr_arc
		(start 145.669 -32.73552)
		(mid 145.579197 -32.772717)
		(end 145.542 -32.86252)
		(stroke
			(width 0.2)
			(type default)
		)
		(layer "In1.Cu")
	)
	(gr_arc
		(start 145.706592 -211.406994)
		(mid 146.217132 -210.896454)
		(end 145.706592 -210.385914)
		(stroke
			(width 0.2)
			(type default)
		)
		(layer "In1.Cu")
	)
	(gr_line
		(start 145.706592 -210.385914)
		(end 144.894046 -210.385914)
		(stroke
			(width 0.2)
			(type default)
		)
		(layer "In1.Cu")
	)
	(gr_line
		(start 145.83156 -17.433544)
		(end 145.831814 -17.433798)
		(stroke
			(width 0.2)
			(type default)
		)
		(layer "In1.Cu")
	)
	(gr_line
		(start 145.831814 -17.433798)
		(end 145.833846 -17.434814)
		(stroke
			(width 0.2)
			(type default)
		)
		(layer "In1.Cu")
	)
	(gr_arc
		(start 145.833592 -21.235162)
		(mid 146.089624 -22.080982)
		(end 146.935444 -21.82495)
		(stroke
			(width 0.2)
			(type default)
		)
		(layer "In1.Cu")
	)
	(gr_arc
		(start 145.833846 -17.434814)
		(mid 146.089522 -18.280715)
		(end 146.935444 -18.024856)
		(stroke
			(width 0.2)
			(type default)
		)
		(layer "In1.Cu")
	)
	(gr_arc
		(start 145.837656 -25.027636)
		(mid 146.08579 -25.879089)
		(end 146.935444 -25.625044)
		(stroke
			(width 0.2)
			(type default)
		)
		(layer "In1.Cu")
	)
	(gr_arc
		(start 145.837656 -13.627608)
		(mid 146.08579 -14.479061)
		(end 146.935444 -14.225016)
		(stroke
			(width 0.2)
			(type default)
		)
		(layer "In1.Cu")
	)
	(gr_line
		(start 145.9103 -35.50666)
		(end 146.7231 -35.50666)
		(stroke
			(width 0.2)
			(type default)
		)
		(layer "In1.Cu")
	)
	(gr_arc
		(start 145.910554 -34.48558)
		(mid 145.39976 -34.995993)
		(end 145.9103 -35.50666)
		(stroke
			(width 0.2)
			(type default)
		)
		(layer "In1.Cu")
	)
	(gr_arc
		(start 146.011392 -213.207854)
		(mid 146.101195 -213.170657)
		(end 146.138392 -213.080854)
		(stroke
			(width 0.2)
			(type default)
		)
		(layer "In1.Cu")
	)
	(gr_line
		(start 146.011392 -211.633054)
		(end 144.588992 -211.633054)
		(stroke
			(width 0.2)
			(type default)
		)
		(layer "In1.Cu")
	)
	(gr_line
		(start 146.138392 -213.080854)
		(end 146.138392 -211.760054)
		(stroke
			(width 0.2)
			(type default)
		)
		(layer "In1.Cu")
	)
	(gr_arc
		(start 146.138392 -211.760054)
		(mid 146.101195 -211.670251)
		(end 146.011392 -211.633054)
		(stroke
			(width 0.2)
			(type default)
		)
		(layer "In1.Cu")
	)
	(gr_line
		(start 146.493738 -222.805244)
		(end 147.306284 -222.805244)
		(stroke
			(width 0.2)
			(type default)
		)
		(layer "In1.Cu")
	)
	(gr_arc
		(start 146.493738 -221.784164)
		(mid 145.983198 -222.294704)
		(end 146.493738 -222.805244)
		(stroke
			(width 0.2)
			(type default)
		)
		(layer "In1.Cu")
	)
	(gr_line
		(start 146.581368 -16.034004)
		(end 145.83156 -17.433544)
		(stroke
			(width 0.2)
			(type default)
		)
		(layer "In1.Cu")
	)
	(gr_line
		(start 146.5834 -23.635208)
		(end 145.837656 -25.027636)
		(stroke
			(width 0.2)
			(type default)
		)
		(layer "In1.Cu")
	)
	(gr_line
		(start 146.5834 -19.835114)
		(end 145.833592 -21.235162)
		(stroke
			(width 0.2)
			(type default)
		)
		(layer "In1.Cu")
	)
	(gr_line
		(start 146.5834 -16.035274)
		(end 146.581368 -16.034004)
		(stroke
			(width 0.2)
			(type default)
		)
		(layer "In1.Cu")
	)
	(gr_line
		(start 146.5834 -12.23518)
		(end 145.837656 -13.627608)
		(stroke
			(width 0.2)
			(type default)
		)
		(layer "In1.Cu")
	)
	(gr_arc
		(start 146.7231 -35.50666)
		(mid 147.23364 -34.99612)
		(end 146.7231 -34.48558)
		(stroke
			(width 0.2)
			(type default)
		)
		(layer "In1.Cu")
	)
	(gr_line
		(start 146.7231 -34.48558)
		(end 145.910554 -34.48558)
		(stroke
			(width 0.2)
			(type default)
		)
		(layer "In1.Cu")
	)
	(gr_line
		(start 146.935444 -25.625044)
		(end 147.685252 -24.224996)
		(stroke
			(width 0.2)
			(type default)
		)
		(layer "In1.Cu")
	)
	(gr_line
		(start 146.935444 -21.82495)
		(end 147.681188 -20.432522)
		(stroke
			(width 0.2)
			(type default)
		)
		(layer "In1.Cu")
	)
	(gr_line
		(start 146.935444 -18.024856)
		(end 146.937476 -18.026126)
		(stroke
			(width 0.2)
			(type default)
		)
		(layer "In1.Cu")
	)
	(gr_line
		(start 146.935444 -14.225016)
		(end 147.685252 -12.824968)
		(stroke
			(width 0.2)
			(type default)
		)
		(layer "In1.Cu")
	)
	(gr_line
		(start 146.937476 -18.026126)
		(end 147.687284 -16.626332)
		(stroke
			(width 0.2)
			(type default)
		)
		(layer "In1.Cu")
	)
	(gr_arc
		(start 146.9644 -34.31032)
		(mid 147.054203 -34.273123)
		(end 147.0914 -34.18332)
		(stroke
			(width 0.2)
			(type default)
		)
		(layer "In1.Cu")
	)
	(gr_line
		(start 146.9644 -32.73552)
		(end 145.669 -32.73552)
		(stroke
			(width 0.2)
			(type default)
		)
		(layer "In1.Cu")
	)
	(gr_line
		(start 147.0914 -34.18332)
		(end 147.0914 -32.86252)
		(stroke
			(width 0.2)
			(type default)
		)
		(layer "In1.Cu")
	)
	(gr_arc
		(start 147.0914 -32.86252)
		(mid 147.054203 -32.772717)
		(end 146.9644 -32.73552)
		(stroke
			(width 0.2)
			(type default)
		)
		(layer "In1.Cu")
	)
	(gr_arc
		(start 147.306284 -222.805244)
		(mid 147.817078 -222.294831)
		(end 147.306538 -221.784164)
		(stroke
			(width 0.2)
			(type default)
		)
		(layer "In1.Cu")
	)
	(gr_line
		(start 147.306538 -221.784164)
		(end 146.493738 -221.784164)
		(stroke
			(width 0.2)
			(type default)
		)
		(layer "In1.Cu")
	)
	(gr_arc
		(start 147.661884 -213.080854)
		(mid 147.699081 -213.170657)
		(end 147.788884 -213.207854)
		(stroke
			(width 0.2)
			(type default)
		)
		(layer "In1.Cu")
	)
	(gr_line
		(start 147.661884 -211.760054)
		(end 147.661884 -213.080854)
		(stroke
			(width 0.2)
			(type default)
		)
		(layer "In1.Cu")
	)
	(gr_arc
		(start 147.681188 -20.432522)
		(mid 147.433054 -19.581069)
		(end 146.5834 -19.835114)
		(stroke
			(width 0.2)
			(type default)
		)
		(layer "In1.Cu")
	)
	(gr_arc
		(start 147.685252 -24.224996)
		(mid 147.42922 -23.379176)
		(end 146.5834 -23.635208)
		(stroke
			(width 0.2)
			(type default)
		)
		(layer "In1.Cu")
	)
	(gr_arc
		(start 147.685252 -16.625062)
		(mid 147.42922 -15.779242)
		(end 146.5834 -16.035274)
		(stroke
			(width 0.2)
			(type default)
		)
		(layer "In1.Cu")
	)
	(gr_arc
		(start 147.685252 -12.824968)
		(mid 147.42922 -11.979148)
		(end 146.5834 -12.23518)
		(stroke
			(width 0.2)
			(type default)
		)
		(layer "In1.Cu")
	)
	(gr_line
		(start 147.687284 -16.626332)
		(end 147.685252 -16.625062)
		(stroke
			(width 0.2)
			(type default)
		)
		(layer "In1.Cu")
	)
	(gr_line
		(start 147.788884 -213.207854)
		(end 148.195284 -213.207854)
		(stroke
			(width 0.2)
			(type default)
		)
		(layer "In1.Cu")
	)
	(gr_arc
		(start 147.788884 -211.633054)
		(mid 147.699081 -211.670251)
		(end 147.661884 -211.760054)
		(stroke
			(width 0.2)
			(type default)
		)
		(layer "In1.Cu")
	)
	(gr_line
		(start 148.081492 -25.033732)
		(end 148.081746 -25.033986)
		(stroke
			(width 0.2)
			(type default)
		)
		(layer "In1.Cu")
	)
	(gr_line
		(start 148.081492 -21.233892)
		(end 148.083524 -21.235162)
		(stroke
			(width 0.2)
			(type default)
		)
		(layer "In1.Cu")
	)
	(gr_line
		(start 148.081492 -17.433544)
		(end 148.081746 -17.433798)
		(stroke
			(width 0.2)
			(type default)
		)
		(layer "In1.Cu")
	)
	(gr_line
		(start 148.081492 -13.633704)
		(end 148.081746 -13.633958)
		(stroke
			(width 0.2)
			(type default)
		)
		(layer "In1.Cu")
	)
	(gr_line
		(start 148.081746 -25.033986)
		(end 148.083778 -25.035002)
		(stroke
			(width 0.2)
			(type default)
		)
		(layer "In1.Cu")
	)
	(gr_line
		(start 148.081746 -17.433798)
		(end 148.083778 -17.434814)
		(stroke
			(width 0.2)
			(type default)
		)
		(layer "In1.Cu")
	)
	(gr_line
		(start 148.081746 -13.633958)
		(end 148.083778 -13.634974)
		(stroke
			(width 0.2)
			(type default)
		)
		(layer "In1.Cu")
	)
	(gr_arc
		(start 148.083524 -21.235162)
		(mid 148.339556 -22.080982)
		(end 149.185376 -21.82495)
		(stroke
			(width 0.2)
			(type default)
		)
		(layer "In1.Cu")
	)
	(gr_arc
		(start 148.083778 -25.035002)
		(mid 148.339454 -25.880903)
		(end 149.185376 -25.625044)
		(stroke
			(width 0.2)
			(type default)
		)
		(layer "In1.Cu")
	)
	(gr_arc
		(start 148.083778 -17.434814)
		(mid 148.339302 -18.280634)
		(end 149.185122 -18.02511)
		(stroke
			(width 0.2)
			(type default)
		)
		(layer "In1.Cu")
	)
	(gr_arc
		(start 148.083778 -13.634974)
		(mid 148.339454 -14.480875)
		(end 149.185376 -14.225016)
		(stroke
			(width 0.2)
			(type default)
		)
		(layer "In1.Cu")
	)
	(gr_line
		(start 148.093684 -211.406994)
		(end 148.906484 -211.406994)
		(stroke
			(width 0.2)
			(type default)
		)
		(layer "In1.Cu")
	)
	(gr_arc
		(start 148.093938 -210.385914)
		(mid 147.583144 -210.896327)
		(end 148.093684 -211.406994)
		(stroke
			(width 0.2)
			(type default)
		)
		(layer "In1.Cu")
	)
	(gr_arc
		(start 148.1328 -34.1884)
		(mid 148.169997 -34.278203)
		(end 148.2598 -34.3154)
		(stroke
			(width 0.2)
			(type default)
		)
		(layer "In1.Cu")
	)
	(gr_line
		(start 148.1328 -32.8676)
		(end 148.1328 -34.1884)
		(stroke
			(width 0.2)
			(type default)
		)
		(layer "In1.Cu")
	)
	(gr_line
		(start 148.195284 -213.207854)
		(end 148.195538 -213.2076)
		(stroke
			(width 0.2)
			(type default)
		)
		(layer "In1.Cu")
	)
	(gr_line
		(start 148.195538 -213.2076)
		(end 148.796756 -213.2076)
		(stroke
			(width 0.2)
			(type default)
		)
		(layer "In1.Cu")
	)
	(gr_line
		(start 148.2598 -34.3154)
		(end 149.5552 -34.3154)
		(stroke
			(width 0.2)
			(type default)
		)
		(layer "In1.Cu")
	)
	(gr_arc
		(start 148.2598 -32.7406)
		(mid 148.169997 -32.777797)
		(end 148.1328 -32.8676)
		(stroke
			(width 0.2)
			(type default)
		)
		(layer "In1.Cu")
	)
	(gr_line
		(start 148.5011 -35.51174)
		(end 149.313646 -35.51174)
		(stroke
			(width 0.2)
			(type default)
		)
		(layer "In1.Cu")
	)
	(gr_arc
		(start 148.5011 -34.49066)
		(mid 147.99056 -35.0012)
		(end 148.5011 -35.51174)
		(stroke
			(width 0.2)
			(type default)
		)
		(layer "In1.Cu")
	)
	(gr_arc
		(start 148.796756 -213.2076)
		(mid 148.800818 -213.207795)
		(end 148.804884 -213.207854)
		(stroke
			(width 0.2)
			(type default)
		)
		(layer "In1.Cu")
	)
	(gr_line
		(start 148.804884 -213.207854)
		(end 149.211284 -213.207854)
		(stroke
			(width 0.2)
			(type default)
		)
		(layer "In1.Cu")
	)
	(gr_line
		(start 148.831554 -23.633938)
		(end 148.081492 -25.033732)
		(stroke
			(width 0.2)
			(type default)
		)
		(layer "In1.Cu")
	)
	(gr_line
		(start 148.831554 -19.833844)
		(end 148.081492 -21.233892)
		(stroke
			(width 0.2)
			(type default)
		)
		(layer "In1.Cu")
	)
	(gr_line
		(start 148.831554 -16.03375)
		(end 148.081492 -17.433544)
		(stroke
			(width 0.2)
			(type default)
		)
		(layer "In1.Cu")
	)
	(gr_line
		(start 148.831554 -12.23391)
		(end 148.081492 -13.633704)
		(stroke
			(width 0.2)
			(type default)
		)
		(layer "In1.Cu")
	)
	(gr_line
		(start 148.833586 -23.635208)
		(end 148.831554 -23.633938)
		(stroke
			(width 0.2)
			(type default)
		)
		(layer "In1.Cu")
	)
	(gr_line
		(start 148.833586 -19.835114)
		(end 148.831554 -19.833844)
		(stroke
			(width 0.2)
			(type default)
		)
		(layer "In1.Cu")
	)
	(gr_line
		(start 148.833586 -12.23518)
		(end 148.831554 -12.23391)
		(stroke
			(width 0.2)
			(type default)
		)
		(layer "In1.Cu")
	)
	(gr_line
		(start 148.83384 -16.03502)
		(end 148.831554 -16.03375)
		(stroke
			(width 0.2)
			(type default)
		)
		(layer "In1.Cu")
	)
	(gr_arc
		(start 148.906484 -211.406994)
		(mid 149.417024 -210.896454)
		(end 148.906484 -210.385914)
		(stroke
			(width 0.2)
			(type default)
		)
		(layer "In1.Cu")
	)
	(gr_line
		(start 148.906484 -210.385914)
		(end 148.093938 -210.385914)
		(stroke
			(width 0.2)
			(type default)
		)
		(layer "In1.Cu")
	)
	(gr_line
		(start 149.185122 -18.02511)
		(end 149.187408 -18.02638)
		(stroke
			(width 0.2)
			(type default)
		)
		(layer "In1.Cu")
	)
	(gr_line
		(start 149.185376 -25.625044)
		(end 149.187408 -25.626314)
		(stroke
			(width 0.2)
			(type default)
		)
		(layer "In1.Cu")
	)
	(gr_line
		(start 149.185376 -21.82495)
		(end 149.187408 -21.82622)
		(stroke
			(width 0.2)
			(type default)
		)
		(layer "In1.Cu")
	)
	(gr_line
		(start 149.185376 -14.225016)
		(end 149.187408 -14.226286)
		(stroke
			(width 0.2)
			(type default)
		)
		(layer "In1.Cu")
	)
	(gr_line
		(start 149.187408 -25.626314)
		(end 149.93747 -24.226266)
		(stroke
			(width 0.2)
			(type default)
		)
		(layer "In1.Cu")
	)
	(gr_line
		(start 149.187408 -21.82622)
		(end 149.93747 -20.426426)
		(stroke
			(width 0.2)
			(type default)
		)
		(layer "In1.Cu")
	)
	(gr_line
		(start 149.187408 -18.02638)
		(end 149.93747 -16.626586)
		(stroke
			(width 0.2)
			(type default)
		)
		(layer "In1.Cu")
	)
	(gr_line
		(start 149.187408 -14.226286)
		(end 149.93747 -12.826238)
		(stroke
			(width 0.2)
			(type default)
		)
		(layer "In1.Cu")
	)
	(gr_arc
		(start 149.211284 -213.207854)
		(mid 149.301087 -213.170657)
		(end 149.338284 -213.080854)
		(stroke
			(width 0.2)
			(type default)
		)
		(layer "In1.Cu")
	)
	(gr_line
		(start 149.211284 -211.633054)
		(end 147.788884 -211.633054)
		(stroke
			(width 0.2)
			(type default)
		)
		(layer "In1.Cu")
	)
	(gr_arc
		(start 149.313646 -35.51174)
		(mid 149.82444 -35.001327)
		(end 149.3139 -34.49066)
		(stroke
			(width 0.2)
			(type default)
		)
		(layer "In1.Cu")
	)
	(gr_line
		(start 149.3139 -34.49066)
		(end 148.5011 -34.49066)
		(stroke
			(width 0.2)
			(type default)
		)
		(layer "In1.Cu")
	)
	(gr_line
		(start 149.338284 -213.080854)
		(end 149.338284 -211.760054)
		(stroke
			(width 0.2)
			(type default)
		)
		(layer "In1.Cu")
	)
	(gr_arc
		(start 149.338284 -211.760054)
		(mid 149.301087 -211.670251)
		(end 149.211284 -211.633054)
		(stroke
			(width 0.2)
			(type default)
		)
		(layer "In1.Cu")
	)
	(gr_arc
		(start 149.5552 -34.3154)
		(mid 149.645003 -34.278203)
		(end 149.6822 -34.1884)
		(stroke
			(width 0.2)
			(type default)
		)
		(layer "In1.Cu")
	)
	(gr_line
		(start 149.5552 -32.7406)
		(end 148.2598 -32.7406)
		(stroke
			(width 0.2)
			(type default)
		)
		(layer "In1.Cu")
	)
	(gr_line
		(start 149.6822 -34.1884)
		(end 149.6822 -32.8676)
		(stroke
			(width 0.2)
			(type default)
		)
		(layer "In1.Cu")
	)
	(gr_arc
		(start 149.6822 -32.8676)
		(mid 149.645003 -32.777797)
		(end 149.5552 -32.7406)
		(stroke
			(width 0.2)
			(type default)
		)
		(layer "In1.Cu")
	)
	(gr_line
		(start 149.69363 -222.805244)
		(end 150.506176 -222.805244)
		(stroke
			(width 0.2)
			(type default)
		)
		(layer "In1.Cu")
	)
	(gr_arc
		(start 149.69363 -221.784164)
		(mid 149.18309 -222.294704)
		(end 149.69363 -222.805244)
		(stroke
			(width 0.2)
			(type default)
		)
		(layer "In1.Cu")
	)
	(gr_arc
		(start 149.935184 -20.425156)
		(mid 149.679508 -19.579255)
		(end 148.833586 -19.835114)
		(stroke
			(width 0.2)
			(type default)
		)
		(layer "In1.Cu")
	)
	(gr_arc
		(start 149.935184 -16.625316)
		(mid 149.67966 -15.779496)
		(end 148.83384 -16.03502)
		(stroke
			(width 0.2)
			(type default)
		)
		(layer "In1.Cu")
	)
	(gr_arc
		(start 149.935438 -24.224996)
		(mid 149.679406 -23.379176)
		(end 148.833586 -23.635208)
		(stroke
			(width 0.2)
			(type default)
		)
		(layer "In1.Cu")
	)
	(gr_arc
		(start 149.935438 -12.824968)
		(mid 149.679406 -11.979148)
		(end 148.833586 -12.23518)
		(stroke
			(width 0.2)
			(type default)
		)
		(layer "In1.Cu")
	)
	(gr_line
		(start 149.937216 -20.426172)
		(end 149.935184 -20.425156)
		(stroke
			(width 0.2)
			(type default)
		)
		(layer "In1.Cu")
	)
	(gr_line
		(start 149.93747 -24.226266)
		(end 149.935438 -24.224996)
		(stroke
			(width 0.2)
			(type default)
		)
		(layer "In1.Cu")
	)
	(gr_line
		(start 149.93747 -20.426426)
		(end 149.937216 -20.426172)
		(stroke
			(width 0.2)
			(type default)
		)
		(layer "In1.Cu")
	)
	(gr_line
		(start 149.93747 -16.626586)
		(end 149.935184 -16.625316)
		(stroke
			(width 0.2)
			(type default)
		)
		(layer "In1.Cu")
	)
	(gr_line
		(start 149.93747 -12.826238)
		(end 149.935438 -12.824968)
		(stroke
			(width 0.2)
			(type default)
		)
		(layer "In1.Cu")
	)
	(gr_arc
		(start 150.2918 -34.1884)
		(mid 150.328997 -34.278203)
		(end 150.4188 -34.3154)
		(stroke
			(width 0.2)
			(type default)
		)
		(layer "In1.Cu")
	)
	(gr_line
		(start 150.2918 -32.8676)
		(end 150.2918 -34.1884)
		(stroke
			(width 0.2)
			(type default)
		)
		(layer "In1.Cu")
	)
	(gr_line
		(start 150.4188 -34.3154)
		(end 151.7142 -34.3154)
		(stroke
			(width 0.2)
			(type default)
		)
		(layer "In1.Cu")
	)
	(gr_arc
		(start 150.4188 -32.7406)
		(mid 150.328997 -32.777797)
		(end 150.2918 -32.8676)
		(stroke
			(width 0.2)
			(type default)
		)
		(layer "In1.Cu")
	)
	(gr_arc
		(start 150.506176 -222.805244)
		(mid 151.01697 -222.294831)
		(end 150.50643 -221.784164)
		(stroke
			(width 0.2)
			(type default)
		)
		(layer "In1.Cu")
	)
	(gr_line
		(start 150.50643 -221.784164)
		(end 149.69363 -221.784164)
		(stroke
			(width 0.2)
			(type default)
		)
		(layer "In1.Cu")
	)
	(gr_arc
		(start 150.86203 -213.080854)
		(mid 150.899227 -213.170657)
		(end 150.98903 -213.207854)
		(stroke
			(width 0.2)
			(type default)
		)
		(layer "In1.Cu")
	)
	(gr_line
		(start 150.86203 -211.760054)
		(end 150.86203 -213.080854)
		(stroke
			(width 0.2)
			(type default)
		)
		(layer "In1.Cu")
	)
	(gr_line
		(start 150.9141 -38.59784)
		(end 151.726646 -38.59784)
		(stroke
			(width 0.2)
			(type default)
		)
		(layer "In1.Cu")
	)
	(gr_arc
		(start 150.9141 -37.57676)
		(mid 150.40356 -38.0873)
		(end 150.9141 -38.59784)
		(stroke
			(width 0.2)
			(type default)
		)
		(layer "In1.Cu")
	)
	(gr_line
		(start 150.98903 -213.207854)
		(end 151.39543 -213.207854)
		(stroke
			(width 0.2)
			(type default)
		)
		(layer "In1.Cu")
	)
	(gr_arc
		(start 150.98903 -211.633054)
		(mid 150.899227 -211.670251)
		(end 150.86203 -211.760054)
		(stroke
			(width 0.2)
			(type default)
		)
		(layer "In1.Cu")
	)
	(gr_line
		(start 151.003 -93.7768)
		(end 151.13 -93.9038)
		(stroke
			(width 0.381)
			(type default)
		)
		(layer "In1.Cu")
	)
	(gr_line
		(start 151.003 -93.345)
		(end 151.003 -93.7768)
		(stroke
			(width 0.381)
			(type default)
		)
		(layer "In1.Cu")
	)
	(gr_line
		(start 151.003 -90.0938)
		(end 151.003 -93.345)
		(stroke
			(width 0.381)
			(type default)
		)
		(layer "In1.Cu")
	)
	(gr_line
		(start 151.13 -93.9038)
		(end 155.0924 -93.9038)
		(stroke
			(width 0.381)
			(type default)
		)
		(layer "In1.Cu")
	)
	(gr_line
		(start 151.29383 -211.406994)
		(end 152.10663 -211.406994)
		(stroke
			(width 0.2)
			(type default)
		)
		(layer "In1.Cu")
	)
	(gr_arc
		(start 151.294084 -210.385914)
		(mid 150.78329 -210.896327)
		(end 151.29383 -211.406994)
		(stroke
			(width 0.2)
			(type default)
		)
		(layer "In1.Cu")
	)
	(gr_line
		(start 151.3078 -89.789)
		(end 151.003 -90.0938)
		(stroke
			(width 0.381)
			(type default)
		)
		(layer "In1.Cu")
	)
	(gr_line
		(start 151.39543 -213.207854)
		(end 151.395684 -213.2076)
		(stroke
			(width 0.2)
			(type default)
		)
		(layer "In1.Cu")
	)
	(gr_line
		(start 151.395684 -213.2076)
		(end 151.996902 -213.2076)
		(stroke
			(width 0.2)
			(type default)
		)
		(layer "In1.Cu")
	)
	(gr_arc
		(start 151.7142 -34.3154)
		(mid 151.804003 -34.278203)
		(end 151.8412 -34.1884)
		(stroke
			(width 0.2)
			(type default)
		)
		(layer "In1.Cu")
	)
	(gr_line
		(start 151.7142 -32.7406)
		(end 150.4188 -32.7406)
		(stroke
			(width 0.2)
			(type default)
		)
		(layer "In1.Cu")
	)
	(gr_arc
		(start 151.726646 -38.59784)
		(mid 152.23744 -38.087427)
		(end 151.7269 -37.57676)
		(stroke
			(width 0.2)
			(type default)
		)
		(layer "In1.Cu")
	)
	(gr_line
		(start 151.7269 -37.57676)
		(end 150.9141 -37.57676)
		(stroke
			(width 0.2)
			(type default)
		)
		(layer "In1.Cu")
	)
	(gr_line
		(start 151.8412 -34.1884)
		(end 151.8412 -32.8676)
		(stroke
			(width 0.2)
			(type default)
		)
		(layer "In1.Cu")
	)
	(gr_arc
		(start 151.8412 -32.8676)
		(mid 151.804003 -32.777797)
		(end 151.7142 -32.7406)
		(stroke
			(width 0.2)
			(type default)
		)
		(layer "In1.Cu")
	)
	(gr_arc
		(start 151.996902 -213.2076)
		(mid 152.000964 -213.207795)
		(end 152.00503 -213.207854)
		(stroke
			(width 0.2)
			(type default)
		)
		(layer "In1.Cu")
	)
	(gr_line
		(start 152.00503 -213.207854)
		(end 152.41143 -213.207854)
		(stroke
			(width 0.2)
			(type default)
		)
		(layer "In1.Cu")
	)
	(gr_arc
		(start 152.10663 -211.406994)
		(mid 152.61717 -210.896454)
		(end 152.10663 -210.385914)
		(stroke
			(width 0.2)
			(type default)
		)
		(layer "In1.Cu")
	)
	(gr_line
		(start 152.10663 -210.385914)
		(end 151.294084 -210.385914)
		(stroke
			(width 0.2)
			(type default)
		)
		(layer "In1.Cu")
	)
	(gr_arc
		(start 152.273 -34.163)
		(mid 152.310197 -34.252803)
		(end 152.4 -34.29)
		(stroke
			(width 0.2)
			(type default)
		)
		(layer "In1.Cu")
	)
	(gr_line
		(start 152.273 -32.8422)
		(end 152.273 -34.163)
		(stroke
			(width 0.2)
			(type default)
		)
		(layer "In1.Cu")
	)
	(gr_line
		(start 152.4 -34.29)
		(end 153.6954 -34.29)
		(stroke
			(width 0.2)
			(type default)
		)
		(layer "In1.Cu")
	)
	(gr_arc
		(start 152.4 -32.7152)
		(mid 152.310197 -32.752397)
		(end 152.273 -32.8422)
		(stroke
			(width 0.2)
			(type default)
		)
		(layer "In1.Cu")
	)
	(gr_arc
		(start 152.41143 -213.207854)
		(mid 152.501233 -213.170657)
		(end 152.53843 -213.080854)
		(stroke
			(width 0.2)
			(type default)
		)
		(layer "In1.Cu")
	)
	(gr_line
		(start 152.41143 -211.633054)
		(end 150.98903 -211.633054)
		(stroke
			(width 0.2)
			(type default)
		)
		(layer "In1.Cu")
	)
	(gr_line
		(start 152.53843 -213.080854)
		(end 152.53843 -211.760054)
		(stroke
			(width 0.2)
			(type default)
		)
		(layer "In1.Cu")
	)
	(gr_arc
		(start 152.53843 -211.760054)
		(mid 152.501233 -211.670251)
		(end 152.41143 -211.633054)
		(stroke
			(width 0.2)
			(type default)
		)
		(layer "In1.Cu")
	)
	(gr_line
		(start 152.7175 -35.50666)
		(end 153.530046 -35.50666)
		(stroke
			(width 0.2)
			(type default)
		)
		(layer "In1.Cu")
	)
	(gr_arc
		(start 152.7175 -34.48558)
		(mid 152.20696 -34.99612)
		(end 152.7175 -35.50666)
		(stroke
			(width 0.2)
			(type default)
		)
		(layer "In1.Cu")
	)
	(gr_line
		(start 152.893776 -222.805244)
		(end 153.706322 -222.805244)
		(stroke
			(width 0.2)
			(type default)
		)
		(layer "In1.Cu")
	)
	(gr_arc
		(start 152.893776 -221.784164)
		(mid 152.383236 -222.294704)
		(end 152.893776 -222.805244)
		(stroke
			(width 0.2)
			(type default)
		)
		(layer "In1.Cu")
	)
	(gr_arc
		(start 153.530046 -35.50666)
		(mid 154.04084 -34.996247)
		(end 153.5303 -34.48558)
		(stroke
			(width 0.2)
			(type default)
		)
		(layer "In1.Cu")
	)
	(gr_line
		(start 153.5303 -34.48558)
		(end 152.7175 -34.48558)
		(stroke
			(width 0.2)
			(type default)
		)
		(layer "In1.Cu")
	)
	(gr_arc
		(start 153.6954 -34.29)
		(mid 153.785203 -34.252803)
		(end 153.8224 -34.163)
		(stroke
			(width 0.2)
			(type default)
		)
		(layer "In1.Cu")
	)
	(gr_line
		(start 153.6954 -32.7152)
		(end 152.4 -32.7152)
		(stroke
			(width 0.2)
			(type default)
		)
		(layer "In1.Cu")
	)
	(gr_arc
		(start 153.706322 -222.805244)
		(mid 154.217116 -222.294831)
		(end 153.706576 -221.784164)
		(stroke
			(width 0.2)
			(type default)
		)
		(layer "In1.Cu")
	)
	(gr_line
		(start 153.706576 -221.784164)
		(end 152.893776 -221.784164)
		(stroke
			(width 0.2)
			(type default)
		)
		(layer "In1.Cu")
	)
	(gr_line
		(start 153.8224 -34.163)
		(end 153.8224 -32.8422)
		(stroke
			(width 0.2)
			(type default)
		)
		(layer "In1.Cu")
	)
	(gr_arc
		(start 153.8224 -32.8422)
		(mid 153.785203 -32.752397)
		(end 153.6954 -32.7152)
		(stroke
			(width 0.2)
			(type default)
		)
		(layer "In1.Cu")
	)
	(gr_arc
		(start 154.061922 -213.080854)
		(mid 154.099119 -213.170657)
		(end 154.188922 -213.207854)
		(stroke
			(width 0.2)
			(type default)
		)
		(layer "In1.Cu")
	)
	(gr_line
		(start 154.061922 -211.760054)
		(end 154.061922 -213.080854)
		(stroke
			(width 0.2)
			(type default)
		)
		(layer "In1.Cu")
	)
	(gr_line
		(start 154.188922 -213.207854)
		(end 154.595322 -213.207854)
		(stroke
			(width 0.2)
			(type default)
		)
		(layer "In1.Cu")
	)
	(gr_arc
		(start 154.188922 -211.633054)
		(mid 154.099119 -211.670251)
		(end 154.061922 -211.760054)
		(stroke
			(width 0.2)
			(type default)
		)
		(layer "In1.Cu")
	)
	(gr_line
		(start 154.493722 -211.406994)
		(end 155.306522 -211.406994)
		(stroke
			(width 0.2)
			(type default)
		)
		(layer "In1.Cu")
	)
	(gr_arc
		(start 154.493976 -210.385914)
		(mid 153.983182 -210.896327)
		(end 154.493722 -211.406994)
		(stroke
			(width 0.2)
			(type default)
		)
		(layer "In1.Cu")
	)
	(gr_arc
		(start 154.583638 -25.035256)
		(mid 154.83967 -25.881076)
		(end 155.68549 -25.625044)
		(stroke
			(width 0.2)
			(type default)
		)
		(layer "In1.Cu")
	)
	(gr_arc
		(start 154.587702 -13.627608)
		(mid 154.835836 -14.479061)
		(end 155.68549 -14.225016)
		(stroke
			(width 0.2)
			(type default)
		)
		(layer "In1.Cu")
	)
	(gr_line
		(start 154.595322 -213.207854)
		(end 154.595576 -213.2076)
		(stroke
			(width 0.2)
			(type default)
		)
		(layer "In1.Cu")
	)
	(gr_line
		(start 154.595576 -213.2076)
		(end 155.196794 -213.2076)
		(stroke
			(width 0.2)
			(type default)
		)
		(layer "In1.Cu")
	)
	(gr_line
		(start 155.0162 -89.789)
		(end 151.3078 -89.789)
		(stroke
			(width 0.381)
			(type default)
		)
		(layer "In1.Cu")
	)
	(gr_line
		(start 155.0924 -93.9038)
		(end 155.2956 -93.7006)
		(stroke
			(width 0.381)
			(type default)
		)
		(layer "In1.Cu")
	)
	(gr_arc
		(start 155.196794 -213.2076)
		(mid 155.200856 -213.207795)
		(end 155.204922 -213.207854)
		(stroke
			(width 0.2)
			(type default)
		)
		(layer "In1.Cu")
	)
	(gr_line
		(start 155.204922 -213.207854)
		(end 155.611322 -213.207854)
		(stroke
			(width 0.2)
			(type default)
		)
		(layer "In1.Cu")
	)
	(gr_line
		(start 155.2956 -93.7006)
		(end 155.2956 -90.0684)
		(stroke
			(width 0.381)
			(type default)
		)
		(layer "In1.Cu")
	)
	(gr_line
		(start 155.2956 -90.0684)
		(end 155.0162 -89.789)
		(stroke
			(width 0.381)
			(type default)
		)
		(layer "In1.Cu")
	)
	(gr_arc
		(start 155.306522 -211.406994)
		(mid 155.817062 -210.896454)
		(end 155.306522 -210.385914)
		(stroke
			(width 0.2)
			(type default)
		)
		(layer "In1.Cu")
	)
	(gr_line
		(start 155.306522 -210.385914)
		(end 154.493976 -210.385914)
		(stroke
			(width 0.2)
			(type default)
		)
		(layer "In1.Cu")
	)
	(gr_line
		(start 155.333446 -23.635208)
		(end 154.583638 -25.035256)
		(stroke
			(width 0.2)
			(type default)
		)
		(layer "In1.Cu")
	)
	(gr_line
		(start 155.333446 -12.23518)
		(end 154.587702 -13.627608)
		(stroke
			(width 0.2)
			(type default)
		)
		(layer "In1.Cu")
	)
	(gr_arc
		(start 155.611322 -213.207854)
		(mid 155.701125 -213.170657)
		(end 155.738322 -213.080854)
		(stroke
			(width 0.2)
			(type default)
		)
		(layer "In1.Cu")
	)
	(gr_line
		(start 155.611322 -211.633054)
		(end 154.188922 -211.633054)
		(stroke
			(width 0.2)
			(type default)
		)
		(layer "In1.Cu")
	)
	(gr_line
		(start 155.68549 -25.625044)
		(end 156.431234 -24.232616)
		(stroke
			(width 0.2)
			(type default)
		)
		(layer "In1.Cu")
	)
	(gr_line
		(start 155.68549 -14.225016)
		(end 156.435298 -12.824968)
		(stroke
			(width 0.2)
			(type default)
		)
		(layer "In1.Cu")
	)
	(gr_line
		(start 155.738322 -213.080854)
		(end 155.738322 -211.760054)
		(stroke
			(width 0.2)
			(type default)
		)
		(layer "In1.Cu")
	)
	(gr_arc
		(start 155.738322 -211.760054)
		(mid 155.701125 -211.670251)
		(end 155.611322 -211.633054)
		(stroke
			(width 0.2)
			(type default)
		)
		(layer "In1.Cu")
	)
	(gr_line
		(start 156.093668 -222.805244)
		(end 156.906214 -222.805244)
		(stroke
			(width 0.2)
			(type default)
		)
		(layer "In1.Cu")
	)
	(gr_arc
		(start 156.093668 -221.784164)
		(mid 155.583128 -222.294704)
		(end 156.093668 -222.805244)
		(stroke
			(width 0.2)
			(type default)
		)
		(layer "In1.Cu")
	)
	(gr_arc
		(start 156.431234 -24.232616)
		(mid 156.1831 -23.381163)
		(end 155.333446 -23.635208)
		(stroke
			(width 0.2)
			(type default)
		)
		(layer "In1.Cu")
	)
	(gr_arc
		(start 156.435298 -12.824968)
		(mid 156.179266 -11.979148)
		(end 155.333446 -12.23518)
		(stroke
			(width 0.2)
			(type default)
		)
		(layer "In1.Cu")
	)
	(gr_line
		(start 156.831538 -25.033732)
		(end 156.831792 -25.033986)
		(stroke
			(width 0.2)
			(type default)
		)
		(layer "In1.Cu")
	)
	(gr_line
		(start 156.831538 -21.233892)
		(end 156.83357 -21.235162)
		(stroke
			(width 0.2)
			(type default)
		)
		(layer "In1.Cu")
	)
	(gr_line
		(start 156.831538 -17.433544)
		(end 156.831792 -17.433798)
		(stroke
			(width 0.2)
			(type default)
		)
		(layer "In1.Cu")
	)
	(gr_line
		(start 156.831538 -13.633704)
		(end 156.831792 -13.633958)
		(stroke
			(width 0.2)
			(type default)
		)
		(layer "In1.Cu")
	)
	(gr_line
		(start 156.831792 -25.033986)
		(end 156.833824 -25.035002)
		(stroke
			(width 0.2)
			(type default)
		)
		(layer "In1.Cu")
	)
	(gr_line
		(start 156.831792 -17.433798)
		(end 156.833824 -17.434814)
		(stroke
			(width 0.2)
			(type default)
		)
		(layer "In1.Cu")
	)
	(gr_line
		(start 156.831792 -13.633958)
		(end 156.833824 -13.634974)
		(stroke
			(width 0.2)
			(type default)
		)
		(layer "In1.Cu")
	)
	(gr_arc
		(start 156.83357 -21.235162)
		(mid 157.089602 -22.080982)
		(end 157.935422 -21.82495)
		(stroke
			(width 0.2)
			(type default)
		)
		(layer "In1.Cu")
	)
	(gr_arc
		(start 156.833824 -25.035002)
		(mid 157.0895 -25.880903)
		(end 157.935422 -25.625044)
		(stroke
			(width 0.2)
			(type default)
		)
		(layer "In1.Cu")
	)
	(gr_arc
		(start 156.833824 -17.434814)
		(mid 157.089348 -18.280634)
		(end 157.935168 -18.02511)
		(stroke
			(width 0.2)
			(type default)
		)
		(layer "In1.Cu")
	)
	(gr_arc
		(start 156.833824 -13.634974)
		(mid 157.0895 -14.480875)
		(end 157.935422 -14.225016)
		(stroke
			(width 0.2)
			(type default)
		)
		(layer "In1.Cu")
	)
	(gr_arc
		(start 156.906214 -222.805244)
		(mid 157.417008 -222.294831)
		(end 156.906468 -221.784164)
		(stroke
			(width 0.2)
			(type default)
		)
		(layer "In1.Cu")
	)
	(gr_line
		(start 156.906468 -221.784164)
		(end 156.093668 -221.784164)
		(stroke
			(width 0.2)
			(type default)
		)
		(layer "In1.Cu")
	)
	(gr_arc
		(start 157.262068 -213.080854)
		(mid 157.299265 -213.170657)
		(end 157.389068 -213.207854)
		(stroke
			(width 0.2)
			(type default)
		)
		(layer "In1.Cu")
	)
	(gr_line
		(start 157.262068 -211.760054)
		(end 157.262068 -213.080854)
		(stroke
			(width 0.2)
			(type default)
		)
		(layer "In1.Cu")
	)
	(gr_line
		(start 157.389068 -213.207854)
		(end 157.795468 -213.207854)
		(stroke
			(width 0.2)
			(type default)
		)
		(layer "In1.Cu")
	)
	(gr_arc
		(start 157.389068 -211.633054)
		(mid 157.299265 -211.670251)
		(end 157.262068 -211.760054)
		(stroke
			(width 0.2)
			(type default)
		)
		(layer "In1.Cu")
	)
	(gr_line
		(start 157.5816 -23.633938)
		(end 156.831538 -25.033732)
		(stroke
			(width 0.2)
			(type default)
		)
		(layer "In1.Cu")
	)
	(gr_line
		(start 157.5816 -19.833844)
		(end 156.831538 -21.233892)
		(stroke
			(width 0.2)
			(type default)
		)
		(layer "In1.Cu")
	)
	(gr_line
		(start 157.5816 -16.03375)
		(end 156.831538 -17.433544)
		(stroke
			(width 0.2)
			(type default)
		)
		(layer "In1.Cu")
	)
	(gr_line
		(start 157.5816 -12.23391)
		(end 156.831538 -13.633704)
		(stroke
			(width 0.2)
			(type default)
		)
		(layer "In1.Cu")
	)
	(gr_line
		(start 157.583632 -23.635208)
		(end 157.5816 -23.633938)
		(stroke
			(width 0.2)
			(type default)
		)
		(layer "In1.Cu")
	)
	(gr_line
		(start 157.583632 -19.835114)
		(end 157.5816 -19.833844)
		(stroke
			(width 0.2)
			(type default)
		)
		(layer "In1.Cu")
	)
	(gr_line
		(start 157.583632 -12.23518)
		(end 157.5816 -12.23391)
		(stroke
			(width 0.2)
			(type default)
		)
		(layer "In1.Cu")
	)
	(gr_line
		(start 157.583886 -16.03502)
		(end 157.5816 -16.03375)
		(stroke
			(width 0.2)
			(type default)
		)
		(layer "In1.Cu")
	)
	(gr_line
		(start 157.693868 -211.406994)
		(end 158.506668 -211.406994)
		(stroke
			(width 0.2)
			(type default)
		)
		(layer "In1.Cu")
	)
	(gr_arc
		(start 157.694122 -210.385914)
		(mid 157.183328 -210.896327)
		(end 157.693868 -211.406994)
		(stroke
			(width 0.2)
			(type default)
		)
		(layer "In1.Cu")
	)
	(gr_line
		(start 157.795468 -213.207854)
		(end 157.795722 -213.2076)
		(stroke
			(width 0.2)
			(type default)
		)
		(layer "In1.Cu")
	)
	(gr_line
		(start 157.795722 -213.2076)
		(end 158.39694 -213.2076)
		(stroke
			(width 0.2)
			(type default)
		)
		(layer "In1.Cu")
	)
	(gr_line
		(start 157.935168 -18.02511)
		(end 157.937454 -18.02638)
		(stroke
			(width 0.2)
			(type default)
		)
		(layer "In1.Cu")
	)
	(gr_line
		(start 157.935422 -25.625044)
		(end 157.937454 -25.626314)
		(stroke
			(width 0.2)
			(type default)
		)
		(layer "In1.Cu")
	)
	(gr_line
		(start 157.935422 -21.82495)
		(end 157.937454 -21.82622)
		(stroke
			(width 0.2)
			(type default)
		)
		(layer "In1.Cu")
	)
	(gr_line
		(start 157.935422 -14.225016)
		(end 157.937454 -14.226286)
		(stroke
			(width 0.2)
			(type default)
		)
		(layer "In1.Cu")
	)
	(gr_line
		(start 157.937454 -25.626314)
		(end 158.687516 -24.226266)
		(stroke
			(width 0.2)
			(type default)
		)
		(layer "In1.Cu")
	)
	(gr_line
		(start 157.937454 -21.82622)
		(end 158.687516 -20.426426)
		(stroke
			(width 0.2)
			(type default)
		)
		(layer "In1.Cu")
	)
	(gr_line
		(start 157.937454 -18.02638)
		(end 158.687516 -16.626586)
		(stroke
			(width 0.2)
			(type default)
		)
		(layer "In1.Cu")
	)
	(gr_line
		(start 157.937454 -14.226286)
		(end 158.687516 -12.826238)
		(stroke
			(width 0.2)
			(type default)
		)
		(layer "In1.Cu")
	)
	(gr_arc
		(start 158.210504 -34.1884)
		(mid 158.247701 -34.278203)
		(end 158.337504 -34.3154)
		(stroke
			(width 0.2)
			(type default)
		)
		(layer "In1.Cu")
	)
	(gr_line
		(start 158.210504 -32.8676)
		(end 158.210504 -34.1884)
		(stroke
			(width 0.2)
			(type default)
		)
		(layer "In1.Cu")
	)
	(gr_line
		(start 158.337504 -34.3154)
		(end 159.632904 -34.3154)
		(stroke
			(width 0.2)
			(type default)
		)
		(layer "In1.Cu")
	)
	(gr_arc
		(start 158.337504 -32.7406)
		(mid 158.247701 -32.777797)
		(end 158.210504 -32.8676)
		(stroke
			(width 0.2)
			(type default)
		)
		(layer "In1.Cu")
	)
	(gr_arc
		(start 158.39694 -213.2076)
		(mid 158.401002 -213.207795)
		(end 158.405068 -213.207854)
		(stroke
			(width 0.2)
			(type default)
		)
		(layer "In1.Cu")
	)
	(gr_line
		(start 158.405068 -213.207854)
		(end 158.811468 -213.207854)
		(stroke
			(width 0.2)
			(type default)
		)
		(layer "In1.Cu")
	)
	(gr_arc
		(start 158.506668 -211.406994)
		(mid 159.017208 -210.896454)
		(end 158.506668 -210.385914)
		(stroke
			(width 0.2)
			(type default)
		)
		(layer "In1.Cu")
	)
	(gr_line
		(start 158.506668 -210.385914)
		(end 157.694122 -210.385914)
		(stroke
			(width 0.2)
			(type default)
		)
		(layer "In1.Cu")
	)
	(gr_line
		(start 158.655004 -35.53206)
		(end 159.467804 -35.53206)
		(stroke
			(width 0.2)
			(type default)
		)
		(layer "In1.Cu")
	)
	(gr_arc
		(start 158.655258 -34.51098)
		(mid 158.144464 -35.021393)
		(end 158.655004 -35.53206)
		(stroke
			(width 0.2)
			(type default)
		)
		(layer "In1.Cu")
	)
	(gr_arc
		(start 158.68523 -20.425156)
		(mid 158.429554 -19.579255)
		(end 157.583632 -19.835114)
		(stroke
			(width 0.2)
			(type default)
		)
		(layer "In1.Cu")
	)
	(gr_arc
		(start 158.68523 -16.625316)
		(mid 158.429706 -15.779496)
		(end 157.583886 -16.03502)
		(stroke
			(width 0.2)
			(type default)
		)
		(layer "In1.Cu")
	)
	(gr_arc
		(start 158.685484 -24.224996)
		(mid 158.429452 -23.379176)
		(end 157.583632 -23.635208)
		(stroke
			(width 0.2)
			(type default)
		)
		(layer "In1.Cu")
	)
	(gr_arc
		(start 158.685484 -12.824968)
		(mid 158.429452 -11.979148)
		(end 157.583632 -12.23518)
		(stroke
			(width 0.2)
			(type default)
		)
		(layer "In1.Cu")
	)
	(gr_line
		(start 158.687262 -20.426172)
		(end 158.68523 -20.425156)
		(stroke
			(width 0.2)
			(type default)
		)
		(layer "In1.Cu")
	)
	(gr_line
		(start 158.687516 -24.226266)
		(end 158.685484 -24.224996)
		(stroke
			(width 0.2)
			(type default)
		)
		(layer "In1.Cu")
	)
	(gr_line
		(start 158.687516 -20.426426)
		(end 158.687262 -20.426172)
		(stroke
			(width 0.2)
			(type default)
		)
		(layer "In1.Cu")
	)
	(gr_line
		(start 158.687516 -16.626586)
		(end 158.68523 -16.625316)
		(stroke
			(width 0.2)
			(type default)
		)
		(layer "In1.Cu")
	)
	(gr_line
		(start 158.687516 -12.826238)
		(end 158.685484 -12.824968)
		(stroke
			(width 0.2)
			(type default)
		)
		(layer "In1.Cu")
	)
	(gr_arc
		(start 158.811468 -213.207854)
		(mid 158.901271 -213.170657)
		(end 158.938468 -213.080854)
		(stroke
			(width 0.2)
			(type default)
		)
		(layer "In1.Cu")
	)
	(gr_line
		(start 158.811468 -211.633054)
		(end 157.389068 -211.633054)
		(stroke
			(width 0.2)
			(type default)
		)
		(layer "In1.Cu")
	)
	(gr_line
		(start 158.938468 -213.080854)
		(end 158.938468 -211.760054)
		(stroke
			(width 0.2)
			(type default)
		)
		(layer "In1.Cu")
	)
	(gr_arc
		(start 158.938468 -211.760054)
		(mid 158.901271 -211.670251)
		(end 158.811468 -211.633054)
		(stroke
			(width 0.2)
			(type default)
		)
		(layer "In1.Cu")
	)
	(gr_line
		(start 159.08147 -25.033732)
		(end 159.081724 -25.033986)
		(stroke
			(width 0.2)
			(type default)
		)
		(layer "In1.Cu")
	)
	(gr_line
		(start 159.08147 -21.233892)
		(end 159.083502 -21.235162)
		(stroke
			(width 0.2)
			(type default)
		)
		(layer "In1.Cu")
	)
	(gr_line
		(start 159.08147 -17.433544)
		(end 159.081724 -17.433798)
		(stroke
			(width 0.2)
			(type default)
		)
		(layer "In1.Cu")
	)
	(gr_line
		(start 159.08147 -13.633704)
		(end 159.081724 -13.633958)
		(stroke
			(width 0.2)
			(type default)
		)
		(layer "In1.Cu")
	)
	(gr_line
		(start 159.081724 -25.033986)
		(end 159.083756 -25.035002)
		(stroke
			(width 0.2)
			(type default)
		)
		(layer "In1.Cu")
	)
	(gr_line
		(start 159.081724 -17.433798)
		(end 159.083756 -17.434814)
		(stroke
			(width 0.2)
			(type default)
		)
		(layer "In1.Cu")
	)
	(gr_line
		(start 159.081724 -13.633958)
		(end 159.083756 -13.634974)
		(stroke
			(width 0.2)
			(type default)
		)
		(layer "In1.Cu")
	)
	(gr_arc
		(start 159.083502 -21.235162)
		(mid 159.339534 -22.080982)
		(end 160.185354 -21.82495)
		(stroke
			(width 0.2)
			(type default)
		)
		(layer "In1.Cu")
	)
	(gr_arc
		(start 159.083756 -25.035002)
		(mid 159.339432 -25.880903)
		(end 160.185354 -25.625044)
		(stroke
			(width 0.2)
			(type default)
		)
		(layer "In1.Cu")
	)
	(gr_arc
		(start 159.083756 -17.434814)
		(mid 159.33928 -18.280634)
		(end 160.1851 -18.02511)
		(stroke
			(width 0.2)
			(type default)
		)
		(layer "In1.Cu")
	)
	(gr_arc
		(start 159.083756 -13.634974)
		(mid 159.339432 -14.480875)
		(end 160.185354 -14.225016)
		(stroke
			(width 0.2)
			(type default)
		)
		(layer "In1.Cu")
	)
	(gr_line
		(start 159.29356 -222.805244)
		(end 160.106106 -222.805244)
		(stroke
			(width 0.2)
			(type default)
		)
		(layer "In1.Cu")
	)
	(gr_arc
		(start 159.29356 -221.784164)
		(mid 158.78302 -222.294704)
		(end 159.29356 -222.805244)
		(stroke
			(width 0.2)
			(type default)
		)
		(layer "In1.Cu")
	)
	(gr_arc
		(start 159.467804 -35.53206)
		(mid 159.978344 -35.02152)
		(end 159.467804 -34.51098)
		(stroke
			(width 0.2)
			(type default)
		)
		(layer "In1.Cu")
	)
	(gr_line
		(start 159.467804 -34.51098)
		(end 158.655258 -34.51098)
		(stroke
			(width 0.2)
			(type default)
		)
		(layer "In1.Cu")
	)
	(gr_arc
		(start 159.632904 -34.3154)
		(mid 159.722707 -34.278203)
		(end 159.759904 -34.1884)
		(stroke
			(width 0.2)
			(type default)
		)
		(layer "In1.Cu")
	)
	(gr_line
		(start 159.632904 -32.7406)
		(end 158.337504 -32.7406)
		(stroke
			(width 0.2)
			(type default)
		)
		(layer "In1.Cu")
	)
	(gr_line
		(start 159.759904 -34.1884)
		(end 159.759904 -32.8676)
		(stroke
			(width 0.2)
			(type default)
		)
		(layer "In1.Cu")
	)
	(gr_arc
		(start 159.759904 -32.8676)
		(mid 159.722707 -32.777797)
		(end 159.632904 -32.7406)
		(stroke
			(width 0.2)
			(type default)
		)
		(layer "In1.Cu")
	)
	(gr_line
		(start 159.831532 -23.633938)
		(end 159.08147 -25.033732)
		(stroke
			(width 0.2)
			(type default)
		)
		(layer "In1.Cu")
	)
	(gr_line
		(start 159.831532 -19.833844)
		(end 159.08147 -21.233892)
		(stroke
			(width 0.2)
			(type default)
		)
		(layer "In1.Cu")
	)
	(gr_line
		(start 159.831532 -16.03375)
		(end 159.08147 -17.433544)
		(stroke
			(width 0.2)
			(type default)
		)
		(layer "In1.Cu")
	)
	(gr_line
		(start 159.831532 -12.23391)
		(end 159.08147 -13.633704)
		(stroke
			(width 0.2)
			(type default)
		)
		(layer "In1.Cu")
	)
	(gr_line
		(start 159.833564 -23.635208)
		(end 159.831532 -23.633938)
		(stroke
			(width 0.2)
			(type default)
		)
		(layer "In1.Cu")
	)
	(gr_line
		(start 159.833564 -19.835114)
		(end 159.831532 -19.833844)
		(stroke
			(width 0.2)
			(type default)
		)
		(layer "In1.Cu")
	)
	(gr_line
		(start 159.833564 -12.23518)
		(end 159.831532 -12.23391)
		(stroke
			(width 0.2)
			(type default)
		)
		(layer "In1.Cu")
	)
	(gr_line
		(start 159.833818 -16.03502)
		(end 159.831532 -16.03375)
		(stroke
			(width 0.2)
			(type default)
		)
		(layer "In1.Cu")
	)
	(gr_arc
		(start 160.106106 -222.805244)
		(mid 160.6169 -222.294831)
		(end 160.10636 -221.784164)
		(stroke
			(width 0.2)
			(type default)
		)
		(layer "In1.Cu")
	)
	(gr_line
		(start 160.10636 -221.784164)
		(end 159.29356 -221.784164)
		(stroke
			(width 0.2)
			(type default)
		)
		(layer "In1.Cu")
	)
	(gr_line
		(start 160.1851 -18.02511)
		(end 160.187386 -18.02638)
		(stroke
			(width 0.2)
			(type default)
		)
		(layer "In1.Cu")
	)
	(gr_line
		(start 160.185354 -25.625044)
		(end 160.187386 -25.626314)
		(stroke
			(width 0.2)
			(type default)
		)
		(layer "In1.Cu")
	)
	(gr_line
		(start 160.185354 -21.82495)
		(end 160.187386 -21.82622)
		(stroke
			(width 0.2)
			(type default)
		)
		(layer "In1.Cu")
	)
	(gr_line
		(start 160.185354 -14.225016)
		(end 160.187386 -14.226286)
		(stroke
			(width 0.2)
			(type default)
		)
		(layer "In1.Cu")
	)
	(gr_line
		(start 160.187386 -25.626314)
		(end 160.937448 -24.226266)
		(stroke
			(width 0.2)
			(type default)
		)
		(layer "In1.Cu")
	)
	(gr_line
		(start 160.187386 -21.82622)
		(end 160.937448 -20.426426)
		(stroke
			(width 0.2)
			(type default)
		)
		(layer "In1.Cu")
	)
	(gr_line
		(start 160.187386 -18.02638)
		(end 160.937448 -16.626586)
		(stroke
			(width 0.2)
			(type default)
		)
		(layer "In1.Cu")
	)
	(gr_line
		(start 160.187386 -14.226286)
		(end 160.937448 -12.826238)
		(stroke
			(width 0.2)
			(type default)
		)
		(layer "In1.Cu")
	)
	(gr_arc
		(start 160.46196 -213.080854)
		(mid 160.499157 -213.170657)
		(end 160.58896 -213.207854)
		(stroke
			(width 0.2)
			(type default)
		)
		(layer "In1.Cu")
	)
	(gr_line
		(start 160.46196 -211.760054)
		(end 160.46196 -213.080854)
		(stroke
			(width 0.2)
			(type default)
		)
		(layer "In1.Cu")
	)
	(gr_line
		(start 160.58896 -213.207854)
		(end 160.99536 -213.207854)
		(stroke
			(width 0.2)
			(type default)
		)
		(layer "In1.Cu")
	)
	(gr_arc
		(start 160.58896 -211.633054)
		(mid 160.499157 -211.670251)
		(end 160.46196 -211.760054)
		(stroke
			(width 0.2)
			(type default)
		)
		(layer "In1.Cu")
	)
	(gr_line
		(start 160.685226 -88.608662)
		(end 160.685226 -87.568024)
		(stroke
			(width 0.2)
			(type default)
		)
		(layer "In1.Cu")
	)
	(gr_line
		(start 160.685226 -87.568024)
		(end 160.879536 -87.568024)
		(stroke
			(width 0.2)
			(type default)
		)
		(layer "In1.Cu")
	)
	(gr_arc
		(start 160.8328 -34.1884)
		(mid 160.869997 -34.278203)
		(end 160.9598 -34.3154)
		(stroke
			(width 0.2)
			(type default)
		)
		(layer "In1.Cu")
	)
	(gr_line
		(start 160.8328 -32.8676)
		(end 160.8328 -34.1884)
		(stroke
			(width 0.2)
			(type default)
		)
		(layer "In1.Cu")
	)
	(gr_line
		(start 160.879536 -88.609678)
		(end 160.879536 -88.608662)
		(stroke
			(width 0.2)
			(type default)
		)
		(layer "In1.Cu")
	)
	(gr_line
		(start 160.879536 -88.608662)
		(end 160.685226 -88.608662)
		(stroke
			(width 0.2)
			(type default)
		)
		(layer "In1.Cu")
	)
	(gr_line
		(start 160.879536 -87.568278)
		(end 161.684462 -87.568278)
		(stroke
			(width 0.2)
			(type default)
		)
		(layer "In1.Cu")
	)
	(gr_line
		(start 160.879536 -87.568024)
		(end 160.879536 -87.568278)
		(stroke
			(width 0.2)
			(type default)
		)
		(layer "In1.Cu")
	)
	(gr_line
		(start 160.89376 -211.406994)
		(end 161.70656 -211.406994)
		(stroke
			(width 0.2)
			(type default)
		)
		(layer "In1.Cu")
	)
	(gr_arc
		(start 160.894014 -210.385914)
		(mid 160.38322 -210.896327)
		(end 160.89376 -211.406994)
		(stroke
			(width 0.2)
			(type default)
		)
		(layer "In1.Cu")
	)
	(gr_arc
		(start 160.935162 -20.425156)
		(mid 160.679486 -19.579255)
		(end 159.833564 -19.835114)
		(stroke
			(width 0.2)
			(type default)
		)
		(layer "In1.Cu")
	)
	(gr_arc
		(start 160.935162 -16.625316)
		(mid 160.679638 -15.779496)
		(end 159.833818 -16.03502)
		(stroke
			(width 0.2)
			(type default)
		)
		(layer "In1.Cu")
	)
	(gr_arc
		(start 160.935416 -24.224996)
		(mid 160.679384 -23.379176)
		(end 159.833564 -23.635208)
		(stroke
			(width 0.2)
			(type default)
		)
		(layer "In1.Cu")
	)
	(gr_arc
		(start 160.935416 -12.824968)
		(mid 160.679384 -11.979148)
		(end 159.833564 -12.23518)
		(stroke
			(width 0.2)
			(type default)
		)
		(layer "In1.Cu")
	)
	(gr_line
		(start 160.937194 -20.426172)
		(end 160.935162 -20.425156)
		(stroke
			(width 0.2)
			(type default)
		)
		(layer "In1.Cu")
	)
	(gr_line
		(start 160.937448 -24.226266)
		(end 160.935416 -24.224996)
		(stroke
			(width 0.2)
			(type default)
		)
		(layer "In1.Cu")
	)
	(gr_line
		(start 160.937448 -20.426426)
		(end 160.937194 -20.426172)
		(stroke
			(width 0.2)
			(type default)
		)
		(layer "In1.Cu")
	)
	(gr_line
		(start 160.937448 -16.626586)
		(end 160.935162 -16.625316)
		(stroke
			(width 0.2)
			(type default)
		)
		(layer "In1.Cu")
	)
	(gr_line
		(start 160.937448 -12.826238)
		(end 160.935416 -12.824968)
		(stroke
			(width 0.2)
			(type default)
		)
		(layer "In1.Cu")
	)
	(gr_line
		(start 160.9598 -34.3154)
		(end 162.2552 -34.3154)
		(stroke
			(width 0.2)
			(type default)
		)
		(layer "In1.Cu")
	)
	(gr_arc
		(start 160.9598 -32.7406)
		(mid 160.869997 -32.777797)
		(end 160.8328 -32.8676)
		(stroke
			(width 0.2)
			(type default)
		)
		(layer "In1.Cu")
	)
	(gr_line
		(start 160.99536 -213.207854)
		(end 160.995614 -213.2076)
		(stroke
			(width 0.2)
			(type default)
		)
		(layer "In1.Cu")
	)
	(gr_line
		(start 160.995614 -213.2076)
		(end 161.596832 -213.2076)
		(stroke
			(width 0.2)
			(type default)
		)
		(layer "In1.Cu")
	)
	(gr_arc
		(start 161.2646 -85.852)
		(mid 161.294358 -85.923842)
		(end 161.3662 -85.9536)
		(stroke
			(width 0.2)
			(type default)
		)
		(layer "In1.Cu")
	)
	(gr_line
		(start 161.2646 -84.6328)
		(end 161.2646 -85.852)
		(stroke
			(width 0.2)
			(type default)
		)
		(layer "In1.Cu")
	)
	(gr_line
		(start 161.2773 -35.53206)
		(end 162.0901 -35.53206)
		(stroke
			(width 0.2)
			(type default)
		)
		(layer "In1.Cu")
	)
	(gr_arc
		(start 161.277554 -34.51098)
		(mid 160.76676 -35.021393)
		(end 161.2773 -35.53206)
		(stroke
			(width 0.2)
			(type default)
		)
		(layer "In1.Cu")
	)
	(gr_line
		(start 161.3662 -85.9536)
		(end 162.7378 -85.9536)
		(stroke
			(width 0.2)
			(type default)
		)
		(layer "In1.Cu")
	)
	(gr_arc
		(start 161.3662 -84.5312)
		(mid 161.294358 -84.560958)
		(end 161.2646 -84.6328)
		(stroke
			(width 0.2)
			(type default)
		)
		(layer "In1.Cu")
	)
	(gr_arc
		(start 161.596832 -213.2076)
		(mid 161.600894 -213.207795)
		(end 161.60496 -213.207854)
		(stroke
			(width 0.2)
			(type default)
		)
		(layer "In1.Cu")
	)
	(gr_line
		(start 161.60496 -213.207854)
		(end 162.01136 -213.207854)
		(stroke
			(width 0.2)
			(type default)
		)
		(layer "In1.Cu")
	)
	(gr_line
		(start 161.684462 -88.609678)
		(end 160.879536 -88.609678)
		(stroke
			(width 0.2)
			(type default)
		)
		(layer "In1.Cu")
	)
	(gr_line
		(start 161.684462 -87.568278)
		(end 161.878264 -87.568278)
		(stroke
			(width 0.2)
			(type default)
		)
		(layer "In1.Cu")
	)
	(gr_arc
		(start 161.70656 -211.406994)
		(mid 162.2171 -210.896454)
		(end 161.70656 -210.385914)
		(stroke
			(width 0.2)
			(type default)
		)
		(layer "In1.Cu")
	)
	(gr_line
		(start 161.70656 -210.385914)
		(end 160.894014 -210.385914)
		(stroke
			(width 0.2)
			(type default)
		)
		(layer "In1.Cu")
	)
	(gr_line
		(start 161.7853 -38.52164)
		(end 162.597846 -38.52164)
		(stroke
			(width 0.2)
			(type default)
		)
		(layer "In1.Cu")
	)
	(gr_arc
		(start 161.7853 -37.50056)
		(mid 161.27476 -38.0111)
		(end 161.7853 -38.52164)
		(stroke
			(width 0.2)
			(type default)
		)
		(layer "In1.Cu")
	)
	(gr_line
		(start 161.878264 -88.609678)
		(end 161.684462 -88.609678)
		(stroke
			(width 0.2)
			(type default)
		)
		(layer "In1.Cu")
	)
	(gr_line
		(start 161.878264 -87.568278)
		(end 161.878264 -88.609678)
		(stroke
			(width 0.2)
			(type default)
		)
		(layer "In1.Cu")
	)
	(gr_arc
		(start 162.01136 -213.207854)
		(mid 162.101163 -213.170657)
		(end 162.13836 -213.080854)
		(stroke
			(width 0.2)
			(type default)
		)
		(layer "In1.Cu")
	)
	(gr_line
		(start 162.01136 -211.633054)
		(end 160.58896 -211.633054)
		(stroke
			(width 0.2)
			(type default)
		)
		(layer "In1.Cu")
	)
	(gr_arc
		(start 162.0901 -35.53206)
		(mid 162.60064 -35.02152)
		(end 162.0901 -34.51098)
		(stroke
			(width 0.2)
			(type default)
		)
		(layer "In1.Cu")
	)
	(gr_line
		(start 162.0901 -34.51098)
		(end 161.277554 -34.51098)
		(stroke
			(width 0.2)
			(type default)
		)
		(layer "In1.Cu")
	)
	(gr_line
		(start 162.13836 -213.080854)
		(end 162.13836 -211.760054)
		(stroke
			(width 0.2)
			(type default)
		)
		(layer "In1.Cu")
	)
	(gr_arc
		(start 162.13836 -211.760054)
		(mid 162.101163 -211.670251)
		(end 162.01136 -211.633054)
		(stroke
			(width 0.2)
			(type default)
		)
		(layer "In1.Cu")
	)
	(gr_arc
		(start 162.2552 -34.3154)
		(mid 162.345003 -34.278203)
		(end 162.3822 -34.1884)
		(stroke
			(width 0.2)
			(type default)
		)
		(layer "In1.Cu")
	)
	(gr_line
		(start 162.2552 -32.7406)
		(end 160.9598 -32.7406)
		(stroke
			(width 0.2)
			(type default)
		)
		(layer "In1.Cu")
	)
	(gr_line
		(start 162.3568 -84.5312)
		(end 161.3662 -84.5312)
		(stroke
			(width 0.2)
			(type default)
		)
		(layer "In1.Cu")
	)
	(gr_line
		(start 162.35934 -84.53374)
		(end 162.3568 -84.5312)
		(stroke
			(width 0.2)
			(type default)
		)
		(layer "In1.Cu")
	)
	(gr_arc
		(start 162.3822 -84.5312)
		(mid 162.370698 -84.531824)
		(end 162.35934 -84.53374)
		(stroke
			(width 0.2)
			(type default)
		)
		(layer "In1.Cu")
	)
	(gr_line
		(start 162.3822 -34.1884)
		(end 162.3822 -32.8676)
		(stroke
			(width 0.2)
			(type default)
		)
		(layer "In1.Cu")
	)
	(gr_arc
		(start 162.3822 -32.8676)
		(mid 162.345003 -32.777797)
		(end 162.2552 -32.7406)
		(stroke
			(width 0.2)
			(type default)
		)
		(layer "In1.Cu")
	)
	(gr_arc
		(start 162.597846 -38.52164)
		(mid 163.10864 -38.011227)
		(end 162.5981 -37.50056)
		(stroke
			(width 0.2)
			(type default)
		)
		(layer "In1.Cu")
	)
	(gr_line
		(start 162.5981 -37.50056)
		(end 161.7853 -37.50056)
		(stroke
			(width 0.2)
			(type default)
		)
		(layer "In1.Cu")
	)
	(gr_line
		(start 162.6997 -82.17154)
		(end 163.512246 -82.17154)
		(stroke
			(width 0.2)
			(type default)
		)
		(layer "In1.Cu")
	)
	(gr_arc
		(start 162.6997 -81.15046)
		(mid 162.18916 -81.661)
		(end 162.6997 -82.17154)
		(stroke
			(width 0.2)
			(type default)
		)
		(layer "In1.Cu")
	)
	(gr_arc
		(start 162.7378 -85.9536)
		(mid 162.809642 -85.923842)
		(end 162.8394 -85.852)
		(stroke
			(width 0.2)
			(type default)
		)
		(layer "In1.Cu")
	)
	(gr_line
		(start 162.7378 -84.5312)
		(end 162.3822 -84.5312)
		(stroke
			(width 0.2)
			(type default)
		)
		(layer "In1.Cu")
	)
	(gr_line
		(start 162.748722 -90.168222)
		(end 162.748722 -89.978738)
		(stroke
			(width 0.2)
			(type default)
		)
		(layer "In1.Cu")
	)
	(gr_line
		(start 162.748722 -89.978738)
		(end 162.748722 -89.174066)
		(stroke
			(width 0.2)
			(type default)
		)
		(layer "In1.Cu")
	)
	(gr_line
		(start 162.748722 -89.174066)
		(end 162.748722 -88.980518)
		(stroke
			(width 0.2)
			(type default)
		)
		(layer "In1.Cu")
	)
	(gr_line
		(start 162.748722 -88.980518)
		(end 163.790122 -88.980518)
		(stroke
			(width 0.2)
			(type default)
		)
		(layer "In1.Cu")
	)
	(gr_line
		(start 162.8394 -85.852)
		(end 162.8394 -84.6328)
		(stroke
			(width 0.2)
			(type default)
		)
		(layer "In1.Cu")
	)
	(gr_arc
		(start 162.8394 -84.6328)
		(mid 162.809642 -84.560958)
		(end 162.7378 -84.5312)
		(stroke
			(width 0.2)
			(type default)
		)
		(layer "In1.Cu")
	)
	(gr_arc
		(start 162.8648 -34.1884)
		(mid 162.901997 -34.278203)
		(end 162.9918 -34.3154)
		(stroke
			(width 0.2)
			(type default)
		)
		(layer "In1.Cu")
	)
	(gr_line
		(start 162.8648 -32.8676)
		(end 162.8648 -34.1884)
		(stroke
			(width 0.2)
			(type default)
		)
		(layer "In1.Cu")
	)
	(gr_line
		(start 162.9918 -34.3154)
		(end 164.2872 -34.3154)
		(stroke
			(width 0.2)
			(type default)
		)
		(layer "In1.Cu")
	)
	(gr_arc
		(start 162.9918 -32.7406)
		(mid 162.901997 -32.777797)
		(end 162.8648 -32.8676)
		(stroke
			(width 0.2)
			(type default)
		)
		(layer "In1.Cu")
	)
	(gr_arc
		(start 163.512246 -82.17154)
		(mid 164.02304 -81.661127)
		(end 163.5125 -81.15046)
		(stroke
			(width 0.2)
			(type default)
		)
		(layer "In1.Cu")
	)
	(gr_line
		(start 163.5125 -81.15046)
		(end 162.6997 -81.15046)
		(stroke
			(width 0.2)
			(type default)
		)
		(layer "In1.Cu")
	)
	(gr_line
		(start 163.790122 -90.168222)
		(end 162.748722 -90.168222)
		(stroke
			(width 0.2)
			(type default)
		)
		(layer "In1.Cu")
	)
	(gr_line
		(start 163.790122 -89.978738)
		(end 163.790122 -90.168222)
		(stroke
			(width 0.2)
			(type default)
		)
		(layer "In1.Cu")
	)
	(gr_line
		(start 163.790122 -89.174066)
		(end 163.790122 -89.978738)
		(stroke
			(width 0.2)
			(type default)
		)
		(layer "In1.Cu")
	)
	(gr_line
		(start 163.790122 -88.980518)
		(end 163.790122 -89.174066)
		(stroke
			(width 0.2)
			(type default)
		)
		(layer "In1.Cu")
	)
	(gr_arc
		(start 164.2872 -34.3154)
		(mid 164.377003 -34.278203)
		(end 164.4142 -34.1884)
		(stroke
			(width 0.2)
			(type default)
		)
		(layer "In1.Cu")
	)
	(gr_line
		(start 164.2872 -32.7406)
		(end 162.9918 -32.7406)
		(stroke
			(width 0.2)
			(type default)
		)
		(layer "In1.Cu")
	)
	(gr_line
		(start 164.4142 -34.1884)
		(end 164.4142 -32.8676)
		(stroke
			(width 0.2)
			(type default)
		)
		(layer "In1.Cu")
	)
	(gr_arc
		(start 164.4142 -32.8676)
		(mid 164.377003 -32.777797)
		(end 164.2872 -32.7406)
		(stroke
			(width 0.2)
			(type default)
		)
		(layer "In1.Cu")
	)
	(gr_line
		(start 164.893752 -222.805244)
		(end 165.706298 -222.805244)
		(stroke
			(width 0.2)
			(type default)
		)
		(layer "In1.Cu")
	)
	(gr_arc
		(start 164.893752 -221.784164)
		(mid 164.383212 -222.294704)
		(end 164.893752 -222.805244)
		(stroke
			(width 0.2)
			(type default)
		)
		(layer "In1.Cu")
	)
	(gr_arc
		(start 165.4048 -89.7382)
		(mid 165.434558 -89.810042)
		(end 165.5064 -89.8398)
		(stroke
			(width 0.2)
			(type default)
		)
		(layer "In1.Cu")
	)
	(gr_line
		(start 165.4048 -88.3666)
		(end 165.4048 -89.7382)
		(stroke
			(width 0.2)
			(type default)
		)
		(layer "In1.Cu")
	)
	(gr_line
		(start 165.5064 -89.8398)
		(end 166.7256 -89.8398)
		(stroke
			(width 0.2)
			(type default)
		)
		(layer "In1.Cu")
	)
	(gr_arc
		(start 165.5064 -88.265)
		(mid 165.434558 -88.294758)
		(end 165.4048 -88.3666)
		(stroke
			(width 0.2)
			(type default)
		)
		(layer "In1.Cu")
	)
	(gr_arc
		(start 165.583616 -25.035256)
		(mid 165.839648 -25.881076)
		(end 166.685468 -25.625044)
		(stroke
			(width 0.2)
			(type default)
		)
		(layer "In1.Cu")
	)
	(gr_arc
		(start 165.58768 -13.627608)
		(mid 165.835814 -14.479061)
		(end 166.685468 -14.225016)
		(stroke
			(width 0.2)
			(type default)
		)
		(layer "In1.Cu")
	)
	(gr_arc
		(start 165.706298 -222.805244)
		(mid 166.217092 -222.294831)
		(end 165.706552 -221.784164)
		(stroke
			(width 0.2)
			(type default)
		)
		(layer "In1.Cu")
	)
	(gr_line
		(start 165.706552 -221.784164)
		(end 164.893752 -221.784164)
		(stroke
			(width 0.2)
			(type default)
		)
		(layer "In1.Cu")
	)
	(gr_arc
		(start 166.061898 -213.080854)
		(mid 166.099095 -213.170657)
		(end 166.188898 -213.207854)
		(stroke
			(width 0.2)
			(type default)
		)
		(layer "In1.Cu")
	)
	(gr_line
		(start 166.061898 -211.760054)
		(end 166.061898 -213.080854)
		(stroke
			(width 0.2)
			(type default)
		)
		(layer "In1.Cu")
	)
	(gr_line
		(start 166.188898 -213.207854)
		(end 166.595298 -213.207854)
		(stroke
			(width 0.2)
			(type default)
		)
		(layer "In1.Cu")
	)
	(gr_arc
		(start 166.188898 -211.633054)
		(mid 166.099095 -211.670251)
		(end 166.061898 -211.760054)
		(stroke
			(width 0.2)
			(type default)
		)
		(layer "In1.Cu")
	)
	(gr_line
		(start 166.333424 -23.635208)
		(end 165.583616 -25.035256)
		(stroke
			(width 0.2)
			(type default)
		)
		(layer "In1.Cu")
	)
	(gr_line
		(start 166.333424 -12.23518)
		(end 165.58768 -13.627608)
		(stroke
			(width 0.2)
			(type default)
		)
		(layer "In1.Cu")
	)
	(gr_line
		(start 166.493698 -211.406994)
		(end 167.306498 -211.406994)
		(stroke
			(width 0.2)
			(type default)
		)
		(layer "In1.Cu")
	)
	(gr_arc
		(start 166.493952 -210.385914)
		(mid 165.983158 -210.896327)
		(end 166.493698 -211.406994)
		(stroke
			(width 0.2)
			(type default)
		)
		(layer "In1.Cu")
	)
	(gr_line
		(start 166.595298 -213.207854)
		(end 166.595552 -213.2076)
		(stroke
			(width 0.2)
			(type default)
		)
		(layer "In1.Cu")
	)
	(gr_line
		(start 166.595552 -213.2076)
		(end 167.19677 -213.2076)
		(stroke
			(width 0.2)
			(type default)
		)
		(layer "In1.Cu")
	)
	(gr_line
		(start 166.685468 -25.625044)
		(end 167.431212 -24.232616)
		(stroke
			(width 0.2)
			(type default)
		)
		(layer "In1.Cu")
	)
	(gr_line
		(start 166.685468 -14.225016)
		(end 167.435276 -12.824968)
		(stroke
			(width 0.2)
			(type default)
		)
		(layer "In1.Cu")
	)
	(gr_arc
		(start 166.7256 -89.8398)
		(mid 166.797442 -89.810042)
		(end 166.8272 -89.7382)
		(stroke
			(width 0.2)
			(type default)
		)
		(layer "In1.Cu")
	)
	(gr_line
		(start 166.7256 -88.265)
		(end 165.5064 -88.265)
		(stroke
			(width 0.2)
			(type default)
		)
		(layer "In1.Cu")
	)
	(gr_line
		(start 166.8272 -89.7382)
		(end 166.8272 -88.3666)
		(stroke
			(width 0.2)
			(type default)
		)
		(layer "In1.Cu")
	)
	(gr_arc
		(start 166.8272 -88.3666)
		(mid 166.797442 -88.294758)
		(end 166.7256 -88.265)
		(stroke
			(width 0.2)
			(type default)
		)
		(layer "In1.Cu")
	)
	(gr_arc
		(start 167.191436 -89.4588)
		(mid 167.701976 -89.96934)
		(end 168.212516 -89.4588)
		(stroke
			(width 0.2)
			(type default)
		)
		(layer "In1.Cu")
	)
	(gr_line
		(start 167.191436 -88.646)
		(end 167.191436 -89.4588)
		(stroke
			(width 0.2)
			(type default)
		)
		(layer "In1.Cu")
	)
	(gr_arc
		(start 167.19677 -213.2076)
		(mid 167.200832 -213.207795)
		(end 167.204898 -213.207854)
		(stroke
			(width 0.2)
			(type default)
		)
		(layer "In1.Cu")
	)
	(gr_line
		(start 167.204898 -213.207854)
		(end 167.611298 -213.207854)
		(stroke
			(width 0.2)
			(type default)
		)
		(layer "In1.Cu")
	)
	(gr_arc
		(start 167.306498 -211.406994)
		(mid 167.817038 -210.896454)
		(end 167.306498 -210.385914)
		(stroke
			(width 0.2)
			(type default)
		)
		(layer "In1.Cu")
	)
	(gr_line
		(start 167.306498 -210.385914)
		(end 166.493952 -210.385914)
		(stroke
			(width 0.2)
			(type default)
		)
		(layer "In1.Cu")
	)
	(gr_arc
		(start 167.431212 -24.232616)
		(mid 167.183078 -23.381163)
		(end 166.333424 -23.635208)
		(stroke
			(width 0.2)
			(type default)
		)
		(layer "In1.Cu")
	)
	(gr_arc
		(start 167.435276 -12.824968)
		(mid 167.179244 -11.979148)
		(end 166.333424 -12.23518)
		(stroke
			(width 0.2)
			(type default)
		)
		(layer "In1.Cu")
	)
	(gr_arc
		(start 167.611298 -213.207854)
		(mid 167.701101 -213.170657)
		(end 167.738298 -213.080854)
		(stroke
			(width 0.2)
			(type default)
		)
		(layer "In1.Cu")
	)
	(gr_line
		(start 167.611298 -211.633054)
		(end 166.188898 -211.633054)
		(stroke
			(width 0.2)
			(type default)
		)
		(layer "In1.Cu")
	)
	(gr_line
		(start 167.738298 -213.080854)
		(end 167.738298 -211.760054)
		(stroke
			(width 0.2)
			(type default)
		)
		(layer "In1.Cu")
	)
	(gr_arc
		(start 167.738298 -211.760054)
		(mid 167.701101 -211.670251)
		(end 167.611298 -211.633054)
		(stroke
			(width 0.2)
			(type default)
		)
		(layer "In1.Cu")
	)
	(gr_line
		(start 167.831516 -25.033732)
		(end 167.83177 -25.033986)
		(stroke
			(width 0.2)
			(type default)
		)
		(layer "In1.Cu")
	)
	(gr_line
		(start 167.831516 -21.233892)
		(end 167.833548 -21.235162)
		(stroke
			(width 0.2)
			(type default)
		)
		(layer "In1.Cu")
	)
	(gr_line
		(start 167.831516 -17.433544)
		(end 167.83177 -17.433798)
		(stroke
			(width 0.2)
			(type default)
		)
		(layer "In1.Cu")
	)
	(gr_line
		(start 167.831516 -13.633704)
		(end 167.83177 -13.633958)
		(stroke
			(width 0.2)
			(type default)
		)
		(layer "In1.Cu")
	)
	(gr_line
		(start 167.83177 -25.033986)
		(end 167.833802 -25.035002)
		(stroke
			(width 0.2)
			(type default)
		)
		(layer "In1.Cu")
	)
	(gr_line
		(start 167.83177 -17.433798)
		(end 167.833802 -17.434814)
		(stroke
			(width 0.2)
			(type default)
		)
		(layer "In1.Cu")
	)
	(gr_line
		(start 167.83177 -13.633958)
		(end 167.833802 -13.634974)
		(stroke
			(width 0.2)
			(type default)
		)
		(layer "In1.Cu")
	)
	(gr_arc
		(start 167.833548 -21.235162)
		(mid 168.08958 -22.080982)
		(end 168.9354 -21.82495)
		(stroke
			(width 0.2)
			(type default)
		)
		(layer "In1.Cu")
	)
	(gr_arc
		(start 167.833802 -25.035002)
		(mid 168.089478 -25.880903)
		(end 168.9354 -25.625044)
		(stroke
			(width 0.2)
			(type default)
		)
		(layer "In1.Cu")
	)
	(gr_arc
		(start 167.833802 -17.434814)
		(mid 168.089326 -18.280634)
		(end 168.935146 -18.02511)
		(stroke
			(width 0.2)
			(type default)
		)
		(layer "In1.Cu")
	)
	(gr_arc
		(start 167.833802 -13.634974)
		(mid 168.089478 -14.480875)
		(end 168.9354 -14.225016)
		(stroke
			(width 0.2)
			(type default)
		)
		(layer "In1.Cu")
	)
	(gr_line
		(start 168.093644 -222.805244)
		(end 168.90619 -222.805244)
		(stroke
			(width 0.2)
			(type default)
		)
		(layer "In1.Cu")
	)
	(gr_arc
		(start 168.093644 -221.784164)
		(mid 167.583104 -222.294704)
		(end 168.093644 -222.805244)
		(stroke
			(width 0.2)
			(type default)
		)
		(layer "In1.Cu")
	)
	(gr_line
		(start 168.212516 -89.4588)
		(end 168.212516 -88.646254)
		(stroke
			(width 0.2)
			(type default)
		)
		(layer "In1.Cu")
	)
	(gr_arc
		(start 168.212516 -88.646254)
		(mid 167.702103 -88.13546)
		(end 167.191436 -88.646)
		(stroke
			(width 0.2)
			(type default)
		)
		(layer "In1.Cu")
	)
	(gr_line
		(start 168.581578 -23.633938)
		(end 167.831516 -25.033732)
		(stroke
			(width 0.2)
			(type default)
		)
		(layer "In1.Cu")
	)
	(gr_line
		(start 168.581578 -19.833844)
		(end 167.831516 -21.233892)
		(stroke
			(width 0.2)
			(type default)
		)
		(layer "In1.Cu")
	)
	(gr_line
		(start 168.581578 -16.03375)
		(end 167.831516 -17.433544)
		(stroke
			(width 0.2)
			(type default)
		)
		(layer "In1.Cu")
	)
	(gr_line
		(start 168.581578 -12.23391)
		(end 167.831516 -13.633704)
		(stroke
			(width 0.2)
			(type default)
		)
		(layer "In1.Cu")
	)
	(gr_line
		(start 168.58361 -23.635208)
		(end 168.581578 -23.633938)
		(stroke
			(width 0.2)
			(type default)
		)
		(layer "In1.Cu")
	)
	(gr_line
		(start 168.58361 -19.835114)
		(end 168.581578 -19.833844)
		(stroke
			(width 0.2)
			(type default)
		)
		(layer "In1.Cu")
	)
	(gr_line
		(start 168.58361 -12.23518)
		(end 168.581578 -12.23391)
		(stroke
			(width 0.2)
			(type default)
		)
		(layer "In1.Cu")
	)
	(gr_line
		(start 168.583864 -16.03502)
		(end 168.581578 -16.03375)
		(stroke
			(width 0.2)
			(type default)
		)
		(layer "In1.Cu")
	)
	(gr_arc
		(start 168.90619 -222.805244)
		(mid 169.416984 -222.294831)
		(end 168.906444 -221.784164)
		(stroke
			(width 0.2)
			(type default)
		)
		(layer "In1.Cu")
	)
	(gr_line
		(start 168.906444 -221.784164)
		(end 168.093644 -221.784164)
		(stroke
			(width 0.2)
			(type default)
		)
		(layer "In1.Cu")
	)
	(gr_line
		(start 168.935146 -18.02511)
		(end 168.937432 -18.02638)
		(stroke
			(width 0.2)
			(type default)
		)
		(layer "In1.Cu")
	)
	(gr_line
		(start 168.9354 -25.625044)
		(end 168.937432 -25.626314)
		(stroke
			(width 0.2)
			(type default)
		)
		(layer "In1.Cu")
	)
	(gr_line
		(start 168.9354 -21.82495)
		(end 168.937432 -21.82622)
		(stroke
			(width 0.2)
			(type default)
		)
		(layer "In1.Cu")
	)
	(gr_line
		(start 168.9354 -14.225016)
		(end 168.937432 -14.226286)
		(stroke
			(width 0.2)
			(type default)
		)
		(layer "In1.Cu")
	)
	(gr_line
		(start 168.937432 -25.626314)
		(end 169.687494 -24.226266)
		(stroke
			(width 0.2)
			(type default)
		)
		(layer "In1.Cu")
	)
	(gr_line
		(start 168.937432 -21.82622)
		(end 169.687494 -20.426426)
		(stroke
			(width 0.2)
			(type default)
		)
		(layer "In1.Cu")
	)
	(gr_line
		(start 168.937432 -18.02638)
		(end 169.687494 -16.626586)
		(stroke
			(width 0.2)
			(type default)
		)
		(layer "In1.Cu")
	)
	(gr_line
		(start 168.937432 -14.226286)
		(end 169.687494 -12.826238)
		(stroke
			(width 0.2)
			(type default)
		)
		(layer "In1.Cu")
	)
	(gr_arc
		(start 169.26179 -213.080854)
		(mid 169.298987 -213.170657)
		(end 169.38879 -213.207854)
		(stroke
			(width 0.2)
			(type default)
		)
		(layer "In1.Cu")
	)
	(gr_line
		(start 169.26179 -211.760054)
		(end 169.26179 -213.080854)
		(stroke
			(width 0.2)
			(type default)
		)
		(layer "In1.Cu")
	)
	(gr_line
		(start 169.38879 -213.207854)
		(end 169.79519 -213.207854)
		(stroke
			(width 0.2)
			(type default)
		)
		(layer "In1.Cu")
	)
	(gr_arc
		(start 169.38879 -211.633054)
		(mid 169.298987 -211.670251)
		(end 169.26179 -211.760054)
		(stroke
			(width 0.2)
			(type default)
		)
		(layer "In1.Cu")
	)
	(gr_arc
		(start 169.685208 -20.425156)
		(mid 169.429532 -19.579255)
		(end 168.58361 -19.835114)
		(stroke
			(width 0.2)
			(type default)
		)
		(layer "In1.Cu")
	)
	(gr_arc
		(start 169.685208 -16.625316)
		(mid 169.429684 -15.779496)
		(end 168.583864 -16.03502)
		(stroke
			(width 0.2)
			(type default)
		)
		(layer "In1.Cu")
	)
	(gr_arc
		(start 169.685462 -24.224996)
		(mid 169.42943 -23.379176)
		(end 168.58361 -23.635208)
		(stroke
			(width 0.2)
			(type default)
		)
		(layer "In1.Cu")
	)
	(gr_arc
		(start 169.685462 -12.824968)
		(mid 169.42943 -11.979148)
		(end 168.58361 -12.23518)
		(stroke
			(width 0.2)
			(type default)
		)
		(layer "In1.Cu")
	)
	(gr_line
		(start 169.68724 -20.426172)
		(end 169.685208 -20.425156)
		(stroke
			(width 0.2)
			(type default)
		)
		(layer "In1.Cu")
	)
	(gr_line
		(start 169.687494 -24.226266)
		(end 169.685462 -24.224996)
		(stroke
			(width 0.2)
			(type default)
		)
		(layer "In1.Cu")
	)
	(gr_line
		(start 169.687494 -20.426426)
		(end 169.68724 -20.426172)
		(stroke
			(width 0.2)
			(type default)
		)
		(layer "In1.Cu")
	)
	(gr_line
		(start 169.687494 -16.626586)
		(end 169.685208 -16.625316)
		(stroke
			(width 0.2)
			(type default)
		)
		(layer "In1.Cu")
	)
	(gr_line
		(start 169.687494 -12.826238)
		(end 169.685462 -12.824968)
		(stroke
			(width 0.2)
			(type default)
		)
		(layer "In1.Cu")
	)
	(gr_line
		(start 169.69359 -211.406994)
		(end 170.50639 -211.406994)
		(stroke
			(width 0.2)
			(type default)
		)
		(layer "In1.Cu")
	)
	(gr_arc
		(start 169.693844 -210.385914)
		(mid 169.18305 -210.896327)
		(end 169.69359 -211.406994)
		(stroke
			(width 0.2)
			(type default)
		)
		(layer "In1.Cu")
	)
	(gr_line
		(start 169.79519 -213.207854)
		(end 169.795444 -213.2076)
		(stroke
			(width 0.2)
			(type default)
		)
		(layer "In1.Cu")
	)
	(gr_line
		(start 169.795444 -213.2076)
		(end 170.396662 -213.2076)
		(stroke
			(width 0.2)
			(type default)
		)
		(layer "In1.Cu")
	)
	(gr_line
		(start 170.081448 -25.033732)
		(end 170.081702 -25.033986)
		(stroke
			(width 0.2)
			(type default)
		)
		(layer "In1.Cu")
	)
	(gr_line
		(start 170.081448 -21.233892)
		(end 170.08348 -21.235162)
		(stroke
			(width 0.2)
			(type default)
		)
		(layer "In1.Cu")
	)
	(gr_line
		(start 170.081448 -17.433544)
		(end 170.081702 -17.433798)
		(stroke
			(width 0.2)
			(type default)
		)
		(layer "In1.Cu")
	)
	(gr_line
		(start 170.081448 -13.633704)
		(end 170.081702 -13.633958)
		(stroke
			(width 0.2)
			(type default)
		)
		(layer "In1.Cu")
	)
	(gr_line
		(start 170.081702 -25.033986)
		(end 170.083734 -25.035002)
		(stroke
			(width 0.2)
			(type default)
		)
		(layer "In1.Cu")
	)
	(gr_line
		(start 170.081702 -17.433798)
		(end 170.083734 -17.434814)
		(stroke
			(width 0.2)
			(type default)
		)
		(layer "In1.Cu")
	)
	(gr_line
		(start 170.081702 -13.633958)
		(end 170.083734 -13.634974)
		(stroke
			(width 0.2)
			(type default)
		)
		(layer "In1.Cu")
	)
	(gr_arc
		(start 170.08348 -21.235162)
		(mid 170.339512 -22.080982)
		(end 171.185332 -21.82495)
		(stroke
			(width 0.2)
			(type default)
		)
		(layer "In1.Cu")
	)
	(gr_arc
		(start 170.083734 -25.035002)
		(mid 170.33941 -25.880903)
		(end 171.185332 -25.625044)
		(stroke
			(width 0.2)
			(type default)
		)
		(layer "In1.Cu")
	)
	(gr_arc
		(start 170.083734 -17.434814)
		(mid 170.339258 -18.280634)
		(end 171.185078 -18.02511)
		(stroke
			(width 0.2)
			(type default)
		)
		(layer "In1.Cu")
	)
	(gr_arc
		(start 170.083734 -13.634974)
		(mid 170.33941 -14.480875)
		(end 171.185332 -14.225016)
		(stroke
			(width 0.2)
			(type default)
		)
		(layer "In1.Cu")
	)
	(gr_arc
		(start 170.396662 -213.2076)
		(mid 170.400724 -213.207795)
		(end 170.40479 -213.207854)
		(stroke
			(width 0.2)
			(type default)
		)
		(layer "In1.Cu")
	)
	(gr_line
		(start 170.40479 -213.207854)
		(end 170.81119 -213.207854)
		(stroke
			(width 0.2)
			(type default)
		)
		(layer "In1.Cu")
	)
	(gr_arc
		(start 170.50639 -211.406994)
		(mid 171.01693 -210.896454)
		(end 170.50639 -210.385914)
		(stroke
			(width 0.2)
			(type default)
		)
		(layer "In1.Cu")
	)
	(gr_line
		(start 170.50639 -210.385914)
		(end 169.693844 -210.385914)
		(stroke
			(width 0.2)
			(type default)
		)
		(layer "In1.Cu")
	)
	(gr_arc
		(start 170.81119 -213.207854)
		(mid 170.900993 -213.170657)
		(end 170.93819 -213.080854)
		(stroke
			(width 0.2)
			(type default)
		)
		(layer "In1.Cu")
	)
	(gr_line
		(start 170.81119 -211.633054)
		(end 169.38879 -211.633054)
		(stroke
			(width 0.2)
			(type default)
		)
		(layer "In1.Cu")
	)
	(gr_line
		(start 170.83151 -23.633938)
		(end 170.081448 -25.033732)
		(stroke
			(width 0.2)
			(type default)
		)
		(layer "In1.Cu")
	)
	(gr_line
		(start 170.83151 -19.833844)
		(end 170.081448 -21.233892)
		(stroke
			(width 0.2)
			(type default)
		)
		(layer "In1.Cu")
	)
	(gr_line
		(start 170.83151 -16.03375)
		(end 170.081448 -17.433544)
		(stroke
			(width 0.2)
			(type default)
		)
		(layer "In1.Cu")
	)
	(gr_line
		(start 170.83151 -12.23391)
		(end 170.081448 -13.633704)
		(stroke
			(width 0.2)
			(type default)
		)
		(layer "In1.Cu")
	)
	(gr_line
		(start 170.833542 -23.635208)
		(end 170.83151 -23.633938)
		(stroke
			(width 0.2)
			(type default)
		)
		(layer "In1.Cu")
	)
	(gr_line
		(start 170.833542 -19.835114)
		(end 170.83151 -19.833844)
		(stroke
			(width 0.2)
			(type default)
		)
		(layer "In1.Cu")
	)
	(gr_line
		(start 170.833542 -12.23518)
		(end 170.83151 -12.23391)
		(stroke
			(width 0.2)
			(type default)
		)
		(layer "In1.Cu")
	)
	(gr_line
		(start 170.833796 -16.03502)
		(end 170.83151 -16.03375)
		(stroke
			(width 0.2)
			(type default)
		)
		(layer "In1.Cu")
	)
	(gr_line
		(start 170.93819 -213.080854)
		(end 170.93819 -211.760054)
		(stroke
			(width 0.2)
			(type default)
		)
		(layer "In1.Cu")
	)
	(gr_arc
		(start 170.93819 -211.760054)
		(mid 170.900993 -211.670251)
		(end 170.81119 -211.633054)
		(stroke
			(width 0.2)
			(type default)
		)
		(layer "In1.Cu")
	)
	(gr_line
		(start 171.185078 -18.02511)
		(end 171.187364 -18.02638)
		(stroke
			(width 0.2)
			(type default)
		)
		(layer "In1.Cu")
	)
	(gr_line
		(start 171.185332 -25.625044)
		(end 171.187364 -25.626314)
		(stroke
			(width 0.2)
			(type default)
		)
		(layer "In1.Cu")
	)
	(gr_line
		(start 171.185332 -21.82495)
		(end 171.187364 -21.82622)
		(stroke
			(width 0.2)
			(type default)
		)
		(layer "In1.Cu")
	)
	(gr_line
		(start 171.185332 -14.225016)
		(end 171.187364 -14.226286)
		(stroke
			(width 0.2)
			(type default)
		)
		(layer "In1.Cu")
	)
	(gr_line
		(start 171.187364 -25.626314)
		(end 171.937426 -24.226266)
		(stroke
			(width 0.2)
			(type default)
		)
		(layer "In1.Cu")
	)
	(gr_line
		(start 171.187364 -21.82622)
		(end 171.937426 -20.426426)
		(stroke
			(width 0.2)
			(type default)
		)
		(layer "In1.Cu")
	)
	(gr_line
		(start 171.187364 -18.02638)
		(end 171.937426 -16.626586)
		(stroke
			(width 0.2)
			(type default)
		)
		(layer "In1.Cu")
	)
	(gr_line
		(start 171.187364 -14.226286)
		(end 171.937426 -12.826238)
		(stroke
			(width 0.2)
			(type default)
		)
		(layer "In1.Cu")
	)
	(gr_line
		(start 171.29379 -222.805244)
		(end 172.106336 -222.805244)
		(stroke
			(width 0.2)
			(type default)
		)
		(layer "In1.Cu")
	)
	(gr_arc
		(start 171.29379 -221.784164)
		(mid 170.78325 -222.294704)
		(end 171.29379 -222.805244)
		(stroke
			(width 0.2)
			(type default)
		)
		(layer "In1.Cu")
	)
	(gr_arc
		(start 171.93514 -20.425156)
		(mid 171.679464 -19.579255)
		(end 170.833542 -19.835114)
		(stroke
			(width 0.2)
			(type default)
		)
		(layer "In1.Cu")
	)
	(gr_arc
		(start 171.93514 -16.625316)
		(mid 171.679616 -15.779496)
		(end 170.833796 -16.03502)
		(stroke
			(width 0.2)
			(type default)
		)
		(layer "In1.Cu")
	)
	(gr_arc
		(start 171.935394 -24.224996)
		(mid 171.679362 -23.379176)
		(end 170.833542 -23.635208)
		(stroke
			(width 0.2)
			(type default)
		)
		(layer "In1.Cu")
	)
	(gr_arc
		(start 171.935394 -12.824968)
		(mid 171.679362 -11.979148)
		(end 170.833542 -12.23518)
		(stroke
			(width 0.2)
			(type default)
		)
		(layer "In1.Cu")
	)
	(gr_line
		(start 171.937172 -20.426172)
		(end 171.93514 -20.425156)
		(stroke
			(width 0.2)
			(type default)
		)
		(layer "In1.Cu")
	)
	(gr_line
		(start 171.937426 -24.226266)
		(end 171.935394 -24.224996)
		(stroke
			(width 0.2)
			(type default)
		)
		(layer "In1.Cu")
	)
	(gr_line
		(start 171.937426 -20.426426)
		(end 171.937172 -20.426172)
		(stroke
			(width 0.2)
			(type default)
		)
		(layer "In1.Cu")
	)
	(gr_line
		(start 171.937426 -16.626586)
		(end 171.93514 -16.625316)
		(stroke
			(width 0.2)
			(type default)
		)
		(layer "In1.Cu")
	)
	(gr_line
		(start 171.937426 -12.826238)
		(end 171.935394 -12.824968)
		(stroke
			(width 0.2)
			(type default)
		)
		(layer "In1.Cu")
	)
	(gr_arc
		(start 172.106336 -222.805244)
		(mid 172.61713 -222.294831)
		(end 172.10659 -221.784164)
		(stroke
			(width 0.2)
			(type default)
		)
		(layer "In1.Cu")
	)
	(gr_line
		(start 172.10659 -221.784164)
		(end 171.29379 -221.784164)
		(stroke
			(width 0.2)
			(type default)
		)
		(layer "In1.Cu")
	)
	(gr_arc
		(start 172.461936 -213.080854)
		(mid 172.499133 -213.170657)
		(end 172.588936 -213.207854)
		(stroke
			(width 0.2)
			(type default)
		)
		(layer "In1.Cu")
	)
	(gr_line
		(start 172.461936 -211.760054)
		(end 172.461936 -213.080854)
		(stroke
			(width 0.2)
			(type default)
		)
		(layer "In1.Cu")
	)
	(gr_line
		(start 172.588936 -213.207854)
		(end 172.995336 -213.207854)
		(stroke
			(width 0.2)
			(type default)
		)
		(layer "In1.Cu")
	)
	(gr_arc
		(start 172.588936 -211.633054)
		(mid 172.499133 -211.670251)
		(end 172.461936 -211.760054)
		(stroke
			(width 0.2)
			(type default)
		)
		(layer "In1.Cu")
	)
	(gr_line
		(start 172.7454 -96.704912)
		(end 173.6344 -96.704912)
		(stroke
			(width 0.2)
			(type default)
		)
		(layer "In1.Cu")
	)
	(gr_arc
		(start 172.745654 -95.683832)
		(mid 172.23486 -96.194245)
		(end 172.7454 -96.704912)
		(stroke
			(width 0.2)
			(type default)
		)
		(layer "In1.Cu")
	)
	(gr_line
		(start 172.893736 -211.406994)
		(end 173.706536 -211.406994)
		(stroke
			(width 0.2)
			(type default)
		)
		(layer "In1.Cu")
	)
	(gr_arc
		(start 172.89399 -210.385914)
		(mid 172.383196 -210.896327)
		(end 172.893736 -211.406994)
		(stroke
			(width 0.2)
			(type default)
		)
		(layer "In1.Cu")
	)
	(gr_line
		(start 172.995336 -213.207854)
		(end 172.99559 -213.2076)
		(stroke
			(width 0.2)
			(type default)
		)
		(layer "In1.Cu")
	)
	(gr_line
		(start 172.99559 -213.2076)
		(end 173.596808 -213.2076)
		(stroke
			(width 0.2)
			(type default)
		)
		(layer "In1.Cu")
	)
	(gr_arc
		(start 173.596808 -213.2076)
		(mid 173.60087 -213.207795)
		(end 173.604936 -213.207854)
		(stroke
			(width 0.2)
			(type default)
		)
		(layer "In1.Cu")
	)
	(gr_line
		(start 173.604936 -213.207854)
		(end 174.011336 -213.207854)
		(stroke
			(width 0.2)
			(type default)
		)
		(layer "In1.Cu")
	)
	(gr_arc
		(start 173.6344 -96.704912)
		(mid 174.14494 -96.194372)
		(end 173.6344 -95.683832)
		(stroke
			(width 0.2)
			(type default)
		)
		(layer "In1.Cu")
	)
	(gr_line
		(start 173.6344 -95.683832)
		(end 172.745654 -95.683832)
		(stroke
			(width 0.2)
			(type default)
		)
		(layer "In1.Cu")
	)
	(gr_arc
		(start 173.706536 -211.406994)
		(mid 174.217076 -210.896454)
		(end 173.706536 -210.385914)
		(stroke
			(width 0.2)
			(type default)
		)
		(layer "In1.Cu")
	)
	(gr_line
		(start 173.706536 -210.385914)
		(end 172.89399 -210.385914)
		(stroke
			(width 0.2)
			(type default)
		)
		(layer "In1.Cu")
	)
	(gr_arc
		(start 174.011336 -213.207854)
		(mid 174.101139 -213.170657)
		(end 174.138336 -213.080854)
		(stroke
			(width 0.2)
			(type default)
		)
		(layer "In1.Cu")
	)
	(gr_line
		(start 174.011336 -211.633054)
		(end 172.588936 -211.633054)
		(stroke
			(width 0.2)
			(type default)
		)
		(layer "In1.Cu")
	)
	(gr_line
		(start 174.138336 -213.080854)
		(end 174.138336 -211.760054)
		(stroke
			(width 0.2)
			(type default)
		)
		(layer "In1.Cu")
	)
	(gr_arc
		(start 174.138336 -211.760054)
		(mid 174.101139 -211.670251)
		(end 174.011336 -211.633054)
		(stroke
			(width 0.2)
			(type default)
		)
		(layer "In1.Cu")
	)
	(gr_line
		(start 174.493682 -222.805244)
		(end 175.306228 -222.805244)
		(stroke
			(width 0.2)
			(type default)
		)
		(layer "In1.Cu")
	)
	(gr_arc
		(start 174.493682 -221.784164)
		(mid 173.983142 -222.294704)
		(end 174.493682 -222.805244)
		(stroke
			(width 0.2)
			(type default)
		)
		(layer "In1.Cu")
	)
	(gr_arc
		(start 175.306228 -222.805244)
		(mid 175.817022 -222.294831)
		(end 175.306482 -221.784164)
		(stroke
			(width 0.2)
			(type default)
		)
		(layer "In1.Cu")
	)
	(gr_line
		(start 175.306482 -221.784164)
		(end 174.493682 -221.784164)
		(stroke
			(width 0.2)
			(type default)
		)
		(layer "In1.Cu")
	)
	(gr_arc
		(start 175.661828 -213.080854)
		(mid 175.699025 -213.170657)
		(end 175.788828 -213.207854)
		(stroke
			(width 0.2)
			(type default)
		)
		(layer "In1.Cu")
	)
	(gr_line
		(start 175.661828 -211.760054)
		(end 175.661828 -213.080854)
		(stroke
			(width 0.2)
			(type default)
		)
		(layer "In1.Cu")
	)
	(gr_line
		(start 175.788828 -213.207854)
		(end 176.195228 -213.207854)
		(stroke
			(width 0.2)
			(type default)
		)
		(layer "In1.Cu")
	)
	(gr_arc
		(start 175.788828 -211.633054)
		(mid 175.699025 -211.670251)
		(end 175.661828 -211.760054)
		(stroke
			(width 0.2)
			(type default)
		)
		(layer "In1.Cu")
	)
	(gr_line
		(start 176.093628 -211.406994)
		(end 176.906428 -211.406994)
		(stroke
			(width 0.2)
			(type default)
		)
		(layer "In1.Cu")
	)
	(gr_arc
		(start 176.093882 -210.385914)
		(mid 175.583088 -210.896327)
		(end 176.093628 -211.406994)
		(stroke
			(width 0.2)
			(type default)
		)
		(layer "In1.Cu")
	)
	(gr_line
		(start 176.195228 -213.207854)
		(end 176.195482 -213.2076)
		(stroke
			(width 0.2)
			(type default)
		)
		(layer "In1.Cu")
	)
	(gr_line
		(start 176.195482 -213.2076)
		(end 176.7967 -213.2076)
		(stroke
			(width 0.2)
			(type default)
		)
		(layer "In1.Cu")
	)
	(gr_arc
		(start 176.7967 -213.2076)
		(mid 176.800762 -213.207795)
		(end 176.804828 -213.207854)
		(stroke
			(width 0.2)
			(type default)
		)
		(layer "In1.Cu")
	)
	(gr_line
		(start 176.804828 -213.207854)
		(end 177.211228 -213.207854)
		(stroke
			(width 0.2)
			(type default)
		)
		(layer "In1.Cu")
	)
	(gr_arc
		(start 176.906428 -211.406994)
		(mid 177.416968 -210.896454)
		(end 176.906428 -210.385914)
		(stroke
			(width 0.2)
			(type default)
		)
		(layer "In1.Cu")
	)
	(gr_line
		(start 176.906428 -210.385914)
		(end 176.093882 -210.385914)
		(stroke
			(width 0.2)
			(type default)
		)
		(layer "In1.Cu")
	)
	(gr_arc
		(start 177.211228 -213.207854)
		(mid 177.301031 -213.170657)
		(end 177.338228 -213.080854)
		(stroke
			(width 0.2)
			(type default)
		)
		(layer "In1.Cu")
	)
	(gr_line
		(start 177.211228 -211.633054)
		(end 175.788828 -211.633054)
		(stroke
			(width 0.2)
			(type default)
		)
		(layer "In1.Cu")
	)
	(gr_line
		(start 177.338228 -213.080854)
		(end 177.338228 -211.760054)
		(stroke
			(width 0.2)
			(type default)
		)
		(layer "In1.Cu")
	)
	(gr_arc
		(start 177.338228 -211.760054)
		(mid 177.301031 -211.670251)
		(end 177.211228 -211.633054)
		(stroke
			(width 0.2)
			(type default)
		)
		(layer "In1.Cu")
	)
	(gr_line
		(start 177.5968 -221.18574)
		(end 178.409346 -221.18574)
		(stroke
			(width 0.2)
			(type default)
		)
		(layer "In1.Cu")
	)
	(gr_arc
		(start 177.5968 -220.16466)
		(mid 177.08626 -220.6752)
		(end 177.5968 -221.18574)
		(stroke
			(width 0.2)
			(type default)
		)
		(layer "In1.Cu")
	)
	(gr_arc
		(start 178.409346 -221.18574)
		(mid 178.92014 -220.675327)
		(end 178.4096 -220.16466)
		(stroke
			(width 0.2)
			(type default)
		)
		(layer "In1.Cu")
	)
	(gr_line
		(start 178.4096 -220.16466)
		(end 177.5968 -220.16466)
		(stroke
			(width 0.2)
			(type default)
		)
		(layer "In1.Cu")
	)
	(gr_line
		(start 180.09997 -228.000052)
		(end 134.500112 -228.000052)
		(stroke
			(width 5.08)
			(type default)
		)
		(layer "In1.Cu")
	)
	(gr_line
		(start 180.09997 -222.600012)
		(end 180.09997 -228.000052)
		(stroke
			(width 1.524)
			(type default)
		)
		(layer "In1.Cu")
	)
	(gr_arc
		(start 180.8226 -30.0482)
		(mid 180.859797 -30.138003)
		(end 180.9496 -30.1752)
		(stroke
			(width 0.2)
			(type default)
		)
		(layer "In1.Cu")
	)
	(gr_line
		(start 180.8226 -28.7528)
		(end 180.8226 -30.0482)
		(stroke
			(width 0.2)
			(type default)
		)
		(layer "In1.Cu")
	)
	(gr_arc
		(start 180.8226 -27.0002)
		(mid 180.859797 -27.090003)
		(end 180.9496 -27.1272)
		(stroke
			(width 0.2)
			(type default)
		)
		(layer "In1.Cu")
	)
	(gr_line
		(start 180.8226 -25.7048)
		(end 180.8226 -27.0002)
		(stroke
			(width 0.2)
			(type default)
		)
		(layer "In1.Cu")
	)
	(gr_arc
		(start 180.8226 -24.7142)
		(mid 180.859797 -24.804003)
		(end 180.9496 -24.8412)
		(stroke
			(width 0.2)
			(type default)
		)
		(layer "In1.Cu")
	)
	(gr_line
		(start 180.8226 -23.4188)
		(end 180.8226 -24.7142)
		(stroke
			(width 0.2)
			(type default)
		)
		(layer "In1.Cu")
	)
	(gr_arc
		(start 180.8226 -22.6822)
		(mid 180.859797 -22.772003)
		(end 180.9496 -22.8092)
		(stroke
			(width 0.2)
			(type default)
		)
		(layer "In1.Cu")
	)
	(gr_line
		(start 180.8226 -21.3868)
		(end 180.8226 -22.6822)
		(stroke
			(width 0.2)
			(type default)
		)
		(layer "In1.Cu")
	)
	(gr_arc
		(start 180.8226 -20.9042)
		(mid 180.859797 -20.994003)
		(end 180.9496 -21.0312)
		(stroke
			(width 0.2)
			(type default)
		)
		(layer "In1.Cu")
	)
	(gr_line
		(start 180.8226 -19.6088)
		(end 180.8226 -20.9042)
		(stroke
			(width 0.2)
			(type default)
		)
		(layer "In1.Cu")
	)
	(gr_line
		(start 180.9496 -30.1752)
		(end 182.2704 -30.1752)
		(stroke
			(width 0.2)
			(type default)
		)
		(layer "In1.Cu")
	)
	(gr_arc
		(start 180.9496 -28.6258)
		(mid 180.859797 -28.662997)
		(end 180.8226 -28.7528)
		(stroke
			(width 0.2)
			(type default)
		)
		(layer "In1.Cu")
	)
	(gr_line
		(start 180.9496 -27.1272)
		(end 182.2704 -27.1272)
		(stroke
			(width 0.2)
			(type default)
		)
		(layer "In1.Cu")
	)
	(gr_arc
		(start 180.9496 -25.5778)
		(mid 180.859797 -25.614997)
		(end 180.8226 -25.7048)
		(stroke
			(width 0.2)
			(type default)
		)
		(layer "In1.Cu")
	)
	(gr_line
		(start 180.9496 -24.8412)
		(end 182.2704 -24.8412)
		(stroke
			(width 0.2)
			(type default)
		)
		(layer "In1.Cu")
	)
	(gr_arc
		(start 180.9496 -23.2918)
		(mid 180.859797 -23.328997)
		(end 180.8226 -23.4188)
		(stroke
			(width 0.2)
			(type default)
		)
		(layer "In1.Cu")
	)
	(gr_line
		(start 180.9496 -22.8092)
		(end 182.2704 -22.8092)
		(stroke
			(width 0.2)
			(type default)
		)
		(layer "In1.Cu")
	)
	(gr_arc
		(start 180.9496 -21.2598)
		(mid 180.859797 -21.296997)
		(end 180.8226 -21.3868)
		(stroke
			(width 0.2)
			(type default)
		)
		(layer "In1.Cu")
	)
	(gr_line
		(start 180.9496 -21.0312)
		(end 182.2704 -21.0312)
		(stroke
			(width 0.2)
			(type default)
		)
		(layer "In1.Cu")
	)
	(gr_arc
		(start 180.9496 -19.4818)
		(mid 180.859797 -19.518997)
		(end 180.8226 -19.6088)
		(stroke
			(width 0.2)
			(type default)
		)
		(layer "In1.Cu")
	)
	(gr_arc
		(start 182.2704 -30.1752)
		(mid 182.360203 -30.138003)
		(end 182.3974 -30.0482)
		(stroke
			(width 0.2)
			(type default)
		)
		(layer "In1.Cu")
	)
	(gr_line
		(start 182.2704 -28.6258)
		(end 180.9496 -28.6258)
		(stroke
			(width 0.2)
			(type default)
		)
		(layer "In1.Cu")
	)
	(gr_arc
		(start 182.2704 -27.1272)
		(mid 182.360203 -27.090003)
		(end 182.3974 -27.0002)
		(stroke
			(width 0.2)
			(type default)
		)
		(layer "In1.Cu")
	)
	(gr_line
		(start 182.2704 -25.5778)
		(end 180.9496 -25.5778)
		(stroke
			(width 0.2)
			(type default)
		)
		(layer "In1.Cu")
	)
	(gr_arc
		(start 182.2704 -24.8412)
		(mid 182.360203 -24.804003)
		(end 182.3974 -24.7142)
		(stroke
			(width 0.2)
			(type default)
		)
		(layer "In1.Cu")
	)
	(gr_line
		(start 182.2704 -23.2918)
		(end 180.9496 -23.2918)
		(stroke
			(width 0.2)
			(type default)
		)
		(layer "In1.Cu")
	)
	(gr_arc
		(start 182.2704 -22.8092)
		(mid 182.360203 -22.772003)
		(end 182.3974 -22.6822)
		(stroke
			(width 0.2)
			(type default)
		)
		(layer "In1.Cu")
	)
	(gr_line
		(start 182.2704 -21.2598)
		(end 180.9496 -21.2598)
		(stroke
			(width 0.2)
			(type default)
		)
		(layer "In1.Cu")
	)
	(gr_arc
		(start 182.2704 -21.0312)
		(mid 182.360203 -20.994003)
		(end 182.3974 -20.9042)
		(stroke
			(width 0.2)
			(type default)
		)
		(layer "In1.Cu")
	)
	(gr_line
		(start 182.2704 -19.4818)
		(end 180.9496 -19.4818)
		(stroke
			(width 0.2)
			(type default)
		)
		(layer "In1.Cu")
	)
	(gr_line
		(start 182.3974 -30.0482)
		(end 182.3974 -28.7528)
		(stroke
			(width 0.2)
			(type default)
		)
		(layer "In1.Cu")
	)
	(gr_arc
		(start 182.3974 -28.7528)
		(mid 182.360203 -28.662997)
		(end 182.2704 -28.6258)
		(stroke
			(width 0.2)
			(type default)
		)
		(layer "In1.Cu")
	)
	(gr_line
		(start 182.3974 -27.0002)
		(end 182.3974 -25.7048)
		(stroke
			(width 0.2)
			(type default)
		)
		(layer "In1.Cu")
	)
	(gr_arc
		(start 182.3974 -25.7048)
		(mid 182.360203 -25.614997)
		(end 182.2704 -25.5778)
		(stroke
			(width 0.2)
			(type default)
		)
		(layer "In1.Cu")
	)
	(gr_line
		(start 182.3974 -24.7142)
		(end 182.3974 -23.4188)
		(stroke
			(width 0.2)
			(type default)
		)
		(layer "In1.Cu")
	)
	(gr_arc
		(start 182.3974 -23.4188)
		(mid 182.360203 -23.328997)
		(end 182.2704 -23.2918)
		(stroke
			(width 0.2)
			(type default)
		)
		(layer "In1.Cu")
	)
	(gr_line
		(start 182.3974 -22.6822)
		(end 182.3974 -21.3868)
		(stroke
			(width 0.2)
			(type default)
		)
		(layer "In1.Cu")
	)
	(gr_arc
		(start 182.3974 -21.3868)
		(mid 182.360203 -21.296997)
		(end 182.2704 -21.2598)
		(stroke
			(width 0.2)
			(type default)
		)
		(layer "In1.Cu")
	)
	(gr_line
		(start 182.3974 -20.9042)
		(end 182.3974 -19.6088)
		(stroke
			(width 0.2)
			(type default)
		)
		(layer "In1.Cu")
	)
	(gr_arc
		(start 182.3974 -19.6088)
		(mid 182.360203 -19.518997)
		(end 182.2704 -19.4818)
		(stroke
			(width 0.2)
			(type default)
		)
		(layer "In1.Cu")
	)
	(gr_line
		(start 182.500016 -228.000052)
		(end 182.500016 -222.600012)
		(stroke
			(width 1.524)
			(type default)
		)
		(layer "In1.Cu")
	)
	(gr_arc
		(start 182.500016 -222.600012)
		(mid 181.30012 -221.400116)
		(end 180.09997 -222.600012)
		(stroke
			(width 1.524)
			(type default)
		)
		(layer "In1.Cu")
	)
	(gr_arc
		(start 182.57266 -29.8069)
		(mid 183.0832 -30.31744)
		(end 183.59374 -29.8069)
		(stroke
			(width 0.2)
			(type default)
		)
		(layer "In1.Cu")
	)
	(gr_line
		(start 182.57266 -28.9941)
		(end 182.57266 -29.8069)
		(stroke
			(width 0.2)
			(type default)
		)
		(layer "In1.Cu")
	)
	(gr_arc
		(start 182.57266 -26.7589)
		(mid 183.0832 -27.26944)
		(end 183.59374 -26.7589)
		(stroke
			(width 0.2)
			(type default)
		)
		(layer "In1.Cu")
	)
	(gr_line
		(start 182.57266 -25.9461)
		(end 182.57266 -26.7589)
		(stroke
			(width 0.2)
			(type default)
		)
		(layer "In1.Cu")
	)
	(gr_arc
		(start 182.57266 -24.472646)
		(mid 183.083073 -24.98344)
		(end 183.59374 -24.4729)
		(stroke
			(width 0.2)
			(type default)
		)
		(layer "In1.Cu")
	)
	(gr_line
		(start 182.57266 -23.6601)
		(end 182.57266 -24.472646)
		(stroke
			(width 0.2)
			(type default)
		)
		(layer "In1.Cu")
	)
	(gr_arc
		(start 182.57266 -20.6629)
		(mid 183.0832 -21.17344)
		(end 183.59374 -20.6629)
		(stroke
			(width 0.2)
			(type default)
		)
		(layer "In1.Cu")
	)
	(gr_line
		(start 182.57266 -19.8501)
		(end 182.57266 -20.6629)
		(stroke
			(width 0.2)
			(type default)
		)
		(layer "In1.Cu")
	)
	(gr_line
		(start 183.59374 -29.8069)
		(end 183.59374 -28.994354)
		(stroke
			(width 0.2)
			(type default)
		)
		(layer "In1.Cu")
	)
	(gr_arc
		(start 183.59374 -28.994354)
		(mid 183.083327 -28.48356)
		(end 182.57266 -28.9941)
		(stroke
			(width 0.2)
			(type default)
		)
		(layer "In1.Cu")
	)
	(gr_line
		(start 183.59374 -26.7589)
		(end 183.59374 -25.946354)
		(stroke
			(width 0.2)
			(type default)
		)
		(layer "In1.Cu")
	)
	(gr_arc
		(start 183.59374 -25.946354)
		(mid 183.083327 -25.43556)
		(end 182.57266 -25.9461)
		(stroke
			(width 0.2)
			(type default)
		)
		(layer "In1.Cu")
	)
	(gr_line
		(start 183.59374 -24.4729)
		(end 183.59374 -23.6601)
		(stroke
			(width 0.2)
			(type default)
		)
		(layer "In1.Cu")
	)
	(gr_arc
		(start 183.59374 -23.6601)
		(mid 183.0832 -23.14956)
		(end 182.57266 -23.6601)
		(stroke
			(width 0.2)
			(type default)
		)
		(layer "In1.Cu")
	)
	(gr_line
		(start 183.59374 -20.6629)
		(end 183.59374 -19.850354)
		(stroke
			(width 0.2)
			(type default)
		)
		(layer "In1.Cu")
	)
	(gr_arc
		(start 183.59374 -19.850354)
		(mid 183.083327 -19.33956)
		(end 182.57266 -19.8501)
		(stroke
			(width 0.2)
			(type default)
		)
		(layer "In1.Cu")
	)
	(gr_line
		(start 183.63057 -8.91667)
		(end 184.443116 -8.91667)
		(stroke
			(width 0.2)
			(type default)
		)
		(layer "In1.Cu")
	)
	(gr_arc
		(start 183.63057 -7.89559)
		(mid 183.12003 -8.40613)
		(end 183.63057 -8.91667)
		(stroke
			(width 0.2)
			(type default)
		)
		(layer "In1.Cu")
	)
	(gr_arc
		(start 183.662066 -213.080854)
		(mid 183.699263 -213.170657)
		(end 183.789066 -213.207854)
		(stroke
			(width 0.2)
			(type default)
		)
		(layer "In1.Cu")
	)
	(gr_line
		(start 183.662066 -211.760054)
		(end 183.662066 -213.080854)
		(stroke
			(width 0.2)
			(type default)
		)
		(layer "In1.Cu")
	)
	(gr_line
		(start 183.789066 -213.207854)
		(end 184.195466 -213.207854)
		(stroke
			(width 0.2)
			(type default)
		)
		(layer "In1.Cu")
	)
	(gr_arc
		(start 183.789066 -211.633054)
		(mid 183.699263 -211.670251)
		(end 183.662066 -211.760054)
		(stroke
			(width 0.2)
			(type default)
		)
		(layer "In1.Cu")
	)
	(gr_arc
		(start 184.048146 -12.509754)
		(mid 184.558686 -13.020294)
		(end 185.069226 -12.509754)
		(stroke
			(width 0.2)
			(type default)
		)
		(layer "In1.Cu")
	)
	(gr_line
		(start 184.048146 -11.696954)
		(end 184.048146 -12.509754)
		(stroke
			(width 0.2)
			(type default)
		)
		(layer "In1.Cu")
	)
	(gr_line
		(start 184.093612 -211.406994)
		(end 184.906412 -211.406994)
		(stroke
			(width 0.2)
			(type default)
		)
		(layer "In1.Cu")
	)
	(gr_arc
		(start 184.093866 -210.385914)
		(mid 183.583072 -210.896327)
		(end 184.093612 -211.406994)
		(stroke
			(width 0.2)
			(type default)
		)
		(layer "In1.Cu")
	)
	(gr_line
		(start 184.195466 -213.207854)
		(end 184.19572 -213.2076)
		(stroke
			(width 0.2)
			(type default)
		)
		(layer "In1.Cu")
	)
	(gr_line
		(start 184.19572 -213.2076)
		(end 184.796938 -213.2076)
		(stroke
			(width 0.2)
			(type default)
		)
		(layer "In1.Cu")
	)
	(gr_arc
		(start 184.443116 -8.91667)
		(mid 184.95391 -8.406257)
		(end 184.44337 -7.89559)
		(stroke
			(width 0.2)
			(type default)
		)
		(layer "In1.Cu")
	)
	(gr_line
		(start 184.44337 -7.89559)
		(end 183.63057 -7.89559)
		(stroke
			(width 0.2)
			(type default)
		)
		(layer "In1.Cu")
	)
	(gr_arc
		(start 184.796938 -213.2076)
		(mid 184.801 -213.207795)
		(end 184.805066 -213.207854)
		(stroke
			(width 0.2)
			(type default)
		)
		(layer "In1.Cu")
	)
	(gr_line
		(start 184.805066 -213.207854)
		(end 185.211466 -213.207854)
		(stroke
			(width 0.2)
			(type default)
		)
		(layer "In1.Cu")
	)
	(gr_arc
		(start 184.906412 -211.406994)
		(mid 185.416952 -210.896454)
		(end 184.906412 -210.385914)
		(stroke
			(width 0.2)
			(type default)
		)
		(layer "In1.Cu")
	)
	(gr_line
		(start 184.906412 -210.385914)
		(end 184.093866 -210.385914)
		(stroke
			(width 0.2)
			(type default)
		)
		(layer "In1.Cu")
	)
	(gr_line
		(start 185.069226 -12.509754)
		(end 185.069226 -11.697208)
		(stroke
			(width 0.2)
			(type default)
		)
		(layer "In1.Cu")
	)
	(gr_arc
		(start 185.069226 -11.697208)
		(mid 184.558813 -11.186414)
		(end 184.048146 -11.696954)
		(stroke
			(width 0.2)
			(type default)
		)
		(layer "In1.Cu")
	)
	(gr_arc
		(start 185.211466 -213.207854)
		(mid 185.301269 -213.170657)
		(end 185.338466 -213.080854)
		(stroke
			(width 0.2)
			(type default)
		)
		(layer "In1.Cu")
	)
	(gr_line
		(start 185.211466 -211.633054)
		(end 183.789066 -211.633054)
		(stroke
			(width 0.2)
			(type default)
		)
		(layer "In1.Cu")
	)
	(gr_line
		(start 185.338466 -213.080854)
		(end 185.338466 -211.760054)
		(stroke
			(width 0.2)
			(type default)
		)
		(layer "In1.Cu")
	)
	(gr_arc
		(start 185.338466 -211.760054)
		(mid 185.301269 -211.670251)
		(end 185.211466 -211.633054)
		(stroke
			(width 0.2)
			(type default)
		)
		(layer "In1.Cu")
	)
	(gr_arc
		(start 185.54446 -25.811734)
		(mid 186.055 -26.322274)
		(end 186.56554 -25.811734)
		(stroke
			(width 0.2)
			(type default)
		)
		(layer "In1.Cu")
	)
	(gr_line
		(start 185.54446 -24.998934)
		(end 185.54446 -25.811734)
		(stroke
			(width 0.2)
			(type default)
		)
		(layer "In1.Cu")
	)
	(gr_line
		(start 185.693558 -222.805244)
		(end 186.506358 -222.805244)
		(stroke
			(width 0.2)
			(type default)
		)
		(layer "In1.Cu")
	)
	(gr_arc
		(start 185.693812 -221.784164)
		(mid 185.183018 -222.294577)
		(end 185.693558 -222.805244)
		(stroke
			(width 0.2)
			(type default)
		)
		(layer "In1.Cu")
	)
	(gr_arc
		(start 186.506358 -222.805244)
		(mid 187.016898 -222.294704)
		(end 186.506358 -221.784164)
		(stroke
			(width 0.2)
			(type default)
		)
		(layer "In1.Cu")
	)
	(gr_line
		(start 186.506358 -221.784164)
		(end 185.693812 -221.784164)
		(stroke
			(width 0.2)
			(type default)
		)
		(layer "In1.Cu")
	)
	(gr_line
		(start 186.56554 -25.811734)
		(end 186.56554 -24.999188)
		(stroke
			(width 0.2)
			(type default)
		)
		(layer "In1.Cu")
	)
	(gr_arc
		(start 186.56554 -24.999188)
		(mid 186.055127 -24.488394)
		(end 185.54446 -24.998934)
		(stroke
			(width 0.2)
			(type default)
		)
		(layer "In1.Cu")
	)
	(gr_arc
		(start 186.861958 -213.080854)
		(mid 186.899155 -213.170657)
		(end 186.988958 -213.207854)
		(stroke
			(width 0.2)
			(type default)
		)
		(layer "In1.Cu")
	)
	(gr_line
		(start 186.861958 -211.760054)
		(end 186.861958 -213.080854)
		(stroke
			(width 0.2)
			(type default)
		)
		(layer "In1.Cu")
	)
	(gr_line
		(start 186.988958 -213.207854)
		(end 187.395358 -213.207854)
		(stroke
			(width 0.2)
			(type default)
		)
		(layer "In1.Cu")
	)
	(gr_arc
		(start 186.988958 -211.633054)
		(mid 186.899155 -211.670251)
		(end 186.861958 -211.760054)
		(stroke
			(width 0.2)
			(type default)
		)
		(layer "In1.Cu")
	)
	(gr_line
		(start 187.293758 -211.406994)
		(end 188.106558 -211.406994)
		(stroke
			(width 0.2)
			(type default)
		)
		(layer "In1.Cu")
	)
	(gr_arc
		(start 187.294012 -210.385914)
		(mid 186.783218 -210.896327)
		(end 187.293758 -211.406994)
		(stroke
			(width 0.2)
			(type default)
		)
		(layer "In1.Cu")
	)
	(gr_line
		(start 187.395358 -213.207854)
		(end 187.395612 -213.2076)
		(stroke
			(width 0.2)
			(type default)
		)
		(layer "In1.Cu")
	)
	(gr_line
		(start 187.395612 -213.2076)
		(end 187.99683 -213.2076)
		(stroke
			(width 0.2)
			(type default)
		)
		(layer "In1.Cu")
	)
	(gr_arc
		(start 187.99683 -213.2076)
		(mid 188.000892 -213.207795)
		(end 188.004958 -213.207854)
		(stroke
			(width 0.2)
			(type default)
		)
		(layer "In1.Cu")
	)
	(gr_line
		(start 188.004958 -213.207854)
		(end 188.411358 -213.207854)
		(stroke
			(width 0.2)
			(type default)
		)
		(layer "In1.Cu")
	)
	(gr_arc
		(start 188.106558 -211.406994)
		(mid 188.617098 -210.896454)
		(end 188.106558 -210.385914)
		(stroke
			(width 0.2)
			(type default)
		)
		(layer "In1.Cu")
	)
	(gr_line
		(start 188.106558 -210.385914)
		(end 187.294012 -210.385914)
		(stroke
			(width 0.2)
			(type default)
		)
		(layer "In1.Cu")
	)
	(gr_arc
		(start 188.411358 -213.207854)
		(mid 188.501161 -213.170657)
		(end 188.538358 -213.080854)
		(stroke
			(width 0.2)
			(type default)
		)
		(layer "In1.Cu")
	)
	(gr_line
		(start 188.411358 -211.633054)
		(end 186.988958 -211.633054)
		(stroke
			(width 0.2)
			(type default)
		)
		(layer "In1.Cu")
	)
	(gr_line
		(start 188.538358 -213.080854)
		(end 188.538358 -211.760054)
		(stroke
			(width 0.2)
			(type default)
		)
		(layer "In1.Cu")
	)
	(gr_arc
		(start 188.538358 -211.760054)
		(mid 188.501161 -211.670251)
		(end 188.411358 -211.633054)
		(stroke
			(width 0.2)
			(type default)
		)
		(layer "In1.Cu")
	)
	(gr_line
		(start 188.893704 -222.805244)
		(end 189.70625 -222.805244)
		(stroke
			(width 0.2)
			(type default)
		)
		(layer "In1.Cu")
	)
	(gr_arc
		(start 188.893704 -221.784164)
		(mid 188.383164 -222.294704)
		(end 188.893704 -222.805244)
		(stroke
			(width 0.2)
			(type default)
		)
		(layer "In1.Cu")
	)
	(gr_arc
		(start 189.70625 -222.805244)
		(mid 190.217044 -222.294831)
		(end 189.706504 -221.784164)
		(stroke
			(width 0.2)
			(type default)
		)
		(layer "In1.Cu")
	)
	(gr_line
		(start 189.706504 -221.784164)
		(end 188.893704 -221.784164)
		(stroke
			(width 0.2)
			(type default)
		)
		(layer "In1.Cu")
	)
	(gr_arc
		(start 190.062104 -213.080854)
		(mid 190.099301 -213.170657)
		(end 190.189104 -213.207854)
		(stroke
			(width 0.2)
			(type default)
		)
		(layer "In1.Cu")
	)
	(gr_line
		(start 190.062104 -211.760054)
		(end 190.062104 -213.080854)
		(stroke
			(width 0.2)
			(type default)
		)
		(layer "In1.Cu")
	)
	(gr_line
		(start 190.189104 -213.207854)
		(end 190.595504 -213.207854)
		(stroke
			(width 0.2)
			(type default)
		)
		(layer "In1.Cu")
	)
	(gr_arc
		(start 190.189104 -211.633054)
		(mid 190.099301 -211.670251)
		(end 190.062104 -211.760054)
		(stroke
			(width 0.2)
			(type default)
		)
		(layer "In1.Cu")
	)
	(gr_line
		(start 190.49365 -211.406994)
		(end 191.30645 -211.406994)
		(stroke
			(width 0.2)
			(type default)
		)
		(layer "In1.Cu")
	)
	(gr_arc
		(start 190.493904 -210.385914)
		(mid 189.98311 -210.896327)
		(end 190.49365 -211.406994)
		(stroke
			(width 0.2)
			(type default)
		)
		(layer "In1.Cu")
	)
	(gr_line
		(start 190.595504 -213.207854)
		(end 190.595758 -213.2076)
		(stroke
			(width 0.2)
			(type default)
		)
		(layer "In1.Cu")
	)
	(gr_line
		(start 190.595758 -213.2076)
		(end 191.196976 -213.2076)
		(stroke
			(width 0.2)
			(type default)
		)
		(layer "In1.Cu")
	)
	(gr_arc
		(start 191.196976 -213.2076)
		(mid 191.201038 -213.207795)
		(end 191.205104 -213.207854)
		(stroke
			(width 0.2)
			(type default)
		)
		(layer "In1.Cu")
	)
	(gr_line
		(start 191.205104 -213.207854)
		(end 191.611504 -213.207854)
		(stroke
			(width 0.2)
			(type default)
		)
		(layer "In1.Cu")
	)
	(gr_arc
		(start 191.30645 -211.406994)
		(mid 191.81699 -210.896454)
		(end 191.30645 -210.385914)
		(stroke
			(width 0.2)
			(type default)
		)
		(layer "In1.Cu")
	)
	(gr_line
		(start 191.30645 -210.385914)
		(end 190.493904 -210.385914)
		(stroke
			(width 0.2)
			(type default)
		)
		(layer "In1.Cu")
	)
	(gr_arc
		(start 191.611504 -213.207854)
		(mid 191.701307 -213.170657)
		(end 191.738504 -213.080854)
		(stroke
			(width 0.2)
			(type default)
		)
		(layer "In1.Cu")
	)
	(gr_line
		(start 191.611504 -211.633054)
		(end 190.189104 -211.633054)
		(stroke
			(width 0.2)
			(type default)
		)
		(layer "In1.Cu")
	)
	(gr_line
		(start 191.738504 -213.080854)
		(end 191.738504 -211.760054)
		(stroke
			(width 0.2)
			(type default)
		)
		(layer "In1.Cu")
	)
	(gr_arc
		(start 191.738504 -211.760054)
		(mid 191.701307 -211.670251)
		(end 191.611504 -211.633054)
		(stroke
			(width 0.2)
			(type default)
		)
		(layer "In1.Cu")
	)
	(gr_line
		(start 192.093596 -222.805244)
		(end 192.906142 -222.805244)
		(stroke
			(width 0.2)
			(type default)
		)
		(layer "In1.Cu")
	)
	(gr_arc
		(start 192.093596 -221.784164)
		(mid 191.583056 -222.294704)
		(end 192.093596 -222.805244)
		(stroke
			(width 0.2)
			(type default)
		)
		(layer "In1.Cu")
	)
	(gr_arc
		(start 192.906142 -222.805244)
		(mid 193.416936 -222.294831)
		(end 192.906396 -221.784164)
		(stroke
			(width 0.2)
			(type default)
		)
		(layer "In1.Cu")
	)
	(gr_line
		(start 192.906396 -221.784164)
		(end 192.093596 -221.784164)
		(stroke
			(width 0.2)
			(type default)
		)
		(layer "In1.Cu")
	)
	(gr_arc
		(start 193.261996 -213.080854)
		(mid 193.299193 -213.170657)
		(end 193.388996 -213.207854)
		(stroke
			(width 0.2)
			(type default)
		)
		(layer "In1.Cu")
	)
	(gr_line
		(start 193.261996 -211.760054)
		(end 193.261996 -213.080854)
		(stroke
			(width 0.2)
			(type default)
		)
		(layer "In1.Cu")
	)
	(gr_line
		(start 193.388996 -213.207854)
		(end 193.795396 -213.207854)
		(stroke
			(width 0.2)
			(type default)
		)
		(layer "In1.Cu")
	)
	(gr_arc
		(start 193.388996 -211.633054)
		(mid 193.299193 -211.670251)
		(end 193.261996 -211.760054)
		(stroke
			(width 0.2)
			(type default)
		)
		(layer "In1.Cu")
	)
	(gr_line
		(start 193.693796 -211.406994)
		(end 194.506596 -211.406994)
		(stroke
			(width 0.2)
			(type default)
		)
		(layer "In1.Cu")
	)
	(gr_arc
		(start 193.69405 -210.385914)
		(mid 193.183256 -210.896327)
		(end 193.693796 -211.406994)
		(stroke
			(width 0.2)
			(type default)
		)
		(layer "In1.Cu")
	)
	(gr_line
		(start 193.795396 -213.207854)
		(end 193.79565 -213.2076)
		(stroke
			(width 0.2)
			(type default)
		)
		(layer "In1.Cu")
	)
	(gr_line
		(start 193.79565 -213.2076)
		(end 194.396868 -213.2076)
		(stroke
			(width 0.2)
			(type default)
		)
		(layer "In1.Cu")
	)
	(gr_arc
		(start 194.396868 -213.2076)
		(mid 194.40093 -213.207795)
		(end 194.404996 -213.207854)
		(stroke
			(width 0.2)
			(type default)
		)
		(layer "In1.Cu")
	)
	(gr_line
		(start 194.404996 -213.207854)
		(end 194.811396 -213.207854)
		(stroke
			(width 0.2)
			(type default)
		)
		(layer "In1.Cu")
	)
	(gr_arc
		(start 194.506596 -211.406994)
		(mid 195.017136 -210.896454)
		(end 194.506596 -210.385914)
		(stroke
			(width 0.2)
			(type default)
		)
		(layer "In1.Cu")
	)
	(gr_line
		(start 194.506596 -210.385914)
		(end 193.69405 -210.385914)
		(stroke
			(width 0.2)
			(type default)
		)
		(layer "In1.Cu")
	)
	(gr_arc
		(start 194.811396 -213.207854)
		(mid 194.901199 -213.170657)
		(end 194.938396 -213.080854)
		(stroke
			(width 0.2)
			(type default)
		)
		(layer "In1.Cu")
	)
	(gr_line
		(start 194.811396 -211.633054)
		(end 193.388996 -211.633054)
		(stroke
			(width 0.2)
			(type default)
		)
		(layer "In1.Cu")
	)
	(gr_line
		(start 194.938396 -213.080854)
		(end 194.938396 -211.760054)
		(stroke
			(width 0.2)
			(type default)
		)
		(layer "In1.Cu")
	)
	(gr_arc
		(start 194.938396 -211.760054)
		(mid 194.901199 -211.670251)
		(end 194.811396 -211.633054)
		(stroke
			(width 0.2)
			(type default)
		)
		(layer "In1.Cu")
	)
	(gr_line
		(start 195.293742 -222.805244)
		(end 196.106288 -222.805244)
		(stroke
			(width 0.2)
			(type default)
		)
		(layer "In1.Cu")
	)
	(gr_arc
		(start 195.293742 -221.784164)
		(mid 194.783202 -222.294704)
		(end 195.293742 -222.805244)
		(stroke
			(width 0.2)
			(type default)
		)
		(layer "In1.Cu")
	)
	(gr_arc
		(start 196.106288 -222.805244)
		(mid 196.617082 -222.294831)
		(end 196.106542 -221.784164)
		(stroke
			(width 0.2)
			(type default)
		)
		(layer "In1.Cu")
	)
	(gr_line
		(start 196.106542 -221.784164)
		(end 195.293742 -221.784164)
		(stroke
			(width 0.2)
			(type default)
		)
		(layer "In1.Cu")
	)
	(gr_arc
		(start 196.461888 -213.080854)
		(mid 196.499085 -213.170657)
		(end 196.588888 -213.207854)
		(stroke
			(width 0.2)
			(type default)
		)
		(layer "In1.Cu")
	)
	(gr_line
		(start 196.461888 -211.760054)
		(end 196.461888 -213.080854)
		(stroke
			(width 0.2)
			(type default)
		)
		(layer "In1.Cu")
	)
	(gr_line
		(start 196.588888 -213.207854)
		(end 196.995288 -213.207854)
		(stroke
			(width 0.2)
			(type default)
		)
		(layer "In1.Cu")
	)
	(gr_arc
		(start 196.588888 -211.633054)
		(mid 196.499085 -211.670251)
		(end 196.461888 -211.760054)
		(stroke
			(width 0.2)
			(type default)
		)
		(layer "In1.Cu")
	)
	(gr_line
		(start 196.893688 -211.406994)
		(end 197.706488 -211.406994)
		(stroke
			(width 0.2)
			(type default)
		)
		(layer "In1.Cu")
	)
	(gr_arc
		(start 196.893942 -210.385914)
		(mid 196.383148 -210.896327)
		(end 196.893688 -211.406994)
		(stroke
			(width 0.2)
			(type default)
		)
		(layer "In1.Cu")
	)
	(gr_line
		(start 196.995288 -213.207854)
		(end 196.995542 -213.2076)
		(stroke
			(width 0.2)
			(type default)
		)
		(layer "In1.Cu")
	)
	(gr_line
		(start 196.995542 -213.2076)
		(end 197.59676 -213.2076)
		(stroke
			(width 0.2)
			(type default)
		)
		(layer "In1.Cu")
	)
	(gr_arc
		(start 197.204838 -46.70806)
		(mid 197.816978 -47.3202)
		(end 198.429118 -46.70806)
		(stroke
			(width 0.2)
			(type default)
		)
		(layer "In1.Cu")
	)
	(gr_line
		(start 197.204838 -45.59046)
		(end 197.204838 -46.70806)
		(stroke
			(width 0.2)
			(type default)
		)
		(layer "In1.Cu")
	)
	(gr_arc
		(start 197.59676 -213.2076)
		(mid 197.600822 -213.207795)
		(end 197.604888 -213.207854)
		(stroke
			(width 0.2)
			(type default)
		)
		(layer "In1.Cu")
	)
	(gr_line
		(start 197.604888 -213.207854)
		(end 198.011288 -213.207854)
		(stroke
			(width 0.2)
			(type default)
		)
		(layer "In1.Cu")
	)
	(gr_arc
		(start 197.706488 -211.406994)
		(mid 198.217028 -210.896454)
		(end 197.706488 -210.385914)
		(stroke
			(width 0.2)
			(type default)
		)
		(layer "In1.Cu")
	)
	(gr_line
		(start 197.706488 -210.385914)
		(end 196.893942 -210.385914)
		(stroke
			(width 0.2)
			(type default)
		)
		(layer "In1.Cu")
	)
	(gr_arc
		(start 198.011288 -213.207854)
		(mid 198.101091 -213.170657)
		(end 198.138288 -213.080854)
		(stroke
			(width 0.2)
			(type default)
		)
		(layer "In1.Cu")
	)
	(gr_line
		(start 198.011288 -211.633054)
		(end 196.588888 -211.633054)
		(stroke
			(width 0.2)
			(type default)
		)
		(layer "In1.Cu")
	)
	(gr_line
		(start 198.138288 -213.080854)
		(end 198.138288 -211.760054)
		(stroke
			(width 0.2)
			(type default)
		)
		(layer "In1.Cu")
	)
	(gr_arc
		(start 198.138288 -211.760054)
		(mid 198.101091 -211.670251)
		(end 198.011288 -211.633054)
		(stroke
			(width 0.2)
			(type default)
		)
		(layer "In1.Cu")
	)
	(gr_line
		(start 198.429118 -46.70806)
		(end 198.429118 -45.590714)
		(stroke
			(width 0.2)
			(type default)
		)
		(layer "In1.Cu")
	)
	(gr_arc
		(start 198.429118 -45.590714)
		(mid 197.817105 -44.97832)
		(end 197.204838 -45.59046)
		(stroke
			(width 0.2)
			(type default)
		)
		(layer "In1.Cu")
	)
	(gr_line
		(start 198.493634 -222.805244)
		(end 199.30618 -222.805244)
		(stroke
			(width 0.2)
			(type default)
		)
		(layer "In1.Cu")
	)
	(gr_arc
		(start 198.493634 -221.784164)
		(mid 197.983094 -222.294704)
		(end 198.493634 -222.805244)
		(stroke
			(width 0.2)
			(type default)
		)
		(layer "In1.Cu")
	)
	(gr_arc
		(start 199.30618 -222.805244)
		(mid 199.816974 -222.294831)
		(end 199.306434 -221.784164)
		(stroke
			(width 0.2)
			(type default)
		)
		(layer "In1.Cu")
	)
	(gr_line
		(start 199.306434 -221.784164)
		(end 198.493634 -221.784164)
		(stroke
			(width 0.2)
			(type default)
		)
		(layer "In1.Cu")
	)
	(gr_arc
		(start 199.66178 -213.080854)
		(mid 199.698977 -213.170657)
		(end 199.78878 -213.207854)
		(stroke
			(width 0.2)
			(type default)
		)
		(layer "In1.Cu")
	)
	(gr_line
		(start 199.66178 -211.760054)
		(end 199.66178 -213.080854)
		(stroke
			(width 0.2)
			(type default)
		)
		(layer "In1.Cu")
	)
	(gr_line
		(start 199.78878 -213.207854)
		(end 200.19518 -213.207854)
		(stroke
			(width 0.2)
			(type default)
		)
		(layer "In1.Cu")
	)
	(gr_arc
		(start 199.78878 -211.633054)
		(mid 199.698977 -211.670251)
		(end 199.66178 -211.760054)
		(stroke
			(width 0.2)
			(type default)
		)
		(layer "In1.Cu")
	)
	(gr_arc
		(start 200.046844 -49.122076)
		(mid 199.43826 -49.737772)
		(end 200.053956 -50.346356)
		(stroke
			(width 0.2)
			(type default)
		)
		(layer "In1.Cu")
	)
	(gr_line
		(start 200.053956 -50.346356)
		(end 201.171302 -50.339752)
		(stroke
			(width 0.2)
			(type default)
		)
		(layer "In1.Cu")
	)
	(gr_line
		(start 200.09358 -211.406994)
		(end 200.90638 -211.406994)
		(stroke
			(width 0.2)
			(type default)
		)
		(layer "In1.Cu")
	)
	(gr_arc
		(start 200.093834 -210.385914)
		(mid 199.58304 -210.896327)
		(end 200.09358 -211.406994)
		(stroke
			(width 0.2)
			(type default)
		)
		(layer "In1.Cu")
	)
	(gr_line
		(start 200.19518 -213.207854)
		(end 200.195434 -213.2076)
		(stroke
			(width 0.2)
			(type default)
		)
		(layer "In1.Cu")
	)
	(gr_line
		(start 200.195434 -213.2076)
		(end 200.796652 -213.2076)
		(stroke
			(width 0.2)
			(type default)
		)
		(layer "In1.Cu")
	)
	(gr_arc
		(start 200.7489 -45.832268)
		(mid 201.360913 -46.444662)
		(end 201.97318 -45.832522)
		(stroke
			(width 0.2)
			(type default)
		)
		(layer "In1.Cu")
	)
	(gr_line
		(start 200.7489 -44.714922)
		(end 200.7489 -45.832268)
		(stroke
			(width 0.2)
			(type default)
		)
		(layer "In1.Cu")
	)
	(gr_arc
		(start 200.796652 -213.2076)
		(mid 200.800714 -213.207795)
		(end 200.80478 -213.207854)
		(stroke
			(width 0.2)
			(type default)
		)
		(layer "In1.Cu")
	)
	(gr_line
		(start 200.80478 -213.207854)
		(end 201.21118 -213.207854)
		(stroke
			(width 0.2)
			(type default)
		)
		(layer "In1.Cu")
	)
	(gr_arc
		(start 200.90638 -211.406994)
		(mid 201.41692 -210.896454)
		(end 200.90638 -210.385914)
		(stroke
			(width 0.2)
			(type default)
		)
		(layer "In1.Cu")
	)
	(gr_line
		(start 200.90638 -210.385914)
		(end 200.093834 -210.385914)
		(stroke
			(width 0.2)
			(type default)
		)
		(layer "In1.Cu")
	)
	(gr_line
		(start 201.164444 -49.115472)
		(end 200.046844 -49.122076)
		(stroke
			(width 0.2)
			(type default)
		)
		(layer "In1.Cu")
	)
	(gr_arc
		(start 201.171302 -50.339752)
		(mid 201.780139 -49.724183)
		(end 201.164444 -49.115472)
		(stroke
			(width 0.2)
			(type default)
		)
		(layer "In1.Cu")
	)
	(gr_arc
		(start 201.21118 -213.207854)
		(mid 201.300983 -213.170657)
		(end 201.33818 -213.080854)
		(stroke
			(width 0.2)
			(type default)
		)
		(layer "In1.Cu")
	)
	(gr_line
		(start 201.21118 -211.633054)
		(end 199.78878 -211.633054)
		(stroke
			(width 0.2)
			(type default)
		)
		(layer "In1.Cu")
	)
	(gr_line
		(start 201.33818 -213.080854)
		(end 201.33818 -211.760054)
		(stroke
			(width 0.2)
			(type default)
		)
		(layer "In1.Cu")
	)
	(gr_arc
		(start 201.33818 -211.760054)
		(mid 201.300983 -211.670251)
		(end 201.21118 -211.633054)
		(stroke
			(width 0.2)
			(type default)
		)
		(layer "In1.Cu")
	)
	(gr_line
		(start 201.69378 -222.805244)
		(end 202.506326 -222.805244)
		(stroke
			(width 0.2)
			(type default)
		)
		(layer "In1.Cu")
	)
	(gr_arc
		(start 201.69378 -221.784164)
		(mid 201.18324 -222.294704)
		(end 201.69378 -222.805244)
		(stroke
			(width 0.2)
			(type default)
		)
		(layer "In1.Cu")
	)
	(gr_line
		(start 201.97318 -45.832522)
		(end 201.97318 -44.714922)
		(stroke
			(width 0.2)
			(type default)
		)
		(layer "In1.Cu")
	)
	(gr_arc
		(start 201.97318 -44.714922)
		(mid 201.36104 -44.102782)
		(end 200.7489 -44.714922)
		(stroke
			(width 0.2)
			(type default)
		)
		(layer "In1.Cu")
	)
	(gr_arc
		(start 202.506326 -222.805244)
		(mid 203.01712 -222.294831)
		(end 202.50658 -221.784164)
		(stroke
			(width 0.2)
			(type default)
		)
		(layer "In1.Cu")
	)
	(gr_line
		(start 202.50658 -221.784164)
		(end 201.69378 -221.784164)
		(stroke
			(width 0.2)
			(type default)
		)
		(layer "In1.Cu")
	)
	(gr_arc
		(start 202.861926 -213.080854)
		(mid 202.899123 -213.170657)
		(end 202.988926 -213.207854)
		(stroke
			(width 0.2)
			(type default)
		)
		(layer "In1.Cu")
	)
	(gr_line
		(start 202.861926 -211.760054)
		(end 202.861926 -213.080854)
		(stroke
			(width 0.2)
			(type default)
		)
		(layer "In1.Cu")
	)
	(gr_line
		(start 202.946 -50.29454)
		(end 203.7588 -50.29454)
		(stroke
			(width 0.2)
			(type default)
		)
		(layer "In1.Cu")
	)
	(gr_arc
		(start 202.946254 -49.27346)
		(mid 202.43546 -49.783873)
		(end 202.946 -50.29454)
		(stroke
			(width 0.2)
			(type default)
		)
		(layer "In1.Cu")
	)
	(gr_line
		(start 202.988926 -213.207854)
		(end 203.395326 -213.207854)
		(stroke
			(width 0.2)
			(type default)
		)
		(layer "In1.Cu")
	)
	(gr_arc
		(start 202.988926 -211.633054)
		(mid 202.899123 -211.670251)
		(end 202.861926 -211.760054)
		(stroke
			(width 0.2)
			(type default)
		)
		(layer "In1.Cu")
	)
	(gr_line
		(start 203.293726 -211.406994)
		(end 204.106526 -211.406994)
		(stroke
			(width 0.2)
			(type default)
		)
		(layer "In1.Cu")
	)
	(gr_arc
		(start 203.29398 -210.385914)
		(mid 202.783186 -210.896327)
		(end 203.293726 -211.406994)
		(stroke
			(width 0.2)
			(type default)
		)
		(layer "In1.Cu")
	)
	(gr_line
		(start 203.395326 -213.207854)
		(end 203.39558 -213.2076)
		(stroke
			(width 0.2)
			(type default)
		)
		(layer "In1.Cu")
	)
	(gr_line
		(start 203.39558 -213.2076)
		(end 203.996798 -213.2076)
		(stroke
			(width 0.2)
			(type default)
		)
		(layer "In1.Cu")
	)
	(gr_arc
		(start 203.7588 -50.29454)
		(mid 204.26934 -49.784)
		(end 203.7588 -49.27346)
		(stroke
			(width 0.2)
			(type default)
		)
		(layer "In1.Cu")
	)
	(gr_line
		(start 203.7588 -49.27346)
		(end 202.946254 -49.27346)
		(stroke
			(width 0.2)
			(type default)
		)
		(layer "In1.Cu")
	)
	(gr_arc
		(start 203.996798 -213.2076)
		(mid 204.00086 -213.207795)
		(end 204.004926 -213.207854)
		(stroke
			(width 0.2)
			(type default)
		)
		(layer "In1.Cu")
	)
	(gr_line
		(start 204.004926 -213.207854)
		(end 204.411326 -213.207854)
		(stroke
			(width 0.2)
			(type default)
		)
		(layer "In1.Cu")
	)
	(gr_arc
		(start 204.106526 -211.406994)
		(mid 204.617066 -210.896454)
		(end 204.106526 -210.385914)
		(stroke
			(width 0.2)
			(type default)
		)
		(layer "In1.Cu")
	)
	(gr_line
		(start 204.106526 -210.385914)
		(end 203.29398 -210.385914)
		(stroke
			(width 0.2)
			(type default)
		)
		(layer "In1.Cu")
	)
	(gr_arc
		(start 204.411326 -213.207854)
		(mid 204.501129 -213.170657)
		(end 204.538326 -213.080854)
		(stroke
			(width 0.2)
			(type default)
		)
		(layer "In1.Cu")
	)
	(gr_line
		(start 204.411326 -211.633054)
		(end 202.988926 -211.633054)
		(stroke
			(width 0.2)
			(type default)
		)
		(layer "In1.Cu")
	)
	(gr_line
		(start 204.538326 -213.080854)
		(end 204.538326 -211.760054)
		(stroke
			(width 0.2)
			(type default)
		)
		(layer "In1.Cu")
	)
	(gr_arc
		(start 204.538326 -211.760054)
		(mid 204.501129 -211.670251)
		(end 204.411326 -211.633054)
		(stroke
			(width 0.2)
			(type default)
		)
		(layer "In1.Cu")
	)
	(gr_line
		(start 204.893672 -222.805244)
		(end 205.706218 -222.805244)
		(stroke
			(width 0.2)
			(type default)
		)
		(layer "In1.Cu")
	)
	(gr_arc
		(start 204.893672 -221.784164)
		(mid 204.383132 -222.294704)
		(end 204.893672 -222.805244)
		(stroke
			(width 0.2)
			(type default)
		)
		(layer "In1.Cu")
	)
	(gr_arc
		(start 205.706218 -222.805244)
		(mid 206.217012 -222.294831)
		(end 205.706472 -221.784164)
		(stroke
			(width 0.2)
			(type default)
		)
		(layer "In1.Cu")
	)
	(gr_line
		(start 205.706472 -221.784164)
		(end 204.893672 -221.784164)
		(stroke
			(width 0.2)
			(type default)
		)
		(layer "In1.Cu")
	)
	(gr_arc
		(start 206.061818 -213.080854)
		(mid 206.099015 -213.170657)
		(end 206.188818 -213.207854)
		(stroke
			(width 0.2)
			(type default)
		)
		(layer "In1.Cu")
	)
	(gr_line
		(start 206.061818 -211.760054)
		(end 206.061818 -213.080854)
		(stroke
			(width 0.2)
			(type default)
		)
		(layer "In1.Cu")
	)
	(gr_line
		(start 206.188818 -213.207854)
		(end 206.595218 -213.207854)
		(stroke
			(width 0.2)
			(type default)
		)
		(layer "In1.Cu")
	)
	(gr_arc
		(start 206.188818 -211.633054)
		(mid 206.099015 -211.670251)
		(end 206.061818 -211.760054)
		(stroke
			(width 0.2)
			(type default)
		)
		(layer "In1.Cu")
	)
	(gr_line
		(start 206.493618 -211.406994)
		(end 207.306418 -211.406994)
		(stroke
			(width 0.2)
			(type default)
		)
		(layer "In1.Cu")
	)
	(gr_arc
		(start 206.493872 -210.385914)
		(mid 205.983078 -210.896327)
		(end 206.493618 -211.406994)
		(stroke
			(width 0.2)
			(type default)
		)
		(layer "In1.Cu")
	)
	(gr_line
		(start 206.595218 -213.207854)
		(end 206.595472 -213.2076)
		(stroke
			(width 0.2)
			(type default)
		)
		(layer "In1.Cu")
	)
	(gr_line
		(start 206.595472 -213.2076)
		(end 207.19669 -213.2076)
		(stroke
			(width 0.2)
			(type default)
		)
		(layer "In1.Cu")
	)
	(gr_arc
		(start 207.19669 -213.2076)
		(mid 207.200752 -213.207795)
		(end 207.204818 -213.207854)
		(stroke
			(width 0.2)
			(type default)
		)
		(layer "In1.Cu")
	)
	(gr_line
		(start 207.204818 -213.207854)
		(end 207.611218 -213.207854)
		(stroke
			(width 0.2)
			(type default)
		)
		(layer "In1.Cu")
	)
	(gr_arc
		(start 207.306418 -211.406994)
		(mid 207.816958 -210.896454)
		(end 207.306418 -210.385914)
		(stroke
			(width 0.2)
			(type default)
		)
		(layer "In1.Cu")
	)
	(gr_line
		(start 207.306418 -210.385914)
		(end 206.493872 -210.385914)
		(stroke
			(width 0.2)
			(type default)
		)
		(layer "In1.Cu")
	)
	(gr_arc
		(start 207.611218 -213.207854)
		(mid 207.701021 -213.170657)
		(end 207.738218 -213.080854)
		(stroke
			(width 0.2)
			(type default)
		)
		(layer "In1.Cu")
	)
	(gr_line
		(start 207.611218 -211.633054)
		(end 206.188818 -211.633054)
		(stroke
			(width 0.2)
			(type default)
		)
		(layer "In1.Cu")
	)
	(gr_line
		(start 207.738218 -213.080854)
		(end 207.738218 -211.760054)
		(stroke
			(width 0.2)
			(type default)
		)
		(layer "In1.Cu")
	)
	(gr_arc
		(start 207.738218 -211.760054)
		(mid 207.701021 -211.670251)
		(end 207.611218 -211.633054)
		(stroke
			(width 0.2)
			(type default)
		)
		(layer "In1.Cu")
	)
	(gr_line
		(start 211.29371 -222.805244)
		(end 212.106256 -222.805244)
		(stroke
			(width 0.2)
			(type default)
		)
		(layer "In1.Cu")
	)
	(gr_arc
		(start 211.29371 -221.784164)
		(mid 210.78317 -222.294704)
		(end 211.29371 -222.805244)
		(stroke
			(width 0.2)
			(type default)
		)
		(layer "In1.Cu")
	)
	(gr_arc
		(start 211.807044 -41.28516)
		(mid 211.844241 -41.374963)
		(end 211.934044 -41.41216)
		(stroke
			(width 0.2)
			(type default)
		)
		(layer "In1.Cu")
	)
	(gr_line
		(start 211.807044 -39.98976)
		(end 211.807044 -41.28516)
		(stroke
			(width 0.2)
			(type default)
		)
		(layer "In1.Cu")
	)
	(gr_line
		(start 211.934044 -41.41216)
		(end 213.254844 -41.41216)
		(stroke
			(width 0.2)
			(type default)
		)
		(layer "In1.Cu")
	)
	(gr_arc
		(start 211.934044 -39.86276)
		(mid 211.844241 -39.899957)
		(end 211.807044 -39.98976)
		(stroke
			(width 0.2)
			(type default)
		)
		(layer "In1.Cu")
	)
	(gr_arc
		(start 212.106256 -222.805244)
		(mid 212.61705 -222.294831)
		(end 212.10651 -221.784164)
		(stroke
			(width 0.2)
			(type default)
		)
		(layer "In1.Cu")
	)
	(gr_line
		(start 212.10651 -221.784164)
		(end 211.29371 -221.784164)
		(stroke
			(width 0.2)
			(type default)
		)
		(layer "In1.Cu")
	)
	(gr_arc
		(start 212.461856 -213.080854)
		(mid 212.499053 -213.170657)
		(end 212.588856 -213.207854)
		(stroke
			(width 0.2)
			(type default)
		)
		(layer "In1.Cu")
	)
	(gr_line
		(start 212.461856 -211.760054)
		(end 212.461856 -213.080854)
		(stroke
			(width 0.2)
			(type default)
		)
		(layer "In1.Cu")
	)
	(gr_line
		(start 212.588856 -213.207854)
		(end 212.995256 -213.207854)
		(stroke
			(width 0.2)
			(type default)
		)
		(layer "In1.Cu")
	)
	(gr_arc
		(start 212.588856 -211.633054)
		(mid 212.499053 -211.670251)
		(end 212.461856 -211.760054)
		(stroke
			(width 0.2)
			(type default)
		)
		(layer "In1.Cu")
	)
	(gr_line
		(start 212.893656 -211.406994)
		(end 213.706456 -211.406994)
		(stroke
			(width 0.2)
			(type default)
		)
		(layer "In1.Cu")
	)
	(gr_arc
		(start 212.89391 -210.385914)
		(mid 212.383116 -210.896327)
		(end 212.893656 -211.406994)
		(stroke
			(width 0.2)
			(type default)
		)
		(layer "In1.Cu")
	)
	(gr_line
		(start 212.995256 -213.207854)
		(end 212.99551 -213.2076)
		(stroke
			(width 0.2)
			(type default)
		)
		(layer "In1.Cu")
	)
	(gr_line
		(start 212.99551 -213.2076)
		(end 213.596728 -213.2076)
		(stroke
			(width 0.2)
			(type default)
		)
		(layer "In1.Cu")
	)
	(gr_arc
		(start 213.254844 -41.41216)
		(mid 213.344647 -41.374963)
		(end 213.381844 -41.28516)
		(stroke
			(width 0.2)
			(type default)
		)
		(layer "In1.Cu")
	)
	(gr_line
		(start 213.254844 -39.86276)
		(end 211.934044 -39.86276)
		(stroke
			(width 0.2)
			(type default)
		)
		(layer "In1.Cu")
	)
	(gr_line
		(start 213.381844 -41.28516)
		(end 213.381844 -39.98976)
		(stroke
			(width 0.2)
			(type default)
		)
		(layer "In1.Cu")
	)
	(gr_arc
		(start 213.381844 -39.98976)
		(mid 213.344647 -39.899957)
		(end 213.254844 -39.86276)
		(stroke
			(width 0.2)
			(type default)
		)
		(layer "In1.Cu")
	)
	(gr_arc
		(start 213.596728 -213.2076)
		(mid 213.60079 -213.207795)
		(end 213.604856 -213.207854)
		(stroke
			(width 0.2)
			(type default)
		)
		(layer "In1.Cu")
	)
	(gr_line
		(start 213.604856 -213.207854)
		(end 214.011256 -213.207854)
		(stroke
			(width 0.2)
			(type default)
		)
		(layer "In1.Cu")
	)
	(gr_arc
		(start 213.706456 -211.406994)
		(mid 214.216996 -210.896454)
		(end 213.706456 -210.385914)
		(stroke
			(width 0.2)
			(type default)
		)
		(layer "In1.Cu")
	)
	(gr_line
		(start 213.706456 -210.385914)
		(end 212.89391 -210.385914)
		(stroke
			(width 0.2)
			(type default)
		)
		(layer "In1.Cu")
	)
	(gr_arc
		(start 214.011256 -213.207854)
		(mid 214.101059 -213.170657)
		(end 214.138256 -213.080854)
		(stroke
			(width 0.2)
			(type default)
		)
		(layer "In1.Cu")
	)
	(gr_line
		(start 214.011256 -211.633054)
		(end 212.588856 -211.633054)
		(stroke
			(width 0.2)
			(type default)
		)
		(layer "In1.Cu")
	)
	(gr_line
		(start 214.138256 -213.080854)
		(end 214.138256 -211.760054)
		(stroke
			(width 0.2)
			(type default)
		)
		(layer "In1.Cu")
	)
	(gr_arc
		(start 214.138256 -211.760054)
		(mid 214.101059 -211.670251)
		(end 214.011256 -211.633054)
		(stroke
			(width 0.2)
			(type default)
		)
		(layer "In1.Cu")
	)
	(gr_line
		(start 214.493602 -222.805244)
		(end 215.306148 -222.805244)
		(stroke
			(width 0.2)
			(type default)
		)
		(layer "In1.Cu")
	)
	(gr_arc
		(start 214.493602 -221.784164)
		(mid 213.983062 -222.294704)
		(end 214.493602 -222.805244)
		(stroke
			(width 0.2)
			(type default)
		)
		(layer "In1.Cu")
	)
	(gr_arc
		(start 215.306148 -222.805244)
		(mid 215.816942 -222.294831)
		(end 215.306402 -221.784164)
		(stroke
			(width 0.2)
			(type default)
		)
		(layer "In1.Cu")
	)
	(gr_line
		(start 215.306402 -221.784164)
		(end 214.493602 -221.784164)
		(stroke
			(width 0.2)
			(type default)
		)
		(layer "In1.Cu")
	)
	(gr_arc
		(start 215.661748 -213.080854)
		(mid 215.698945 -213.170657)
		(end 215.788748 -213.207854)
		(stroke
			(width 0.2)
			(type default)
		)
		(layer "In1.Cu")
	)
	(gr_line
		(start 215.661748 -211.760054)
		(end 215.661748 -213.080854)
		(stroke
			(width 0.2)
			(type default)
		)
		(layer "In1.Cu")
	)
	(gr_line
		(start 215.788748 -213.207854)
		(end 216.195148 -213.207854)
		(stroke
			(width 0.2)
			(type default)
		)
		(layer "In1.Cu")
	)
	(gr_arc
		(start 215.788748 -211.633054)
		(mid 215.698945 -211.670251)
		(end 215.661748 -211.760054)
		(stroke
			(width 0.2)
			(type default)
		)
		(layer "In1.Cu")
	)
	(gr_line
		(start 216.093548 -211.406994)
		(end 216.906348 -211.406994)
		(stroke
			(width 0.2)
			(type default)
		)
		(layer "In1.Cu")
	)
	(gr_arc
		(start 216.093802 -210.385914)
		(mid 215.583008 -210.896327)
		(end 216.093548 -211.406994)
		(stroke
			(width 0.2)
			(type default)
		)
		(layer "In1.Cu")
	)
	(gr_line
		(start 216.195148 -213.207854)
		(end 216.195402 -213.2076)
		(stroke
			(width 0.2)
			(type default)
		)
		(layer "In1.Cu")
	)
	(gr_line
		(start 216.195402 -213.2076)
		(end 216.79662 -213.2076)
		(stroke
			(width 0.2)
			(type default)
		)
		(layer "In1.Cu")
	)
	(gr_arc
		(start 216.79662 -213.2076)
		(mid 216.800682 -213.207795)
		(end 216.804748 -213.207854)
		(stroke
			(width 0.2)
			(type default)
		)
		(layer "In1.Cu")
	)
	(gr_line
		(start 216.804748 -213.207854)
		(end 217.211148 -213.207854)
		(stroke
			(width 0.2)
			(type default)
		)
		(layer "In1.Cu")
	)
	(gr_arc
		(start 216.906348 -211.406994)
		(mid 217.416888 -210.896454)
		(end 216.906348 -210.385914)
		(stroke
			(width 0.2)
			(type default)
		)
		(layer "In1.Cu")
	)
	(gr_line
		(start 216.906348 -210.385914)
		(end 216.093802 -210.385914)
		(stroke
			(width 0.2)
			(type default)
		)
		(layer "In1.Cu")
	)
	(gr_arc
		(start 217.211148 -213.207854)
		(mid 217.300951 -213.170657)
		(end 217.338148 -213.080854)
		(stroke
			(width 0.2)
			(type default)
		)
		(layer "In1.Cu")
	)
	(gr_line
		(start 217.211148 -211.633054)
		(end 215.788748 -211.633054)
		(stroke
			(width 0.2)
			(type default)
		)
		(layer "In1.Cu")
	)
	(gr_line
		(start 217.338148 -213.080854)
		(end 217.338148 -211.760054)
		(stroke
			(width 0.2)
			(type default)
		)
		(layer "In1.Cu")
	)
	(gr_arc
		(start 217.338148 -211.760054)
		(mid 217.300951 -211.670251)
		(end 217.211148 -211.633054)
		(stroke
			(width 0.2)
			(type default)
		)
		(layer "In1.Cu")
	)
	(gr_line
		(start 218.499944 -228.000052)
		(end 182.500016 -228.000052)
		(stroke
			(width 5.08)
			(type default)
		)
		(layer "In1.Cu")
	)
	(gr_line
		(start 218.499944 -222.400114)
		(end 218.499944 -228.000052)
		(stroke
			(width 1.524)
			(type default)
		)
		(layer "In1.Cu")
	)
	(gr_arc
		(start 219.00007 -221.899988)
		(mid 218.646428 -222.046472)
		(end 218.499944 -222.400114)
		(stroke
			(width 1.524)
			(type default)
		)
		(layer "In1.Cu")
	)
	(gr_line
		(start 219.799916 -221.899988)
		(end 219.00007 -221.899988)
		(stroke
			(width 1.524)
			(type default)
		)
		(layer "In1.Cu")
	)
	(gr_arc
		(start 219.799916 -221.899988)
		(mid 220.153445 -221.753586)
		(end 220.300042 -221.400116)
		(stroke
			(width 1.524)
			(type default)
		)
		(layer "In1.Cu")
	)
	(gr_line
		(start 220.300042 -214.799926)
		(end 220.300042 -221.400116)
		(stroke
			(width 1.524)
			(type default)
		)
		(layer "In1.Cu")
	)
	(gr_arc
		(start 221.600014 -213.499954)
		(mid 220.680795 -213.880707)
		(end 220.300042 -214.799926)
		(stroke
			(width 1.524)
			(type default)
		)
		(layer "In1.Cu")
	)
	(gr_line
		(start 229.142036 -213.499954)
		(end 221.600014 -213.499954)
		(stroke
			(width 1.524)
			(type default)
		)
		(layer "In1.Cu")
	)
	(gr_arc
		(start 229.142036 -213.499954)
		(mid 232.677527 -212.035476)
		(end 234.142026 -208.499964)
		(stroke
			(width 1.524)
			(type default)
		)
		(layer "In1.Cu")
	)
	(gr_line
		(start 234.142026 -165.269926)
		(end 234.142026 -208.499964)
		(stroke
			(width 1.524)
			(type default)
		)
		(layer "In1.Cu")
	)
	(gr_arc
		(start 235.412026 -163.999926)
		(mid 234.514 -164.3719)
		(end 234.142026 -165.269926)
		(stroke
			(width 1.524)
			(type default)
		)
		(layer "In1.Cu")
	)
	(gr_line
		(start 249.871992 -163.999926)
		(end 235.412026 -163.999926)
		(stroke
			(width 1.524)
			(type default)
		)
		(layer "In1.Cu")
	)
	(gr_line
		(start 251.141992 -208.499964)
		(end 251.141992 -165.269926)
		(stroke
			(width 1.524)
			(type default)
		)
		(layer "In1.Cu")
	)
	(gr_arc
		(start 251.141992 -208.499964)
		(mid 252.606441 -212.03552)
		(end 256.141982 -213.499954)
		(stroke
			(width 1.524)
			(type default)
		)
		(layer "In1.Cu")
	)
	(gr_arc
		(start 251.141992 -165.269926)
		(mid 250.770018 -164.3719)
		(end 249.871992 -163.999926)
		(stroke
			(width 1.524)
			(type default)
		)
		(layer "In1.Cu")
	)
	(gr_line
		(start 257.400044 -213.499954)
		(end 256.141982 -213.499954)
		(stroke
			(width 1.524)
			(type default)
		)
		(layer "In1.Cu")
	)
	(gr_line
		(start 258.700016 -221.400116)
		(end 258.700016 -214.799926)
		(stroke
			(width 1.524)
			(type default)
		)
		(layer "In1.Cu")
	)
	(gr_arc
		(start 258.700016 -221.400116)
		(mid 258.84643 -221.753573)
		(end 259.199888 -221.899988)
		(stroke
			(width 1.524)
			(type default)
		)
		(layer "In1.Cu")
	)
	(gr_arc
		(start 258.700016 -214.799926)
		(mid 258.319263 -213.880707)
		(end 257.400044 -213.499954)
		(stroke
			(width 1.524)
			(type default)
		)
		(layer "In1.Cu")
	)
	(gr_line
		(start 259.999988 -221.899988)
		(end 259.199888 -221.899988)
		(stroke
			(width 1.524)
			(type default)
		)
		(layer "In1.Cu")
	)
	(gr_line
		(start 260.500114 -228.000052)
		(end 260.500114 -222.400114)
		(stroke
			(width 1.524)
			(type default)
		)
		(layer "In1.Cu")
	)
	(gr_arc
		(start 260.500114 -222.400114)
		(mid 260.35363 -222.046472)
		(end 259.999988 -221.899988)
		(stroke
			(width 1.524)
			(type default)
		)
		(layer "In1.Cu")
	)
	(gr_line
		(start 262.893556 -222.805244)
		(end 263.706102 -222.805244)
		(stroke
			(width 0.2)
			(type default)
		)
		(layer "In1.Cu")
	)
	(gr_arc
		(start 262.893556 -221.784164)
		(mid 262.383016 -222.294704)
		(end 262.893556 -222.805244)
		(stroke
			(width 0.2)
			(type default)
		)
		(layer "In1.Cu")
	)
	(gr_arc
		(start 263.706102 -222.805244)
		(mid 264.216896 -222.294831)
		(end 263.706356 -221.784164)
		(stroke
			(width 0.2)
			(type default)
		)
		(layer "In1.Cu")
	)
	(gr_line
		(start 263.706356 -221.784164)
		(end 262.893556 -221.784164)
		(stroke
			(width 0.2)
			(type default)
		)
		(layer "In1.Cu")
	)
	(gr_arc
		(start 264.061956 -213.080854)
		(mid 264.099153 -213.170657)
		(end 264.188956 -213.207854)
		(stroke
			(width 0.2)
			(type default)
		)
		(layer "In1.Cu")
	)
	(gr_line
		(start 264.061956 -211.760054)
		(end 264.061956 -213.080854)
		(stroke
			(width 0.2)
			(type default)
		)
		(layer "In1.Cu")
	)
	(gr_line
		(start 264.188956 -213.207854)
		(end 264.595356 -213.207854)
		(stroke
			(width 0.2)
			(type default)
		)
		(layer "In1.Cu")
	)
	(gr_arc
		(start 264.188956 -211.633054)
		(mid 264.099153 -211.670251)
		(end 264.061956 -211.760054)
		(stroke
			(width 0.2)
			(type default)
		)
		(layer "In1.Cu")
	)
	(gr_line
		(start 264.493756 -211.406994)
		(end 265.306556 -211.406994)
		(stroke
			(width 0.2)
			(type default)
		)
		(layer "In1.Cu")
	)
	(gr_arc
		(start 264.49401 -210.385914)
		(mid 263.983216 -210.896327)
		(end 264.493756 -211.406994)
		(stroke
			(width 0.2)
			(type default)
		)
		(layer "In1.Cu")
	)
	(gr_line
		(start 264.595356 -213.207854)
		(end 264.59561 -213.2076)
		(stroke
			(width 0.2)
			(type default)
		)
		(layer "In1.Cu")
	)
	(gr_line
		(start 264.59561 -213.2076)
		(end 265.196828 -213.2076)
		(stroke
			(width 0.2)
			(type default)
		)
		(layer "In1.Cu")
	)
	(gr_arc
		(start 265.196828 -213.2076)
		(mid 265.20089 -213.207795)
		(end 265.204956 -213.207854)
		(stroke
			(width 0.2)
			(type default)
		)
		(layer "In1.Cu")
	)
	(gr_line
		(start 265.204956 -213.207854)
		(end 265.611356 -213.207854)
		(stroke
			(width 0.2)
			(type default)
		)
		(layer "In1.Cu")
	)
	(gr_arc
		(start 265.306556 -211.406994)
		(mid 265.817096 -210.896454)
		(end 265.306556 -210.385914)
		(stroke
			(width 0.2)
			(type default)
		)
		(layer "In1.Cu")
	)
	(gr_line
		(start 265.306556 -210.385914)
		(end 264.49401 -210.385914)
		(stroke
			(width 0.2)
			(type default)
		)
		(layer "In1.Cu")
	)
	(gr_arc
		(start 265.611356 -213.207854)
		(mid 265.701159 -213.170657)
		(end 265.738356 -213.080854)
		(stroke
			(width 0.2)
			(type default)
		)
		(layer "In1.Cu")
	)
	(gr_line
		(start 265.611356 -211.633054)
		(end 264.188956 -211.633054)
		(stroke
			(width 0.2)
			(type default)
		)
		(layer "In1.Cu")
	)
	(gr_line
		(start 265.738356 -213.080854)
		(end 265.738356 -211.760054)
		(stroke
			(width 0.2)
			(type default)
		)
		(layer "In1.Cu")
	)
	(gr_arc
		(start 265.738356 -211.760054)
		(mid 265.701159 -211.670251)
		(end 265.611356 -211.633054)
		(stroke
			(width 0.2)
			(type default)
		)
		(layer "In1.Cu")
	)
	(gr_line
		(start 266.093702 -222.805244)
		(end 266.906248 -222.805244)
		(stroke
			(width 0.2)
			(type default)
		)
		(layer "In1.Cu")
	)
	(gr_arc
		(start 266.093702 -221.784164)
		(mid 265.583162 -222.294704)
		(end 266.093702 -222.805244)
		(stroke
			(width 0.2)
			(type default)
		)
		(layer "In1.Cu")
	)
	(gr_arc
		(start 266.906248 -222.805244)
		(mid 267.417042 -222.294831)
		(end 266.906502 -221.784164)
		(stroke
			(width 0.2)
			(type default)
		)
		(layer "In1.Cu")
	)
	(gr_line
		(start 266.906502 -221.784164)
		(end 266.093702 -221.784164)
		(stroke
			(width 0.2)
			(type default)
		)
		(layer "In1.Cu")
	)
	(gr_arc
		(start 267.261848 -213.080854)
		(mid 267.299045 -213.170657)
		(end 267.388848 -213.207854)
		(stroke
			(width 0.2)
			(type default)
		)
		(layer "In1.Cu")
	)
	(gr_line
		(start 267.261848 -211.760054)
		(end 267.261848 -213.080854)
		(stroke
			(width 0.2)
			(type default)
		)
		(layer "In1.Cu")
	)
	(gr_line
		(start 267.388848 -213.207854)
		(end 267.795248 -213.207854)
		(stroke
			(width 0.2)
			(type default)
		)
		(layer "In1.Cu")
	)
	(gr_arc
		(start 267.388848 -211.633054)
		(mid 267.299045 -211.670251)
		(end 267.261848 -211.760054)
		(stroke
			(width 0.2)
			(type default)
		)
		(layer "In1.Cu")
	)
	(gr_line
		(start 267.693648 -211.406994)
		(end 268.506448 -211.406994)
		(stroke
			(width 0.2)
			(type default)
		)
		(layer "In1.Cu")
	)
	(gr_arc
		(start 267.693902 -210.385914)
		(mid 267.183108 -210.896327)
		(end 267.693648 -211.406994)
		(stroke
			(width 0.2)
			(type default)
		)
		(layer "In1.Cu")
	)
	(gr_line
		(start 267.795248 -213.207854)
		(end 267.795502 -213.2076)
		(stroke
			(width 0.2)
			(type default)
		)
		(layer "In1.Cu")
	)
	(gr_line
		(start 267.795502 -213.2076)
		(end 268.39672 -213.2076)
		(stroke
			(width 0.2)
			(type default)
		)
		(layer "In1.Cu")
	)
	(gr_arc
		(start 267.96746 -14.6558)
		(mid 268.478 -15.16634)
		(end 268.98854 -14.6558)
		(stroke
			(width 0.2)
			(type default)
		)
		(layer "In1.Cu")
	)
	(gr_line
		(start 267.96746 -13.843)
		(end 267.96746 -14.6558)
		(stroke
			(width 0.2)
			(type default)
		)
		(layer "In1.Cu")
	)
	(gr_arc
		(start 268.39672 -213.2076)
		(mid 268.400782 -213.207795)
		(end 268.404848 -213.207854)
		(stroke
			(width 0.2)
			(type default)
		)
		(layer "In1.Cu")
	)
	(gr_line
		(start 268.404848 -213.207854)
		(end 268.811248 -213.207854)
		(stroke
			(width 0.2)
			(type default)
		)
		(layer "In1.Cu")
	)
	(gr_arc
		(start 268.506448 -211.406994)
		(mid 269.016988 -210.896454)
		(end 268.506448 -210.385914)
		(stroke
			(width 0.2)
			(type default)
		)
		(layer "In1.Cu")
	)
	(gr_line
		(start 268.506448 -210.385914)
		(end 267.693902 -210.385914)
		(stroke
			(width 0.2)
			(type default)
		)
		(layer "In1.Cu")
	)
	(gr_arc
		(start 268.811248 -213.207854)
		(mid 268.901051 -213.170657)
		(end 268.938248 -213.080854)
		(stroke
			(width 0.2)
			(type default)
		)
		(layer "In1.Cu")
	)
	(gr_line
		(start 268.811248 -211.633054)
		(end 267.388848 -211.633054)
		(stroke
			(width 0.2)
			(type default)
		)
		(layer "In1.Cu")
	)
	(gr_line
		(start 268.938248 -213.080854)
		(end 268.938248 -211.760054)
		(stroke
			(width 0.2)
			(type default)
		)
		(layer "In1.Cu")
	)
	(gr_arc
		(start 268.938248 -211.760054)
		(mid 268.901051 -211.670251)
		(end 268.811248 -211.633054)
		(stroke
			(width 0.2)
			(type default)
		)
		(layer "In1.Cu")
	)
	(gr_line
		(start 268.98854 -14.6558)
		(end 268.98854 -13.843254)
		(stroke
			(width 0.2)
			(type default)
		)
		(layer "In1.Cu")
	)
	(gr_arc
		(start 268.98854 -13.843254)
		(mid 268.478127 -13.33246)
		(end 267.96746 -13.843)
		(stroke
			(width 0.2)
			(type default)
		)
		(layer "In1.Cu")
	)
	(gr_arc
		(start 269.03426 -6.118352)
		(mid 269.5448 -6.628892)
		(end 270.05534 -6.118352)
		(stroke
			(width 0.2)
			(type default)
		)
		(layer "In1.Cu")
	)
	(gr_line
		(start 269.03426 -5.305552)
		(end 269.03426 -6.118352)
		(stroke
			(width 0.2)
			(type default)
		)
		(layer "In1.Cu")
	)
	(gr_line
		(start 270.05534 -6.118352)
		(end 270.05534 -5.305806)
		(stroke
			(width 0.2)
			(type default)
		)
		(layer "In1.Cu")
	)
	(gr_arc
		(start 270.05534 -5.305806)
		(mid 269.544927 -4.795012)
		(end 269.03426 -5.305552)
		(stroke
			(width 0.2)
			(type default)
		)
		(layer "In1.Cu")
	)
	(gr_arc
		(start 270.17726 -9.166352)
		(mid 270.6878 -9.676892)
		(end 271.19834 -9.166352)
		(stroke
			(width 0.2)
			(type default)
		)
		(layer "In1.Cu")
	)
	(gr_line
		(start 270.17726 -8.353552)
		(end 270.17726 -9.166352)
		(stroke
			(width 0.2)
			(type default)
		)
		(layer "In1.Cu")
	)
	(gr_arc
		(start 270.461994 -213.080854)
		(mid 270.499191 -213.170657)
		(end 270.588994 -213.207854)
		(stroke
			(width 0.2)
			(type default)
		)
		(layer "In1.Cu")
	)
	(gr_line
		(start 270.461994 -211.760054)
		(end 270.461994 -213.080854)
		(stroke
			(width 0.2)
			(type default)
		)
		(layer "In1.Cu")
	)
	(gr_line
		(start 270.588994 -213.207854)
		(end 270.995394 -213.207854)
		(stroke
			(width 0.2)
			(type default)
		)
		(layer "In1.Cu")
	)
	(gr_arc
		(start 270.588994 -211.633054)
		(mid 270.499191 -211.670251)
		(end 270.461994 -211.760054)
		(stroke
			(width 0.2)
			(type default)
		)
		(layer "In1.Cu")
	)
	(gr_line
		(start 270.893794 -211.406994)
		(end 271.706594 -211.406994)
		(stroke
			(width 0.2)
			(type default)
		)
		(layer "In1.Cu")
	)
	(gr_arc
		(start 270.894048 -210.385914)
		(mid 270.383254 -210.896327)
		(end 270.893794 -211.406994)
		(stroke
			(width 0.2)
			(type default)
		)
		(layer "In1.Cu")
	)
	(gr_line
		(start 270.995394 -213.207854)
		(end 270.995648 -213.2076)
		(stroke
			(width 0.2)
			(type default)
		)
		(layer "In1.Cu")
	)
	(gr_line
		(start 270.995648 -213.2076)
		(end 271.596866 -213.2076)
		(stroke
			(width 0.2)
			(type default)
		)
		(layer "In1.Cu")
	)
	(gr_line
		(start 271.19834 -9.166352)
		(end 271.19834 -8.353806)
		(stroke
			(width 0.2)
			(type default)
		)
		(layer "In1.Cu")
	)
	(gr_arc
		(start 271.19834 -8.353806)
		(mid 270.687927 -7.843012)
		(end 270.17726 -8.353552)
		(stroke
			(width 0.2)
			(type default)
		)
		(layer "In1.Cu")
	)
	(gr_arc
		(start 271.55775 -15.334996)
		(mid 272.068163 -15.84579)
		(end 272.57883 -15.33525)
		(stroke
			(width 0.2)
			(type default)
		)
		(layer "In1.Cu")
	)
	(gr_line
		(start 271.55775 -14.52245)
		(end 271.55775 -15.334996)
		(stroke
			(width 0.2)
			(type default)
		)
		(layer "In1.Cu")
	)
	(gr_arc
		(start 271.596866 -213.2076)
		(mid 271.600928 -213.207795)
		(end 271.604994 -213.207854)
		(stroke
			(width 0.2)
			(type default)
		)
		(layer "In1.Cu")
	)
	(gr_line
		(start 271.604994 -213.207854)
		(end 272.011394 -213.207854)
		(stroke
			(width 0.2)
			(type default)
		)
		(layer "In1.Cu")
	)
	(gr_arc
		(start 271.706594 -211.406994)
		(mid 272.217134 -210.896454)
		(end 271.706594 -210.385914)
		(stroke
			(width 0.2)
			(type default)
		)
		(layer "In1.Cu")
	)
	(gr_line
		(start 271.706594 -210.385914)
		(end 270.894048 -210.385914)
		(stroke
			(width 0.2)
			(type default)
		)
		(layer "In1.Cu")
	)
	(gr_arc
		(start 272.011394 -213.207854)
		(mid 272.101197 -213.170657)
		(end 272.138394 -213.080854)
		(stroke
			(width 0.2)
			(type default)
		)
		(layer "In1.Cu")
	)
	(gr_line
		(start 272.011394 -211.633054)
		(end 270.588994 -211.633054)
		(stroke
			(width 0.2)
			(type default)
		)
		(layer "In1.Cu")
	)
	(gr_line
		(start 272.138394 -213.080854)
		(end 272.138394 -211.760054)
		(stroke
			(width 0.2)
			(type default)
		)
		(layer "In1.Cu")
	)
	(gr_arc
		(start 272.138394 -211.760054)
		(mid 272.101197 -211.670251)
		(end 272.011394 -211.633054)
		(stroke
			(width 0.2)
			(type default)
		)
		(layer "In1.Cu")
	)
	(gr_line
		(start 272.49374 -222.805244)
		(end 273.306286 -222.805244)
		(stroke
			(width 0.2)
			(type default)
		)
		(layer "In1.Cu")
	)
	(gr_arc
		(start 272.49374 -221.784164)
		(mid 271.9832 -222.294704)
		(end 272.49374 -222.805244)
		(stroke
			(width 0.2)
			(type default)
		)
		(layer "In1.Cu")
	)
	(gr_line
		(start 272.57883 -15.33525)
		(end 272.57883 -14.52245)
		(stroke
			(width 0.2)
			(type default)
		)
		(layer "In1.Cu")
	)
	(gr_arc
		(start 272.57883 -14.52245)
		(mid 272.06829 -14.01191)
		(end 271.55775 -14.52245)
		(stroke
			(width 0.2)
			(type default)
		)
		(layer "In1.Cu")
	)
	(gr_arc
		(start 273.1516 -15.5702)
		(mid 273.188797 -15.660003)
		(end 273.2786 -15.6972)
		(stroke
			(width 0.2)
			(type default)
		)
		(layer "In1.Cu")
	)
	(gr_line
		(start 273.1516 -14.2748)
		(end 273.1516 -15.5702)
		(stroke
			(width 0.2)
			(type default)
		)
		(layer "In1.Cu")
	)
	(gr_arc
		(start 273.1516 -13.7922)
		(mid 273.188797 -13.882003)
		(end 273.2786 -13.9192)
		(stroke
			(width 0.2)
			(type default)
		)
		(layer "In1.Cu")
	)
	(gr_line
		(start 273.1516 -12.4968)
		(end 273.1516 -13.7922)
		(stroke
			(width 0.2)
			(type default)
		)
		(layer "In1.Cu")
	)
	(gr_line
		(start 273.2786 -15.6972)
		(end 274.5994 -15.6972)
		(stroke
			(width 0.2)
			(type default)
		)
		(layer "In1.Cu")
	)
	(gr_arc
		(start 273.2786 -14.1478)
		(mid 273.188797 -14.184997)
		(end 273.1516 -14.2748)
		(stroke
			(width 0.2)
			(type default)
		)
		(layer "In1.Cu")
	)
	(gr_line
		(start 273.2786 -13.9192)
		(end 274.5994 -13.9192)
		(stroke
			(width 0.2)
			(type default)
		)
		(layer "In1.Cu")
	)
	(gr_arc
		(start 273.2786 -12.3698)
		(mid 273.188797 -12.406997)
		(end 273.1516 -12.4968)
		(stroke
			(width 0.2)
			(type default)
		)
		(layer "In1.Cu")
	)
	(gr_arc
		(start 273.306286 -222.805244)
		(mid 273.81708 -222.294831)
		(end 273.30654 -221.784164)
		(stroke
			(width 0.2)
			(type default)
		)
		(layer "In1.Cu")
	)
	(gr_line
		(start 273.30654 -221.784164)
		(end 272.49374 -221.784164)
		(stroke
			(width 0.2)
			(type default)
		)
		(layer "In1.Cu")
	)
	(gr_arc
		(start 273.661886 -213.080854)
		(mid 273.699083 -213.170657)
		(end 273.788886 -213.207854)
		(stroke
			(width 0.2)
			(type default)
		)
		(layer "In1.Cu")
	)
	(gr_line
		(start 273.661886 -211.760054)
		(end 273.661886 -213.080854)
		(stroke
			(width 0.2)
			(type default)
		)
		(layer "In1.Cu")
	)
	(gr_line
		(start 273.788886 -213.207854)
		(end 274.195286 -213.207854)
		(stroke
			(width 0.2)
			(type default)
		)
		(layer "In1.Cu")
	)
	(gr_arc
		(start 273.788886 -211.633054)
		(mid 273.699083 -211.670251)
		(end 273.661886 -211.760054)
		(stroke
			(width 0.2)
			(type default)
		)
		(layer "In1.Cu")
	)
	(gr_line
		(start 274.093686 -211.406994)
		(end 274.906486 -211.406994)
		(stroke
			(width 0.2)
			(type default)
		)
		(layer "In1.Cu")
	)
	(gr_arc
		(start 274.09394 -210.385914)
		(mid 273.583146 -210.896327)
		(end 274.093686 -211.406994)
		(stroke
			(width 0.2)
			(type default)
		)
		(layer "In1.Cu")
	)
	(gr_line
		(start 274.195286 -213.207854)
		(end 274.19554 -213.2076)
		(stroke
			(width 0.2)
			(type default)
		)
		(layer "In1.Cu")
	)
	(gr_line
		(start 274.19554 -213.2076)
		(end 274.796758 -213.2076)
		(stroke
			(width 0.2)
			(type default)
		)
		(layer "In1.Cu")
	)
	(gr_arc
		(start 274.5994 -15.6972)
		(mid 274.689203 -15.660003)
		(end 274.7264 -15.5702)
		(stroke
			(width 0.2)
			(type default)
		)
		(layer "In1.Cu")
	)
	(gr_line
		(start 274.5994 -14.1478)
		(end 273.2786 -14.1478)
		(stroke
			(width 0.2)
			(type default)
		)
		(layer "In1.Cu")
	)
	(gr_arc
		(start 274.5994 -13.9192)
		(mid 274.689203 -13.882003)
		(end 274.7264 -13.7922)
		(stroke
			(width 0.2)
			(type default)
		)
		(layer "In1.Cu")
	)
	(gr_line
		(start 274.5994 -12.3698)
		(end 273.2786 -12.3698)
		(stroke
			(width 0.2)
			(type default)
		)
		(layer "In1.Cu")
	)
	(gr_line
		(start 274.7264 -15.5702)
		(end 274.7264 -14.2748)
		(stroke
			(width 0.2)
			(type default)
		)
		(layer "In1.Cu")
	)
	(gr_arc
		(start 274.7264 -14.2748)
		(mid 274.689203 -14.184997)
		(end 274.5994 -14.1478)
		(stroke
			(width 0.2)
			(type default)
		)
		(layer "In1.Cu")
	)
	(gr_line
		(start 274.7264 -13.7922)
		(end 274.7264 -12.4968)
		(stroke
			(width 0.2)
			(type default)
		)
		(layer "In1.Cu")
	)
	(gr_arc
		(start 274.7264 -12.4968)
		(mid 274.689203 -12.406997)
		(end 274.5994 -12.3698)
		(stroke
			(width 0.2)
			(type default)
		)
		(layer "In1.Cu")
	)
	(gr_arc
		(start 274.796758 -213.2076)
		(mid 274.80082 -213.207795)
		(end 274.804886 -213.207854)
		(stroke
			(width 0.2)
			(type default)
		)
		(layer "In1.Cu")
	)
	(gr_line
		(start 274.804886 -213.207854)
		(end 275.211286 -213.207854)
		(stroke
			(width 0.2)
			(type default)
		)
		(layer "In1.Cu")
	)
	(gr_arc
		(start 274.906486 -211.406994)
		(mid 275.417026 -210.896454)
		(end 274.906486 -210.385914)
		(stroke
			(width 0.2)
			(type default)
		)
		(layer "In1.Cu")
	)
	(gr_line
		(start 274.906486 -210.385914)
		(end 274.09394 -210.385914)
		(stroke
			(width 0.2)
			(type default)
		)
		(layer "In1.Cu")
	)
	(gr_arc
		(start 275.211286 -213.207854)
		(mid 275.301089 -213.170657)
		(end 275.338286 -213.080854)
		(stroke
			(width 0.2)
			(type default)
		)
		(layer "In1.Cu")
	)
	(gr_line
		(start 275.211286 -211.633054)
		(end 273.788886 -211.633054)
		(stroke
			(width 0.2)
			(type default)
		)
		(layer "In1.Cu")
	)
	(gr_line
		(start 275.338286 -213.080854)
		(end 275.338286 -211.760054)
		(stroke
			(width 0.2)
			(type default)
		)
		(layer "In1.Cu")
	)
	(gr_arc
		(start 275.338286 -211.760054)
		(mid 275.301089 -211.670251)
		(end 275.211286 -211.633054)
		(stroke
			(width 0.2)
			(type default)
		)
		(layer "In1.Cu")
	)
	(gr_line
		(start 275.693632 -222.805244)
		(end 276.506178 -222.805244)
		(stroke
			(width 0.2)
			(type default)
		)
		(layer "In1.Cu")
	)
	(gr_arc
		(start 275.693632 -221.784164)
		(mid 275.183092 -222.294704)
		(end 275.693632 -222.805244)
		(stroke
			(width 0.2)
			(type default)
		)
		(layer "In1.Cu")
	)
	(gr_arc
		(start 276.506178 -222.805244)
		(mid 277.016972 -222.294831)
		(end 276.506432 -221.784164)
		(stroke
			(width 0.2)
			(type default)
		)
		(layer "In1.Cu")
	)
	(gr_line
		(start 276.506432 -221.784164)
		(end 275.693632 -221.784164)
		(stroke
			(width 0.2)
			(type default)
		)
		(layer "In1.Cu")
	)
	(gr_arc
		(start 276.861778 -213.080854)
		(mid 276.898975 -213.170657)
		(end 276.988778 -213.207854)
		(stroke
			(width 0.2)
			(type default)
		)
		(layer "In1.Cu")
	)
	(gr_line
		(start 276.861778 -211.760054)
		(end 276.861778 -213.080854)
		(stroke
			(width 0.2)
			(type default)
		)
		(layer "In1.Cu")
	)
	(gr_line
		(start 276.988778 -213.207854)
		(end 277.395178 -213.207854)
		(stroke
			(width 0.2)
			(type default)
		)
		(layer "In1.Cu")
	)
	(gr_arc
		(start 276.988778 -211.633054)
		(mid 276.898975 -211.670251)
		(end 276.861778 -211.760054)
		(stroke
			(width 0.2)
			(type default)
		)
		(layer "In1.Cu")
	)
	(gr_line
		(start 277.293578 -211.406994)
		(end 278.106378 -211.406994)
		(stroke
			(width 0.2)
			(type default)
		)
		(layer "In1.Cu")
	)
	(gr_arc
		(start 277.293832 -210.385914)
		(mid 276.783038 -210.896327)
		(end 277.293578 -211.406994)
		(stroke
			(width 0.2)
			(type default)
		)
		(layer "In1.Cu")
	)
	(gr_line
		(start 277.395178 -213.207854)
		(end 277.395432 -213.2076)
		(stroke
			(width 0.2)
			(type default)
		)
		(layer "In1.Cu")
	)
	(gr_line
		(start 277.395432 -213.2076)
		(end 277.99665 -213.2076)
		(stroke
			(width 0.2)
			(type default)
		)
		(layer "In1.Cu")
	)
	(gr_arc
		(start 277.99665 -213.2076)
		(mid 278.000712 -213.207795)
		(end 278.004778 -213.207854)
		(stroke
			(width 0.2)
			(type default)
		)
		(layer "In1.Cu")
	)
	(gr_line
		(start 278.004778 -213.207854)
		(end 278.411178 -213.207854)
		(stroke
			(width 0.2)
			(type default)
		)
		(layer "In1.Cu")
	)
	(gr_arc
		(start 278.106378 -211.406994)
		(mid 278.616918 -210.896454)
		(end 278.106378 -210.385914)
		(stroke
			(width 0.2)
			(type default)
		)
		(layer "In1.Cu")
	)
	(gr_line
		(start 278.106378 -210.385914)
		(end 277.293832 -210.385914)
		(stroke
			(width 0.2)
			(type default)
		)
		(layer "In1.Cu")
	)
	(gr_arc
		(start 278.411178 -213.207854)
		(mid 278.500981 -213.170657)
		(end 278.538178 -213.080854)
		(stroke
			(width 0.2)
			(type default)
		)
		(layer "In1.Cu")
	)
	(gr_line
		(start 278.411178 -211.633054)
		(end 276.988778 -211.633054)
		(stroke
			(width 0.2)
			(type default)
		)
		(layer "In1.Cu")
	)
	(gr_line
		(start 278.538178 -213.080854)
		(end 278.538178 -211.760054)
		(stroke
			(width 0.2)
			(type default)
		)
		(layer "In1.Cu")
	)
	(gr_arc
		(start 278.538178 -211.760054)
		(mid 278.500981 -211.670251)
		(end 278.411178 -211.633054)
		(stroke
			(width 0.2)
			(type default)
		)
		(layer "In1.Cu")
	)
	(gr_line
		(start 278.893778 -222.805244)
		(end 279.706324 -222.805244)
		(stroke
			(width 0.2)
			(type default)
		)
		(layer "In1.Cu")
	)
	(gr_arc
		(start 278.893778 -221.784164)
		(mid 278.383238 -222.294704)
		(end 278.893778 -222.805244)
		(stroke
			(width 0.2)
			(type default)
		)
		(layer "In1.Cu")
	)
	(gr_arc
		(start 279.706324 -222.805244)
		(mid 280.217118 -222.294831)
		(end 279.706578 -221.784164)
		(stroke
			(width 0.2)
			(type default)
		)
		(layer "In1.Cu")
	)
	(gr_line
		(start 279.706578 -221.784164)
		(end 278.893778 -221.784164)
		(stroke
			(width 0.2)
			(type default)
		)
		(layer "In1.Cu")
	)
	(gr_arc
		(start 279.72766 -18.762726)
		(mid 280.230326 -19.28114)
		(end 280.74874 -18.778474)
		(stroke
			(width 0.2)
			(type default)
		)
		(layer "In1.Cu")
	)
	(gr_line
		(start 279.740106 -17.949926)
		(end 279.72766 -18.762726)
		(stroke
			(width 0.2)
			(type default)
		)
		(layer "In1.Cu")
	)
	(gr_arc
		(start 280.061924 -213.080854)
		(mid 280.099121 -213.170657)
		(end 280.188924 -213.207854)
		(stroke
			(width 0.2)
			(type default)
		)
		(layer "In1.Cu")
	)
	(gr_line
		(start 280.061924 -211.760054)
		(end 280.061924 -213.080854)
		(stroke
			(width 0.2)
			(type default)
		)
		(layer "In1.Cu")
	)
	(gr_line
		(start 280.188924 -213.207854)
		(end 280.595324 -213.207854)
		(stroke
			(width 0.2)
			(type default)
		)
		(layer "In1.Cu")
	)
	(gr_arc
		(start 280.188924 -211.633054)
		(mid 280.099121 -211.670251)
		(end 280.061924 -211.760054)
		(stroke
			(width 0.2)
			(type default)
		)
		(layer "In1.Cu")
	)
	(gr_line
		(start 280.493724 -211.406994)
		(end 281.306524 -211.406994)
		(stroke
			(width 0.2)
			(type default)
		)
		(layer "In1.Cu")
	)
	(gr_arc
		(start 280.493978 -210.385914)
		(mid 279.983184 -210.896327)
		(end 280.493724 -211.406994)
		(stroke
			(width 0.2)
			(type default)
		)
		(layer "In1.Cu")
	)
	(gr_line
		(start 280.595324 -213.207854)
		(end 280.595578 -213.2076)
		(stroke
			(width 0.2)
			(type default)
		)
		(layer "In1.Cu")
	)
	(gr_line
		(start 280.595578 -213.2076)
		(end 281.196796 -213.2076)
		(stroke
			(width 0.2)
			(type default)
		)
		(layer "In1.Cu")
	)
	(gr_line
		(start 280.74874 -18.778474)
		(end 280.761186 -17.965928)
		(stroke
			(width 0.2)
			(type default)
		)
		(layer "In1.Cu")
	)
	(gr_arc
		(start 280.761186 -17.965928)
		(mid 280.258647 -17.447516)
		(end 279.740106 -17.949926)
		(stroke
			(width 0.2)
			(type default)
		)
		(layer "In1.Cu")
	)
	(gr_arc
		(start 281.196796 -213.2076)
		(mid 281.200858 -213.207795)
		(end 281.204924 -213.207854)
		(stroke
			(width 0.2)
			(type default)
		)
		(layer "In1.Cu")
	)
	(gr_line
		(start 281.204924 -213.207854)
		(end 281.611324 -213.207854)
		(stroke
			(width 0.2)
			(type default)
		)
		(layer "In1.Cu")
	)
	(gr_arc
		(start 281.306524 -211.406994)
		(mid 281.817064 -210.896454)
		(end 281.306524 -210.385914)
		(stroke
			(width 0.2)
			(type default)
		)
		(layer "In1.Cu")
	)
	(gr_line
		(start 281.306524 -210.385914)
		(end 280.493978 -210.385914)
		(stroke
			(width 0.2)
			(type default)
		)
		(layer "In1.Cu")
	)
	(gr_arc
		(start 281.611324 -213.207854)
		(mid 281.701127 -213.170657)
		(end 281.738324 -213.080854)
		(stroke
			(width 0.2)
			(type default)
		)
		(layer "In1.Cu")
	)
	(gr_line
		(start 281.611324 -211.633054)
		(end 280.188924 -211.633054)
		(stroke
			(width 0.2)
			(type default)
		)
		(layer "In1.Cu")
	)
	(gr_line
		(start 281.738324 -213.080854)
		(end 281.738324 -211.760054)
		(stroke
			(width 0.2)
			(type default)
		)
		(layer "In1.Cu")
	)
	(gr_arc
		(start 281.738324 -211.760054)
		(mid 281.701127 -211.670251)
		(end 281.611324 -211.633054)
		(stroke
			(width 0.2)
			(type default)
		)
		(layer "In1.Cu")
	)
	(gr_line
		(start 282.09367 -222.805244)
		(end 282.906216 -222.805244)
		(stroke
			(width 0.2)
			(type default)
		)
		(layer "In1.Cu")
	)
	(gr_arc
		(start 282.09367 -221.784164)
		(mid 281.58313 -222.294704)
		(end 282.09367 -222.805244)
		(stroke
			(width 0.2)
			(type default)
		)
		(layer "In1.Cu")
	)
	(gr_line
		(start 282.244546 -20.841208)
		(end 282.788614 -21.44522)
		(stroke
			(width 0.2)
			(type default)
		)
		(layer "In1.Cu")
	)
	(gr_line
		(start 282.246578 -20.83943)
		(end 282.244546 -20.841208)
		(stroke
			(width 0.2)
			(type default)
		)
		(layer "In1.Cu")
	)
	(gr_line
		(start 282.788614 -21.44522)
		(end 282.790646 -21.443442)
		(stroke
			(width 0.2)
			(type default)
		)
		(layer "In1.Cu")
	)
	(gr_arc
		(start 282.790646 -21.443442)
		(mid 283.511498 -21.481034)
		(end 283.54909 -20.760182)
		(stroke
			(width 0.2)
			(type default)
		)
		(layer "In1.Cu")
	)
	(gr_arc
		(start 282.906216 -222.805244)
		(mid 283.41701 -222.294831)
		(end 282.90647 -221.784164)
		(stroke
			(width 0.2)
			(type default)
		)
		(layer "In1.Cu")
	)
	(gr_line
		(start 282.90647 -221.784164)
		(end 282.09367 -221.784164)
		(stroke
			(width 0.2)
			(type default)
		)
		(layer "In1.Cu")
	)
	(gr_arc
		(start 283.005276 -20.15617)
		(mid 282.284107 -20.118381)
		(end 282.246578 -20.83943)
		(stroke
			(width 0.2)
			(type default)
		)
		(layer "In1.Cu")
	)
	(gr_line
		(start 283.0068 -20.154646)
		(end 283.005276 -20.15617)
		(stroke
			(width 0.2)
			(type default)
		)
		(layer "In1.Cu")
	)
	(gr_line
		(start 283.007308 -20.154646)
		(end 283.0068 -20.154646)
		(stroke
			(width 0.2)
			(type default)
		)
		(layer "In1.Cu")
	)
	(gr_arc
		(start 283.261816 -213.080854)
		(mid 283.299013 -213.170657)
		(end 283.388816 -213.207854)
		(stroke
			(width 0.2)
			(type default)
		)
		(layer "In1.Cu")
	)
	(gr_line
		(start 283.261816 -211.760054)
		(end 283.261816 -213.080854)
		(stroke
			(width 0.2)
			(type default)
		)
		(layer "In1.Cu")
	)
	(gr_line
		(start 283.388816 -213.207854)
		(end 283.795216 -213.207854)
		(stroke
			(width 0.2)
			(type default)
		)
		(layer "In1.Cu")
	)
	(gr_arc
		(start 283.388816 -211.633054)
		(mid 283.299013 -211.670251)
		(end 283.261816 -211.760054)
		(stroke
			(width 0.2)
			(type default)
		)
		(layer "In1.Cu")
	)
	(gr_line
		(start 283.54909 -20.760182)
		(end 283.551122 -20.758404)
		(stroke
			(width 0.2)
			(type default)
		)
		(layer "In1.Cu")
	)
	(gr_line
		(start 283.551122 -20.758404)
		(end 283.007308 -20.154646)
		(stroke
			(width 0.2)
			(type default)
		)
		(layer "In1.Cu")
	)
	(gr_line
		(start 283.693616 -211.406994)
		(end 284.506416 -211.406994)
		(stroke
			(width 0.2)
			(type default)
		)
		(layer "In1.Cu")
	)
	(gr_arc
		(start 283.69387 -210.385914)
		(mid 283.183076 -210.896327)
		(end 283.693616 -211.406994)
		(stroke
			(width 0.2)
			(type default)
		)
		(layer "In1.Cu")
	)
	(gr_line
		(start 283.795216 -213.207854)
		(end 283.79547 -213.2076)
		(stroke
			(width 0.2)
			(type default)
		)
		(layer "In1.Cu")
	)
	(gr_line
		(start 283.79547 -213.2076)
		(end 284.396688 -213.2076)
		(stroke
			(width 0.2)
			(type default)
		)
		(layer "In1.Cu")
	)
	(gr_arc
		(start 284.396688 -213.2076)
		(mid 284.40075 -213.207795)
		(end 284.404816 -213.207854)
		(stroke
			(width 0.2)
			(type default)
		)
		(layer "In1.Cu")
	)
	(gr_line
		(start 284.404816 -213.207854)
		(end 284.811216 -213.207854)
		(stroke
			(width 0.2)
			(type default)
		)
		(layer "In1.Cu")
	)
	(gr_arc
		(start 284.477714 -33.864042)
		(mid 284.988127 -34.374836)
		(end 285.498794 -33.864296)
		(stroke
			(width 0.2)
			(type default)
		)
		(layer "In1.Cu")
	)
	(gr_line
		(start 284.477714 -33.051496)
		(end 284.477714 -33.864042)
		(stroke
			(width 0.2)
			(type default)
		)
		(layer "In1.Cu")
	)
	(gr_arc
		(start 284.506416 -211.406994)
		(mid 285.016956 -210.896454)
		(end 284.506416 -210.385914)
		(stroke
			(width 0.2)
			(type default)
		)
		(layer "In1.Cu")
	)
	(gr_line
		(start 284.506416 -210.385914)
		(end 283.69387 -210.385914)
		(stroke
			(width 0.2)
			(type default)
		)
		(layer "In1.Cu")
	)
	(gr_arc
		(start 284.811216 -213.207854)
		(mid 284.901019 -213.170657)
		(end 284.938216 -213.080854)
		(stroke
			(width 0.2)
			(type default)
		)
		(layer "In1.Cu")
	)
	(gr_line
		(start 284.811216 -211.633054)
		(end 283.388816 -211.633054)
		(stroke
			(width 0.2)
			(type default)
		)
		(layer "In1.Cu")
	)
	(gr_line
		(start 284.938216 -213.080854)
		(end 284.938216 -211.760054)
		(stroke
			(width 0.2)
			(type default)
		)
		(layer "In1.Cu")
	)
	(gr_arc
		(start 284.938216 -211.760054)
		(mid 284.901019 -211.670251)
		(end 284.811216 -211.633054)
		(stroke
			(width 0.2)
			(type default)
		)
		(layer "In1.Cu")
	)
	(gr_line
		(start 285.293562 -222.805244)
		(end 286.106108 -222.805244)
		(stroke
			(width 0.2)
			(type default)
		)
		(layer "In1.Cu")
	)
	(gr_arc
		(start 285.293562 -221.784164)
		(mid 284.783022 -222.294704)
		(end 285.293562 -222.805244)
		(stroke
			(width 0.2)
			(type default)
		)
		(layer "In1.Cu")
	)
	(gr_line
		(start 285.498794 -33.864296)
		(end 285.498794 -33.051496)
		(stroke
			(width 0.2)
			(type default)
		)
		(layer "In1.Cu")
	)
	(gr_arc
		(start 285.498794 -33.051496)
		(mid 284.988254 -32.540956)
		(end 284.477714 -33.051496)
		(stroke
			(width 0.2)
			(type default)
		)
		(layer "In1.Cu")
	)
	(gr_line
		(start 285.581344 -25.033732)
		(end 285.581598 -25.033986)
		(stroke
			(width 0.2)
			(type default)
		)
		(layer "In1.Cu")
	)
	(gr_line
		(start 285.581344 -13.633958)
		(end 285.583376 -13.635228)
		(stroke
			(width 0.2)
			(type default)
		)
		(layer "In1.Cu")
	)
	(gr_line
		(start 285.581598 -25.033986)
		(end 285.58363 -25.035002)
		(stroke
			(width 0.2)
			(type default)
		)
		(layer "In1.Cu")
	)
	(gr_arc
		(start 285.583376 -13.635228)
		(mid 285.839408 -14.481048)
		(end 286.685228 -14.225016)
		(stroke
			(width 0.2)
			(type default)
		)
		(layer "In1.Cu")
	)
	(gr_arc
		(start 285.58363 -25.035002)
		(mid 285.839306 -25.880903)
		(end 286.685228 -25.625044)
		(stroke
			(width 0.2)
			(type default)
		)
		(layer "In1.Cu")
	)
	(gr_arc
		(start 285.6992 -34.0614)
		(mid 285.736397 -34.151203)
		(end 285.8262 -34.1884)
		(stroke
			(width 0.2)
			(type default)
		)
		(layer "In1.Cu")
	)
	(gr_line
		(start 285.6992 -32.766)
		(end 285.6992 -34.0614)
		(stroke
			(width 0.2)
			(type default)
		)
		(layer "In1.Cu")
	)
	(gr_line
		(start 285.8262 -34.1884)
		(end 287.147 -34.1884)
		(stroke
			(width 0.2)
			(type default)
		)
		(layer "In1.Cu")
	)
	(gr_arc
		(start 285.8262 -32.639)
		(mid 285.736397 -32.676197)
		(end 285.6992 -32.766)
		(stroke
			(width 0.2)
			(type default)
		)
		(layer "In1.Cu")
	)
	(gr_arc
		(start 286.106108 -222.805244)
		(mid 286.616902 -222.294831)
		(end 286.106362 -221.784164)
		(stroke
			(width 0.2)
			(type default)
		)
		(layer "In1.Cu")
	)
	(gr_line
		(start 286.106362 -221.784164)
		(end 285.293562 -221.784164)
		(stroke
			(width 0.2)
			(type default)
		)
		(layer "In1.Cu")
	)
	(gr_line
		(start 286.331406 -23.633938)
		(end 285.581344 -25.033732)
		(stroke
			(width 0.2)
			(type default)
		)
		(layer "In1.Cu")
	)
	(gr_line
		(start 286.331406 -12.23391)
		(end 285.581344 -13.633958)
		(stroke
			(width 0.2)
			(type default)
		)
		(layer "In1.Cu")
	)
	(gr_line
		(start 286.333438 -23.635208)
		(end 286.331406 -23.633938)
		(stroke
			(width 0.2)
			(type default)
		)
		(layer "In1.Cu")
	)
	(gr_line
		(start 286.333438 -12.23518)
		(end 286.331406 -12.23391)
		(stroke
			(width 0.2)
			(type default)
		)
		(layer "In1.Cu")
	)
	(gr_arc
		(start 286.461962 -213.080854)
		(mid 286.499159 -213.170657)
		(end 286.588962 -213.207854)
		(stroke
			(width 0.2)
			(type default)
		)
		(layer "In1.Cu")
	)
	(gr_line
		(start 286.461962 -211.760054)
		(end 286.461962 -213.080854)
		(stroke
			(width 0.2)
			(type default)
		)
		(layer "In1.Cu")
	)
	(gr_line
		(start 286.588962 -213.207854)
		(end 286.995362 -213.207854)
		(stroke
			(width 0.2)
			(type default)
		)
		(layer "In1.Cu")
	)
	(gr_arc
		(start 286.588962 -211.633054)
		(mid 286.499159 -211.670251)
		(end 286.461962 -211.760054)
		(stroke
			(width 0.2)
			(type default)
		)
		(layer "In1.Cu")
	)
	(gr_line
		(start 286.685228 -25.625044)
		(end 286.68726 -25.626314)
		(stroke
			(width 0.2)
			(type default)
		)
		(layer "In1.Cu")
	)
	(gr_line
		(start 286.685228 -14.225016)
		(end 286.68726 -14.226286)
		(stroke
			(width 0.2)
			(type default)
		)
		(layer "In1.Cu")
	)
	(gr_line
		(start 286.68726 -25.626314)
		(end 287.437322 -24.226266)
		(stroke
			(width 0.2)
			(type default)
		)
		(layer "In1.Cu")
	)
	(gr_line
		(start 286.68726 -14.226286)
		(end 287.437322 -12.826492)
		(stroke
			(width 0.2)
			(type default)
		)
		(layer "In1.Cu")
	)
	(gr_line
		(start 286.893762 -211.406994)
		(end 287.706308 -211.406994)
		(stroke
			(width 0.2)
			(type default)
		)
		(layer "In1.Cu")
	)
	(gr_arc
		(start 286.893762 -210.385914)
		(mid 286.383222 -210.896454)
		(end 286.893762 -211.406994)
		(stroke
			(width 0.2)
			(type default)
		)
		(layer "In1.Cu")
	)
	(gr_line
		(start 286.995362 -213.207854)
		(end 286.995616 -213.2076)
		(stroke
			(width 0.2)
			(type default)
		)
		(layer "In1.Cu")
	)
	(gr_line
		(start 286.995616 -213.2076)
		(end 287.596834 -213.2076)
		(stroke
			(width 0.2)
			(type default)
		)
		(layer "In1.Cu")
	)
	(gr_arc
		(start 287.147 -34.1884)
		(mid 287.236803 -34.151203)
		(end 287.274 -34.0614)
		(stroke
			(width 0.2)
			(type default)
		)
		(layer "In1.Cu")
	)
	(gr_line
		(start 287.147 -32.639)
		(end 285.8262 -32.639)
		(stroke
			(width 0.2)
			(type default)
		)
		(layer "In1.Cu")
	)
	(gr_line
		(start 287.274 -34.0614)
		(end 287.274 -32.766)
		(stroke
			(width 0.2)
			(type default)
		)
		(layer "In1.Cu")
	)
	(gr_arc
		(start 287.274 -32.766)
		(mid 287.236803 -32.676197)
		(end 287.147 -32.639)
		(stroke
			(width 0.2)
			(type default)
		)
		(layer "In1.Cu")
	)
	(gr_arc
		(start 287.435036 -12.825222)
		(mid 287.17936 -11.979321)
		(end 286.333438 -12.23518)
		(stroke
			(width 0.2)
			(type default)
		)
		(layer "In1.Cu")
	)
	(gr_arc
		(start 287.43529 -24.224996)
		(mid 287.179258 -23.379176)
		(end 286.333438 -23.635208)
		(stroke
			(width 0.2)
			(type default)
		)
		(layer "In1.Cu")
	)
	(gr_line
		(start 287.437068 -12.826238)
		(end 287.435036 -12.825222)
		(stroke
			(width 0.2)
			(type default)
		)
		(layer "In1.Cu")
	)
	(gr_line
		(start 287.437322 -24.226266)
		(end 287.43529 -24.224996)
		(stroke
			(width 0.2)
			(type default)
		)
		(layer "In1.Cu")
	)
	(gr_line
		(start 287.437322 -12.826492)
		(end 287.437068 -12.826238)
		(stroke
			(width 0.2)
			(type default)
		)
		(layer "In1.Cu")
	)
	(gr_arc
		(start 287.596834 -213.2076)
		(mid 287.600896 -213.207795)
		(end 287.604962 -213.207854)
		(stroke
			(width 0.2)
			(type default)
		)
		(layer "In1.Cu")
	)
	(gr_line
		(start 287.604962 -213.207854)
		(end 288.011362 -213.207854)
		(stroke
			(width 0.2)
			(type default)
		)
		(layer "In1.Cu")
	)
	(gr_arc
		(start 287.706308 -211.406994)
		(mid 288.217102 -210.896581)
		(end 287.706562 -210.385914)
		(stroke
			(width 0.2)
			(type default)
		)
		(layer "In1.Cu")
	)
	(gr_line
		(start 287.706562 -210.385914)
		(end 286.893762 -210.385914)
		(stroke
			(width 0.2)
			(type default)
		)
		(layer "In1.Cu")
	)
	(gr_line
		(start 287.83153 -17.433544)
		(end 287.831784 -17.433798)
		(stroke
			(width 0.2)
			(type default)
		)
		(layer "In1.Cu")
	)
	(gr_line
		(start 287.831784 -17.433798)
		(end 287.833816 -17.434814)
		(stroke
			(width 0.2)
			(type default)
		)
		(layer "In1.Cu")
	)
	(gr_arc
		(start 287.833562 -13.635228)
		(mid 288.089594 -14.481048)
		(end 288.935414 -14.225016)
		(stroke
			(width 0.2)
			(type default)
		)
		(layer "In1.Cu")
	)
	(gr_arc
		(start 287.833816 -17.434814)
		(mid 288.089492 -18.280715)
		(end 288.935414 -18.024856)
		(stroke
			(width 0.2)
			(type default)
		)
		(layer "In1.Cu")
	)
	(gr_arc
		(start 287.837626 -25.027636)
		(mid 288.08576 -25.879089)
		(end 288.935414 -25.625044)
		(stroke
			(width 0.2)
			(type default)
		)
		(layer "In1.Cu")
	)
	(gr_arc
		(start 287.837626 -21.227542)
		(mid 288.08576 -22.078995)
		(end 288.935414 -21.82495)
		(stroke
			(width 0.2)
			(type default)
		)
		(layer "In1.Cu")
	)
	(gr_arc
		(start 288.011362 -213.207854)
		(mid 288.101165 -213.170657)
		(end 288.138362 -213.080854)
		(stroke
			(width 0.2)
			(type default)
		)
		(layer "In1.Cu")
	)
	(gr_line
		(start 288.011362 -211.633054)
		(end 286.588962 -211.633054)
		(stroke
			(width 0.2)
			(type default)
		)
		(layer "In1.Cu")
	)
	(gr_line
		(start 288.138362 -213.080854)
		(end 288.138362 -211.760054)
		(stroke
			(width 0.2)
			(type default)
		)
		(layer "In1.Cu")
	)
	(gr_arc
		(start 288.138362 -211.760054)
		(mid 288.101165 -211.670251)
		(end 288.011362 -211.633054)
		(stroke
			(width 0.2)
			(type default)
		)
		(layer "In1.Cu")
	)
	(gr_line
		(start 288.493708 -222.805244)
		(end 289.306254 -222.805244)
		(stroke
			(width 0.2)
			(type default)
		)
		(layer "In1.Cu")
	)
	(gr_arc
		(start 288.493708 -221.784164)
		(mid 287.983168 -222.294704)
		(end 288.493708 -222.805244)
		(stroke
			(width 0.2)
			(type default)
		)
		(layer "In1.Cu")
	)
	(gr_line
		(start 288.581338 -16.034004)
		(end 287.83153 -17.433544)
		(stroke
			(width 0.2)
			(type default)
		)
		(layer "In1.Cu")
	)
	(gr_line
		(start 288.58337 -23.635208)
		(end 287.837626 -25.027636)
		(stroke
			(width 0.2)
			(type default)
		)
		(layer "In1.Cu")
	)
	(gr_line
		(start 288.58337 -19.835114)
		(end 287.837626 -21.227542)
		(stroke
			(width 0.2)
			(type default)
		)
		(layer "In1.Cu")
	)
	(gr_line
		(start 288.58337 -16.035274)
		(end 288.581338 -16.034004)
		(stroke
			(width 0.2)
			(type default)
		)
		(layer "In1.Cu")
	)
	(gr_line
		(start 288.58337 -12.23518)
		(end 287.833562 -13.635228)
		(stroke
			(width 0.2)
			(type default)
		)
		(layer "In1.Cu")
	)
	(gr_arc
		(start 288.8488 -34.1884)
		(mid 288.885997 -34.278203)
		(end 288.9758 -34.3154)
		(stroke
			(width 0.2)
			(type default)
		)
		(layer "In1.Cu")
	)
	(gr_line
		(start 288.8488 -32.8676)
		(end 288.8488 -34.1884)
		(stroke
			(width 0.2)
			(type default)
		)
		(layer "In1.Cu")
	)
	(gr_line
		(start 288.935414 -25.625044)
		(end 289.685222 -24.224996)
		(stroke
			(width 0.2)
			(type default)
		)
		(layer "In1.Cu")
	)
	(gr_line
		(start 288.935414 -21.82495)
		(end 289.685222 -20.424902)
		(stroke
			(width 0.2)
			(type default)
		)
		(layer "In1.Cu")
	)
	(gr_line
		(start 288.935414 -18.024856)
		(end 288.937446 -18.026126)
		(stroke
			(width 0.2)
			(type default)
		)
		(layer "In1.Cu")
	)
	(gr_line
		(start 288.935414 -14.225016)
		(end 289.681158 -12.832588)
		(stroke
			(width 0.2)
			(type default)
		)
		(layer "In1.Cu")
	)
	(gr_line
		(start 288.937446 -18.026126)
		(end 289.687254 -16.626332)
		(stroke
			(width 0.2)
			(type default)
		)
		(layer "In1.Cu")
	)
	(gr_line
		(start 288.9758 -34.3154)
		(end 290.2712 -34.3154)
		(stroke
			(width 0.2)
			(type default)
		)
		(layer "In1.Cu")
	)
	(gr_arc
		(start 288.9758 -32.7406)
		(mid 288.885997 -32.777797)
		(end 288.8488 -32.8676)
		(stroke
			(width 0.2)
			(type default)
		)
		(layer "In1.Cu")
	)
	(gr_line
		(start 289.2298 -35.524694)
		(end 290.042346 -35.524694)
		(stroke
			(width 0.2)
			(type default)
		)
		(layer "In1.Cu")
	)
	(gr_arc
		(start 289.2298 -34.503614)
		(mid 288.71926 -35.014154)
		(end 289.2298 -35.524694)
		(stroke
			(width 0.2)
			(type default)
		)
		(layer "In1.Cu")
	)
	(gr_arc
		(start 289.306254 -222.805244)
		(mid 289.817048 -222.294831)
		(end 289.306508 -221.784164)
		(stroke
			(width 0.2)
			(type default)
		)
		(layer "In1.Cu")
	)
	(gr_line
		(start 289.306508 -221.784164)
		(end 288.493708 -221.784164)
		(stroke
			(width 0.2)
			(type default)
		)
		(layer "In1.Cu")
	)
	(gr_arc
		(start 289.661854 -213.080854)
		(mid 289.699051 -213.170657)
		(end 289.788854 -213.207854)
		(stroke
			(width 0.2)
			(type default)
		)
		(layer "In1.Cu")
	)
	(gr_line
		(start 289.661854 -211.760054)
		(end 289.661854 -213.080854)
		(stroke
			(width 0.2)
			(type default)
		)
		(layer "In1.Cu")
	)
	(gr_arc
		(start 289.681158 -12.832588)
		(mid 289.433024 -11.981135)
		(end 288.58337 -12.23518)
		(stroke
			(width 0.2)
			(type default)
		)
		(layer "In1.Cu")
	)
	(gr_arc
		(start 289.685222 -24.224996)
		(mid 289.42919 -23.379176)
		(end 288.58337 -23.635208)
		(stroke
			(width 0.2)
			(type default)
		)
		(layer "In1.Cu")
	)
	(gr_arc
		(start 289.685222 -20.424902)
		(mid 289.42919 -19.579082)
		(end 288.58337 -19.835114)
		(stroke
			(width 0.2)
			(type default)
		)
		(layer "In1.Cu")
	)
	(gr_arc
		(start 289.685222 -16.625062)
		(mid 289.42919 -15.779242)
		(end 288.58337 -16.035274)
		(stroke
			(width 0.2)
			(type default)
		)
		(layer "In1.Cu")
	)
	(gr_line
		(start 289.687254 -16.626332)
		(end 289.685222 -16.625062)
		(stroke
			(width 0.2)
			(type default)
		)
		(layer "In1.Cu")
	)
	(gr_line
		(start 289.788854 -213.207854)
		(end 290.195254 -213.207854)
		(stroke
			(width 0.2)
			(type default)
		)
		(layer "In1.Cu")
	)
	(gr_arc
		(start 289.788854 -211.633054)
		(mid 289.699051 -211.670251)
		(end 289.661854 -211.760054)
		(stroke
			(width 0.2)
			(type default)
		)
		(layer "In1.Cu")
	)
	(gr_arc
		(start 290.042346 -35.524694)
		(mid 290.55314 -35.014281)
		(end 290.0426 -34.503614)
		(stroke
			(width 0.2)
			(type default)
		)
		(layer "In1.Cu")
	)
	(gr_line
		(start 290.0426 -34.503614)
		(end 289.2298 -34.503614)
		(stroke
			(width 0.2)
			(type default)
		)
		(layer "In1.Cu")
	)
	(gr_line
		(start 290.081462 -25.033732)
		(end 290.081716 -25.033986)
		(stroke
			(width 0.2)
			(type default)
		)
		(layer "In1.Cu")
	)
	(gr_line
		(start 290.081462 -21.233638)
		(end 290.081716 -21.233892)
		(stroke
			(width 0.2)
			(type default)
		)
		(layer "In1.Cu")
	)
	(gr_line
		(start 290.081462 -17.433544)
		(end 290.081716 -17.433798)
		(stroke
			(width 0.2)
			(type default)
		)
		(layer "In1.Cu")
	)
	(gr_line
		(start 290.081462 -13.633958)
		(end 290.083494 -13.635228)
		(stroke
			(width 0.2)
			(type default)
		)
		(layer "In1.Cu")
	)
	(gr_line
		(start 290.081716 -25.033986)
		(end 290.083748 -25.035002)
		(stroke
			(width 0.2)
			(type default)
		)
		(layer "In1.Cu")
	)
	(gr_line
		(start 290.081716 -21.233892)
		(end 290.083748 -21.234908)
		(stroke
			(width 0.2)
			(type default)
		)
		(layer "In1.Cu")
	)
	(gr_line
		(start 290.081716 -17.433798)
		(end 290.083748 -17.434814)
		(stroke
			(width 0.2)
			(type default)
		)
		(layer "In1.Cu")
	)
	(gr_arc
		(start 290.083494 -13.635228)
		(mid 290.339526 -14.481048)
		(end 291.185346 -14.225016)
		(stroke
			(width 0.2)
			(type default)
		)
		(layer "In1.Cu")
	)
	(gr_arc
		(start 290.083748 -25.035002)
		(mid 290.339424 -25.880903)
		(end 291.185346 -25.625044)
		(stroke
			(width 0.2)
			(type default)
		)
		(layer "In1.Cu")
	)
	(gr_arc
		(start 290.083748 -21.234908)
		(mid 290.339424 -22.080809)
		(end 291.185346 -21.82495)
		(stroke
			(width 0.2)
			(type default)
		)
		(layer "In1.Cu")
	)
	(gr_arc
		(start 290.083748 -17.434814)
		(mid 290.339272 -18.280634)
		(end 291.185092 -18.02511)
		(stroke
			(width 0.2)
			(type default)
		)
		(layer "In1.Cu")
	)
	(gr_line
		(start 290.093654 -211.406994)
		(end 290.906454 -211.406994)
		(stroke
			(width 0.2)
			(type default)
		)
		(layer "In1.Cu")
	)
	(gr_arc
		(start 290.093908 -210.385914)
		(mid 289.583114 -210.896327)
		(end 290.093654 -211.406994)
		(stroke
			(width 0.2)
			(type default)
		)
		(layer "In1.Cu")
	)
	(gr_line
		(start 290.195254 -213.207854)
		(end 290.195508 -213.2076)
		(stroke
			(width 0.2)
			(type default)
		)
		(layer "In1.Cu")
	)
	(gr_line
		(start 290.195508 -213.2076)
		(end 290.796726 -213.2076)
		(stroke
			(width 0.2)
			(type default)
		)
		(layer "In1.Cu")
	)
	(gr_arc
		(start 290.2712 -34.3154)
		(mid 290.361003 -34.278203)
		(end 290.3982 -34.1884)
		(stroke
			(width 0.2)
			(type default)
		)
		(layer "In1.Cu")
	)
	(gr_line
		(start 290.2712 -32.7406)
		(end 288.9758 -32.7406)
		(stroke
			(width 0.2)
			(type default)
		)
		(layer "In1.Cu")
	)
	(gr_line
		(start 290.3982 -34.1884)
		(end 290.3982 -32.8676)
		(stroke
			(width 0.2)
			(type default)
		)
		(layer "In1.Cu")
	)
	(gr_arc
		(start 290.3982 -32.8676)
		(mid 290.361003 -32.777797)
		(end 290.2712 -32.7406)
		(stroke
			(width 0.2)
			(type default)
		)
		(layer "In1.Cu")
	)
	(gr_arc
		(start 290.796726 -213.2076)
		(mid 290.800788 -213.207795)
		(end 290.804854 -213.207854)
		(stroke
			(width 0.2)
			(type default)
		)
		(layer "In1.Cu")
	)
	(gr_line
		(start 290.804854 -213.207854)
		(end 291.211254 -213.207854)
		(stroke
			(width 0.2)
			(type default)
		)
		(layer "In1.Cu")
	)
	(gr_line
		(start 290.831524 -23.633938)
		(end 290.081462 -25.033732)
		(stroke
			(width 0.2)
			(type default)
		)
		(layer "In1.Cu")
	)
	(gr_line
		(start 290.831524 -19.833844)
		(end 290.081462 -21.233638)
		(stroke
			(width 0.2)
			(type default)
		)
		(layer "In1.Cu")
	)
	(gr_line
		(start 290.831524 -16.03375)
		(end 290.081462 -17.433544)
		(stroke
			(width 0.2)
			(type default)
		)
		(layer "In1.Cu")
	)
	(gr_line
		(start 290.831524 -12.23391)
		(end 290.081462 -13.633958)
		(stroke
			(width 0.2)
			(type default)
		)
		(layer "In1.Cu")
	)
	(gr_line
		(start 290.833556 -23.635208)
		(end 290.831524 -23.633938)
		(stroke
			(width 0.2)
			(type default)
		)
		(layer "In1.Cu")
	)
	(gr_line
		(start 290.833556 -19.835114)
		(end 290.831524 -19.833844)
		(stroke
			(width 0.2)
			(type default)
		)
		(layer "In1.Cu")
	)
	(gr_line
		(start 290.833556 -12.23518)
		(end 290.831524 -12.23391)
		(stroke
			(width 0.2)
			(type default)
		)
		(layer "In1.Cu")
	)
	(gr_line
		(start 290.83381 -16.03502)
		(end 290.831524 -16.03375)
		(stroke
			(width 0.2)
			(type default)
		)
		(layer "In1.Cu")
	)
	(gr_arc
		(start 290.906454 -211.406994)
		(mid 291.416994 -210.896454)
		(end 290.906454 -210.385914)
		(stroke
			(width 0.2)
			(type default)
		)
		(layer "In1.Cu")
	)
	(gr_line
		(start 290.906454 -210.385914)
		(end 290.093908 -210.385914)
		(stroke
			(width 0.2)
			(type default)
		)
		(layer "In1.Cu")
	)
	(gr_line
		(start 291.185092 -18.02511)
		(end 291.187378 -18.02638)
		(stroke
			(width 0.2)
			(type default)
		)
		(layer "In1.Cu")
	)
	(gr_line
		(start 291.185346 -25.625044)
		(end 291.187378 -25.626314)
		(stroke
			(width 0.2)
			(type default)
		)
		(layer "In1.Cu")
	)
	(gr_line
		(start 291.185346 -21.82495)
		(end 291.187378 -21.82622)
		(stroke
			(width 0.2)
			(type default)
		)
		(layer "In1.Cu")
	)
	(gr_line
		(start 291.185346 -14.225016)
		(end 291.187378 -14.226286)
		(stroke
			(width 0.2)
			(type default)
		)
		(layer "In1.Cu")
	)
	(gr_line
		(start 291.187378 -25.626314)
		(end 291.93744 -24.226266)
		(stroke
			(width 0.2)
			(type default)
		)
		(layer "In1.Cu")
	)
	(gr_line
		(start 291.187378 -21.82622)
		(end 291.93744 -20.426172)
		(stroke
			(width 0.2)
			(type default)
		)
		(layer "In1.Cu")
	)
	(gr_line
		(start 291.187378 -18.02638)
		(end 291.93744 -16.626586)
		(stroke
			(width 0.2)
			(type default)
		)
		(layer "In1.Cu")
	)
	(gr_line
		(start 291.187378 -14.226286)
		(end 291.93744 -12.826492)
		(stroke
			(width 0.2)
			(type default)
		)
		(layer "In1.Cu")
	)
	(gr_arc
		(start 291.211254 -213.207854)
		(mid 291.301057 -213.170657)
		(end 291.338254 -213.080854)
		(stroke
			(width 0.2)
			(type default)
		)
		(layer "In1.Cu")
	)
	(gr_line
		(start 291.211254 -211.633054)
		(end 289.788854 -211.633054)
		(stroke
			(width 0.2)
			(type default)
		)
		(layer "In1.Cu")
	)
	(gr_line
		(start 291.338254 -213.080854)
		(end 291.338254 -211.760054)
		(stroke
			(width 0.2)
			(type default)
		)
		(layer "In1.Cu")
	)
	(gr_arc
		(start 291.338254 -211.760054)
		(mid 291.301057 -211.670251)
		(end 291.211254 -211.633054)
		(stroke
			(width 0.2)
			(type default)
		)
		(layer "In1.Cu")
	)
	(gr_line
		(start 291.6936 -222.805244)
		(end 292.506146 -222.805244)
		(stroke
			(width 0.2)
			(type default)
		)
		(layer "In1.Cu")
	)
	(gr_arc
		(start 291.6936 -221.784164)
		(mid 291.18306 -222.294704)
		(end 291.6936 -222.805244)
		(stroke
			(width 0.2)
			(type default)
		)
		(layer "In1.Cu")
	)
	(gr_arc
		(start 291.935154 -16.625316)
		(mid 291.67963 -15.779496)
		(end 290.83381 -16.03502)
		(stroke
			(width 0.2)
			(type default)
		)
		(layer "In1.Cu")
	)
	(gr_arc
		(start 291.935154 -12.825222)
		(mid 291.679478 -11.979321)
		(end 290.833556 -12.23518)
		(stroke
			(width 0.2)
			(type default)
		)
		(layer "In1.Cu")
	)
	(gr_arc
		(start 291.935408 -24.224996)
		(mid 291.679376 -23.379176)
		(end 290.833556 -23.635208)
		(stroke
			(width 0.2)
			(type default)
		)
		(layer "In1.Cu")
	)
	(gr_arc
		(start 291.935408 -20.424902)
		(mid 291.679376 -19.579082)
		(end 290.833556 -19.835114)
		(stroke
			(width 0.2)
			(type default)
		)
		(layer "In1.Cu")
	)
	(gr_line
		(start 291.937186 -12.826238)
		(end 291.935154 -12.825222)
		(stroke
			(width 0.2)
			(type default)
		)
		(layer "In1.Cu")
	)
	(gr_line
		(start 291.93744 -24.226266)
		(end 291.935408 -24.224996)
		(stroke
			(width 0.2)
			(type default)
		)
		(layer "In1.Cu")
	)
	(gr_line
		(start 291.93744 -20.426172)
		(end 291.935408 -20.424902)
		(stroke
			(width 0.2)
			(type default)
		)
		(layer "In1.Cu")
	)
	(gr_line
		(start 291.93744 -16.626586)
		(end 291.935154 -16.625316)
		(stroke
			(width 0.2)
			(type default)
		)
		(layer "In1.Cu")
	)
	(gr_line
		(start 291.93744 -12.826492)
		(end 291.937186 -12.826238)
		(stroke
			(width 0.2)
			(type default)
		)
		(layer "In1.Cu")
	)
	(gr_arc
		(start 292.506146 -222.805244)
		(mid 293.01694 -222.294831)
		(end 292.5064 -221.784164)
		(stroke
			(width 0.2)
			(type default)
		)
		(layer "In1.Cu")
	)
	(gr_line
		(start 292.5064 -221.784164)
		(end 291.6936 -221.784164)
		(stroke
			(width 0.2)
			(type default)
		)
		(layer "In1.Cu")
	)
	(gr_arc
		(start 292.861746 -213.080854)
		(mid 292.898943 -213.170657)
		(end 292.988746 -213.207854)
		(stroke
			(width 0.2)
			(type default)
		)
		(layer "In1.Cu")
	)
	(gr_line
		(start 292.861746 -211.760054)
		(end 292.861746 -213.080854)
		(stroke
			(width 0.2)
			(type default)
		)
		(layer "In1.Cu")
	)
	(gr_line
		(start 292.988746 -213.207854)
		(end 293.395146 -213.207854)
		(stroke
			(width 0.2)
			(type default)
		)
		(layer "In1.Cu")
	)
	(gr_arc
		(start 292.988746 -211.633054)
		(mid 292.898943 -211.670251)
		(end 292.861746 -211.760054)
		(stroke
			(width 0.2)
			(type default)
		)
		(layer "In1.Cu")
	)
	(gr_line
		(start 293.293546 -211.406994)
		(end 294.106346 -211.406994)
		(stroke
			(width 0.2)
			(type default)
		)
		(layer "In1.Cu")
	)
	(gr_arc
		(start 293.2938 -210.385914)
		(mid 292.783006 -210.896327)
		(end 293.293546 -211.406994)
		(stroke
			(width 0.2)
			(type default)
		)
		(layer "In1.Cu")
	)
	(gr_line
		(start 293.395146 -213.207854)
		(end 293.3954 -213.2076)
		(stroke
			(width 0.2)
			(type default)
		)
		(layer "In1.Cu")
	)
	(gr_line
		(start 293.3954 -213.2076)
		(end 293.996618 -213.2076)
		(stroke
			(width 0.2)
			(type default)
		)
		(layer "In1.Cu")
	)
	(gr_arc
		(start 293.780464 -34.3408)
		(mid 293.817661 -34.430603)
		(end 293.907464 -34.4678)
		(stroke
			(width 0.2)
			(type default)
		)
		(layer "In1.Cu")
	)
	(gr_line
		(start 293.780464 -33.02)
		(end 293.780464 -34.3408)
		(stroke
			(width 0.2)
			(type default)
		)
		(layer "In1.Cu")
	)
	(gr_line
		(start 293.907464 -34.4678)
		(end 295.202864 -34.4678)
		(stroke
			(width 0.2)
			(type default)
		)
		(layer "In1.Cu")
	)
	(gr_arc
		(start 293.907464 -32.893)
		(mid 293.817661 -32.930197)
		(end 293.780464 -33.02)
		(stroke
			(width 0.2)
			(type default)
		)
		(layer "In1.Cu")
	)
	(gr_arc
		(start 293.996618 -213.2076)
		(mid 294.00068 -213.207795)
		(end 294.004746 -213.207854)
		(stroke
			(width 0.2)
			(type default)
		)
		(layer "In1.Cu")
	)
	(gr_line
		(start 294.004746 -213.207854)
		(end 294.411146 -213.207854)
		(stroke
			(width 0.2)
			(type default)
		)
		(layer "In1.Cu")
	)
	(gr_arc
		(start 294.106346 -211.406994)
		(mid 294.616886 -210.896454)
		(end 294.106346 -210.385914)
		(stroke
			(width 0.2)
			(type default)
		)
		(layer "In1.Cu")
	)
	(gr_line
		(start 294.106346 -210.385914)
		(end 293.2938 -210.385914)
		(stroke
			(width 0.2)
			(type default)
		)
		(layer "In1.Cu")
	)
	(gr_line
		(start 294.159178 -35.69081)
		(end 294.971978 -35.69081)
		(stroke
			(width 0.2)
			(type default)
		)
		(layer "In1.Cu")
	)
	(gr_arc
		(start 294.159432 -34.66973)
		(mid 293.648638 -35.180143)
		(end 294.159178 -35.69081)
		(stroke
			(width 0.2)
			(type default)
		)
		(layer "In1.Cu")
	)
	(gr_arc
		(start 294.411146 -213.207854)
		(mid 294.500949 -213.170657)
		(end 294.538146 -213.080854)
		(stroke
			(width 0.2)
			(type default)
		)
		(layer "In1.Cu")
	)
	(gr_line
		(start 294.411146 -211.633054)
		(end 292.988746 -211.633054)
		(stroke
			(width 0.2)
			(type default)
		)
		(layer "In1.Cu")
	)
	(gr_line
		(start 294.538146 -213.080854)
		(end 294.538146 -211.760054)
		(stroke
			(width 0.2)
			(type default)
		)
		(layer "In1.Cu")
	)
	(gr_arc
		(start 294.538146 -211.760054)
		(mid 294.500949 -211.670251)
		(end 294.411146 -211.633054)
		(stroke
			(width 0.2)
			(type default)
		)
		(layer "In1.Cu")
	)
	(gr_line
		(start 294.893746 -222.805244)
		(end 295.706292 -222.805244)
		(stroke
			(width 0.2)
			(type default)
		)
		(layer "In1.Cu")
	)
	(gr_arc
		(start 294.893746 -221.784164)
		(mid 294.383206 -222.294704)
		(end 294.893746 -222.805244)
		(stroke
			(width 0.2)
			(type default)
		)
		(layer "In1.Cu")
	)
	(gr_arc
		(start 294.971978 -35.69081)
		(mid 295.482518 -35.18027)
		(end 294.971978 -34.66973)
		(stroke
			(width 0.2)
			(type default)
		)
		(layer "In1.Cu")
	)
	(gr_line
		(start 294.971978 -34.66973)
		(end 294.159432 -34.66973)
		(stroke
			(width 0.2)
			(type default)
		)
		(layer "In1.Cu")
	)
	(gr_arc
		(start 295.202864 -34.4678)
		(mid 295.292667 -34.430603)
		(end 295.329864 -34.3408)
		(stroke
			(width 0.2)
			(type default)
		)
		(layer "In1.Cu")
	)
	(gr_line
		(start 295.202864 -32.893)
		(end 293.907464 -32.893)
		(stroke
			(width 0.2)
			(type default)
		)
		(layer "In1.Cu")
	)
	(gr_line
		(start 295.329864 -34.3408)
		(end 295.329864 -33.02)
		(stroke
			(width 0.2)
			(type default)
		)
		(layer "In1.Cu")
	)
	(gr_arc
		(start 295.329864 -33.02)
		(mid 295.292667 -32.930197)
		(end 295.202864 -32.893)
		(stroke
			(width 0.2)
			(type default)
		)
		(layer "In1.Cu")
	)
	(gr_arc
		(start 295.706292 -222.805244)
		(mid 296.217086 -222.294831)
		(end 295.706546 -221.784164)
		(stroke
			(width 0.2)
			(type default)
		)
		(layer "In1.Cu")
	)
	(gr_line
		(start 295.706546 -221.784164)
		(end 294.893746 -221.784164)
		(stroke
			(width 0.2)
			(type default)
		)
		(layer "In1.Cu")
	)
	(gr_line
		(start 296.581322 -25.033986)
		(end 296.583354 -25.035256)
		(stroke
			(width 0.2)
			(type default)
		)
		(layer "In1.Cu")
	)
	(gr_line
		(start 296.581322 -13.633704)
		(end 296.581576 -13.633958)
		(stroke
			(width 0.2)
			(type default)
		)
		(layer "In1.Cu")
	)
	(gr_line
		(start 296.581576 -13.633958)
		(end 296.583608 -13.634974)
		(stroke
			(width 0.2)
			(type default)
		)
		(layer "In1.Cu")
	)
	(gr_arc
		(start 296.583354 -25.035256)
		(mid 296.839386 -25.881076)
		(end 297.685206 -25.625044)
		(stroke
			(width 0.2)
			(type default)
		)
		(layer "In1.Cu")
	)
	(gr_arc
		(start 296.583608 -13.634974)
		(mid 296.839284 -14.480875)
		(end 297.685206 -14.225016)
		(stroke
			(width 0.2)
			(type default)
		)
		(layer "In1.Cu")
	)
	(gr_line
		(start 297.331384 -23.633938)
		(end 296.581322 -25.033986)
		(stroke
			(width 0.2)
			(type default)
		)
		(layer "In1.Cu")
	)
	(gr_line
		(start 297.331384 -12.23391)
		(end 296.581322 -13.633704)
		(stroke
			(width 0.2)
			(type default)
		)
		(layer "In1.Cu")
	)
	(gr_line
		(start 297.333416 -23.635208)
		(end 297.331384 -23.633938)
		(stroke
			(width 0.2)
			(type default)
		)
		(layer "In1.Cu")
	)
	(gr_line
		(start 297.333416 -12.23518)
		(end 297.331384 -12.23391)
		(stroke
			(width 0.2)
			(type default)
		)
		(layer "In1.Cu")
	)
	(gr_line
		(start 297.685206 -25.625044)
		(end 297.687238 -25.626314)
		(stroke
			(width 0.2)
			(type default)
		)
		(layer "In1.Cu")
	)
	(gr_line
		(start 297.685206 -14.225016)
		(end 297.687238 -14.226286)
		(stroke
			(width 0.2)
			(type default)
		)
		(layer "In1.Cu")
	)
	(gr_line
		(start 297.687238 -25.626314)
		(end 298.4373 -24.22652)
		(stroke
			(width 0.2)
			(type default)
		)
		(layer "In1.Cu")
	)
	(gr_line
		(start 297.687238 -14.226286)
		(end 298.4373 -12.826238)
		(stroke
			(width 0.2)
			(type default)
		)
		(layer "In1.Cu")
	)
	(gr_arc
		(start 298.435014 -24.22525)
		(mid 298.179338 -23.379349)
		(end 297.333416 -23.635208)
		(stroke
			(width 0.2)
			(type default)
		)
		(layer "In1.Cu")
	)
	(gr_arc
		(start 298.435268 -12.824968)
		(mid 298.179236 -11.979148)
		(end 297.333416 -12.23518)
		(stroke
			(width 0.2)
			(type default)
		)
		(layer "In1.Cu")
	)
	(gr_line
		(start 298.437046 -24.226266)
		(end 298.435014 -24.22525)
		(stroke
			(width 0.2)
			(type default)
		)
		(layer "In1.Cu")
	)
	(gr_line
		(start 298.4373 -24.22652)
		(end 298.437046 -24.226266)
		(stroke
			(width 0.2)
			(type default)
		)
		(layer "In1.Cu")
	)
	(gr_line
		(start 298.4373 -12.826238)
		(end 298.435268 -12.824968)
		(stroke
			(width 0.2)
			(type default)
		)
		(layer "In1.Cu")
	)
	(gr_arc
		(start 298.461938 -213.080854)
		(mid 298.499135 -213.170657)
		(end 298.588938 -213.207854)
		(stroke
			(width 0.2)
			(type default)
		)
		(layer "In1.Cu")
	)
	(gr_line
		(start 298.461938 -211.760054)
		(end 298.461938 -213.080854)
		(stroke
			(width 0.2)
			(type default)
		)
		(layer "In1.Cu")
	)
	(gr_line
		(start 298.588938 -213.207854)
		(end 298.995338 -213.207854)
		(stroke
			(width 0.2)
			(type default)
		)
		(layer "In1.Cu")
	)
	(gr_arc
		(start 298.588938 -211.633054)
		(mid 298.499135 -211.670251)
		(end 298.461938 -211.760054)
		(stroke
			(width 0.2)
			(type default)
		)
		(layer "In1.Cu")
	)
	(gr_line
		(start 298.831508 -17.433544)
		(end 298.831762 -17.433798)
		(stroke
			(width 0.2)
			(type default)
		)
		(layer "In1.Cu")
	)
	(gr_line
		(start 298.831762 -17.433798)
		(end 298.833794 -17.434814)
		(stroke
			(width 0.2)
			(type default)
		)
		(layer "In1.Cu")
	)
	(gr_arc
		(start 298.83354 -21.235162)
		(mid 299.089572 -22.080982)
		(end 299.935392 -21.82495)
		(stroke
			(width 0.2)
			(type default)
		)
		(layer "In1.Cu")
	)
	(gr_arc
		(start 298.833794 -17.434814)
		(mid 299.08947 -18.280715)
		(end 299.935392 -18.024856)
		(stroke
			(width 0.2)
			(type default)
		)
		(layer "In1.Cu")
	)
	(gr_arc
		(start 298.837604 -25.027636)
		(mid 299.085738 -25.879089)
		(end 299.935392 -25.625044)
		(stroke
			(width 0.2)
			(type default)
		)
		(layer "In1.Cu")
	)
	(gr_arc
		(start 298.837604 -13.627608)
		(mid 299.085738 -14.479061)
		(end 299.935392 -14.225016)
		(stroke
			(width 0.2)
			(type default)
		)
		(layer "In1.Cu")
	)
	(gr_line
		(start 298.893738 -211.406994)
		(end 299.706538 -211.406994)
		(stroke
			(width 0.2)
			(type default)
		)
		(layer "In1.Cu")
	)
	(gr_arc
		(start 298.893992 -210.385914)
		(mid 298.383198 -210.896327)
		(end 298.893738 -211.406994)
		(stroke
			(width 0.2)
			(type default)
		)
		(layer "In1.Cu")
	)
	(gr_line
		(start 298.995338 -213.207854)
		(end 298.995592 -213.2076)
		(stroke
			(width 0.2)
			(type default)
		)
		(layer "In1.Cu")
	)
	(gr_line
		(start 298.995592 -213.2076)
		(end 299.59681 -213.2076)
		(stroke
			(width 0.2)
			(type default)
		)
		(layer "In1.Cu")
	)
	(gr_arc
		(start 299.049694 -34.220658)
		(mid 299.086891 -34.310461)
		(end 299.176694 -34.347658)
		(stroke
			(width 0.2)
			(type default)
		)
		(layer "In1.Cu")
	)
	(gr_line
		(start 299.049694 -32.899858)
		(end 299.049694 -34.220658)
		(stroke
			(width 0.2)
			(type default)
		)
		(layer "In1.Cu")
	)
	(gr_line
		(start 299.176694 -34.347658)
		(end 300.472094 -34.347658)
		(stroke
			(width 0.2)
			(type default)
		)
		(layer "In1.Cu")
	)
	(gr_arc
		(start 299.176694 -32.772858)
		(mid 299.086891 -32.810055)
		(end 299.049694 -32.899858)
		(stroke
			(width 0.2)
			(type default)
		)
		(layer "In1.Cu")
	)
	(gr_line
		(start 299.430694 -36.699952)
		(end 300.243494 -36.699952)
		(stroke
			(width 0.2)
			(type default)
		)
		(layer "In1.Cu")
	)
	(gr_arc
		(start 299.430948 -35.678872)
		(mid 298.920154 -36.189285)
		(end 299.430694 -36.699952)
		(stroke
			(width 0.2)
			(type default)
		)
		(layer "In1.Cu")
	)
	(gr_line
		(start 299.581316 -16.034004)
		(end 298.831508 -17.433544)
		(stroke
			(width 0.2)
			(type default)
		)
		(layer "In1.Cu")
	)
	(gr_line
		(start 299.583348 -23.635208)
		(end 298.837604 -25.027636)
		(stroke
			(width 0.2)
			(type default)
		)
		(layer "In1.Cu")
	)
	(gr_line
		(start 299.583348 -19.835114)
		(end 298.83354 -21.235162)
		(stroke
			(width 0.2)
			(type default)
		)
		(layer "In1.Cu")
	)
	(gr_line
		(start 299.583348 -16.035274)
		(end 299.581316 -16.034004)
		(stroke
			(width 0.2)
			(type default)
		)
		(layer "In1.Cu")
	)
	(gr_line
		(start 299.583348 -12.23518)
		(end 298.837604 -13.627608)
		(stroke
			(width 0.2)
			(type default)
		)
		(layer "In1.Cu")
	)
	(gr_arc
		(start 299.59681 -213.2076)
		(mid 299.600872 -213.207795)
		(end 299.604938 -213.207854)
		(stroke
			(width 0.2)
			(type default)
		)
		(layer "In1.Cu")
	)
	(gr_line
		(start 299.604938 -213.207854)
		(end 300.011338 -213.207854)
		(stroke
			(width 0.2)
			(type default)
		)
		(layer "In1.Cu")
	)
	(gr_arc
		(start 299.706538 -211.406994)
		(mid 300.217078 -210.896454)
		(end 299.706538 -210.385914)
		(stroke
			(width 0.2)
			(type default)
		)
		(layer "In1.Cu")
	)
	(gr_line
		(start 299.706538 -210.385914)
		(end 298.893992 -210.385914)
		(stroke
			(width 0.2)
			(type default)
		)
		(layer "In1.Cu")
	)
	(gr_line
		(start 299.935392 -25.625044)
		(end 300.6852 -24.224996)
		(stroke
			(width 0.2)
			(type default)
		)
		(layer "In1.Cu")
	)
	(gr_line
		(start 299.935392 -21.82495)
		(end 300.681136 -20.432522)
		(stroke
			(width 0.2)
			(type default)
		)
		(layer "In1.Cu")
	)
	(gr_line
		(start 299.935392 -18.024856)
		(end 299.937424 -18.026126)
		(stroke
			(width 0.2)
			(type default)
		)
		(layer "In1.Cu")
	)
	(gr_line
		(start 299.935392 -14.225016)
		(end 300.6852 -12.824968)
		(stroke
			(width 0.2)
			(type default)
		)
		(layer "In1.Cu")
	)
	(gr_line
		(start 299.937424 -18.026126)
		(end 300.687232 -16.626332)
		(stroke
			(width 0.2)
			(type default)
		)
		(layer "In1.Cu")
	)
	(gr_arc
		(start 300.011338 -213.207854)
		(mid 300.101141 -213.170657)
		(end 300.138338 -213.080854)
		(stroke
			(width 0.2)
			(type default)
		)
		(layer "In1.Cu")
	)
	(gr_line
		(start 300.011338 -211.633054)
		(end 298.588938 -211.633054)
		(stroke
			(width 0.2)
			(type default)
		)
		(layer "In1.Cu")
	)
	(gr_line
		(start 300.138338 -213.080854)
		(end 300.138338 -211.760054)
		(stroke
			(width 0.2)
			(type default)
		)
		(layer "In1.Cu")
	)
	(gr_arc
		(start 300.138338 -211.760054)
		(mid 300.101141 -211.670251)
		(end 300.011338 -211.633054)
		(stroke
			(width 0.2)
			(type default)
		)
		(layer "In1.Cu")
	)
	(gr_arc
		(start 300.243494 -36.699952)
		(mid 300.754034 -36.189412)
		(end 300.243494 -35.678872)
		(stroke
			(width 0.2)
			(type default)
		)
		(layer "In1.Cu")
	)
	(gr_line
		(start 300.243494 -35.678872)
		(end 299.430948 -35.678872)
		(stroke
			(width 0.2)
			(type default)
		)
		(layer "In1.Cu")
	)
	(gr_arc
		(start 300.472094 -34.347658)
		(mid 300.561897 -34.310461)
		(end 300.599094 -34.220658)
		(stroke
			(width 0.2)
			(type default)
		)
		(layer "In1.Cu")
	)
	(gr_line
		(start 300.472094 -32.772858)
		(end 299.176694 -32.772858)
		(stroke
			(width 0.2)
			(type default)
		)
		(layer "In1.Cu")
	)
	(gr_line
		(start 300.493684 -222.805244)
		(end 301.30623 -222.805244)
		(stroke
			(width 0.2)
			(type default)
		)
		(layer "In1.Cu")
	)
	(gr_arc
		(start 300.493684 -221.784164)
		(mid 299.983144 -222.294704)
		(end 300.493684 -222.805244)
		(stroke
			(width 0.2)
			(type default)
		)
		(layer "In1.Cu")
	)
	(gr_line
		(start 300.599094 -34.220658)
		(end 300.599094 -32.899858)
		(stroke
			(width 0.2)
			(type default)
		)
		(layer "In1.Cu")
	)
	(gr_arc
		(start 300.599094 -32.899858)
		(mid 300.561897 -32.810055)
		(end 300.472094 -32.772858)
		(stroke
			(width 0.2)
			(type default)
		)
		(layer "In1.Cu")
	)
	(gr_arc
		(start 300.681136 -20.432522)
		(mid 300.433002 -19.581069)
		(end 299.583348 -19.835114)
		(stroke
			(width 0.2)
			(type default)
		)
		(layer "In1.Cu")
	)
	(gr_arc
		(start 300.6852 -24.224996)
		(mid 300.429168 -23.379176)
		(end 299.583348 -23.635208)
		(stroke
			(width 0.2)
			(type default)
		)
		(layer "In1.Cu")
	)
	(gr_arc
		(start 300.6852 -16.625062)
		(mid 300.429168 -15.779242)
		(end 299.583348 -16.035274)
		(stroke
			(width 0.2)
			(type default)
		)
		(layer "In1.Cu")
	)
	(gr_arc
		(start 300.6852 -12.824968)
		(mid 300.429168 -11.979148)
		(end 299.583348 -12.23518)
		(stroke
			(width 0.2)
			(type default)
		)
		(layer "In1.Cu")
	)
	(gr_line
		(start 300.687232 -16.626332)
		(end 300.6852 -16.625062)
		(stroke
			(width 0.2)
			(type default)
		)
		(layer "In1.Cu")
	)
	(gr_line
		(start 301.08144 -25.033732)
		(end 301.081694 -25.033986)
		(stroke
			(width 0.2)
			(type default)
		)
		(layer "In1.Cu")
	)
	(gr_line
		(start 301.08144 -21.233892)
		(end 301.083472 -21.235162)
		(stroke
			(width 0.2)
			(type default)
		)
		(layer "In1.Cu")
	)
	(gr_line
		(start 301.08144 -17.433544)
		(end 301.081694 -17.433798)
		(stroke
			(width 0.2)
			(type default)
		)
		(layer "In1.Cu")
	)
	(gr_line
		(start 301.08144 -13.633704)
		(end 301.081694 -13.633958)
		(stroke
			(width 0.2)
			(type default)
		)
		(layer "In1.Cu")
	)
	(gr_line
		(start 301.081694 -25.033986)
		(end 301.083726 -25.035002)
		(stroke
			(width 0.2)
			(type default)
		)
		(layer "In1.Cu")
	)
	(gr_line
		(start 301.081694 -17.433798)
		(end 301.083726 -17.434814)
		(stroke
			(width 0.2)
			(type default)
		)
		(layer "In1.Cu")
	)
	(gr_line
		(start 301.081694 -13.633958)
		(end 301.083726 -13.634974)
		(stroke
			(width 0.2)
			(type default)
		)
		(layer "In1.Cu")
	)
	(gr_arc
		(start 301.083472 -21.235162)
		(mid 301.339504 -22.080982)
		(end 302.185324 -21.82495)
		(stroke
			(width 0.2)
			(type default)
		)
		(layer "In1.Cu")
	)
	(gr_arc
		(start 301.083726 -25.035002)
		(mid 301.339402 -25.880903)
		(end 302.185324 -25.625044)
		(stroke
			(width 0.2)
			(type default)
		)
		(layer "In1.Cu")
	)
	(gr_arc
		(start 301.083726 -17.434814)
		(mid 301.33925 -18.280634)
		(end 302.18507 -18.02511)
		(stroke
			(width 0.2)
			(type default)
		)
		(layer "In1.Cu")
	)
	(gr_arc
		(start 301.083726 -13.634974)
		(mid 301.339402 -14.480875)
		(end 302.185324 -14.225016)
		(stroke
			(width 0.2)
			(type default)
		)
		(layer "In1.Cu")
	)
	(gr_arc
		(start 301.27829 -34.200592)
		(mid 301.315487 -34.290395)
		(end 301.40529 -34.327592)
		(stroke
			(width 0.2)
			(type default)
		)
		(layer "In1.Cu")
	)
	(gr_line
		(start 301.27829 -32.879792)
		(end 301.27829 -34.200592)
		(stroke
			(width 0.2)
			(type default)
		)
		(layer "In1.Cu")
	)
	(gr_arc
		(start 301.30623 -222.805244)
		(mid 301.817024 -222.294831)
		(end 301.306484 -221.784164)
		(stroke
			(width 0.2)
			(type default)
		)
		(layer "In1.Cu")
	)
	(gr_line
		(start 301.306484 -221.784164)
		(end 300.493684 -221.784164)
		(stroke
			(width 0.2)
			(type default)
		)
		(layer "In1.Cu")
	)
	(gr_line
		(start 301.40529 -34.327592)
		(end 302.70069 -34.327592)
		(stroke
			(width 0.2)
			(type default)
		)
		(layer "In1.Cu")
	)
	(gr_arc
		(start 301.40529 -32.752792)
		(mid 301.315487 -32.789989)
		(end 301.27829 -32.879792)
		(stroke
			(width 0.2)
			(type default)
		)
		(layer "In1.Cu")
	)
	(gr_line
		(start 301.65929 -35.536886)
		(end 302.471836 -35.536886)
		(stroke
			(width 0.2)
			(type default)
		)
		(layer "In1.Cu")
	)
	(gr_arc
		(start 301.65929 -34.515806)
		(mid 301.14875 -35.026346)
		(end 301.65929 -35.536886)
		(stroke
			(width 0.2)
			(type default)
		)
		(layer "In1.Cu")
	)
	(gr_arc
		(start 301.66183 -213.080854)
		(mid 301.699027 -213.170657)
		(end 301.78883 -213.207854)
		(stroke
			(width 0.2)
			(type default)
		)
		(layer "In1.Cu")
	)
	(gr_line
		(start 301.66183 -211.760054)
		(end 301.66183 -213.080854)
		(stroke
			(width 0.2)
			(type default)
		)
		(layer "In1.Cu")
	)
	(gr_line
		(start 301.78883 -213.207854)
		(end 302.19523 -213.207854)
		(stroke
			(width 0.2)
			(type default)
		)
		(layer "In1.Cu")
	)
	(gr_arc
		(start 301.78883 -211.633054)
		(mid 301.699027 -211.670251)
		(end 301.66183 -211.760054)
		(stroke
			(width 0.2)
			(type default)
		)
		(layer "In1.Cu")
	)
	(gr_line
		(start 301.831502 -23.633938)
		(end 301.08144 -25.033732)
		(stroke
			(width 0.2)
			(type default)
		)
		(layer "In1.Cu")
	)
	(gr_line
		(start 301.831502 -19.833844)
		(end 301.08144 -21.233892)
		(stroke
			(width 0.2)
			(type default)
		)
		(layer "In1.Cu")
	)
	(gr_line
		(start 301.831502 -16.03375)
		(end 301.08144 -17.433544)
		(stroke
			(width 0.2)
			(type default)
		)
		(layer "In1.Cu")
	)
	(gr_line
		(start 301.831502 -12.23391)
		(end 301.08144 -13.633704)
		(stroke
			(width 0.2)
			(type default)
		)
		(layer "In1.Cu")
	)
	(gr_line
		(start 301.833534 -23.635208)
		(end 301.831502 -23.633938)
		(stroke
			(width 0.2)
			(type default)
		)
		(layer "In1.Cu")
	)
	(gr_line
		(start 301.833534 -19.835114)
		(end 301.831502 -19.833844)
		(stroke
			(width 0.2)
			(type default)
		)
		(layer "In1.Cu")
	)
	(gr_line
		(start 301.833534 -12.23518)
		(end 301.831502 -12.23391)
		(stroke
			(width 0.2)
			(type default)
		)
		(layer "In1.Cu")
	)
	(gr_line
		(start 301.833788 -16.03502)
		(end 301.831502 -16.03375)
		(stroke
			(width 0.2)
			(type default)
		)
		(layer "In1.Cu")
	)
	(gr_line
		(start 302.09363 -211.406994)
		(end 302.90643 -211.406994)
		(stroke
			(width 0.2)
			(type default)
		)
		(layer "In1.Cu")
	)
	(gr_arc
		(start 302.093884 -210.385914)
		(mid 301.58309 -210.896327)
		(end 302.09363 -211.406994)
		(stroke
			(width 0.2)
			(type default)
		)
		(layer "In1.Cu")
	)
	(gr_line
		(start 302.18507 -18.02511)
		(end 302.187356 -18.02638)
		(stroke
			(width 0.2)
			(type default)
		)
		(layer "In1.Cu")
	)
	(gr_line
		(start 302.185324 -25.625044)
		(end 302.187356 -25.626314)
		(stroke
			(width 0.2)
			(type default)
		)
		(layer "In1.Cu")
	)
	(gr_line
		(start 302.185324 -21.82495)
		(end 302.187356 -21.82622)
		(stroke
			(width 0.2)
			(type default)
		)
		(layer "In1.Cu")
	)
	(gr_line
		(start 302.185324 -14.225016)
		(end 302.187356 -14.226286)
		(stroke
			(width 0.2)
			(type default)
		)
		(layer "In1.Cu")
	)
	(gr_line
		(start 302.187356 -25.626314)
		(end 302.937418 -24.226266)
		(stroke
			(width 0.2)
			(type default)
		)
		(layer "In1.Cu")
	)
	(gr_line
		(start 302.187356 -21.82622)
		(end 302.937418 -20.426426)
		(stroke
			(width 0.2)
			(type default)
		)
		(layer "In1.Cu")
	)
	(gr_line
		(start 302.187356 -18.02638)
		(end 302.937418 -16.626586)
		(stroke
			(width 0.2)
			(type default)
		)
		(layer "In1.Cu")
	)
	(gr_line
		(start 302.187356 -14.226286)
		(end 302.937418 -12.826238)
		(stroke
			(width 0.2)
			(type default)
		)
		(layer "In1.Cu")
	)
	(gr_line
		(start 302.19523 -213.207854)
		(end 302.195484 -213.2076)
		(stroke
			(width 0.2)
			(type default)
		)
		(layer "In1.Cu")
	)
	(gr_line
		(start 302.195484 -213.2076)
		(end 302.796702 -213.2076)
		(stroke
			(width 0.2)
			(type default)
		)
		(layer "In1.Cu")
	)
	(gr_arc
		(start 302.471836 -35.536886)
		(mid 302.98263 -35.026473)
		(end 302.47209 -34.515806)
		(stroke
			(width 0.2)
			(type default)
		)
		(layer "In1.Cu")
	)
	(gr_line
		(start 302.47209 -34.515806)
		(end 301.65929 -34.515806)
		(stroke
			(width 0.2)
			(type default)
		)
		(layer "In1.Cu")
	)
	(gr_arc
		(start 302.70069 -34.327592)
		(mid 302.790493 -34.290395)
		(end 302.82769 -34.200592)
		(stroke
			(width 0.2)
			(type default)
		)
		(layer "In1.Cu")
	)
	(gr_line
		(start 302.70069 -32.752792)
		(end 301.40529 -32.752792)
		(stroke
			(width 0.2)
			(type default)
		)
		(layer "In1.Cu")
	)
	(gr_arc
		(start 302.796702 -213.2076)
		(mid 302.800764 -213.207795)
		(end 302.80483 -213.207854)
		(stroke
			(width 0.2)
			(type default)
		)
		(layer "In1.Cu")
	)
	(gr_line
		(start 302.80483 -213.207854)
		(end 303.21123 -213.207854)
		(stroke
			(width 0.2)
			(type default)
		)
		(layer "In1.Cu")
	)
	(gr_line
		(start 302.82769 -34.200592)
		(end 302.82769 -32.879792)
		(stroke
			(width 0.2)
			(type default)
		)
		(layer "In1.Cu")
	)
	(gr_arc
		(start 302.82769 -32.879792)
		(mid 302.790493 -32.789989)
		(end 302.70069 -32.752792)
		(stroke
			(width 0.2)
			(type default)
		)
		(layer "In1.Cu")
	)
	(gr_arc
		(start 302.90643 -211.406994)
		(mid 303.41697 -210.896454)
		(end 302.90643 -210.385914)
		(stroke
			(width 0.2)
			(type default)
		)
		(layer "In1.Cu")
	)
	(gr_line
		(start 302.90643 -210.385914)
		(end 302.093884 -210.385914)
		(stroke
			(width 0.2)
			(type default)
		)
		(layer "In1.Cu")
	)
	(gr_arc
		(start 302.935132 -20.425156)
		(mid 302.679456 -19.579255)
		(end 301.833534 -19.835114)
		(stroke
			(width 0.2)
			(type default)
		)
		(layer "In1.Cu")
	)
	(gr_arc
		(start 302.935132 -16.625316)
		(mid 302.679608 -15.779496)
		(end 301.833788 -16.03502)
		(stroke
			(width 0.2)
			(type default)
		)
		(layer "In1.Cu")
	)
	(gr_arc
		(start 302.935386 -24.224996)
		(mid 302.679354 -23.379176)
		(end 301.833534 -23.635208)
		(stroke
			(width 0.2)
			(type default)
		)
		(layer "In1.Cu")
	)
	(gr_arc
		(start 302.935386 -12.824968)
		(mid 302.679354 -11.979148)
		(end 301.833534 -12.23518)
		(stroke
			(width 0.2)
			(type default)
		)
		(layer "In1.Cu")
	)
	(gr_line
		(start 302.937164 -20.426172)
		(end 302.935132 -20.425156)
		(stroke
			(width 0.2)
			(type default)
		)
		(layer "In1.Cu")
	)
	(gr_line
		(start 302.937418 -24.226266)
		(end 302.935386 -24.224996)
		(stroke
			(width 0.2)
			(type default)
		)
		(layer "In1.Cu")
	)
	(gr_line
		(start 302.937418 -20.426426)
		(end 302.937164 -20.426172)
		(stroke
			(width 0.2)
			(type default)
		)
		(layer "In1.Cu")
	)
	(gr_line
		(start 302.937418 -16.626586)
		(end 302.935132 -16.625316)
		(stroke
			(width 0.2)
			(type default)
		)
		(layer "In1.Cu")
	)
	(gr_line
		(start 302.937418 -12.826238)
		(end 302.935386 -12.824968)
		(stroke
			(width 0.2)
			(type default)
		)
		(layer "In1.Cu")
	)
	(gr_arc
		(start 303.21123 -213.207854)
		(mid 303.301033 -213.170657)
		(end 303.33823 -213.080854)
		(stroke
			(width 0.2)
			(type default)
		)
		(layer "In1.Cu")
	)
	(gr_line
		(start 303.21123 -211.633054)
		(end 301.78883 -211.633054)
		(stroke
			(width 0.2)
			(type default)
		)
		(layer "In1.Cu")
	)
	(gr_line
		(start 303.33823 -213.080854)
		(end 303.33823 -211.760054)
		(stroke
			(width 0.2)
			(type default)
		)
		(layer "In1.Cu")
	)
	(gr_arc
		(start 303.33823 -211.760054)
		(mid 303.301033 -211.670251)
		(end 303.21123 -211.633054)
		(stroke
			(width 0.2)
			(type default)
		)
		(layer "In1.Cu")
	)
	(gr_arc
		(start 303.4538 -34.1884)
		(mid 303.490997 -34.278203)
		(end 303.5808 -34.3154)
		(stroke
			(width 0.2)
			(type default)
		)
		(layer "In1.Cu")
	)
	(gr_line
		(start 303.4538 -32.8676)
		(end 303.4538 -34.1884)
		(stroke
			(width 0.2)
			(type default)
		)
		(layer "In1.Cu")
	)
	(gr_line
		(start 303.5808 -34.3154)
		(end 304.8762 -34.3154)
		(stroke
			(width 0.2)
			(type default)
		)
		(layer "In1.Cu")
	)
	(gr_arc
		(start 303.5808 -32.7406)
		(mid 303.490997 -32.777797)
		(end 303.4538 -32.8676)
		(stroke
			(width 0.2)
			(type default)
		)
		(layer "In1.Cu")
	)
	(gr_arc
		(start 303.717198 -219.783914)
		(mid 303.222914 -220.310202)
		(end 303.749202 -220.804486)
		(stroke
			(width 0.2)
			(type default)
		)
		(layer "In1.Cu")
	)
	(gr_line
		(start 303.717198 -219.781374)
		(end 303.717198 -219.783914)
		(stroke
			(width 0.2)
			(type default)
		)
		(layer "In1.Cu")
	)
	(gr_line
		(start 303.749202 -220.807026)
		(end 304.561748 -220.781626)
		(stroke
			(width 0.2)
			(type default)
		)
		(layer "In1.Cu")
	)
	(gr_line
		(start 303.749202 -220.804486)
		(end 303.749202 -220.807026)
		(stroke
			(width 0.2)
			(type default)
		)
		(layer "In1.Cu")
	)
	(gr_line
		(start 303.8348 -36.794694)
		(end 304.647346 -36.794694)
		(stroke
			(width 0.2)
			(type default)
		)
		(layer "In1.Cu")
	)
	(gr_arc
		(start 303.8348 -35.773614)
		(mid 303.32426 -36.284154)
		(end 303.8348 -36.794694)
		(stroke
			(width 0.2)
			(type default)
		)
		(layer "In1.Cu")
	)
	(gr_line
		(start 304.529998 -219.758514)
		(end 304.529998 -219.755974)
		(stroke
			(width 0.2)
			(type default)
		)
		(layer "In1.Cu")
	)
	(gr_line
		(start 304.529998 -219.755974)
		(end 303.717198 -219.781374)
		(stroke
			(width 0.2)
			(type default)
		)
		(layer "In1.Cu")
	)
	(gr_line
		(start 304.561748 -220.781626)
		(end 304.562002 -220.781372)
		(stroke
			(width 0.2)
			(type default)
		)
		(layer "In1.Cu")
	)
	(gr_line
		(start 304.562002 -220.781372)
		(end 304.562002 -220.779086)
		(stroke
			(width 0.2)
			(type default)
		)
		(layer "In1.Cu")
	)
	(gr_arc
		(start 304.562002 -220.779086)
		(mid 305.056286 -220.252798)
		(end 304.529998 -219.758514)
		(stroke
			(width 0.2)
			(type default)
		)
		(layer "In1.Cu")
	)
	(gr_arc
		(start 304.647346 -36.794694)
		(mid 305.15814 -36.284281)
		(end 304.6476 -35.773614)
		(stroke
			(width 0.2)
			(type default)
		)
		(layer "In1.Cu")
	)
	(gr_line
		(start 304.6476 -35.773614)
		(end 303.8348 -35.773614)
		(stroke
			(width 0.2)
			(type default)
		)
		(layer "In1.Cu")
	)
	(gr_arc
		(start 304.8762 -34.3154)
		(mid 304.966003 -34.278203)
		(end 305.0032 -34.1884)
		(stroke
			(width 0.2)
			(type default)
		)
		(layer "In1.Cu")
	)
	(gr_line
		(start 304.8762 -32.7406)
		(end 303.5808 -32.7406)
		(stroke
			(width 0.2)
			(type default)
		)
		(layer "In1.Cu")
	)
	(gr_line
		(start 305.0032 -34.1884)
		(end 305.0032 -32.8676)
		(stroke
			(width 0.2)
			(type default)
		)
		(layer "In1.Cu")
	)
	(gr_arc
		(start 305.0032 -32.8676)
		(mid 304.966003 -32.777797)
		(end 304.8762 -32.7406)
		(stroke
			(width 0.2)
			(type default)
		)
		(layer "In1.Cu")
	)
	(gr_arc
		(start 305.605434 -34.174938)
		(mid 305.642631 -34.264741)
		(end 305.732434 -34.301938)
		(stroke
			(width 0.2)
			(type default)
		)
		(layer "In1.Cu")
	)
	(gr_line
		(start 305.605434 -32.854138)
		(end 305.605434 -34.174938)
		(stroke
			(width 0.2)
			(type default)
		)
		(layer "In1.Cu")
	)
	(gr_line
		(start 305.732434 -34.301938)
		(end 307.027834 -34.301938)
		(stroke
			(width 0.2)
			(type default)
		)
		(layer "In1.Cu")
	)
	(gr_arc
		(start 305.732434 -32.727138)
		(mid 305.642631 -32.764335)
		(end 305.605434 -32.854138)
		(stroke
			(width 0.2)
			(type default)
		)
		(layer "In1.Cu")
	)
	(gr_line
		(start 305.762914 -40.31996)
		(end 306.57546 -40.31996)
		(stroke
			(width 0.2)
			(type default)
		)
		(layer "In1.Cu")
	)
	(gr_arc
		(start 305.762914 -39.29888)
		(mid 305.252374 -39.80942)
		(end 305.762914 -40.31996)
		(stroke
			(width 0.2)
			(type default)
		)
		(layer "In1.Cu")
	)
	(gr_line
		(start 306.099972 -228.000052)
		(end 260.500114 -228.000052)
		(stroke
			(width 5.08)
			(type default)
		)
		(layer "In1.Cu")
	)
	(gr_line
		(start 306.099972 -222.600012)
		(end 306.099972 -228.000052)
		(stroke
			(width 1.524)
			(type default)
		)
		(layer "In1.Cu")
	)
	(gr_arc
		(start 306.57546 -40.31996)
		(mid 307.086254 -39.809547)
		(end 306.575714 -39.29888)
		(stroke
			(width 0.2)
			(type default)
		)
		(layer "In1.Cu")
	)
	(gr_line
		(start 306.575714 -39.29888)
		(end 305.762914 -39.29888)
		(stroke
			(width 0.2)
			(type default)
		)
		(layer "In1.Cu")
	)
	(gr_arc
		(start 307.027834 -34.301938)
		(mid 307.117637 -34.264741)
		(end 307.154834 -34.174938)
		(stroke
			(width 0.2)
			(type default)
		)
		(layer "In1.Cu")
	)
	(gr_line
		(start 307.027834 -32.727138)
		(end 305.732434 -32.727138)
		(stroke
			(width 0.2)
			(type default)
		)
		(layer "In1.Cu")
	)
	(gr_line
		(start 307.154834 -34.174938)
		(end 307.154834 -32.854138)
		(stroke
			(width 0.2)
			(type default)
		)
		(layer "In1.Cu")
	)
	(gr_arc
		(start 307.154834 -32.854138)
		(mid 307.117637 -32.764335)
		(end 307.027834 -32.727138)
		(stroke
			(width 0.2)
			(type default)
		)
		(layer "In1.Cu")
	)
	(gr_arc
		(start 307.583586 -25.035256)
		(mid 307.839618 -25.881076)
		(end 308.685438 -25.625044)
		(stroke
			(width 0.2)
			(type default)
		)
		(layer "In1.Cu")
	)
	(gr_arc
		(start 307.58765 -13.627608)
		(mid 307.835784 -14.479061)
		(end 308.685438 -14.225016)
		(stroke
			(width 0.2)
			(type default)
		)
		(layer "In1.Cu")
	)
	(gr_line
		(start 308.333394 -23.635208)
		(end 307.583586 -25.035256)
		(stroke
			(width 0.2)
			(type default)
		)
		(layer "In1.Cu")
	)
	(gr_line
		(start 308.333394 -12.23518)
		(end 307.58765 -13.627608)
		(stroke
			(width 0.2)
			(type default)
		)
		(layer "In1.Cu")
	)
	(gr_line
		(start 308.500018 -228.000052)
		(end 308.500018 -222.600012)
		(stroke
			(width 1.524)
			(type default)
		)
		(layer "In1.Cu")
	)
	(gr_arc
		(start 308.500018 -222.600012)
		(mid 307.300122 -221.400116)
		(end 306.099972 -222.600012)
		(stroke
			(width 1.524)
			(type default)
		)
		(layer "In1.Cu")
	)
	(gr_line
		(start 308.685438 -25.625044)
		(end 309.431182 -24.232616)
		(stroke
			(width 0.2)
			(type default)
		)
		(layer "In1.Cu")
	)
	(gr_line
		(start 308.685438 -14.225016)
		(end 309.435246 -12.824968)
		(stroke
			(width 0.2)
			(type default)
		)
		(layer "In1.Cu")
	)
	(gr_arc
		(start 309.431182 -24.232616)
		(mid 309.183048 -23.381163)
		(end 308.333394 -23.635208)
		(stroke
			(width 0.2)
			(type default)
		)
		(layer "In1.Cu")
	)
	(gr_arc
		(start 309.435246 -12.824968)
		(mid 309.179214 -11.979148)
		(end 308.333394 -12.23518)
		(stroke
			(width 0.2)
			(type default)
		)
		(layer "In1.Cu")
	)
	(gr_arc
		(start 309.661814 -213.080854)
		(mid 309.699011 -213.170657)
		(end 309.788814 -213.207854)
		(stroke
			(width 0.2)
			(type default)
		)
		(layer "In1.Cu")
	)
	(gr_line
		(start 309.661814 -211.760054)
		(end 309.661814 -213.080854)
		(stroke
			(width 0.2)
			(type default)
		)
		(layer "In1.Cu")
	)
	(gr_line
		(start 309.788814 -213.207854)
		(end 310.195214 -213.207854)
		(stroke
			(width 0.2)
			(type default)
		)
		(layer "In1.Cu")
	)
	(gr_arc
		(start 309.788814 -211.633054)
		(mid 309.699011 -211.670251)
		(end 309.661814 -211.760054)
		(stroke
			(width 0.2)
			(type default)
		)
		(layer "In1.Cu")
	)
	(gr_line
		(start 309.831486 -25.033732)
		(end 309.83174 -25.033986)
		(stroke
			(width 0.2)
			(type default)
		)
		(layer "In1.Cu")
	)
	(gr_line
		(start 309.831486 -21.233892)
		(end 309.833518 -21.235162)
		(stroke
			(width 0.2)
			(type default)
		)
		(layer "In1.Cu")
	)
	(gr_line
		(start 309.831486 -17.433544)
		(end 309.83174 -17.433798)
		(stroke
			(width 0.2)
			(type default)
		)
		(layer "In1.Cu")
	)
	(gr_line
		(start 309.831486 -13.633704)
		(end 309.83174 -13.633958)
		(stroke
			(width 0.2)
			(type default)
		)
		(layer "In1.Cu")
	)
	(gr_line
		(start 309.83174 -25.033986)
		(end 309.833772 -25.035002)
		(stroke
			(width 0.2)
			(type default)
		)
		(layer "In1.Cu")
	)
	(gr_line
		(start 309.83174 -17.433798)
		(end 309.833772 -17.434814)
		(stroke
			(width 0.2)
			(type default)
		)
		(layer "In1.Cu")
	)
	(gr_line
		(start 309.83174 -13.633958)
		(end 309.833772 -13.634974)
		(stroke
			(width 0.2)
			(type default)
		)
		(layer "In1.Cu")
	)
	(gr_arc
		(start 309.833518 -21.235162)
		(mid 310.08955 -22.080982)
		(end 310.93537 -21.82495)
		(stroke
			(width 0.2)
			(type default)
		)
		(layer "In1.Cu")
	)
	(gr_arc
		(start 309.833772 -25.035002)
		(mid 310.089448 -25.880903)
		(end 310.93537 -25.625044)
		(stroke
			(width 0.2)
			(type default)
		)
		(layer "In1.Cu")
	)
	(gr_arc
		(start 309.833772 -17.434814)
		(mid 310.089296 -18.280634)
		(end 310.935116 -18.02511)
		(stroke
			(width 0.2)
			(type default)
		)
		(layer "In1.Cu")
	)
	(gr_arc
		(start 309.833772 -13.634974)
		(mid 310.089448 -14.480875)
		(end 310.93537 -14.225016)
		(stroke
			(width 0.2)
			(type default)
		)
		(layer "In1.Cu")
	)
	(gr_arc
		(start 310.044592 -34.216086)
		(mid 310.081789 -34.305889)
		(end 310.171592 -34.343086)
		(stroke
			(width 0.2)
			(type default)
		)
		(layer "In1.Cu")
	)
	(gr_line
		(start 310.044592 -32.895286)
		(end 310.044592 -34.216086)
		(stroke
			(width 0.2)
			(type default)
		)
		(layer "In1.Cu")
	)
	(gr_line
		(start 310.093868 -211.406994)
		(end 310.906414 -211.406994)
		(stroke
			(width 0.2)
			(type default)
		)
		(layer "In1.Cu")
	)
	(gr_arc
		(start 310.093868 -210.385914)
		(mid 309.583328 -210.896454)
		(end 310.093868 -211.406994)
		(stroke
			(width 0.2)
			(type default)
		)
		(layer "In1.Cu")
	)
	(gr_line
		(start 310.171592 -34.343086)
		(end 311.466992 -34.343086)
		(stroke
			(width 0.2)
			(type default)
		)
		(layer "In1.Cu")
	)
	(gr_arc
		(start 310.171592 -32.768286)
		(mid 310.081789 -32.805483)
		(end 310.044592 -32.895286)
		(stroke
			(width 0.2)
			(type default)
		)
		(layer "In1.Cu")
	)
	(gr_line
		(start 310.195214 -213.207854)
		(end 310.195468 -213.2076)
		(stroke
			(width 0.2)
			(type default)
		)
		(layer "In1.Cu")
	)
	(gr_line
		(start 310.195468 -213.2076)
		(end 310.796686 -213.2076)
		(stroke
			(width 0.2)
			(type default)
		)
		(layer "In1.Cu")
	)
	(gr_line
		(start 310.425592 -35.55238)
		(end 311.238138 -35.55238)
		(stroke
			(width 0.2)
			(type default)
		)
		(layer "In1.Cu")
	)
	(gr_arc
		(start 310.425592 -34.5313)
		(mid 309.915052 -35.04184)
		(end 310.425592 -35.55238)
		(stroke
			(width 0.2)
			(type default)
		)
		(layer "In1.Cu")
	)
	(gr_line
		(start 310.581548 -23.633938)
		(end 309.831486 -25.033732)
		(stroke
			(width 0.2)
			(type default)
		)
		(layer "In1.Cu")
	)
	(gr_line
		(start 310.581548 -19.833844)
		(end 309.831486 -21.233892)
		(stroke
			(width 0.2)
			(type default)
		)
		(layer "In1.Cu")
	)
	(gr_line
		(start 310.581548 -16.03375)
		(end 309.831486 -17.433544)
		(stroke
			(width 0.2)
			(type default)
		)
		(layer "In1.Cu")
	)
	(gr_line
		(start 310.581548 -12.23391)
		(end 309.831486 -13.633704)
		(stroke
			(width 0.2)
			(type default)
		)
		(layer "In1.Cu")
	)
	(gr_line
		(start 310.58358 -23.635208)
		(end 310.581548 -23.633938)
		(stroke
			(width 0.2)
			(type default)
		)
		(layer "In1.Cu")
	)
	(gr_line
		(start 310.58358 -19.835114)
		(end 310.581548 -19.833844)
		(stroke
			(width 0.2)
			(type default)
		)
		(layer "In1.Cu")
	)
	(gr_line
		(start 310.58358 -12.23518)
		(end 310.581548 -12.23391)
		(stroke
			(width 0.2)
			(type default)
		)
		(layer "In1.Cu")
	)
	(gr_line
		(start 310.583834 -16.03502)
		(end 310.581548 -16.03375)
		(stroke
			(width 0.2)
			(type default)
		)
		(layer "In1.Cu")
	)
	(gr_arc
		(start 310.796686 -213.2076)
		(mid 310.800748 -213.207795)
		(end 310.804814 -213.207854)
		(stroke
			(width 0.2)
			(type default)
		)
		(layer "In1.Cu")
	)
	(gr_line
		(start 310.804814 -213.207854)
		(end 311.211214 -213.207854)
		(stroke
			(width 0.2)
			(type default)
		)
		(layer "In1.Cu")
	)
	(gr_arc
		(start 310.906414 -211.406994)
		(mid 311.417208 -210.896581)
		(end 310.906668 -210.385914)
		(stroke
			(width 0.2)
			(type default)
		)
		(layer "In1.Cu")
	)
	(gr_line
		(start 310.906668 -210.385914)
		(end 310.093868 -210.385914)
		(stroke
			(width 0.2)
			(type default)
		)
		(layer "In1.Cu")
	)
	(gr_line
		(start 310.935116 -18.02511)
		(end 310.937402 -18.02638)
		(stroke
			(width 0.2)
			(type default)
		)
		(layer "In1.Cu")
	)
	(gr_line
		(start 310.93537 -25.625044)
		(end 310.937402 -25.626314)
		(stroke
			(width 0.2)
			(type default)
		)
		(layer "In1.Cu")
	)
	(gr_line
		(start 310.93537 -21.82495)
		(end 310.937402 -21.82622)
		(stroke
			(width 0.2)
			(type default)
		)
		(layer "In1.Cu")
	)
	(gr_line
		(start 310.93537 -14.225016)
		(end 310.937402 -14.226286)
		(stroke
			(width 0.2)
			(type default)
		)
		(layer "In1.Cu")
	)
	(gr_line
		(start 310.937402 -25.626314)
		(end 311.687464 -24.226266)
		(stroke
			(width 0.2)
			(type default)
		)
		(layer "In1.Cu")
	)
	(gr_line
		(start 310.937402 -21.82622)
		(end 311.687464 -20.426426)
		(stroke
			(width 0.2)
			(type default)
		)
		(layer "In1.Cu")
	)
	(gr_line
		(start 310.937402 -18.02638)
		(end 311.687464 -16.626586)
		(stroke
			(width 0.2)
			(type default)
		)
		(layer "In1.Cu")
	)
	(gr_line
		(start 310.937402 -14.226286)
		(end 311.687464 -12.826238)
		(stroke
			(width 0.2)
			(type default)
		)
		(layer "In1.Cu")
	)
	(gr_arc
		(start 311.211214 -213.207854)
		(mid 311.301017 -213.170657)
		(end 311.338214 -213.080854)
		(stroke
			(width 0.2)
			(type default)
		)
		(layer "In1.Cu")
	)
	(gr_line
		(start 311.211214 -211.633054)
		(end 309.788814 -211.633054)
		(stroke
			(width 0.2)
			(type default)
		)
		(layer "In1.Cu")
	)
	(gr_arc
		(start 311.238138 -35.55238)
		(mid 311.748932 -35.041967)
		(end 311.238392 -34.5313)
		(stroke
			(width 0.2)
			(type default)
		)
		(layer "In1.Cu")
	)
	(gr_line
		(start 311.238392 -34.5313)
		(end 310.425592 -34.5313)
		(stroke
			(width 0.2)
			(type default)
		)
		(layer "In1.Cu")
	)
	(gr_line
		(start 311.338214 -213.080854)
		(end 311.338214 -211.760054)
		(stroke
			(width 0.2)
			(type default)
		)
		(layer "In1.Cu")
	)
	(gr_arc
		(start 311.338214 -211.760054)
		(mid 311.301017 -211.670251)
		(end 311.211214 -211.633054)
		(stroke
			(width 0.2)
			(type default)
		)
		(layer "In1.Cu")
	)
	(gr_arc
		(start 311.466992 -34.343086)
		(mid 311.556795 -34.305889)
		(end 311.593992 -34.216086)
		(stroke
			(width 0.2)
			(type default)
		)
		(layer "In1.Cu")
	)
	(gr_line
		(start 311.466992 -32.768286)
		(end 310.171592 -32.768286)
		(stroke
			(width 0.2)
			(type default)
		)
		(layer "In1.Cu")
	)
	(gr_line
		(start 311.593992 -34.216086)
		(end 311.593992 -32.895286)
		(stroke
			(width 0.2)
			(type default)
		)
		(layer "In1.Cu")
	)
	(gr_arc
		(start 311.593992 -32.895286)
		(mid 311.556795 -32.805483)
		(end 311.466992 -32.768286)
		(stroke
			(width 0.2)
			(type default)
		)
		(layer "In1.Cu")
	)
	(gr_arc
		(start 311.685178 -20.425156)
		(mid 311.429502 -19.579255)
		(end 310.58358 -19.835114)
		(stroke
			(width 0.2)
			(type default)
		)
		(layer "In1.Cu")
	)
	(gr_arc
		(start 311.685178 -16.625316)
		(mid 311.429654 -15.779496)
		(end 310.583834 -16.03502)
		(stroke
			(width 0.2)
			(type default)
		)
		(layer "In1.Cu")
	)
	(gr_arc
		(start 311.685432 -24.224996)
		(mid 311.4294 -23.379176)
		(end 310.58358 -23.635208)
		(stroke
			(width 0.2)
			(type default)
		)
		(layer "In1.Cu")
	)
	(gr_arc
		(start 311.685432 -12.824968)
		(mid 311.4294 -11.979148)
		(end 310.58358 -12.23518)
		(stroke
			(width 0.2)
			(type default)
		)
		(layer "In1.Cu")
	)
	(gr_line
		(start 311.68721 -20.426172)
		(end 311.685178 -20.425156)
		(stroke
			(width 0.2)
			(type default)
		)
		(layer "In1.Cu")
	)
	(gr_line
		(start 311.687464 -24.226266)
		(end 311.685432 -24.224996)
		(stroke
			(width 0.2)
			(type default)
		)
		(layer "In1.Cu")
	)
	(gr_line
		(start 311.687464 -20.426426)
		(end 311.68721 -20.426172)
		(stroke
			(width 0.2)
			(type default)
		)
		(layer "In1.Cu")
	)
	(gr_line
		(start 311.687464 -16.626586)
		(end 311.685178 -16.625316)
		(stroke
			(width 0.2)
			(type default)
		)
		(layer "In1.Cu")
	)
	(gr_line
		(start 311.687464 -12.826238)
		(end 311.685432 -12.824968)
		(stroke
			(width 0.2)
			(type default)
		)
		(layer "In1.Cu")
	)
	(gr_line
		(start 311.69356 -222.805244)
		(end 312.506106 -222.805244)
		(stroke
			(width 0.2)
			(type default)
		)
		(layer "In1.Cu")
	)
	(gr_arc
		(start 311.69356 -221.784164)
		(mid 311.18302 -222.294704)
		(end 311.69356 -222.805244)
		(stroke
			(width 0.2)
			(type default)
		)
		(layer "In1.Cu")
	)
	(gr_line
		(start 312.081418 -25.033732)
		(end 312.081672 -25.033986)
		(stroke
			(width 0.2)
			(type default)
		)
		(layer "In1.Cu")
	)
	(gr_line
		(start 312.081418 -21.233892)
		(end 312.08345 -21.235162)
		(stroke
			(width 0.2)
			(type default)
		)
		(layer "In1.Cu")
	)
	(gr_line
		(start 312.081418 -17.433544)
		(end 312.081672 -17.433798)
		(stroke
			(width 0.2)
			(type default)
		)
		(layer "In1.Cu")
	)
	(gr_line
		(start 312.081418 -13.633704)
		(end 312.081672 -13.633958)
		(stroke
			(width 0.2)
			(type default)
		)
		(layer "In1.Cu")
	)
	(gr_line
		(start 312.081672 -25.033986)
		(end 312.083704 -25.035002)
		(stroke
			(width 0.2)
			(type default)
		)
		(layer "In1.Cu")
	)
	(gr_line
		(start 312.081672 -17.433798)
		(end 312.083704 -17.434814)
		(stroke
			(width 0.2)
			(type default)
		)
		(layer "In1.Cu")
	)
	(gr_line
		(start 312.081672 -13.633958)
		(end 312.083704 -13.634974)
		(stroke
			(width 0.2)
			(type default)
		)
		(layer "In1.Cu")
	)
	(gr_arc
		(start 312.08345 -21.235162)
		(mid 312.339482 -22.080982)
		(end 313.185302 -21.82495)
		(stroke
			(width 0.2)
			(type default)
		)
		(layer "In1.Cu")
	)
	(gr_arc
		(start 312.083704 -25.035002)
		(mid 312.33938 -25.880903)
		(end 313.185302 -25.625044)
		(stroke
			(width 0.2)
			(type default)
		)
		(layer "In1.Cu")
	)
	(gr_arc
		(start 312.083704 -17.434814)
		(mid 312.339228 -18.280634)
		(end 313.185048 -18.02511)
		(stroke
			(width 0.2)
			(type default)
		)
		(layer "In1.Cu")
	)
	(gr_arc
		(start 312.083704 -13.634974)
		(mid 312.33938 -14.480875)
		(end 313.185302 -14.225016)
		(stroke
			(width 0.2)
			(type default)
		)
		(layer "In1.Cu")
	)
	(gr_arc
		(start 312.295286 -34.216848)
		(mid 312.332483 -34.306651)
		(end 312.422286 -34.343848)
		(stroke
			(width 0.2)
			(type default)
		)
		(layer "In1.Cu")
	)
	(gr_line
		(start 312.295286 -32.896048)
		(end 312.295286 -34.216848)
		(stroke
			(width 0.2)
			(type default)
		)
		(layer "In1.Cu")
	)
	(gr_line
		(start 312.422286 -34.343848)
		(end 313.717686 -34.343848)
		(stroke
			(width 0.2)
			(type default)
		)
		(layer "In1.Cu")
	)
	(gr_arc
		(start 312.422286 -32.769048)
		(mid 312.332483 -32.806245)
		(end 312.295286 -32.896048)
		(stroke
			(width 0.2)
			(type default)
		)
		(layer "In1.Cu")
	)
	(gr_arc
		(start 312.506106 -222.805244)
		(mid 313.0169 -222.294831)
		(end 312.50636 -221.784164)
		(stroke
			(width 0.2)
			(type default)
		)
		(layer "In1.Cu")
	)
	(gr_line
		(start 312.50636 -221.784164)
		(end 311.69356 -221.784164)
		(stroke
			(width 0.2)
			(type default)
		)
		(layer "In1.Cu")
	)
	(gr_line
		(start 312.676286 -36.696142)
		(end 313.489086 -36.696142)
		(stroke
			(width 0.2)
			(type default)
		)
		(layer "In1.Cu")
	)
	(gr_arc
		(start 312.67654 -35.675062)
		(mid 312.165746 -36.185475)
		(end 312.676286 -36.696142)
		(stroke
			(width 0.2)
			(type default)
		)
		(layer "In1.Cu")
	)
	(gr_line
		(start 312.83148 -23.633938)
		(end 312.081418 -25.033732)
		(stroke
			(width 0.2)
			(type default)
		)
		(layer "In1.Cu")
	)
	(gr_line
		(start 312.83148 -19.833844)
		(end 312.081418 -21.233892)
		(stroke
			(width 0.2)
			(type default)
		)
		(layer "In1.Cu")
	)
	(gr_line
		(start 312.83148 -16.03375)
		(end 312.081418 -17.433544)
		(stroke
			(width 0.2)
			(type default)
		)
		(layer "In1.Cu")
	)
	(gr_line
		(start 312.83148 -12.23391)
		(end 312.081418 -13.633704)
		(stroke
			(width 0.2)
			(type default)
		)
		(layer "In1.Cu")
	)
	(gr_line
		(start 312.833512 -23.635208)
		(end 312.83148 -23.633938)
		(stroke
			(width 0.2)
			(type default)
		)
		(layer "In1.Cu")
	)
	(gr_line
		(start 312.833512 -19.835114)
		(end 312.83148 -19.833844)
		(stroke
			(width 0.2)
			(type default)
		)
		(layer "In1.Cu")
	)
	(gr_line
		(start 312.833512 -12.23518)
		(end 312.83148 -12.23391)
		(stroke
			(width 0.2)
			(type default)
		)
		(layer "In1.Cu")
	)
	(gr_line
		(start 312.833766 -16.03502)
		(end 312.83148 -16.03375)
		(stroke
			(width 0.2)
			(type default)
		)
		(layer "In1.Cu")
	)
	(gr_arc
		(start 312.86196 -213.080854)
		(mid 312.899157 -213.170657)
		(end 312.98896 -213.207854)
		(stroke
			(width 0.2)
			(type default)
		)
		(layer "In1.Cu")
	)
	(gr_line
		(start 312.86196 -211.760054)
		(end 312.86196 -213.080854)
		(stroke
			(width 0.2)
			(type default)
		)
		(layer "In1.Cu")
	)
	(gr_line
		(start 312.98896 -213.207854)
		(end 313.39536 -213.207854)
		(stroke
			(width 0.2)
			(type default)
		)
		(layer "In1.Cu")
	)
	(gr_arc
		(start 312.98896 -211.633054)
		(mid 312.899157 -211.670251)
		(end 312.86196 -211.760054)
		(stroke
			(width 0.2)
			(type default)
		)
		(layer "In1.Cu")
	)
	(gr_line
		(start 313.185048 -18.02511)
		(end 313.187334 -18.02638)
		(stroke
			(width 0.2)
			(type default)
		)
		(layer "In1.Cu")
	)
	(gr_line
		(start 313.185302 -25.625044)
		(end 313.187334 -25.626314)
		(stroke
			(width 0.2)
			(type default)
		)
		(layer "In1.Cu")
	)
	(gr_line
		(start 313.185302 -21.82495)
		(end 313.187334 -21.82622)
		(stroke
			(width 0.2)
			(type default)
		)
		(layer "In1.Cu")
	)
	(gr_line
		(start 313.185302 -14.225016)
		(end 313.187334 -14.226286)
		(stroke
			(width 0.2)
			(type default)
		)
		(layer "In1.Cu")
	)
	(gr_line
		(start 313.187334 -25.626314)
		(end 313.937396 -24.226266)
		(stroke
			(width 0.2)
			(type default)
		)
		(layer "In1.Cu")
	)
	(gr_line
		(start 313.187334 -21.82622)
		(end 313.937396 -20.426426)
		(stroke
			(width 0.2)
			(type default)
		)
		(layer "In1.Cu")
	)
	(gr_line
		(start 313.187334 -18.02638)
		(end 313.937396 -16.626586)
		(stroke
			(width 0.2)
			(type default)
		)
		(layer "In1.Cu")
	)
	(gr_line
		(start 313.187334 -14.226286)
		(end 313.937396 -12.826238)
		(stroke
			(width 0.2)
			(type default)
		)
		(layer "In1.Cu")
	)
	(gr_line
		(start 313.29376 -211.406994)
		(end 314.10656 -211.406994)
		(stroke
			(width 0.2)
			(type default)
		)
		(layer "In1.Cu")
	)
	(gr_arc
		(start 313.294014 -210.385914)
		(mid 312.78322 -210.896327)
		(end 313.29376 -211.406994)
		(stroke
			(width 0.2)
			(type default)
		)
		(layer "In1.Cu")
	)
	(gr_line
		(start 313.39536 -213.207854)
		(end 313.395614 -213.2076)
		(stroke
			(width 0.2)
			(type default)
		)
		(layer "In1.Cu")
	)
	(gr_line
		(start 313.395614 -213.2076)
		(end 313.996832 -213.2076)
		(stroke
			(width 0.2)
			(type default)
		)
		(layer "In1.Cu")
	)
	(gr_arc
		(start 313.489086 -36.696142)
		(mid 313.999626 -36.185602)
		(end 313.489086 -35.675062)
		(stroke
			(width 0.2)
			(type default)
		)
		(layer "In1.Cu")
	)
	(gr_line
		(start 313.489086 -35.675062)
		(end 312.67654 -35.675062)
		(stroke
			(width 0.2)
			(type default)
		)
		(layer "In1.Cu")
	)
	(gr_arc
		(start 313.717686 -34.343848)
		(mid 313.807489 -34.306651)
		(end 313.844686 -34.216848)
		(stroke
			(width 0.2)
			(type default)
		)
		(layer "In1.Cu")
	)
	(gr_line
		(start 313.717686 -32.769048)
		(end 312.422286 -32.769048)
		(stroke
			(width 0.2)
			(type default)
		)
		(layer "In1.Cu")
	)
	(gr_line
		(start 313.844686 -34.216848)
		(end 313.844686 -32.896048)
		(stroke
			(width 0.2)
			(type default)
		)
		(layer "In1.Cu")
	)
	(gr_arc
		(start 313.844686 -32.896048)
		(mid 313.807489 -32.806245)
		(end 313.717686 -32.769048)
		(stroke
			(width 0.2)
			(type default)
		)
		(layer "In1.Cu")
	)
	(gr_arc
		(start 313.93511 -20.425156)
		(mid 313.679434 -19.579255)
		(end 312.833512 -19.835114)
		(stroke
			(width 0.2)
			(type default)
		)
		(layer "In1.Cu")
	)
	(gr_arc
		(start 313.93511 -16.625316)
		(mid 313.679586 -15.779496)
		(end 312.833766 -16.03502)
		(stroke
			(width 0.2)
			(type default)
		)
		(layer "In1.Cu")
	)
	(gr_arc
		(start 313.935364 -24.224996)
		(mid 313.679332 -23.379176)
		(end 312.833512 -23.635208)
		(stroke
			(width 0.2)
			(type default)
		)
		(layer "In1.Cu")
	)
	(gr_arc
		(start 313.935364 -12.824968)
		(mid 313.679332 -11.979148)
		(end 312.833512 -12.23518)
		(stroke
			(width 0.2)
			(type default)
		)
		(layer "In1.Cu")
	)
	(gr_line
		(start 313.937142 -20.426172)
		(end 313.93511 -20.425156)
		(stroke
			(width 0.2)
			(type default)
		)
		(layer "In1.Cu")
	)
	(gr_line
		(start 313.937396 -24.226266)
		(end 313.935364 -24.224996)
		(stroke
			(width 0.2)
			(type default)
		)
		(layer "In1.Cu")
	)
	(gr_line
		(start 313.937396 -20.426426)
		(end 313.937142 -20.426172)
		(stroke
			(width 0.2)
			(type default)
		)
		(layer "In1.Cu")
	)
	(gr_line
		(start 313.937396 -16.626586)
		(end 313.93511 -16.625316)
		(stroke
			(width 0.2)
			(type default)
		)
		(layer "In1.Cu")
	)
	(gr_line
		(start 313.937396 -12.826238)
		(end 313.935364 -12.824968)
		(stroke
			(width 0.2)
			(type default)
		)
		(layer "In1.Cu")
	)
	(gr_arc
		(start 313.996832 -213.2076)
		(mid 314.000894 -213.207795)
		(end 314.00496 -213.207854)
		(stroke
			(width 0.2)
			(type default)
		)
		(layer "In1.Cu")
	)
	(gr_line
		(start 314.00496 -213.207854)
		(end 314.41136 -213.207854)
		(stroke
			(width 0.2)
			(type default)
		)
		(layer "In1.Cu")
	)
	(gr_arc
		(start 314.10656 -211.406994)
		(mid 314.6171 -210.896454)
		(end 314.10656 -210.385914)
		(stroke
			(width 0.2)
			(type default)
		)
		(layer "In1.Cu")
	)
	(gr_line
		(start 314.10656 -210.385914)
		(end 313.294014 -210.385914)
		(stroke
			(width 0.2)
			(type default)
		)
		(layer "In1.Cu")
	)
	(gr_arc
		(start 314.41136 -213.207854)
		(mid 314.501163 -213.170657)
		(end 314.53836 -213.080854)
		(stroke
			(width 0.2)
			(type default)
		)
		(layer "In1.Cu")
	)
	(gr_line
		(start 314.41136 -211.633054)
		(end 312.98896 -211.633054)
		(stroke
			(width 0.2)
			(type default)
		)
		(layer "In1.Cu")
	)
	(gr_arc
		(start 314.5028 -34.1884)
		(mid 314.539997 -34.278203)
		(end 314.6298 -34.3154)
		(stroke
			(width 0.2)
			(type default)
		)
		(layer "In1.Cu")
	)
	(gr_line
		(start 314.5028 -32.8676)
		(end 314.5028 -34.1884)
		(stroke
			(width 0.2)
			(type default)
		)
		(layer "In1.Cu")
	)
	(gr_line
		(start 314.53836 -213.080854)
		(end 314.53836 -211.760054)
		(stroke
			(width 0.2)
			(type default)
		)
		(layer "In1.Cu")
	)
	(gr_arc
		(start 314.53836 -211.760054)
		(mid 314.501163 -211.670251)
		(end 314.41136 -211.633054)
		(stroke
			(width 0.2)
			(type default)
		)
		(layer "In1.Cu")
	)
	(gr_line
		(start 314.6298 -34.3154)
		(end 315.9252 -34.3154)
		(stroke
			(width 0.2)
			(type default)
		)
		(layer "In1.Cu")
	)
	(gr_arc
		(start 314.6298 -32.7406)
		(mid 314.539997 -32.777797)
		(end 314.5028 -32.8676)
		(stroke
			(width 0.2)
			(type default)
		)
		(layer "In1.Cu")
	)
	(gr_line
		(start 314.8838 -35.524694)
		(end 315.696346 -35.524694)
		(stroke
			(width 0.2)
			(type default)
		)
		(layer "In1.Cu")
	)
	(gr_arc
		(start 314.8838 -34.503614)
		(mid 314.37326 -35.014154)
		(end 314.8838 -35.524694)
		(stroke
			(width 0.2)
			(type default)
		)
		(layer "In1.Cu")
	)
	(gr_line
		(start 314.893706 -222.805244)
		(end 315.706252 -222.805244)
		(stroke
			(width 0.2)
			(type default)
		)
		(layer "In1.Cu")
	)
	(gr_arc
		(start 314.893706 -221.784164)
		(mid 314.383166 -222.294704)
		(end 314.893706 -222.805244)
		(stroke
			(width 0.2)
			(type default)
		)
		(layer "In1.Cu")
	)
	(gr_arc
		(start 315.696346 -35.524694)
		(mid 316.20714 -35.014281)
		(end 315.6966 -34.503614)
		(stroke
			(width 0.2)
			(type default)
		)
		(layer "In1.Cu")
	)
	(gr_line
		(start 315.6966 -34.503614)
		(end 314.8838 -34.503614)
		(stroke
			(width 0.2)
			(type default)
		)
		(layer "In1.Cu")
	)
	(gr_arc
		(start 315.706252 -222.805244)
		(mid 316.217046 -222.294831)
		(end 315.706506 -221.784164)
		(stroke
			(width 0.2)
			(type default)
		)
		(layer "In1.Cu")
	)
	(gr_line
		(start 315.706506 -221.784164)
		(end 314.893706 -221.784164)
		(stroke
			(width 0.2)
			(type default)
		)
		(layer "In1.Cu")
	)
	(gr_arc
		(start 315.9252 -34.3154)
		(mid 316.015003 -34.278203)
		(end 316.0522 -34.1884)
		(stroke
			(width 0.2)
			(type default)
		)
		(layer "In1.Cu")
	)
	(gr_line
		(start 315.9252 -32.7406)
		(end 314.6298 -32.7406)
		(stroke
			(width 0.2)
			(type default)
		)
		(layer "In1.Cu")
	)
	(gr_line
		(start 316.0522 -34.1884)
		(end 316.0522 -32.8676)
		(stroke
			(width 0.2)
			(type default)
		)
		(layer "In1.Cu")
	)
	(gr_arc
		(start 316.0522 -32.8676)
		(mid 316.015003 -32.777797)
		(end 315.9252 -32.7406)
		(stroke
			(width 0.2)
			(type default)
		)
		(layer "In1.Cu")
	)
	(gr_arc
		(start 316.061852 -213.080854)
		(mid 316.099049 -213.170657)
		(end 316.188852 -213.207854)
		(stroke
			(width 0.2)
			(type default)
		)
		(layer "In1.Cu")
	)
	(gr_line
		(start 316.061852 -211.760054)
		(end 316.061852 -213.080854)
		(stroke
			(width 0.2)
			(type default)
		)
		(layer "In1.Cu")
	)
	(gr_line
		(start 316.188852 -213.207854)
		(end 316.595252 -213.207854)
		(stroke
			(width 0.2)
			(type default)
		)
		(layer "In1.Cu")
	)
	(gr_arc
		(start 316.188852 -211.633054)
		(mid 316.099049 -211.670251)
		(end 316.061852 -211.760054)
		(stroke
			(width 0.2)
			(type default)
		)
		(layer "In1.Cu")
	)
	(gr_line
		(start 316.493906 -211.406994)
		(end 317.306706 -211.406994)
		(stroke
			(width 0.2)
			(type default)
		)
		(layer "In1.Cu")
	)
	(gr_arc
		(start 316.49416 -210.385914)
		(mid 315.983366 -210.896327)
		(end 316.493906 -211.406994)
		(stroke
			(width 0.2)
			(type default)
		)
		(layer "In1.Cu")
	)
	(gr_line
		(start 316.595252 -213.207854)
		(end 316.595506 -213.2076)
		(stroke
			(width 0.2)
			(type default)
		)
		(layer "In1.Cu")
	)
	(gr_line
		(start 316.595506 -213.2076)
		(end 317.196724 -213.2076)
		(stroke
			(width 0.2)
			(type default)
		)
		(layer "In1.Cu")
	)
	(gr_arc
		(start 317.196724 -213.2076)
		(mid 317.200786 -213.207795)
		(end 317.204852 -213.207854)
		(stroke
			(width 0.2)
			(type default)
		)
		(layer "In1.Cu")
	)
	(gr_line
		(start 317.204852 -213.207854)
		(end 317.611252 -213.207854)
		(stroke
			(width 0.2)
			(type default)
		)
		(layer "In1.Cu")
	)
	(gr_arc
		(start 317.306706 -211.406994)
		(mid 317.817246 -210.896454)
		(end 317.306706 -210.385914)
		(stroke
			(width 0.2)
			(type default)
		)
		(layer "In1.Cu")
	)
	(gr_line
		(start 317.306706 -210.385914)
		(end 316.49416 -210.385914)
		(stroke
			(width 0.2)
			(type default)
		)
		(layer "In1.Cu")
	)
	(gr_arc
		(start 317.611252 -213.207854)
		(mid 317.701055 -213.170657)
		(end 317.738252 -213.080854)
		(stroke
			(width 0.2)
			(type default)
		)
		(layer "In1.Cu")
	)
	(gr_line
		(start 317.611252 -211.633054)
		(end 316.188852 -211.633054)
		(stroke
			(width 0.2)
			(type default)
		)
		(layer "In1.Cu")
	)
	(gr_line
		(start 317.738252 -213.080854)
		(end 317.738252 -211.760054)
		(stroke
			(width 0.2)
			(type default)
		)
		(layer "In1.Cu")
	)
	(gr_arc
		(start 317.738252 -211.760054)
		(mid 317.701055 -211.670251)
		(end 317.611252 -211.633054)
		(stroke
			(width 0.2)
			(type default)
		)
		(layer "In1.Cu")
	)
	(gr_line
		(start 318.093598 -222.805244)
		(end 318.906144 -222.805244)
		(stroke
			(width 0.2)
			(type default)
		)
		(layer "In1.Cu")
	)
	(gr_arc
		(start 318.093598 -221.784164)
		(mid 317.583058 -222.294704)
		(end 318.093598 -222.805244)
		(stroke
			(width 0.2)
			(type default)
		)
		(layer "In1.Cu")
	)
	(gr_arc
		(start 318.583564 -25.035256)
		(mid 318.839596 -25.881076)
		(end 319.685416 -25.625044)
		(stroke
			(width 0.2)
			(type default)
		)
		(layer "In1.Cu")
	)
	(gr_arc
		(start 318.587628 -13.627608)
		(mid 318.835762 -14.479061)
		(end 319.685416 -14.225016)
		(stroke
			(width 0.2)
			(type default)
		)
		(layer "In1.Cu")
	)
	(gr_arc
		(start 318.906144 -222.805244)
		(mid 319.416938 -222.294831)
		(end 318.906398 -221.784164)
		(stroke
			(width 0.2)
			(type default)
		)
		(layer "In1.Cu")
	)
	(gr_line
		(start 318.906398 -221.784164)
		(end 318.093598 -221.784164)
		(stroke
			(width 0.2)
			(type default)
		)
		(layer "In1.Cu")
	)
	(gr_arc
		(start 319.261998 -213.080854)
		(mid 319.299195 -213.170657)
		(end 319.388998 -213.207854)
		(stroke
			(width 0.2)
			(type default)
		)
		(layer "In1.Cu")
	)
	(gr_line
		(start 319.261998 -211.760054)
		(end 319.261998 -213.080854)
		(stroke
			(width 0.2)
			(type default)
		)
		(layer "In1.Cu")
	)
	(gr_line
		(start 319.333372 -23.635208)
		(end 318.583564 -25.035256)
		(stroke
			(width 0.2)
			(type default)
		)
		(layer "In1.Cu")
	)
	(gr_line
		(start 319.333372 -12.23518)
		(end 318.587628 -13.627608)
		(stroke
			(width 0.2)
			(type default)
		)
		(layer "In1.Cu")
	)
	(gr_arc
		(start 319.339976 -34.167826)
		(mid 319.377173 -34.257629)
		(end 319.466976 -34.294826)
		(stroke
			(width 0.2)
			(type default)
		)
		(layer "In1.Cu")
	)
	(gr_line
		(start 319.339976 -32.847026)
		(end 319.339976 -34.167826)
		(stroke
			(width 0.2)
			(type default)
		)
		(layer "In1.Cu")
	)
	(gr_line
		(start 319.388998 -213.207854)
		(end 319.795398 -213.207854)
		(stroke
			(width 0.2)
			(type default)
		)
		(layer "In1.Cu")
	)
	(gr_arc
		(start 319.388998 -211.633054)
		(mid 319.299195 -211.670251)
		(end 319.261998 -211.760054)
		(stroke
			(width 0.2)
			(type default)
		)
		(layer "In1.Cu")
	)
	(gr_line
		(start 319.466976 -34.294826)
		(end 320.762376 -34.294826)
		(stroke
			(width 0.2)
			(type default)
		)
		(layer "In1.Cu")
	)
	(gr_arc
		(start 319.466976 -32.720026)
		(mid 319.377173 -32.757223)
		(end 319.339976 -32.847026)
		(stroke
			(width 0.2)
			(type default)
		)
		(layer "In1.Cu")
	)
	(gr_line
		(start 319.685416 -25.625044)
		(end 320.43116 -24.232616)
		(stroke
			(width 0.2)
			(type default)
		)
		(layer "In1.Cu")
	)
	(gr_line
		(start 319.685416 -14.225016)
		(end 320.435224 -12.824968)
		(stroke
			(width 0.2)
			(type default)
		)
		(layer "In1.Cu")
	)
	(gr_line
		(start 319.693798 -211.406994)
		(end 320.506598 -211.406994)
		(stroke
			(width 0.2)
			(type default)
		)
		(layer "In1.Cu")
	)
	(gr_arc
		(start 319.694052 -210.385914)
		(mid 319.183258 -210.896327)
		(end 319.693798 -211.406994)
		(stroke
			(width 0.2)
			(type default)
		)
		(layer "In1.Cu")
	)
	(gr_line
		(start 319.720976 -37.53612)
		(end 320.533522 -37.53612)
		(stroke
			(width 0.2)
			(type default)
		)
		(layer "In1.Cu")
	)
	(gr_line
		(start 319.720976 -37.53612)
		(end 320.533776 -37.53612)
		(stroke
			(width 0.2)
			(type default)
		)
		(layer "In1.Cu")
	)
	(gr_arc
		(start 319.720976 -36.51504)
		(mid 319.210436 -37.02558)
		(end 319.720976 -37.53612)
		(stroke
			(width 0.2)
			(type default)
		)
		(layer "In1.Cu")
	)
	(gr_arc
		(start 319.72123 -36.51504)
		(mid 319.210436 -37.025453)
		(end 319.720976 -37.53612)
		(stroke
			(width 0.2)
			(type default)
		)
		(layer "In1.Cu")
	)
	(gr_line
		(start 319.795398 -213.207854)
		(end 319.795652 -213.2076)
		(stroke
			(width 0.2)
			(type default)
		)
		(layer "In1.Cu")
	)
	(gr_line
		(start 319.795652 -213.2076)
		(end 320.39687 -213.2076)
		(stroke
			(width 0.2)
			(type default)
		)
		(layer "In1.Cu")
	)
	(gr_arc
		(start 320.39687 -213.2076)
		(mid 320.400932 -213.207795)
		(end 320.404998 -213.207854)
		(stroke
			(width 0.2)
			(type default)
		)
		(layer "In1.Cu")
	)
	(gr_line
		(start 320.404998 -213.207854)
		(end 320.811398 -213.207854)
		(stroke
			(width 0.2)
			(type default)
		)
		(layer "In1.Cu")
	)
	(gr_arc
		(start 320.43116 -24.232616)
		(mid 320.183026 -23.381163)
		(end 319.333372 -23.635208)
		(stroke
			(width 0.2)
			(type default)
		)
		(layer "In1.Cu")
	)
	(gr_arc
		(start 320.435224 -12.824968)
		(mid 320.179192 -11.979148)
		(end 319.333372 -12.23518)
		(stroke
			(width 0.2)
			(type default)
		)
		(layer "In1.Cu")
	)
	(gr_arc
		(start 320.506598 -211.406994)
		(mid 321.017138 -210.896454)
		(end 320.506598 -210.385914)
		(stroke
			(width 0.2)
			(type default)
		)
		(layer "In1.Cu")
	)
	(gr_line
		(start 320.506598 -210.385914)
		(end 319.694052 -210.385914)
		(stroke
			(width 0.2)
			(type default)
		)
		(layer "In1.Cu")
	)
	(gr_arc
		(start 320.533522 -37.53612)
		(mid 321.044316 -37.025707)
		(end 320.533776 -36.51504)
		(stroke
			(width 0.2)
			(type default)
		)
		(layer "In1.Cu")
	)
	(gr_arc
		(start 320.533776 -37.53612)
		(mid 321.044316 -37.02558)
		(end 320.533776 -36.51504)
		(stroke
			(width 0.2)
			(type default)
		)
		(layer "In1.Cu")
	)
	(gr_line
		(start 320.533776 -36.51504)
		(end 319.720976 -36.51504)
		(stroke
			(width 0.2)
			(type default)
		)
		(layer "In1.Cu")
	)
	(gr_line
		(start 320.533776 -36.51504)
		(end 319.72123 -36.51504)
		(stroke
			(width 0.2)
			(type default)
		)
		(layer "In1.Cu")
	)
	(gr_arc
		(start 320.762376 -34.294826)
		(mid 320.852179 -34.257629)
		(end 320.889376 -34.167826)
		(stroke
			(width 0.2)
			(type default)
		)
		(layer "In1.Cu")
	)
	(gr_line
		(start 320.762376 -32.720026)
		(end 319.466976 -32.720026)
		(stroke
			(width 0.2)
			(type default)
		)
		(layer "In1.Cu")
	)
	(gr_arc
		(start 320.811398 -213.207854)
		(mid 320.901201 -213.170657)
		(end 320.938398 -213.080854)
		(stroke
			(width 0.2)
			(type default)
		)
		(layer "In1.Cu")
	)
	(gr_line
		(start 320.811398 -211.633054)
		(end 319.388998 -211.633054)
		(stroke
			(width 0.2)
			(type default)
		)
		(layer "In1.Cu")
	)
	(gr_line
		(start 320.831464 -25.033732)
		(end 320.831718 -25.033986)
		(stroke
			(width 0.2)
			(type default)
		)
		(layer "In1.Cu")
	)
	(gr_line
		(start 320.831464 -21.233892)
		(end 320.833496 -21.235162)
		(stroke
			(width 0.2)
			(type default)
		)
		(layer "In1.Cu")
	)
	(gr_line
		(start 320.831464 -17.433544)
		(end 320.831718 -17.433798)
		(stroke
			(width 0.2)
			(type default)
		)
		(layer "In1.Cu")
	)
	(gr_line
		(start 320.831464 -13.633704)
		(end 320.831718 -13.633958)
		(stroke
			(width 0.2)
			(type default)
		)
		(layer "In1.Cu")
	)
	(gr_line
		(start 320.831718 -25.033986)
		(end 320.83375 -25.035002)
		(stroke
			(width 0.2)
			(type default)
		)
		(layer "In1.Cu")
	)
	(gr_line
		(start 320.831718 -17.433798)
		(end 320.83375 -17.434814)
		(stroke
			(width 0.2)
			(type default)
		)
		(layer "In1.Cu")
	)
	(gr_line
		(start 320.831718 -13.633958)
		(end 320.83375 -13.634974)
		(stroke
			(width 0.2)
			(type default)
		)
		(layer "In1.Cu")
	)
	(gr_arc
		(start 320.833496 -21.235162)
		(mid 321.089528 -22.080982)
		(end 321.935348 -21.82495)
		(stroke
			(width 0.2)
			(type default)
		)
		(layer "In1.Cu")
	)
	(gr_arc
		(start 320.83375 -25.035002)
		(mid 321.089426 -25.880903)
		(end 321.935348 -25.625044)
		(stroke
			(width 0.2)
			(type default)
		)
		(layer "In1.Cu")
	)
	(gr_arc
		(start 320.83375 -17.434814)
		(mid 321.089274 -18.280634)
		(end 321.935094 -18.02511)
		(stroke
			(width 0.2)
			(type default)
		)
		(layer "In1.Cu")
	)
	(gr_arc
		(start 320.83375 -13.634974)
		(mid 321.089426 -14.480875)
		(end 321.935348 -14.225016)
		(stroke
			(width 0.2)
			(type default)
		)
		(layer "In1.Cu")
	)
	(gr_line
		(start 320.889376 -34.167826)
		(end 320.889376 -32.847026)
		(stroke
			(width 0.2)
			(type default)
		)
		(layer "In1.Cu")
	)
	(gr_arc
		(start 320.889376 -32.847026)
		(mid 320.852179 -32.757223)
		(end 320.762376 -32.720026)
		(stroke
			(width 0.2)
			(type default)
		)
		(layer "In1.Cu")
	)
	(gr_line
		(start 320.938398 -213.080854)
		(end 320.938398 -211.760054)
		(stroke
			(width 0.2)
			(type default)
		)
		(layer "In1.Cu")
	)
	(gr_arc
		(start 320.938398 -211.760054)
		(mid 320.901201 -211.670251)
		(end 320.811398 -211.633054)
		(stroke
			(width 0.2)
			(type default)
		)
		(layer "In1.Cu")
	)
	(gr_line
		(start 321.293744 -222.805244)
		(end 322.10629 -222.805244)
		(stroke
			(width 0.2)
			(type default)
		)
		(layer "In1.Cu")
	)
	(gr_arc
		(start 321.293744 -221.784164)
		(mid 320.783204 -222.294704)
		(end 321.293744 -222.805244)
		(stroke
			(width 0.2)
			(type default)
		)
		(layer "In1.Cu")
	)
	(gr_line
		(start 321.581526 -23.633938)
		(end 320.831464 -25.033732)
		(stroke
			(width 0.2)
			(type default)
		)
		(layer "In1.Cu")
	)
	(gr_line
		(start 321.581526 -19.833844)
		(end 320.831464 -21.233892)
		(stroke
			(width 0.2)
			(type default)
		)
		(layer "In1.Cu")
	)
	(gr_line
		(start 321.581526 -16.03375)
		(end 320.831464 -17.433544)
		(stroke
			(width 0.2)
			(type default)
		)
		(layer "In1.Cu")
	)
	(gr_line
		(start 321.581526 -12.23391)
		(end 320.831464 -13.633704)
		(stroke
			(width 0.2)
			(type default)
		)
		(layer "In1.Cu")
	)
	(gr_line
		(start 321.583558 -23.635208)
		(end 321.581526 -23.633938)
		(stroke
			(width 0.2)
			(type default)
		)
		(layer "In1.Cu")
	)
	(gr_line
		(start 321.583558 -19.835114)
		(end 321.581526 -19.833844)
		(stroke
			(width 0.2)
			(type default)
		)
		(layer "In1.Cu")
	)
	(gr_line
		(start 321.583558 -12.23518)
		(end 321.581526 -12.23391)
		(stroke
			(width 0.2)
			(type default)
		)
		(layer "In1.Cu")
	)
	(gr_line
		(start 321.583812 -16.03502)
		(end 321.581526 -16.03375)
		(stroke
			(width 0.2)
			(type default)
		)
		(layer "In1.Cu")
	)
	(gr_line
		(start 321.935094 -18.02511)
		(end 321.93738 -18.02638)
		(stroke
			(width 0.2)
			(type default)
		)
		(layer "In1.Cu")
	)
	(gr_line
		(start 321.935348 -25.625044)
		(end 321.93738 -25.626314)
		(stroke
			(width 0.2)
			(type default)
		)
		(layer "In1.Cu")
	)
	(gr_line
		(start 321.935348 -21.82495)
		(end 321.93738 -21.82622)
		(stroke
			(width 0.2)
			(type default)
		)
		(layer "In1.Cu")
	)
	(gr_line
		(start 321.935348 -14.225016)
		(end 321.93738 -14.226286)
		(stroke
			(width 0.2)
			(type default)
		)
		(layer "In1.Cu")
	)
	(gr_line
		(start 321.93738 -25.626314)
		(end 322.687442 -24.226266)
		(stroke
			(width 0.2)
			(type default)
		)
		(layer "In1.Cu")
	)
	(gr_line
		(start 321.93738 -21.82622)
		(end 322.687442 -20.426426)
		(stroke
			(width 0.2)
			(type default)
		)
		(layer "In1.Cu")
	)
	(gr_line
		(start 321.93738 -18.02638)
		(end 322.687442 -16.626586)
		(stroke
			(width 0.2)
			(type default)
		)
		(layer "In1.Cu")
	)
	(gr_line
		(start 321.93738 -14.226286)
		(end 322.687442 -12.826238)
		(stroke
			(width 0.2)
			(type default)
		)
		(layer "In1.Cu")
	)
	(gr_arc
		(start 322.10629 -222.805244)
		(mid 322.617084 -222.294831)
		(end 322.106544 -221.784164)
		(stroke
			(width 0.2)
			(type default)
		)
		(layer "In1.Cu")
	)
	(gr_line
		(start 322.106544 -221.784164)
		(end 321.293744 -221.784164)
		(stroke
			(width 0.2)
			(type default)
		)
		(layer "In1.Cu")
	)
	(gr_arc
		(start 322.46189 -213.080854)
		(mid 322.499087 -213.170657)
		(end 322.58889 -213.207854)
		(stroke
			(width 0.2)
			(type default)
		)
		(layer "In1.Cu")
	)
	(gr_line
		(start 322.46189 -211.760054)
		(end 322.46189 -213.080854)
		(stroke
			(width 0.2)
			(type default)
		)
		(layer "In1.Cu")
	)
	(gr_line
		(start 322.58889 -213.207854)
		(end 322.99529 -213.207854)
		(stroke
			(width 0.2)
			(type default)
		)
		(layer "In1.Cu")
	)
	(gr_arc
		(start 322.58889 -211.633054)
		(mid 322.499087 -211.670251)
		(end 322.46189 -211.760054)
		(stroke
			(width 0.2)
			(type default)
		)
		(layer "In1.Cu")
	)
	(gr_arc
		(start 322.685156 -20.425156)
		(mid 322.42948 -19.579255)
		(end 321.583558 -19.835114)
		(stroke
			(width 0.2)
			(type default)
		)
		(layer "In1.Cu")
	)
	(gr_arc
		(start 322.685156 -16.625316)
		(mid 322.429632 -15.779496)
		(end 321.583812 -16.03502)
		(stroke
			(width 0.2)
			(type default)
		)
		(layer "In1.Cu")
	)
	(gr_arc
		(start 322.68541 -24.224996)
		(mid 322.429378 -23.379176)
		(end 321.583558 -23.635208)
		(stroke
			(width 0.2)
			(type default)
		)
		(layer "In1.Cu")
	)
	(gr_arc
		(start 322.68541 -12.824968)
		(mid 322.429378 -11.979148)
		(end 321.583558 -12.23518)
		(stroke
			(width 0.2)
			(type default)
		)
		(layer "In1.Cu")
	)
	(gr_line
		(start 322.687188 -20.426172)
		(end 322.685156 -20.425156)
		(stroke
			(width 0.2)
			(type default)
		)
		(layer "In1.Cu")
	)
	(gr_line
		(start 322.687442 -24.226266)
		(end 322.68541 -24.224996)
		(stroke
			(width 0.2)
			(type default)
		)
		(layer "In1.Cu")
	)
	(gr_line
		(start 322.687442 -20.426426)
		(end 322.687188 -20.426172)
		(stroke
			(width 0.2)
			(type default)
		)
		(layer "In1.Cu")
	)
	(gr_line
		(start 322.687442 -16.626586)
		(end 322.685156 -16.625316)
		(stroke
			(width 0.2)
			(type default)
		)
		(layer "In1.Cu")
	)
	(gr_line
		(start 322.687442 -12.826238)
		(end 322.68541 -12.824968)
		(stroke
			(width 0.2)
			(type default)
		)
		(layer "In1.Cu")
	)
	(gr_line
		(start 322.89369 -211.406994)
		(end 323.70649 -211.406994)
		(stroke
			(width 0.2)
			(type default)
		)
		(layer "In1.Cu")
	)
	(gr_arc
		(start 322.893944 -210.385914)
		(mid 322.38315 -210.896327)
		(end 322.89369 -211.406994)
		(stroke
			(width 0.2)
			(type default)
		)
		(layer "In1.Cu")
	)
	(gr_line
		(start 322.99529 -213.207854)
		(end 322.995544 -213.2076)
		(stroke
			(width 0.2)
			(type default)
		)
		(layer "In1.Cu")
	)
	(gr_line
		(start 322.995544 -213.2076)
		(end 323.596762 -213.2076)
		(stroke
			(width 0.2)
			(type default)
		)
		(layer "In1.Cu")
	)
	(gr_line
		(start 323.081396 -25.033732)
		(end 323.08165 -25.033986)
		(stroke
			(width 0.2)
			(type default)
		)
		(layer "In1.Cu")
	)
	(gr_line
		(start 323.081396 -21.233892)
		(end 323.083428 -21.235162)
		(stroke
			(width 0.2)
			(type default)
		)
		(layer "In1.Cu")
	)
	(gr_line
		(start 323.081396 -17.433544)
		(end 323.08165 -17.433798)
		(stroke
			(width 0.2)
			(type default)
		)
		(layer "In1.Cu")
	)
	(gr_line
		(start 323.081396 -13.633704)
		(end 323.08165 -13.633958)
		(stroke
			(width 0.2)
			(type default)
		)
		(layer "In1.Cu")
	)
	(gr_line
		(start 323.08165 -25.033986)
		(end 323.083682 -25.035002)
		(stroke
			(width 0.2)
			(type default)
		)
		(layer "In1.Cu")
	)
	(gr_line
		(start 323.08165 -17.433798)
		(end 323.083682 -17.434814)
		(stroke
			(width 0.2)
			(type default)
		)
		(layer "In1.Cu")
	)
	(gr_line
		(start 323.08165 -13.633958)
		(end 323.083682 -13.634974)
		(stroke
			(width 0.2)
			(type default)
		)
		(layer "In1.Cu")
	)
	(gr_arc
		(start 323.083428 -21.235162)
		(mid 323.33946 -22.080982)
		(end 324.18528 -21.82495)
		(stroke
			(width 0.2)
			(type default)
		)
		(layer "In1.Cu")
	)
	(gr_arc
		(start 323.083682 -25.035002)
		(mid 323.339358 -25.880903)
		(end 324.18528 -25.625044)
		(stroke
			(width 0.2)
			(type default)
		)
		(layer "In1.Cu")
	)
	(gr_arc
		(start 323.083682 -17.434814)
		(mid 323.339206 -18.280634)
		(end 324.185026 -18.02511)
		(stroke
			(width 0.2)
			(type default)
		)
		(layer "In1.Cu")
	)
	(gr_arc
		(start 323.083682 -13.634974)
		(mid 323.339358 -14.480875)
		(end 324.18528 -14.225016)
		(stroke
			(width 0.2)
			(type default)
		)
		(layer "In1.Cu")
	)
	(gr_arc
		(start 323.23151 -34.143188)
		(mid 323.268707 -34.232991)
		(end 323.35851 -34.270188)
		(stroke
			(width 0.2)
			(type default)
		)
		(layer "In1.Cu")
	)
	(gr_line
		(start 323.23151 -32.822388)
		(end 323.23151 -34.143188)
		(stroke
			(width 0.2)
			(type default)
		)
		(layer "In1.Cu")
	)
	(gr_line
		(start 323.35851 -34.270188)
		(end 324.65391 -34.270188)
		(stroke
			(width 0.2)
			(type default)
		)
		(layer "In1.Cu")
	)
	(gr_arc
		(start 323.35851 -32.695388)
		(mid 323.268707 -32.732585)
		(end 323.23151 -32.822388)
		(stroke
			(width 0.2)
			(type default)
		)
		(layer "In1.Cu")
	)
	(gr_arc
		(start 323.596762 -213.2076)
		(mid 323.600824 -213.207795)
		(end 323.60489 -213.207854)
		(stroke
			(width 0.2)
			(type default)
		)
		(layer "In1.Cu")
	)
	(gr_line
		(start 323.60489 -213.207854)
		(end 324.01129 -213.207854)
		(stroke
			(width 0.2)
			(type default)
		)
		(layer "In1.Cu")
	)
	(gr_line
		(start 323.61251 -35.479482)
		(end 324.425056 -35.479482)
		(stroke
			(width 0.2)
			(type default)
		)
		(layer "In1.Cu")
	)
	(gr_line
		(start 323.61251 -35.479482)
		(end 324.42531 -35.479482)
		(stroke
			(width 0.2)
			(type default)
		)
		(layer "In1.Cu")
	)
	(gr_arc
		(start 323.61251 -34.458402)
		(mid 323.10197 -34.968942)
		(end 323.61251 -35.479482)
		(stroke
			(width 0.2)
			(type default)
		)
		(layer "In1.Cu")
	)
	(gr_arc
		(start 323.612764 -34.458402)
		(mid 323.10197 -34.968815)
		(end 323.61251 -35.479482)
		(stroke
			(width 0.2)
			(type default)
		)
		(layer "In1.Cu")
	)
	(gr_arc
		(start 323.70649 -211.406994)
		(mid 324.21703 -210.896454)
		(end 323.70649 -210.385914)
		(stroke
			(width 0.2)
			(type default)
		)
		(layer "In1.Cu")
	)
	(gr_line
		(start 323.70649 -210.385914)
		(end 322.893944 -210.385914)
		(stroke
			(width 0.2)
			(type default)
		)
		(layer "In1.Cu")
	)
	(gr_line
		(start 323.831458 -23.633938)
		(end 323.081396 -25.033732)
		(stroke
			(width 0.2)
			(type default)
		)
		(layer "In1.Cu")
	)
	(gr_line
		(start 323.831458 -19.833844)
		(end 323.081396 -21.233892)
		(stroke
			(width 0.2)
			(type default)
		)
		(layer "In1.Cu")
	)
	(gr_line
		(start 323.831458 -16.03375)
		(end 323.081396 -17.433544)
		(stroke
			(width 0.2)
			(type default)
		)
		(layer "In1.Cu")
	)
	(gr_line
		(start 323.831458 -12.23391)
		(end 323.081396 -13.633704)
		(stroke
			(width 0.2)
			(type default)
		)
		(layer "In1.Cu")
	)
	(gr_line
		(start 323.83349 -23.635208)
		(end 323.831458 -23.633938)
		(stroke
			(width 0.2)
			(type default)
		)
		(layer "In1.Cu")
	)
	(gr_line
		(start 323.83349 -19.835114)
		(end 323.831458 -19.833844)
		(stroke
			(width 0.2)
			(type default)
		)
		(layer "In1.Cu")
	)
	(gr_line
		(start 323.83349 -12.23518)
		(end 323.831458 -12.23391)
		(stroke
			(width 0.2)
			(type default)
		)
		(layer "In1.Cu")
	)
	(gr_line
		(start 323.833744 -16.03502)
		(end 323.831458 -16.03375)
		(stroke
			(width 0.2)
			(type default)
		)
		(layer "In1.Cu")
	)
	(gr_arc
		(start 324.01129 -213.207854)
		(mid 324.101093 -213.170657)
		(end 324.13829 -213.080854)
		(stroke
			(width 0.2)
			(type default)
		)
		(layer "In1.Cu")
	)
	(gr_line
		(start 324.01129 -211.633054)
		(end 322.58889 -211.633054)
		(stroke
			(width 0.2)
			(type default)
		)
		(layer "In1.Cu")
	)
	(gr_line
		(start 324.13829 -213.080854)
		(end 324.13829 -211.760054)
		(stroke
			(width 0.2)
			(type default)
		)
		(layer "In1.Cu")
	)
	(gr_arc
		(start 324.13829 -211.760054)
		(mid 324.101093 -211.670251)
		(end 324.01129 -211.633054)
		(stroke
			(width 0.2)
			(type default)
		)
		(layer "In1.Cu")
	)
	(gr_line
		(start 324.185026 -18.02511)
		(end 324.187312 -18.02638)
		(stroke
			(width 0.2)
			(type default)
		)
		(layer "In1.Cu")
	)
	(gr_line
		(start 324.18528 -25.625044)
		(end 324.187312 -25.626314)
		(stroke
			(width 0.2)
			(type default)
		)
		(layer "In1.Cu")
	)
	(gr_line
		(start 324.18528 -21.82495)
		(end 324.187312 -21.82622)
		(stroke
			(width 0.2)
			(type default)
		)
		(layer "In1.Cu")
	)
	(gr_line
		(start 324.18528 -14.225016)
		(end 324.187312 -14.226286)
		(stroke
			(width 0.2)
			(type default)
		)
		(layer "In1.Cu")
	)
	(gr_line
		(start 324.187312 -25.626314)
		(end 324.937374 -24.226266)
		(stroke
			(width 0.2)
			(type default)
		)
		(layer "In1.Cu")
	)
	(gr_line
		(start 324.187312 -21.82622)
		(end 324.937374 -20.426426)
		(stroke
			(width 0.2)
			(type default)
		)
		(layer "In1.Cu")
	)
	(gr_line
		(start 324.187312 -18.02638)
		(end 324.937374 -16.626586)
		(stroke
			(width 0.2)
			(type default)
		)
		(layer "In1.Cu")
	)
	(gr_line
		(start 324.187312 -14.226286)
		(end 324.937374 -12.826238)
		(stroke
			(width 0.2)
			(type default)
		)
		(layer "In1.Cu")
	)
	(gr_arc
		(start 324.425056 -35.479482)
		(mid 324.93585 -34.969069)
		(end 324.42531 -34.458402)
		(stroke
			(width 0.2)
			(type default)
		)
		(layer "In1.Cu")
	)
	(gr_arc
		(start 324.42531 -35.479482)
		(mid 324.93585 -34.968942)
		(end 324.42531 -34.458402)
		(stroke
			(width 0.2)
			(type default)
		)
		(layer "In1.Cu")
	)
	(gr_line
		(start 324.42531 -34.458402)
		(end 323.61251 -34.458402)
		(stroke
			(width 0.2)
			(type default)
		)
		(layer "In1.Cu")
	)
	(gr_line
		(start 324.42531 -34.458402)
		(end 323.612764 -34.458402)
		(stroke
			(width 0.2)
			(type default)
		)
		(layer "In1.Cu")
	)
	(gr_line
		(start 324.493636 -222.805244)
		(end 325.306182 -222.805244)
		(stroke
			(width 0.2)
			(type default)
		)
		(layer "In1.Cu")
	)
	(gr_arc
		(start 324.493636 -221.784164)
		(mid 323.983096 -222.294704)
		(end 324.493636 -222.805244)
		(stroke
			(width 0.2)
			(type default)
		)
		(layer "In1.Cu")
	)
	(gr_arc
		(start 324.65391 -34.270188)
		(mid 324.743713 -34.232991)
		(end 324.78091 -34.143188)
		(stroke
			(width 0.2)
			(type default)
		)
		(layer "In1.Cu")
	)
	(gr_line
		(start 324.65391 -32.695388)
		(end 323.35851 -32.695388)
		(stroke
			(width 0.2)
			(type default)
		)
		(layer "In1.Cu")
	)
	(gr_line
		(start 324.78091 -34.143188)
		(end 324.78091 -32.822388)
		(stroke
			(width 0.2)
			(type default)
		)
		(layer "In1.Cu")
	)
	(gr_arc
		(start 324.78091 -32.822388)
		(mid 324.743713 -32.732585)
		(end 324.65391 -32.695388)
		(stroke
			(width 0.2)
			(type default)
		)
		(layer "In1.Cu")
	)
	(gr_arc
		(start 324.935088 -20.425156)
		(mid 324.679412 -19.579255)
		(end 323.83349 -19.835114)
		(stroke
			(width 0.2)
			(type default)
		)
		(layer "In1.Cu")
	)
	(gr_arc
		(start 324.935088 -16.625316)
		(mid 324.679564 -15.779496)
		(end 323.833744 -16.03502)
		(stroke
			(width 0.2)
			(type default)
		)
		(layer "In1.Cu")
	)
	(gr_arc
		(start 324.935342 -24.224996)
		(mid 324.67931 -23.379176)
		(end 323.83349 -23.635208)
		(stroke
			(width 0.2)
			(type default)
		)
		(layer "In1.Cu")
	)
	(gr_arc
		(start 324.935342 -12.824968)
		(mid 324.67931 -11.979148)
		(end 323.83349 -12.23518)
		(stroke
			(width 0.2)
			(type default)
		)
		(layer "In1.Cu")
	)
	(gr_line
		(start 324.93712 -20.426172)
		(end 324.935088 -20.425156)
		(stroke
			(width 0.2)
			(type default)
		)
		(layer "In1.Cu")
	)
	(gr_line
		(start 324.937374 -24.226266)
		(end 324.935342 -24.224996)
		(stroke
			(width 0.2)
			(type default)
		)
		(layer "In1.Cu")
	)
	(gr_line
		(start 324.937374 -20.426426)
		(end 324.93712 -20.426172)
		(stroke
			(width 0.2)
			(type default)
		)
		(layer "In1.Cu")
	)
	(gr_line
		(start 324.937374 -16.626586)
		(end 324.935088 -16.625316)
		(stroke
			(width 0.2)
			(type default)
		)
		(layer "In1.Cu")
	)
	(gr_line
		(start 324.937374 -12.826238)
		(end 324.935342 -12.824968)
		(stroke
			(width 0.2)
			(type default)
		)
		(layer "In1.Cu")
	)
	(gr_arc
		(start 325.306182 -222.805244)
		(mid 325.816976 -222.294831)
		(end 325.306436 -221.784164)
		(stroke
			(width 0.2)
			(type default)
		)
		(layer "In1.Cu")
	)
	(gr_line
		(start 325.306436 -221.784164)
		(end 324.493636 -221.784164)
		(stroke
			(width 0.2)
			(type default)
		)
		(layer "In1.Cu")
	)
	(gr_arc
		(start 325.588122 -34.11982)
		(mid 325.625319 -34.209623)
		(end 325.715122 -34.24682)
		(stroke
			(width 0.2)
			(type default)
		)
		(layer "In1.Cu")
	)
	(gr_line
		(start 325.588122 -32.79902)
		(end 325.588122 -34.11982)
		(stroke
			(width 0.2)
			(type default)
		)
		(layer "In1.Cu")
	)
	(gr_arc
		(start 325.661782 -213.080854)
		(mid 325.698979 -213.170657)
		(end 325.788782 -213.207854)
		(stroke
			(width 0.2)
			(type default)
		)
		(layer "In1.Cu")
	)
	(gr_line
		(start 325.661782 -211.760054)
		(end 325.661782 -213.080854)
		(stroke
			(width 0.2)
			(type default)
		)
		(layer "In1.Cu")
	)
	(gr_line
		(start 325.715122 -34.24682)
		(end 327.010522 -34.24682)
		(stroke
			(width 0.2)
			(type default)
		)
		(layer "In1.Cu")
	)
	(gr_arc
		(start 325.715122 -32.67202)
		(mid 325.625319 -32.709217)
		(end 325.588122 -32.79902)
		(stroke
			(width 0.2)
			(type default)
		)
		(layer "In1.Cu")
	)
	(gr_line
		(start 325.788782 -213.207854)
		(end 326.195182 -213.207854)
		(stroke
			(width 0.2)
			(type default)
		)
		(layer "In1.Cu")
	)
	(gr_arc
		(start 325.788782 -211.633054)
		(mid 325.698979 -211.670251)
		(end 325.661782 -211.760054)
		(stroke
			(width 0.2)
			(type default)
		)
		(layer "In1.Cu")
	)
	(gr_line
		(start 325.969122 -36.472114)
		(end 326.781668 -36.472114)
		(stroke
			(width 0.2)
			(type default)
		)
		(layer "In1.Cu")
	)
	(gr_arc
		(start 325.969122 -35.451034)
		(mid 325.458582 -35.961574)
		(end 325.969122 -36.472114)
		(stroke
			(width 0.2)
			(type default)
		)
		(layer "In1.Cu")
	)
	(gr_line
		(start 326.093582 -211.406994)
		(end 326.906382 -211.406994)
		(stroke
			(width 0.2)
			(type default)
		)
		(layer "In1.Cu")
	)
	(gr_arc
		(start 326.093836 -210.385914)
		(mid 325.583042 -210.896327)
		(end 326.093582 -211.406994)
		(stroke
			(width 0.2)
			(type default)
		)
		(layer "In1.Cu")
	)
	(gr_line
		(start 326.195182 -213.207854)
		(end 326.195436 -213.2076)
		(stroke
			(width 0.2)
			(type default)
		)
		(layer "In1.Cu")
	)
	(gr_line
		(start 326.195436 -213.2076)
		(end 326.796654 -213.2076)
		(stroke
			(width 0.2)
			(type default)
		)
		(layer "In1.Cu")
	)
	(gr_arc
		(start 326.781668 -36.472114)
		(mid 327.292462 -35.961701)
		(end 326.781922 -35.451034)
		(stroke
			(width 0.2)
			(type default)
		)
		(layer "In1.Cu")
	)
	(gr_line
		(start 326.781922 -35.451034)
		(end 325.969122 -35.451034)
		(stroke
			(width 0.2)
			(type default)
		)
		(layer "In1.Cu")
	)
	(gr_arc
		(start 326.796654 -213.2076)
		(mid 326.800716 -213.207795)
		(end 326.804782 -213.207854)
		(stroke
			(width 0.2)
			(type default)
		)
		(layer "In1.Cu")
	)
	(gr_line
		(start 326.804782 -213.207854)
		(end 327.211182 -213.207854)
		(stroke
			(width 0.2)
			(type default)
		)
		(layer "In1.Cu")
	)
	(gr_arc
		(start 326.906382 -211.406994)
		(mid 327.416922 -210.896454)
		(end 326.906382 -210.385914)
		(stroke
			(width 0.2)
			(type default)
		)
		(layer "In1.Cu")
	)
	(gr_line
		(start 326.906382 -210.385914)
		(end 326.093836 -210.385914)
		(stroke
			(width 0.2)
			(type default)
		)
		(layer "In1.Cu")
	)
	(gr_arc
		(start 327.010522 -34.24682)
		(mid 327.100325 -34.209623)
		(end 327.137522 -34.11982)
		(stroke
			(width 0.2)
			(type default)
		)
		(layer "In1.Cu")
	)
	(gr_line
		(start 327.010522 -32.67202)
		(end 325.715122 -32.67202)
		(stroke
			(width 0.2)
			(type default)
		)
		(layer "In1.Cu")
	)
	(gr_line
		(start 327.137522 -34.11982)
		(end 327.137522 -32.79902)
		(stroke
			(width 0.2)
			(type default)
		)
		(layer "In1.Cu")
	)
	(gr_arc
		(start 327.137522 -32.79902)
		(mid 327.100325 -32.709217)
		(end 327.010522 -32.67202)
		(stroke
			(width 0.2)
			(type default)
		)
		(layer "In1.Cu")
	)
	(gr_arc
		(start 327.211182 -213.207854)
		(mid 327.300985 -213.170657)
		(end 327.338182 -213.080854)
		(stroke
			(width 0.2)
			(type default)
		)
		(layer "In1.Cu")
	)
	(gr_line
		(start 327.211182 -211.633054)
		(end 325.788782 -211.633054)
		(stroke
			(width 0.2)
			(type default)
		)
		(layer "In1.Cu")
	)
	(gr_line
		(start 327.338182 -213.080854)
		(end 327.338182 -211.760054)
		(stroke
			(width 0.2)
			(type default)
		)
		(layer "In1.Cu")
	)
	(gr_arc
		(start 327.338182 -211.760054)
		(mid 327.300985 -211.670251)
		(end 327.211182 -211.633054)
		(stroke
			(width 0.2)
			(type default)
		)
		(layer "In1.Cu")
	)
	(gr_line
		(start 327.693782 -222.805244)
		(end 328.506328 -222.805244)
		(stroke
			(width 0.2)
			(type default)
		)
		(layer "In1.Cu")
	)
	(gr_arc
		(start 327.693782 -221.784164)
		(mid 327.183242 -222.294704)
		(end 327.693782 -222.805244)
		(stroke
			(width 0.2)
			(type default)
		)
		(layer "In1.Cu")
	)
	(gr_line
		(start 328.375518 -35.429952)
		(end 329.188064 -35.429952)
		(stroke
			(width 0.2)
			(type default)
		)
		(layer "In1.Cu")
	)
	(gr_arc
		(start 328.375518 -34.408872)
		(mid 327.864978 -34.919412)
		(end 328.375518 -35.429952)
		(stroke
			(width 0.2)
			(type default)
		)
		(layer "In1.Cu")
	)
	(gr_arc
		(start 328.506328 -222.805244)
		(mid 329.017122 -222.294831)
		(end 328.506582 -221.784164)
		(stroke
			(width 0.2)
			(type default)
		)
		(layer "In1.Cu")
	)
	(gr_line
		(start 328.506582 -221.784164)
		(end 327.693782 -221.784164)
		(stroke
			(width 0.2)
			(type default)
		)
		(layer "In1.Cu")
	)
	(gr_arc
		(start 329.188064 -35.429952)
		(mid 329.698858 -34.919539)
		(end 329.188318 -34.408872)
		(stroke
			(width 0.2)
			(type default)
		)
		(layer "In1.Cu")
	)
	(gr_line
		(start 329.188318 -34.408872)
		(end 328.375518 -34.408872)
		(stroke
			(width 0.2)
			(type default)
		)
		(layer "In1.Cu")
	)
	(gr_line
		(start 330.893674 -222.805244)
		(end 331.70622 -222.805244)
		(stroke
			(width 0.2)
			(type default)
		)
		(layer "In1.Cu")
	)
	(gr_arc
		(start 330.893674 -221.784164)
		(mid 330.383134 -222.294704)
		(end 330.893674 -222.805244)
		(stroke
			(width 0.2)
			(type default)
		)
		(layer "In1.Cu")
	)
	(gr_arc
		(start 331.70622 -222.805244)
		(mid 332.217014 -222.294831)
		(end 331.706474 -221.784164)
		(stroke
			(width 0.2)
			(type default)
		)
		(layer "In1.Cu")
	)
	(gr_line
		(start 331.706474 -221.784164)
		(end 330.893674 -221.784164)
		(stroke
			(width 0.2)
			(type default)
		)
		(layer "In1.Cu")
	)
	(gr_arc
		(start 331.749908 0.999998)
		(mid 332.042801 0.292893)
		(end 332.749906 0)
		(stroke
			(width 1.524)
			(type default)
		)
		(layer "In1.Cu")
	)
	(gr_arc
		(start 331.749908 3.999992)
		(mid 331.457019 4.707106)
		(end 330.74991 4.99999)
		(stroke
			(width 1.524)
			(type default)
		)
		(layer "In1.Cu")
	)
	(gr_line
		(start 331.749908 3.999992)
		(end 331.749908 0.999998)
		(stroke
			(width 1.524)
			(type default)
		)
		(layer "In1.Cu")
	)
	(gr_arc
		(start 332.06182 -213.080854)
		(mid 332.099017 -213.170657)
		(end 332.18882 -213.207854)
		(stroke
			(width 0.2)
			(type default)
		)
		(layer "In1.Cu")
	)
	(gr_line
		(start 332.06182 -211.760054)
		(end 332.06182 -213.080854)
		(stroke
			(width 0.2)
			(type default)
		)
		(layer "In1.Cu")
	)
	(gr_line
		(start 332.18882 -213.207854)
		(end 332.59522 -213.207854)
		(stroke
			(width 0.2)
			(type default)
		)
		(layer "In1.Cu")
	)
	(gr_arc
		(start 332.18882 -211.633054)
		(mid 332.099017 -211.670251)
		(end 332.06182 -211.760054)
		(stroke
			(width 0.2)
			(type default)
		)
		(layer "In1.Cu")
	)
	(gr_line
		(start 332.493874 -211.406994)
		(end 333.306674 -211.406994)
		(stroke
			(width 0.2)
			(type default)
		)
		(layer "In1.Cu")
	)
	(gr_arc
		(start 332.494128 -210.385914)
		(mid 331.983334 -210.896327)
		(end 332.493874 -211.406994)
		(stroke
			(width 0.2)
			(type default)
		)
		(layer "In1.Cu")
	)
	(gr_line
		(start 332.59522 -213.207854)
		(end 332.595474 -213.2076)
		(stroke
			(width 0.2)
			(type default)
		)
		(layer "In1.Cu")
	)
	(gr_line
		(start 332.595474 -213.2076)
		(end 333.196692 -213.2076)
		(stroke
			(width 0.2)
			(type default)
		)
		(layer "In1.Cu")
	)
	(gr_line
		(start 332.749906 0)
		(end 354.600002 0)
		(stroke
			(width 1.524)
			(type default)
		)
		(layer "In1.Cu")
	)
	(gr_arc
		(start 333.196692 -213.2076)
		(mid 333.200754 -213.207795)
		(end 333.20482 -213.207854)
		(stroke
			(width 0.2)
			(type default)
		)
		(layer "In1.Cu")
	)
	(gr_line
		(start 333.20482 -213.207854)
		(end 333.61122 -213.207854)
		(stroke
			(width 0.2)
			(type default)
		)
		(layer "In1.Cu")
	)
	(gr_arc
		(start 333.306674 -211.406994)
		(mid 333.817214 -210.896454)
		(end 333.306674 -210.385914)
		(stroke
			(width 0.2)
			(type default)
		)
		(layer "In1.Cu")
	)
	(gr_line
		(start 333.306674 -210.385914)
		(end 332.494128 -210.385914)
		(stroke
			(width 0.2)
			(type default)
		)
		(layer "In1.Cu")
	)
	(gr_arc
		(start 333.61122 -213.207854)
		(mid 333.701023 -213.170657)
		(end 333.73822 -213.080854)
		(stroke
			(width 0.2)
			(type default)
		)
		(layer "In1.Cu")
	)
	(gr_line
		(start 333.61122 -211.633054)
		(end 332.18882 -211.633054)
		(stroke
			(width 0.2)
			(type default)
		)
		(layer "In1.Cu")
	)
	(gr_line
		(start 333.73822 -213.080854)
		(end 333.73822 -211.760054)
		(stroke
			(width 0.2)
			(type default)
		)
		(layer "In1.Cu")
	)
	(gr_arc
		(start 333.73822 -211.760054)
		(mid 333.701023 -211.670251)
		(end 333.61122 -211.633054)
		(stroke
			(width 0.2)
			(type default)
		)
		(layer "In1.Cu")
	)
	(gr_line
		(start 334.093566 -222.805244)
		(end 334.906112 -222.805244)
		(stroke
			(width 0.2)
			(type default)
		)
		(layer "In1.Cu")
	)
	(gr_arc
		(start 334.093566 -221.784164)
		(mid 333.583026 -222.294704)
		(end 334.093566 -222.805244)
		(stroke
			(width 0.2)
			(type default)
		)
		(layer "In1.Cu")
	)
	(gr_arc
		(start 334.906112 -222.805244)
		(mid 335.416906 -222.294831)
		(end 334.906366 -221.784164)
		(stroke
			(width 0.2)
			(type default)
		)
		(layer "In1.Cu")
	)
	(gr_line
		(start 334.906366 -221.784164)
		(end 334.093566 -221.784164)
		(stroke
			(width 0.2)
			(type default)
		)
		(layer "In1.Cu")
	)
	(gr_arc
		(start 335.261966 -213.080854)
		(mid 335.299163 -213.170657)
		(end 335.388966 -213.207854)
		(stroke
			(width 0.2)
			(type default)
		)
		(layer "In1.Cu")
	)
	(gr_line
		(start 335.261966 -211.760054)
		(end 335.261966 -213.080854)
		(stroke
			(width 0.2)
			(type default)
		)
		(layer "In1.Cu")
	)
	(gr_line
		(start 335.388966 -213.207854)
		(end 335.795366 -213.207854)
		(stroke
			(width 0.2)
			(type default)
		)
		(layer "In1.Cu")
	)
	(gr_arc
		(start 335.388966 -211.633054)
		(mid 335.299163 -211.670251)
		(end 335.261966 -211.760054)
		(stroke
			(width 0.2)
			(type default)
		)
		(layer "In1.Cu")
	)
	(gr_line
		(start 335.693766 -211.406994)
		(end 336.506566 -211.406994)
		(stroke
			(width 0.2)
			(type default)
		)
		(layer "In1.Cu")
	)
	(gr_arc
		(start 335.69402 -210.385914)
		(mid 335.183226 -210.896327)
		(end 335.693766 -211.406994)
		(stroke
			(width 0.2)
			(type default)
		)
		(layer "In1.Cu")
	)
	(gr_line
		(start 335.795366 -213.207854)
		(end 335.79562 -213.2076)
		(stroke
			(width 0.2)
			(type default)
		)
		(layer "In1.Cu")
	)
	(gr_line
		(start 335.79562 -213.2076)
		(end 336.396838 -213.2076)
		(stroke
			(width 0.2)
			(type default)
		)
		(layer "In1.Cu")
	)
	(gr_arc
		(start 336.396838 -213.2076)
		(mid 336.4009 -213.207795)
		(end 336.404966 -213.207854)
		(stroke
			(width 0.2)
			(type default)
		)
		(layer "In1.Cu")
	)
	(gr_line
		(start 336.404966 -213.207854)
		(end 336.811366 -213.207854)
		(stroke
			(width 0.2)
			(type default)
		)
		(layer "In1.Cu")
	)
	(gr_arc
		(start 336.506566 -211.406994)
		(mid 337.017106 -210.896454)
		(end 336.506566 -210.385914)
		(stroke
			(width 0.2)
			(type default)
		)
		(layer "In1.Cu")
	)
	(gr_line
		(start 336.506566 -210.385914)
		(end 335.69402 -210.385914)
		(stroke
			(width 0.2)
			(type default)
		)
		(layer "In1.Cu")
	)
	(gr_arc
		(start 336.811366 -213.207854)
		(mid 336.901169 -213.170657)
		(end 336.938366 -213.080854)
		(stroke
			(width 0.2)
			(type default)
		)
		(layer "In1.Cu")
	)
	(gr_line
		(start 336.811366 -211.633054)
		(end 335.388966 -211.633054)
		(stroke
			(width 0.2)
			(type default)
		)
		(layer "In1.Cu")
	)
	(gr_line
		(start 336.938366 -213.080854)
		(end 336.938366 -211.760054)
		(stroke
			(width 0.2)
			(type default)
		)
		(layer "In1.Cu")
	)
	(gr_arc
		(start 336.938366 -211.760054)
		(mid 336.901169 -211.670251)
		(end 336.811366 -211.633054)
		(stroke
			(width 0.2)
			(type default)
		)
		(layer "In1.Cu")
	)
	(gr_line
		(start 337.293712 -222.805244)
		(end 338.106258 -222.805244)
		(stroke
			(width 0.2)
			(type default)
		)
		(layer "In1.Cu")
	)
	(gr_arc
		(start 337.293712 -221.784164)
		(mid 336.783172 -222.294704)
		(end 337.293712 -222.805244)
		(stroke
			(width 0.2)
			(type default)
		)
		(layer "In1.Cu")
	)
	(gr_arc
		(start 338.106258 -222.805244)
		(mid 338.617052 -222.294831)
		(end 338.106512 -221.784164)
		(stroke
			(width 0.2)
			(type default)
		)
		(layer "In1.Cu")
	)
	(gr_line
		(start 338.106512 -221.784164)
		(end 337.293712 -221.784164)
		(stroke
			(width 0.2)
			(type default)
		)
		(layer "In1.Cu")
	)
	(gr_arc
		(start 338.461858 -213.080854)
		(mid 338.499055 -213.170657)
		(end 338.588858 -213.207854)
		(stroke
			(width 0.2)
			(type default)
		)
		(layer "In1.Cu")
	)
	(gr_line
		(start 338.461858 -211.760054)
		(end 338.461858 -213.080854)
		(stroke
			(width 0.2)
			(type default)
		)
		(layer "In1.Cu")
	)
	(gr_line
		(start 338.588858 -213.207854)
		(end 338.995258 -213.207854)
		(stroke
			(width 0.2)
			(type default)
		)
		(layer "In1.Cu")
	)
	(gr_arc
		(start 338.588858 -211.633054)
		(mid 338.499055 -211.670251)
		(end 338.461858 -211.760054)
		(stroke
			(width 0.2)
			(type default)
		)
		(layer "In1.Cu")
	)
	(gr_line
		(start 338.893658 -211.406994)
		(end 339.706204 -211.406994)
		(stroke
			(width 0.2)
			(type default)
		)
		(layer "In1.Cu")
	)
	(gr_arc
		(start 338.893658 -210.385914)
		(mid 338.383118 -210.896454)
		(end 338.893658 -211.406994)
		(stroke
			(width 0.2)
			(type default)
		)
		(layer "In1.Cu")
	)
	(gr_line
		(start 338.995258 -213.207854)
		(end 338.995512 -213.2076)
		(stroke
			(width 0.2)
			(type default)
		)
		(layer "In1.Cu")
	)
	(gr_line
		(start 338.995512 -213.2076)
		(end 339.59673 -213.2076)
		(stroke
			(width 0.2)
			(type default)
		)
		(layer "In1.Cu")
	)
	(gr_arc
		(start 339.59673 -213.2076)
		(mid 339.600792 -213.207795)
		(end 339.604858 -213.207854)
		(stroke
			(width 0.2)
			(type default)
		)
		(layer "In1.Cu")
	)
	(gr_line
		(start 339.604858 -213.207854)
		(end 340.011258 -213.207854)
		(stroke
			(width 0.2)
			(type default)
		)
		(layer "In1.Cu")
	)
	(gr_arc
		(start 339.706204 -211.406994)
		(mid 340.216998 -210.896581)
		(end 339.706458 -210.385914)
		(stroke
			(width 0.2)
			(type default)
		)
		(layer "In1.Cu")
	)
	(gr_line
		(start 339.706458 -210.385914)
		(end 338.893658 -210.385914)
		(stroke
			(width 0.2)
			(type default)
		)
		(layer "In1.Cu")
	)
	(gr_arc
		(start 340.011258 -213.207854)
		(mid 340.101061 -213.170657)
		(end 340.138258 -213.080854)
		(stroke
			(width 0.2)
			(type default)
		)
		(layer "In1.Cu")
	)
	(gr_line
		(start 340.011258 -211.633054)
		(end 338.588858 -211.633054)
		(stroke
			(width 0.2)
			(type default)
		)
		(layer "In1.Cu")
	)
	(gr_line
		(start 340.138258 -213.080854)
		(end 340.138258 -211.760054)
		(stroke
			(width 0.2)
			(type default)
		)
		(layer "In1.Cu")
	)
	(gr_arc
		(start 340.138258 -211.760054)
		(mid 340.101061 -211.670251)
		(end 340.011258 -211.633054)
		(stroke
			(width 0.2)
			(type default)
		)
		(layer "In1.Cu")
	)
	(gr_line
		(start 340.493604 -222.805244)
		(end 341.306404 -222.805244)
		(stroke
			(width 0.2)
			(type default)
		)
		(layer "In1.Cu")
	)
	(gr_arc
		(start 340.493858 -221.784164)
		(mid 339.983064 -222.294577)
		(end 340.493604 -222.805244)
		(stroke
			(width 0.2)
			(type default)
		)
		(layer "In1.Cu")
	)
	(gr_arc
		(start 341.306404 -222.805244)
		(mid 341.816944 -222.294704)
		(end 341.306404 -221.784164)
		(stroke
			(width 0.2)
			(type default)
		)
		(layer "In1.Cu")
	)
	(gr_line
		(start 341.306404 -221.784164)
		(end 340.493858 -221.784164)
		(stroke
			(width 0.2)
			(type default)
		)
		(layer "In1.Cu")
	)
	(gr_line
		(start 342.09355 -211.406994)
		(end 342.906096 -211.406994)
		(stroke
			(width 0.2)
			(type default)
		)
		(layer "In1.Cu")
	)
	(gr_arc
		(start 342.09355 -210.385914)
		(mid 341.58301 -210.896454)
		(end 342.09355 -211.406994)
		(stroke
			(width 0.2)
			(type default)
		)
		(layer "In1.Cu")
	)
	(gr_arc
		(start 342.906096 -211.406994)
		(mid 343.41689 -210.896581)
		(end 342.90635 -210.385914)
		(stroke
			(width 0.2)
			(type default)
		)
		(layer "In1.Cu")
	)
	(gr_line
		(start 342.90635 -210.385914)
		(end 342.09355 -210.385914)
		(stroke
			(width 0.2)
			(type default)
		)
		(layer "In1.Cu")
	)
	(gr_line
		(start 344.499946 -228.000052)
		(end 308.500018 -228.000052)
		(stroke
			(width 5.08)
			(type default)
		)
		(layer "In1.Cu")
	)
	(gr_line
		(start 344.499946 -222.400114)
		(end 344.499946 -228.000052)
		(stroke
			(width 1.524)
			(type default)
		)
		(layer "In1.Cu")
	)
	(gr_arc
		(start 345.000072 -221.899988)
		(mid 344.64643 -222.046472)
		(end 344.499946 -222.400114)
		(stroke
			(width 1.524)
			(type default)
		)
		(layer "In1.Cu")
	)
	(gr_line
		(start 345.799918 -221.899988)
		(end 345.000072 -221.899988)
		(stroke
			(width 1.524)
			(type default)
		)
		(layer "In1.Cu")
	)
	(gr_arc
		(start 345.799918 -221.899988)
		(mid 346.153446 -221.753586)
		(end 346.300044 -221.400116)
		(stroke
			(width 1.524)
			(type default)
		)
		(layer "In1.Cu")
	)
	(gr_line
		(start 346.300044 -214.799926)
		(end 346.300044 -221.400116)
		(stroke
			(width 1.524)
			(type default)
		)
		(layer "In1.Cu")
	)
	(gr_arc
		(start 347.600016 -213.499954)
		(mid 346.680797 -213.880707)
		(end 346.300044 -214.799926)
		(stroke
			(width 1.524)
			(type default)
		)
		(layer "In1.Cu")
	)
	(gr_arc
		(start 354.24999 -18.200116)
		(mid 354.396563 -18.553594)
		(end 354.750116 -18.699988)
		(stroke
			(width 1.524)
			(type default)
		)
		(layer "In1.Cu")
	)
	(gr_line
		(start 354.24999 -10.199878)
		(end 354.24999 -18.200116)
		(stroke
			(width 1.524)
			(type default)
		)
		(layer "In1.Cu")
	)
	(gr_line
		(start 354.600002 -213.499954)
		(end 347.600016 -213.499954)
		(stroke
			(width 1.524)
			(type default)
		)
		(layer "In1.Cu")
	)
	(gr_arc
		(start 354.600002 -213.499954)
		(mid 355.307091 -213.207058)
		(end 355.6 -212.499956)
		(stroke
			(width 1.524)
			(type default)
		)
		(layer "In1.Cu")
	)
	(gr_line
		(start 354.750116 -18.699988)
		(end 355.099874 -18.699988)
		(stroke
			(width 1.524)
			(type default)
		)
		(layer "In1.Cu")
	)
	(gr_arc
		(start 354.750116 -9.700006)
		(mid 354.396563 -9.8464)
		(end 354.24999 -10.199878)
		(stroke
			(width 1.524)
			(type default)
		)
		(layer "In1.Cu")
	)
	(gr_line
		(start 355.099874 -9.700006)
		(end 354.750116 -9.700006)
		(stroke
			(width 1.524)
			(type default)
		)
		(layer "In1.Cu")
	)
	(gr_arc
		(start 355.099874 -9.700006)
		(mid 355.453526 -9.55353)
		(end 355.6 -9.19988)
		(stroke
			(width 1.524)
			(type default)
		)
		(layer "In1.Cu")
	)
	(gr_arc
		(start 355.6 -19.200114)
		(mid 355.45352 -18.846472)
		(end 355.099874 -18.699988)
		(stroke
			(width 1.524)
			(type default)
		)
		(layer "In1.Cu")
	)
	(gr_line
		(start 355.6 -19.200114)
		(end 355.6 -212.499956)
		(stroke
			(width 1.524)
			(type default)
		)
		(layer "In1.Cu")
	)
	(gr_arc
		(start 355.6 -0.999998)
		(mid 355.307107 -0.292893)
		(end 354.600002 0)
		(stroke
			(width 1.524)
			(type default)
		)
		(layer "In1.Cu")
	)
	(gr_line
		(start 355.6 -0.999998)
		(end 355.6 -9.19988)
		(stroke
			(width 1.524)
			(type default)
		)
		(layer "In1.Cu")
	)
	(gr_line
		(start 6.7564 -64.409828)
		(end 6.949694 -64.216534)
		(stroke
			(width 0.0635)
			(type default)
		)
		(layer "In2.Cu")
	)
	(gr_line
		(start 6.7564 -63.301118)
		(end 6.949694 -63.494412)
		(stroke
			(width 0.0635)
			(type default)
		)
		(layer "In2.Cu")
	)
	(gr_line
		(start 8.042148 -77.028548)
		(end 9.138666 -78.125066)
		(stroke
			(width 0.0635)
			(type default)
		)
		(layer "In2.Cu")
	)
	(gr_line
		(start 8.0518 -79.9338)
		(end 9.138666 -78.846934)
		(stroke
			(width 0.0635)
			(type default)
		)
		(layer "In2.Cu")
	)
	(gr_line
		(start 8.5344 -93.591888)
		(end 8.647938 -93.47835)
		(stroke
			(width 0.0635)
			(type default)
		)
		(layer "In2.Cu")
	)
	(gr_line
		(start 8.674862 -95.736664)
		(end 8.868156 -95.54337)
		(stroke
			(width 0.0635)
			(type default)
		)
		(layer "In2.Cu")
	)
	(gr_line
		(start 9.590278 -95.54337)
		(end 9.783572 -95.736664)
		(stroke
			(width 0.0635)
			(type default)
		)
		(layer "In2.Cu")
	)
	(gr_line
		(start 9.74852 -92.37726)
		(end 9.861804 -92.263976)
		(stroke
			(width 0.0635)
			(type default)
		)
		(layer "In2.Cu")
	)
	(gr_line
		(start 11.922506 -140.543788)
		(end 11.980926 -140.543788)
		(stroke
			(width 0.06985)
			(type default)
		)
		(layer "In2.Cu")
	)
	(gr_line
		(start 12.118594 -140.21435)
		(end 12.311126 -140.21435)
		(stroke
			(width 0.06985)
			(type default)
		)
		(layer "In2.Cu")
	)
	(gr_line
		(start 12.73556 -125.617986)
		(end 13.193014 -125.617986)
		(stroke
			(width 0.0635)
			(type default)
		)
		(layer "In2.Cu")
	)
	(gr_line
		(start 13.193014 -125.617986)
		(end 13.8176 -124.9934)
		(stroke
			(width 0.0635)
			(type default)
		)
		(layer "In2.Cu")
	)
	(gr_line
		(start 13.8176 -124.66574)
		(end 13.8176 -124.9934)
		(stroke
			(width 0.0635)
			(type default)
		)
		(layer "In2.Cu")
	)
	(gr_line
		(start 14.32814 -124.15774)
		(end 14.56563 -124.39523)
		(stroke
			(width 0.0635)
			(type default)
		)
		(layer "In2.Cu")
	)
	(gr_line
		(start 14.56563 -124.39523)
		(end 15.35811 -124.39523)
		(stroke
			(width 0.0635)
			(type default)
		)
		(layer "In2.Cu")
	)
	(gr_line
		(start 14.7066 -122.194066)
		(end 14.820138 -122.080528)
		(stroke
			(width 0.0635)
			(type default)
		)
		(layer "In2.Cu")
	)
	(gr_line
		(start 15.35811 -124.39523)
		(end 15.490698 -124.262642)
		(stroke
			(width 0.0635)
			(type default)
		)
		(layer "In2.Cu")
	)
	(gr_line
		(start 15.8496 -87.0458)
		(end 16.173196 -86.722204)
		(stroke
			(width 0.06985)
			(type default)
		)
		(layer "In2.Cu")
	)
	(gr_line
		(start 16.643604 -86.722204)
		(end 16.9672 -87.0458)
		(stroke
			(width 0.06985)
			(type default)
		)
		(layer "In2.Cu")
	)
	(gr_line
		(start 16.950182 -113.870486)
		(end 17.062958 -113.98377)
		(stroke
			(width 0.0635)
			(type default)
		)
		(layer "In2.Cu")
	)
	(gr_line
		(start 16.950182 -113.711228)
		(end 16.950182 -113.870486)
		(stroke
			(width 0.0635)
			(type default)
		)
		(layer "In2.Cu")
	)
	(gr_line
		(start 17.183862 -120.435116)
		(end 17.2974 -120.321578)
		(stroke
			(width 0.0635)
			(type default)
		)
		(layer "In2.Cu")
	)
	(gr_line
		(start 17.666462 -113.869216)
		(end 17.78 -113.983008)
		(stroke
			(width 0.0635)
			(type default)
		)
		(layer "In2.Cu")
	)
	(gr_line
		(start 17.969484 -85.003894)
		(end 17.987264 -84.992464)
		(stroke
			(width 0.06985)
			(type default)
		)
		(layer "In2.Cu")
	)
	(gr_line
		(start 17.987264 -84.992464)
		(end 18.008346 -84.987892)
		(stroke
			(width 0.06985)
			(type default)
		)
		(layer "In2.Cu")
	)
	(gr_line
		(start 18.6944 -58.239406)
		(end 19.035776 -57.89803)
		(stroke
			(width 0.0508)
			(type default)
		)
		(layer "In2.Cu")
	)
	(gr_line
		(start 19.148552 -84.745322)
		(end 19.179032 -84.738972)
		(stroke
			(width 0.06985)
			(type default)
		)
		(layer "In2.Cu")
	)
	(gr_line
		(start 19.179032 -84.738972)
		(end 19.208496 -84.745322)
		(stroke
			(width 0.06985)
			(type default)
		)
		(layer "In2.Cu")
	)
	(gr_line
		(start 19.470624 -57.89803)
		(end 19.812 -58.239406)
		(stroke
			(width 0.0508)
			(type default)
		)
		(layer "In2.Cu")
	)
	(gr_line
		(start 21.316442 -103.959152)
		(end 21.430234 -103.845106)
		(stroke
			(width 0.0635)
			(type default)
		)
		(layer "In2.Cu")
	)
	(gr_line
		(start 21.326856 -85.533738)
		(end 21.357336 -85.540088)
		(stroke
			(width 0.06985)
			(type default)
		)
		(layer "In2.Cu")
	)
	(gr_line
		(start 21.357336 -85.540088)
		(end 21.387562 -85.533738)
		(stroke
			(width 0.06985)
			(type default)
		)
		(layer "In2.Cu")
	)
	(gr_line
		(start 21.811488 -85.443314)
		(end 21.832824 -85.438742)
		(stroke
			(width 0.06985)
			(type default)
		)
		(layer "In2.Cu")
	)
	(gr_line
		(start 21.832824 -85.438742)
		(end 21.851366 -85.426804)
		(stroke
			(width 0.06985)
			(type default)
		)
		(layer "In2.Cu")
	)
	(gr_line
		(start 22.364192 -85.093556)
		(end 22.38883 -85.077554)
		(stroke
			(width 0.06985)
			(type default)
		)
		(layer "In2.Cu")
	)
	(gr_line
		(start 22.38883 -85.077554)
		(end 22.405086 -85.052662)
		(stroke
			(width 0.06985)
			(type default)
		)
		(layer "In2.Cu")
	)
	(gr_line
		(start 22.417786 -56.688736)
		(end 22.759162 -57.030112)
		(stroke
			(width 0.0508)
			(type default)
		)
		(layer "In2.Cu")
	)
	(gr_line
		(start 23.1648 -115.1128)
		(end 23.517606 -114.759994)
		(stroke
			(width 0.06985)
			(type default)
		)
		(layer "In2.Cu")
	)
	(gr_line
		(start 23.1648 -113.9952)
		(end 23.517606 -114.348006)
		(stroke
			(width 0.06985)
			(type default)
		)
		(layer "In2.Cu")
	)
	(gr_line
		(start 23.19401 -57.030112)
		(end 23.535386 -56.688736)
		(stroke
			(width 0.0508)
			(type default)
		)
		(layer "In2.Cu")
	)
	(gr_arc
		(start 23.517606 -114.348006)
		(mid 23.562945 -114.378283)
		(end 23.616412 -114.3889)
		(stroke
			(width 0.06985)
			(type default)
		)
		(layer "In2.Cu")
	)
	(gr_line
		(start 23.600156 -82.606134)
		(end 23.616412 -82.581242)
		(stroke
			(width 0.06985)
			(type default)
		)
		(layer "In2.Cu")
	)
	(gr_arc
		(start 23.616412 -114.7191)
		(mid 23.562939 -114.729709)
		(end 23.517606 -114.759994)
		(stroke
			(width 0.06985)
			(type default)
		)
		(layer "In2.Cu")
	)
	(gr_line
		(start 23.616412 -82.581242)
		(end 23.641304 -82.564986)
		(stroke
			(width 0.06985)
			(type default)
		)
		(layer "In2.Cu")
	)
	(gr_line
		(start 24.039322 -101.234494)
		(end 24.153876 -101.11994)
		(stroke
			(width 0.0635)
			(type default)
		)
		(layer "In2.Cu")
	)
	(gr_arc
		(start 24.079454 -114.7191)
		(mid 24.108771 -114.717982)
		(end 24.137874 -114.714274)
		(stroke
			(width 0.06985)
			(type default)
		)
		(layer "In2.Cu")
	)
	(gr_line
		(start 24.153876 -101.11994)
		(end 24.313896 -101.11994)
		(stroke
			(width 0.0635)
			(type default)
		)
		(layer "In2.Cu")
	)
	(gr_line
		(start 24.2316 -185.8264)
		(end 24.302466 -185.755534)
		(stroke
			(width 0.0635)
			(type default)
		)
		(layer "In2.Cu")
	)
	(gr_line
		(start 24.2316 -184.9628)
		(end 24.302466 -185.033666)
		(stroke
			(width 0.0635)
			(type default)
		)
		(layer "In2.Cu")
	)
	(gr_line
		(start 24.473154 -112.522)
		(end 24.82596 -112.169194)
		(stroke
			(width 0.06985)
			(type default)
		)
		(layer "In2.Cu")
	)
	(gr_line
		(start 24.473154 -111.4044)
		(end 24.82596 -111.757206)
		(stroke
			(width 0.06985)
			(type default)
		)
		(layer "In2.Cu")
	)
	(gr_arc
		(start 24.82596 -111.757206)
		(mid 24.871293 -111.787496)
		(end 24.924766 -111.7981)
		(stroke
			(width 0.06985)
			(type default)
		)
		(layer "In2.Cu")
	)
	(gr_arc
		(start 24.924766 -112.1283)
		(mid 24.871305 -112.138934)
		(end 24.82596 -112.169194)
		(stroke
			(width 0.06985)
			(type default)
		)
		(layer "In2.Cu")
	)
	(gr_line
		(start 25.805384 -143.374364)
		(end 26.12898 -143.69796)
		(stroke
			(width 0.06985)
			(type default)
		)
		(layer "In2.Cu")
	)
	(gr_line
		(start 25.805384 -142.903956)
		(end 26.12898 -142.58036)
		(stroke
			(width 0.06985)
			(type default)
		)
		(layer "In2.Cu")
	)
	(gr_line
		(start 25.92324 -111.987584)
		(end 25.97912 -111.948976)
		(stroke
			(width 0.06985)
			(type default)
		)
		(layer "In2.Cu")
	)
	(gr_line
		(start 26.256488 -80.866996)
		(end 26.274268 -80.855566)
		(stroke
			(width 0.06985)
			(type default)
		)
		(layer "In2.Cu")
	)
	(gr_line
		(start 26.274268 -80.855566)
		(end 26.29408 -80.851502)
		(stroke
			(width 0.06985)
			(type default)
		)
		(layer "In2.Cu")
	)
	(gr_line
		(start 26.630376 -112.722406)
		(end 27.19959 -112.32896)
		(stroke
			(width 0.06985)
			(type default)
		)
		(layer "In2.Cu")
	)
	(gr_line
		(start 26.787856 -113.017808)
		(end 27.03195 -113.062512)
		(stroke
			(width 0.06985)
			(type default)
		)
		(layer "In2.Cu")
	)
	(gr_line
		(start 27.03195 -113.062512)
		(end 27.376628 -112.824006)
		(stroke
			(width 0.06985)
			(type default)
		)
		(layer "In2.Cu")
	)
	(gr_line
		(start 27.254962 -80.646778)
		(end 27.285442 -80.640428)
		(stroke
			(width 0.06985)
			(type default)
		)
		(layer "In2.Cu")
	)
	(gr_line
		(start 27.285442 -80.640428)
		(end 27.314906 -80.646778)
		(stroke
			(width 0.06985)
			(type default)
		)
		(layer "In2.Cu")
	)
	(gr_line
		(start 27.376628 -112.824006)
		(end 27.421332 -112.580166)
		(stroke
			(width 0.06985)
			(type default)
		)
		(layer "In2.Cu")
	)
	(gr_line
		(start 27.613102 -112.042956)
		(end 28.183078 -111.649002)
		(stroke
			(width 0.06985)
			(type default)
		)
		(layer "In2.Cu")
	)
	(gr_line
		(start 27.76982 -112.338866)
		(end 28.013914 -112.38357)
		(stroke
			(width 0.06985)
			(type default)
		)
		(layer "In2.Cu")
	)
	(gr_line
		(start 28.013914 -112.38357)
		(end 28.358592 -112.145064)
		(stroke
			(width 0.06985)
			(type default)
		)
		(layer "In2.Cu")
	)
	(gr_arc
		(start 28.043124 -105.935018)
		(mid 28.316673 -106.050197)
		(end 28.59278 -105.941368)
		(stroke
			(width 0.06985)
			(type default)
		)
		(layer "In2.Cu")
	)
	(gr_line
		(start 28.358592 -112.145064)
		(end 28.403296 -111.901224)
		(stroke
			(width 0.06985)
			(type default)
		)
		(layer "In2.Cu")
	)
	(gr_line
		(start 29.312108 -86.45525)
		(end 29.340302 -86.45525)
		(stroke
			(width 0.06985)
			(type default)
		)
		(layer "In2.Cu")
	)
	(gr_line
		(start 29.336746 -111.252508)
		(end 29.351478 -111.242602)
		(stroke
			(width 0.06985)
			(type default)
		)
		(layer "In2.Cu")
	)
	(gr_line
		(start 29.351478 -111.242602)
		(end 29.351732 -111.242348)
		(stroke
			(width 0.06985)
			(type default)
		)
		(layer "In2.Cu")
	)
	(gr_line
		(start 29.351732 -111.242094)
		(end 29.351732 -111.242348)
		(stroke
			(width 0.06985)
			(type default)
		)
		(layer "In2.Cu")
	)
	(gr_line
		(start 29.351732 -111.242094)
		(end 29.352494 -111.241332)
		(stroke
			(width 0.06985)
			(type default)
		)
		(layer "In2.Cu")
	)
	(gr_line
		(start 29.352494 -111.241332)
		(end 29.362654 -111.226854)
		(stroke
			(width 0.06985)
			(type default)
		)
		(layer "In2.Cu")
	)
	(gr_line
		(start 29.642308 -86.62035)
		(end 29.670502 -86.62035)
		(stroke
			(width 0.06985)
			(type default)
		)
		(layer "In2.Cu")
	)
	(gr_line
		(start 29.920438 -96.909382)
		(end 29.921454 -97.070418)
		(stroke
			(width 0.0635)
			(type default)
		)
		(layer "In2.Cu")
	)
	(gr_line
		(start 32.224218 -82.028284)
		(end 32.253682 -82.034634)
		(stroke
			(width 0.06985)
			(type default)
		)
		(layer "In2.Cu")
	)
	(gr_line
		(start 32.253682 -82.034634)
		(end 32.283146 -82.028284)
		(stroke
			(width 0.06985)
			(type default)
		)
		(layer "In2.Cu")
	)
	(gr_line
		(start 32.307784 -101.868478)
		(end 32.320992 -101.849174)
		(stroke
			(width 0.06985)
			(type default)
		)
		(layer "In2.Cu")
	)
	(gr_line
		(start 32.320992 -101.849174)
		(end 32.339788 -101.836474)
		(stroke
			(width 0.06985)
			(type default)
		)
		(layer "In2.Cu")
	)
	(gr_line
		(start 32.668972 -103.698548)
		(end 32.579818 -103.783638)
		(stroke
			(width 0.06985)
			(type default)
		)
		(layer "In2.Cu")
	)
	(gr_line
		(start 32.831532 -103.999792)
		(end 32.84855 -103.975662)
		(stroke
			(width 0.06985)
			(type default)
		)
		(layer "In2.Cu")
	)
	(gr_line
		(start 32.84855 -103.975662)
		(end 32.874712 -103.958644)
		(stroke
			(width 0.06985)
			(type default)
		)
		(layer "In2.Cu")
	)
	(gr_line
		(start 32.874712 -101.475286)
		(end 32.89427 -101.462078)
		(stroke
			(width 0.06985)
			(type default)
		)
		(layer "In2.Cu")
	)
	(gr_line
		(start 32.89427 -101.462078)
		(end 32.916876 -101.457252)
		(stroke
			(width 0.06985)
			(type default)
		)
		(layer "In2.Cu")
	)
	(gr_line
		(start 33.412938 -104.865678)
		(end 33.427162 -104.845358)
		(stroke
			(width 0.06985)
			(type default)
		)
		(layer "In2.Cu")
	)
	(gr_line
		(start 33.427162 -104.845358)
		(end 33.448498 -104.831388)
		(stroke
			(width 0.06985)
			(type default)
		)
		(layer "In2.Cu")
	)
	(gr_line
		(start 33.517586 -81.428336)
		(end 33.54705 -81.421986)
		(stroke
			(width 0.06985)
			(type default)
		)
		(layer "In2.Cu")
	)
	(gr_line
		(start 33.54705 -81.421986)
		(end 33.576514 -81.428336)
		(stroke
			(width 0.06985)
			(type default)
		)
		(layer "In2.Cu")
	)
	(gr_line
		(start 33.906206 -102.894892)
		(end 33.923986 -102.883462)
		(stroke
			(width 0.06985)
			(type default)
		)
		(layer "In2.Cu")
	)
	(gr_line
		(start 33.923986 -102.883462)
		(end 33.943798 -102.879398)
		(stroke
			(width 0.06985)
			(type default)
		)
		(layer "In2.Cu")
	)
	(gr_line
		(start 34.605976 -104.075992)
		(end 34.623756 -104.064054)
		(stroke
			(width 0.06985)
			(type default)
		)
		(layer "In2.Cu")
	)
	(gr_line
		(start 34.623756 -104.064054)
		(end 34.644838 -104.059736)
		(stroke
			(width 0.06985)
			(type default)
		)
		(layer "In2.Cu")
	)
	(gr_line
		(start 34.708846 -102.71633)
		(end 34.739326 -102.70998)
		(stroke
			(width 0.06985)
			(type default)
		)
		(layer "In2.Cu")
	)
	(gr_line
		(start 34.739326 -102.70998)
		(end 34.76879 -102.71633)
		(stroke
			(width 0.06985)
			(type default)
		)
		(layer "In2.Cu")
	)
	(gr_line
		(start 35.276536 -103.92537)
		(end 35.306 -103.91902)
		(stroke
			(width 0.06985)
			(type default)
		)
		(layer "In2.Cu")
	)
	(gr_line
		(start 35.306 -103.91902)
		(end 35.33648 -103.92537)
		(stroke
			(width 0.06985)
			(type default)
		)
		(layer "In2.Cu")
	)
	(gr_line
		(start 36.882832 -103.503222)
		(end 36.912296 -103.509572)
		(stroke
			(width 0.06985)
			(type default)
		)
		(layer "In2.Cu")
	)
	(gr_line
		(start 36.891976 -104.594406)
		(end 36.922456 -104.600756)
		(stroke
			(width 0.06985)
			(type default)
		)
		(layer "In2.Cu")
	)
	(gr_line
		(start 36.912296 -103.509572)
		(end 36.94176 -103.503222)
		(stroke
			(width 0.06985)
			(type default)
		)
		(layer "In2.Cu")
	)
	(gr_line
		(start 36.922456 -104.600756)
		(end 36.95192 -104.594406)
		(stroke
			(width 0.06985)
			(type default)
		)
		(layer "In2.Cu")
	)
	(gr_line
		(start 37.908992 -82.684874)
		(end 37.938456 -82.691224)
		(stroke
			(width 0.06985)
			(type default)
		)
		(layer "In2.Cu")
	)
	(gr_line
		(start 37.938456 -82.691224)
		(end 37.96792 -82.684874)
		(stroke
			(width 0.06985)
			(type default)
		)
		(layer "In2.Cu")
	)
	(gr_line
		(start 39.20617 -103.021892)
		(end 39.225982 -103.017828)
		(stroke
			(width 0.06985)
			(type default)
		)
		(layer "In2.Cu")
	)
	(gr_line
		(start 39.225982 -103.017828)
		(end 39.243762 -103.006398)
		(stroke
			(width 0.06985)
			(type default)
		)
		(layer "In2.Cu")
	)
	(gr_line
		(start 39.863014 -103.637842)
		(end 39.892478 -103.631492)
		(stroke
			(width 0.06985)
			(type default)
		)
		(layer "In2.Cu")
	)
	(gr_line
		(start 39.892478 -103.631492)
		(end 39.921942 -103.637842)
		(stroke
			(width 0.06985)
			(type default)
		)
		(layer "In2.Cu")
	)
	(gr_line
		(start 40.13454 -102.033832)
		(end 40.15232 -102.022402)
		(stroke
			(width 0.06985)
			(type default)
		)
		(layer "In2.Cu")
	)
	(gr_line
		(start 40.15232 -102.022402)
		(end 40.17264 -102.018084)
		(stroke
			(width 0.06985)
			(type default)
		)
		(layer "In2.Cu")
	)
	(gr_line
		(start 40.710612 -101.903784)
		(end 40.740076 -101.897434)
		(stroke
			(width 0.06985)
			(type default)
		)
		(layer "In2.Cu")
	)
	(gr_line
		(start 40.740076 -101.897434)
		(end 40.76954 -101.903784)
		(stroke
			(width 0.06985)
			(type default)
		)
		(layer "In2.Cu")
	)
	(gr_line
		(start 41.799764 -99.569524)
		(end 41.828466 -99.563428)
		(stroke
			(width 0.06985)
			(type default)
		)
		(layer "In2.Cu")
	)
	(gr_line
		(start 41.828466 -99.563428)
		(end 41.856914 -99.569524)
		(stroke
			(width 0.06985)
			(type default)
		)
		(layer "In2.Cu")
	)
	(gr_line
		(start 42.186098 -77.3049)
		(end 42.3037 -77.187298)
		(stroke
			(width 0.0635)
			(type default)
		)
		(layer "In2.Cu")
	)
	(gr_line
		(start 42.197274 -104.459024)
		(end 42.226738 -104.465374)
		(stroke
			(width 0.06985)
			(type default)
		)
		(layer "In2.Cu")
	)
	(gr_line
		(start 42.226738 -104.465374)
		(end 42.257218 -104.459024)
		(stroke
			(width 0.06985)
			(type default)
		)
		(layer "In2.Cu")
	)
	(gr_line
		(start 42.450766 -102.599236)
		(end 42.481246 -102.605586)
		(stroke
			(width 0.06985)
			(type default)
		)
		(layer "In2.Cu")
	)
	(gr_line
		(start 42.481246 -102.605586)
		(end 42.51071 -102.599236)
		(stroke
			(width 0.06985)
			(type default)
		)
		(layer "In2.Cu")
	)
	(gr_line
		(start 42.858182 -81.645252)
		(end 42.877994 -81.641188)
		(stroke
			(width 0.06985)
			(type default)
		)
		(layer "In2.Cu")
	)
	(gr_line
		(start 42.877994 -81.641188)
		(end 42.895774 -81.629758)
		(stroke
			(width 0.06985)
			(type default)
		)
		(layer "In2.Cu")
	)
	(gr_line
		(start 43.002454 -104.300528)
		(end 43.022774 -104.29621)
		(stroke
			(width 0.06985)
			(type default)
		)
		(layer "In2.Cu")
	)
	(gr_line
		(start 43.022774 -104.29621)
		(end 43.040554 -104.28478)
		(stroke
			(width 0.06985)
			(type default)
		)
		(layer "In2.Cu")
	)
	(gr_line
		(start 43.025822 -77.187298)
		(end 43.195748 -77.357224)
		(stroke
			(width 0.0635)
			(type default)
		)
		(layer "In2.Cu")
	)
	(gr_line
		(start 43.490896 -102.390702)
		(end 43.510708 -102.386638)
		(stroke
			(width 0.06985)
			(type default)
		)
		(layer "In2.Cu")
	)
	(gr_line
		(start 43.510708 -102.386638)
		(end 43.528488 -102.375208)
		(stroke
			(width 0.06985)
			(type default)
		)
		(layer "In2.Cu")
	)
	(gr_line
		(start 43.70451 -125.685042)
		(end 44.10456 -125.284992)
		(stroke
			(width 0.0635)
			(type default)
		)
		(layer "In2.Cu")
	)
	(gr_line
		(start 43.70451 -124.642118)
		(end 43.70451 -124.885196)
		(stroke
			(width 0.0635)
			(type default)
		)
		(layer "In2.Cu")
	)
	(gr_line
		(start 43.70451 -124.642118)
		(end 44.111164 -124.235464)
		(stroke
			(width 0.0635)
			(type default)
		)
		(layer "In2.Cu")
	)
	(gr_line
		(start 44.10456 -124.728224)
		(end 44.10456 -125.284992)
		(stroke
			(width 0.0635)
			(type default)
		)
		(layer "In2.Cu")
	)
	(gr_line
		(start 44.10456 -124.728224)
		(end 44.347638 -124.485146)
		(stroke
			(width 0.0635)
			(type default)
		)
		(layer "In2.Cu")
	)
	(gr_line
		(start 44.111164 -123.92152)
		(end 44.111164 -124.235464)
		(stroke
			(width 0.0635)
			(type default)
		)
		(layer "In2.Cu")
	)
	(gr_line
		(start 44.111164 -123.92152)
		(end 44.353988 -123.678696)
		(stroke
			(width 0.0635)
			(type default)
		)
		(layer "In2.Cu")
	)
	(gr_line
		(start 44.27982 -101.49332)
		(end 44.2976 -101.48189)
		(stroke
			(width 0.06985)
			(type default)
		)
		(layer "In2.Cu")
	)
	(gr_line
		(start 44.2976 -101.48189)
		(end 44.317412 -101.477826)
		(stroke
			(width 0.06985)
			(type default)
		)
		(layer "In2.Cu")
	)
	(gr_line
		(start 44.347638 -124.485146)
		(end 46.261528 -124.485146)
		(stroke
			(width 0.0635)
			(type default)
		)
		(layer "In2.Cu")
	)
	(gr_line
		(start 44.353988 -123.678696)
		(end 44.667932 -123.678696)
		(stroke
			(width 0.0635)
			(type default)
		)
		(layer "In2.Cu")
	)
	(gr_line
		(start 44.50461 -125.685042)
		(end 44.910756 -125.278896)
		(stroke
			(width 0.0635)
			(type default)
		)
		(layer "In2.Cu")
	)
	(gr_line
		(start 44.667932 -123.678696)
		(end 44.898818 -123.44781)
		(stroke
			(width 0.0635)
			(type default)
		)
		(layer "In2.Cu")
	)
	(gr_line
		(start 44.667932 -100.494084)
		(end 44.696126 -100.50018)
		(stroke
			(width 0.06985)
			(type default)
		)
		(layer "In2.Cu")
	)
	(gr_line
		(start 44.696126 -100.50018)
		(end 44.723558 -100.494084)
		(stroke
			(width 0.06985)
			(type default)
		)
		(layer "In2.Cu")
	)
	(gr_line
		(start 44.898818 -122.154188)
		(end 44.898818 -123.44781)
		(stroke
			(width 0.0635)
			(type default)
		)
		(layer "In2.Cu")
	)
	(gr_line
		(start 44.898818 -122.154188)
		(end 45.594016 -121.45899)
		(stroke
			(width 0.0635)
			(type default)
		)
		(layer "In2.Cu")
	)
	(gr_line
		(start 44.910756 -125.278896)
		(end 46.605952 -125.278896)
		(stroke
			(width 0.0635)
			(type default)
		)
		(layer "In2.Cu")
	)
	(gr_line
		(start 45.149262 -102.521766)
		(end 45.16755 -102.509574)
		(stroke
			(width 0.06985)
			(type default)
		)
		(layer "In2.Cu")
	)
	(gr_line
		(start 45.16755 -102.509574)
		(end 45.18914 -102.505256)
		(stroke
			(width 0.06985)
			(type default)
		)
		(layer "In2.Cu")
	)
	(gr_line
		(start 45.510196 -79.538322)
		(end 45.527976 -79.526892)
		(stroke
			(width 0.06985)
			(type default)
		)
		(layer "In2.Cu")
	)
	(gr_line
		(start 45.527976 -79.526892)
		(end 45.547788 -79.522828)
		(stroke
			(width 0.06985)
			(type default)
		)
		(layer "In2.Cu")
	)
	(gr_line
		(start 45.8724 -45.126656)
		(end 45.8724 -45.392848)
		(stroke
			(width 0.0508)
			(type default)
		)
		(layer "In2.Cu")
	)
	(gr_line
		(start 45.8724 -45.126656)
		(end 46.087792 -44.911264)
		(stroke
			(width 0.0508)
			(type default)
		)
		(layer "In2.Cu")
	)
	(gr_line
		(start 46.087792 -44.911264)
		(end 46.353984 -44.911264)
		(stroke
			(width 0.0508)
			(type default)
		)
		(layer "In2.Cu")
	)
	(gr_line
		(start 46.261528 -124.485146)
		(end 46.504606 -124.242068)
		(stroke
			(width 0.0635)
			(type default)
		)
		(layer "In2.Cu")
	)
	(gr_line
		(start 46.30547 -45.394372)
		(end 46.355508 -45.344334)
		(stroke
			(width 0.0508)
			(type default)
		)
		(layer "In2.Cu")
	)
	(gr_line
		(start 46.504606 -123.927616)
		(end 46.504606 -124.242068)
		(stroke
			(width 0.0635)
			(type default)
		)
		(layer "In2.Cu")
	)
	(gr_line
		(start 46.504606 -123.927616)
		(end 46.665134 -123.767088)
		(stroke
			(width 0.0635)
			(type default)
		)
		(layer "In2.Cu")
	)
	(gr_line
		(start 46.572932 -44.426378)
		(end 46.572932 -44.692316)
		(stroke
			(width 0.0508)
			(type default)
		)
		(layer "In2.Cu")
	)
	(gr_line
		(start 46.572932 -44.426378)
		(end 46.788324 -44.210732)
		(stroke
			(width 0.0508)
			(type default)
		)
		(layer "In2.Cu")
	)
	(gr_line
		(start 46.666912 -123.76531)
		(end 46.741334 -123.690888)
		(stroke
			(width 0.0635)
			(type default)
		)
		(layer "In2.Cu")
	)
	(gr_line
		(start 46.741334 -123.690888)
		(end 47.067978 -123.690888)
		(stroke
			(width 0.0635)
			(type default)
		)
		(layer "In2.Cu")
	)
	(gr_line
		(start 46.788324 -44.210732)
		(end 47.054516 -44.210732)
		(stroke
			(width 0.0508)
			(type default)
		)
		(layer "In2.Cu")
	)
	(gr_line
		(start 46.904656 -124.55906)
		(end 47.113952 -124.768356)
		(stroke
			(width 0.0635)
			(type default)
		)
		(layer "In2.Cu")
	)
	(gr_line
		(start 46.904656 -124.084588)
		(end 46.904656 -124.55906)
		(stroke
			(width 0.0635)
			(type default)
		)
		(layer "In2.Cu")
	)
	(gr_line
		(start 46.904656 -123.284488)
		(end 46.90491 -123.284742)
		(stroke
			(width 0.0635)
			(type default)
		)
		(layer "In2.Cu")
	)
	(gr_line
		(start 46.90491 -123.284742)
		(end 46.918118 -123.284742)
		(stroke
			(width 0.0635)
			(type default)
		)
		(layer "In2.Cu")
	)
	(gr_line
		(start 46.918118 -123.284742)
		(end 46.938946 -123.263914)
		(stroke
			(width 0.0635)
			(type default)
		)
		(layer "In2.Cu")
	)
	(gr_line
		(start 46.938946 -123.263914)
		(end 47.35957 -123.263914)
		(stroke
			(width 0.0635)
			(type default)
		)
		(layer "In2.Cu")
	)
	(gr_line
		(start 46.99 -106.6546)
		(end 48.28413 -106.243628)
		(stroke
			(width 0.0635)
			(type default)
		)
		(layer "In2.Cu")
	)
	(gr_line
		(start 47.006002 -44.69384)
		(end 47.05604 -44.643802)
		(stroke
			(width 0.0508)
			(type default)
		)
		(layer "In2.Cu")
	)
	(gr_line
		(start 47.067978 -123.690888)
		(end 47.149258 -123.772168)
		(stroke
			(width 0.0635)
			(type default)
		)
		(layer "In2.Cu")
	)
	(gr_line
		(start 47.244762 -102.078282)
		(end 47.923958 -101.937058)
		(stroke
			(width 0.06985)
			(type default)
		)
		(layer "In2.Cu")
	)
	(gr_line
		(start 47.27321 -43.725846)
		(end 47.27321 -43.992038)
		(stroke
			(width 0.0508)
			(type default)
		)
		(layer "In2.Cu")
	)
	(gr_line
		(start 47.27321 -43.725846)
		(end 47.488856 -43.510454)
		(stroke
			(width 0.0508)
			(type default)
		)
		(layer "In2.Cu")
	)
	(gr_line
		(start 47.275242 -102.41153)
		(end 47.48276 -102.547674)
		(stroke
			(width 0.06985)
			(type default)
		)
		(layer "In2.Cu")
	)
	(gr_line
		(start 47.392844 -123.297188)
		(end 47.575978 -123.297188)
		(stroke
			(width 0.0635)
			(type default)
		)
		(layer "In2.Cu")
	)
	(gr_line
		(start 47.48276 -102.547674)
		(end 47.893224 -102.46233)
		(stroke
			(width 0.06985)
			(type default)
		)
		(layer "In2.Cu")
	)
	(gr_line
		(start 47.488856 -43.510454)
		(end 47.754794 -43.510454)
		(stroke
			(width 0.0508)
			(type default)
		)
		(layer "In2.Cu")
	)
	(gr_line
		(start 47.70628 -43.993562)
		(end 47.756318 -43.943524)
		(stroke
			(width 0.0508)
			(type default)
		)
		(layer "In2.Cu")
	)
	(gr_line
		(start 47.893224 -102.46233)
		(end 48.029368 -102.254812)
		(stroke
			(width 0.06985)
			(type default)
		)
		(layer "In2.Cu")
	)
	(gr_line
		(start 47.973742 -43.025314)
		(end 47.973742 -43.291506)
		(stroke
			(width 0.0508)
			(type default)
		)
		(layer "In2.Cu")
	)
	(gr_line
		(start 47.973742 -43.025314)
		(end 48.189388 -42.809922)
		(stroke
			(width 0.0508)
			(type default)
		)
		(layer "In2.Cu")
	)
	(gr_line
		(start 48.189388 -42.809922)
		(end 48.455326 -42.809922)
		(stroke
			(width 0.0508)
			(type default)
		)
		(layer "In2.Cu")
	)
	(gr_line
		(start 48.28413 -106.243628)
		(end 48.703738 -106.243628)
		(stroke
			(width 0.0635)
			(type default)
		)
		(layer "In2.Cu")
	)
	(gr_line
		(start 48.406812 -43.29303)
		(end 48.45685 -43.242992)
		(stroke
			(width 0.0508)
			(type default)
		)
		(layer "In2.Cu")
	)
	(gr_line
		(start 48.41367 -101.835204)
		(end 49.094898 -101.693472)
		(stroke
			(width 0.06985)
			(type default)
		)
		(layer "In2.Cu")
	)
	(gr_line
		(start 48.44415 -102.168706)
		(end 48.651668 -102.304596)
		(stroke
			(width 0.06985)
			(type default)
		)
		(layer "In2.Cu")
	)
	(gr_line
		(start 48.651668 -102.304596)
		(end 49.062132 -102.219506)
		(stroke
			(width 0.06985)
			(type default)
		)
		(layer "In2.Cu")
	)
	(gr_line
		(start 48.703738 -106.243628)
		(end 48.7045 -106.24439)
		(stroke
			(width 0.0635)
			(type default)
		)
		(layer "In2.Cu")
	)
	(gr_line
		(start 48.7045 -106.24439)
		(end 48.718978 -106.287824)
		(stroke
			(width 0.0635)
			(type default)
		)
		(layer "In2.Cu")
	)
	(gr_line
		(start 48.718978 -106.289348)
		(end 48.7426 -106.364278)
		(stroke
			(width 0.0635)
			(type default)
		)
		(layer "In2.Cu")
	)
	(gr_line
		(start 48.718978 -106.287824)
		(end 48.718978 -106.289348)
		(stroke
			(width 0.0635)
			(type default)
		)
		(layer "In2.Cu")
	)
	(gr_line
		(start 48.7426 -106.364278)
		(end 48.7426 -106.574336)
		(stroke
			(width 0.0635)
			(type default)
		)
		(layer "In2.Cu")
	)
	(gr_line
		(start 49.062132 -102.219506)
		(end 49.198276 -102.011988)
		(stroke
			(width 0.06985)
			(type default)
		)
		(layer "In2.Cu")
	)
	(gr_line
		(start 49.14519 -78.757526)
		(end 49.17567 -78.751176)
		(stroke
			(width 0.06985)
			(type default)
		)
		(layer "In2.Cu")
	)
	(gr_line
		(start 49.17567 -78.751176)
		(end 49.205134 -78.757526)
		(stroke
			(width 0.06985)
			(type default)
		)
		(layer "In2.Cu")
	)
	(gr_line
		(start 49.28743 -106.149902)
		(end 49.28743 -106.397044)
		(stroke
			(width 0.0635)
			(type default)
		)
		(layer "In2.Cu")
	)
	(gr_line
		(start 49.28743 -106.149902)
		(end 49.618646 -105.818686)
		(stroke
			(width 0.0635)
			(type default)
		)
		(layer "In2.Cu")
	)
	(gr_line
		(start 49.618646 -105.818686)
		(end 50.8254 -105.4354)
		(stroke
			(width 0.0635)
			(type default)
		)
		(layer "In2.Cu")
	)
	(gr_arc
		(start 50.093372 -221.405704)
		(mid 50.234468 -221.211211)
		(end 50.308256 -220.98254)
		(stroke
			(width 0.06985)
			(type default)
		)
		(layer "In2.Cu")
	)
	(gr_arc
		(start 50.14468 -208.712054)
		(mid 50.316477 -208.460729)
		(end 50.385218 -208.164176)
		(stroke
			(width 0.06985)
			(type default)
		)
		(layer "In2.Cu")
	)
	(gr_arc
		(start 50.308256 -220.98254)
		(mid 50.315107 -220.923916)
		(end 50.3174 -220.864938)
		(stroke
			(width 0.06985)
			(type default)
		)
		(layer "In2.Cu")
	)
	(gr_line
		(start 50.3174 -220.078808)
		(end 50.346864 -220.032072)
		(stroke
			(width 0.06985)
			(type default)
		)
		(layer "In2.Cu")
	)
	(gr_arc
		(start 50.385218 -208.164176)
		(mid 50.385785 -208.146781)
		(end 50.38598 -208.129378)
		(stroke
			(width 0.06985)
			(type default)
		)
		(layer "In2.Cu")
	)
	(gr_arc
		(start 50.6476 -221.035626)
		(mid 50.668012 -221.138713)
		(end 50.72634 -221.226126)
		(stroke
			(width 0.06985)
			(type default)
		)
		(layer "In2.Cu")
	)
	(gr_line
		(start 50.6857 -38.4175)
		(end 50.87366 -38.60546)
		(stroke
			(width 0.0508)
			(type default)
		)
		(layer "In2.Cu")
	)
	(gr_line
		(start 50.6857 -38.1127)
		(end 50.6857 -38.4175)
		(stroke
			(width 0.0508)
			(type default)
		)
		(layer "In2.Cu")
	)
	(gr_line
		(start 50.6857 -38.1127)
		(end 50.87366 -37.92474)
		(stroke
			(width 0.0508)
			(type default)
		)
		(layer "In2.Cu")
	)
	(gr_line
		(start 50.6857 -37.4269)
		(end 50.87366 -37.61486)
		(stroke
			(width 0.0508)
			(type default)
		)
		(layer "In2.Cu")
	)
	(gr_line
		(start 50.6857 -37.1221)
		(end 50.6857 -37.4269)
		(stroke
			(width 0.0508)
			(type default)
		)
		(layer "In2.Cu")
	)
	(gr_line
		(start 50.6857 -37.1221)
		(end 50.87366 -36.93414)
		(stroke
			(width 0.0508)
			(type default)
		)
		(layer "In2.Cu")
	)
	(gr_arc
		(start 50.71618 -208.1784)
		(mid 50.779283 -208.471251)
		(end 50.95748 -208.712054)
		(stroke
			(width 0.06985)
			(type default)
		)
		(layer "In2.Cu")
	)
	(gr_line
		(start 50.72634 -221.226126)
		(end 50.906172 -221.405704)
		(stroke
			(width 0.06985)
			(type default)
		)
		(layer "In2.Cu")
	)
	(gr_line
		(start 50.869596 -100.08489)
		(end 50.89271 -100.080064)
		(stroke
			(width 0.06985)
			(type default)
		)
		(layer "In2.Cu")
	)
	(gr_line
		(start 50.89271 -100.080064)
		(end 50.915062 -100.083874)
		(stroke
			(width 0.06985)
			(type default)
		)
		(layer "In2.Cu")
	)
	(gr_line
		(start 51.001168 -101.297486)
		(end 51.023012 -101.292914)
		(stroke
			(width 0.06985)
			(type default)
		)
		(layer "In2.Cu")
	)
	(gr_line
		(start 51.023012 -101.292914)
		(end 51.045618 -101.296978)
		(stroke
			(width 0.06985)
			(type default)
		)
		(layer "In2.Cu")
	)
	(gr_line
		(start 51.181 -38.22954)
		(end 51.181 -38.30066)
		(stroke
			(width 0.0508)
			(type default)
		)
		(layer "In2.Cu")
	)
	(gr_line
		(start 51.181 -37.23894)
		(end 51.181 -37.31006)
		(stroke
			(width 0.0508)
			(type default)
		)
		(layer "In2.Cu")
	)
	(gr_line
		(start 51.600608 -98.694494)
		(end 51.624992 -98.689414)
		(stroke
			(width 0.06985)
			(type default)
		)
		(layer "In2.Cu")
	)
	(gr_line
		(start 51.624992 -98.689414)
		(end 51.64963 -98.693732)
		(stroke
			(width 0.06985)
			(type default)
		)
		(layer "In2.Cu")
	)
	(gr_line
		(start 52.28336 -82.646774)
		(end 52.551076 -82.379058)
		(stroke
			(width 0.0635)
			(type default)
		)
		(layer "In2.Cu")
	)
	(gr_line
		(start 53.06314 -82.347816)
		(end 53.086 -82.347816)
		(stroke
			(width 0.0635)
			(type default)
		)
		(layer "In2.Cu")
	)
	(gr_line
		(start 53.086 -82.347816)
		(end 53.384958 -82.646774)
		(stroke
			(width 0.0635)
			(type default)
		)
		(layer "In2.Cu")
	)
	(gr_arc
		(start 53.293518 -222.294704)
		(mid 53.472082 -222.027352)
		(end 53.534818 -221.712028)
		(stroke
			(width 0.06985)
			(type default)
		)
		(layer "In2.Cu")
	)
	(gr_line
		(start 53.5178 -208.115916)
		(end 53.55463 -208.063338)
		(stroke
			(width 0.06985)
			(type default)
		)
		(layer "In2.Cu")
	)
	(gr_line
		(start 53.534818 -219.998036)
		(end 53.559456 -219.955872)
		(stroke
			(width 0.06985)
			(type default)
		)
		(layer "In2.Cu")
	)
	(gr_line
		(start 53.818536 -215.152224)
		(end 53.848 -215.105488)
		(stroke
			(width 0.06985)
			(type default)
		)
		(layer "In2.Cu")
	)
	(gr_arc
		(start 53.865018 -221.7166)
		(mid 53.926991 -222.027689)
		(end 54.10327 -222.291402)
		(stroke
			(width 0.06985)
			(type default)
		)
		(layer "In2.Cu")
	)
	(gr_line
		(start 54.10327 -222.291402)
		(end 54.106318 -222.294704)
		(stroke
			(width 0.06985)
			(type default)
		)
		(layer "In2.Cu")
	)
	(gr_line
		(start 55.630572 -96.012)
		(end 55.912258 -95.730314)
		(stroke
			(width 0.0635)
			(type default)
		)
		(layer "In2.Cu")
	)
	(gr_arc
		(start 55.799228 -85.60435)
		(mid 56.098741 -85.492065)
		(end 56.25084 -85.21065)
		(stroke
			(width 0.06985)
			(type default)
		)
		(layer "In2.Cu")
	)
	(gr_line
		(start 56.051958 -102.17912)
		(end 56.084724 -102.184962)
		(stroke
			(width 0.06985)
			(type default)
		)
		(layer "In2.Cu")
	)
	(gr_line
		(start 56.084724 -102.18547)
		(end 56.110632 -102.203504)
		(stroke
			(width 0.06985)
			(type default)
		)
		(layer "In2.Cu")
	)
	(gr_line
		(start 56.084724 -102.184962)
		(end 56.084724 -102.18547)
		(stroke
			(width 0.06985)
			(type default)
		)
		(layer "In2.Cu")
	)
	(gr_arc
		(start 56.25084 -86.32825)
		(mid 56.098775 -86.046827)
		(end 55.799228 -85.93455)
		(stroke
			(width 0.06985)
			(type default)
		)
		(layer "In2.Cu")
	)
	(gr_line
		(start 56.381904 -80.619854)
		(end 56.411368 -80.626204)
		(stroke
			(width 0.06985)
			(type default)
		)
		(layer "In2.Cu")
	)
	(gr_line
		(start 56.411368 -80.626204)
		(end 56.440832 -80.619854)
		(stroke
			(width 0.06985)
			(type default)
		)
		(layer "In2.Cu")
	)
	(gr_line
		(start 56.477916 -26.163524)
		(end 60.003436 -26.163524)
		(stroke
			(width 0.0635)
			(type default)
		)
		(layer "In2.Cu")
	)
	(gr_arc
		(start 56.49341 -222.294704)
		(mid 56.671975 -222.027353)
		(end 56.73471 -221.712028)
		(stroke
			(width 0.06985)
			(type default)
		)
		(layer "In2.Cu")
	)
	(gr_line
		(start 56.508396 -95.78086)
		(end 56.739282 -96.012)
		(stroke
			(width 0.0635)
			(type default)
		)
		(layer "In2.Cu")
	)
	(gr_line
		(start 56.718708 -207.485488)
		(end 56.718708 -207.54848)
		(stroke
			(width 0.06985)
			(type default)
		)
		(layer "In2.Cu")
	)
	(gr_line
		(start 56.718708 -207.485488)
		(end 56.754776 -207.433926)
		(stroke
			(width 0.06985)
			(type default)
		)
		(layer "In2.Cu")
	)
	(gr_line
		(start 56.73471 -219.205556)
		(end 56.770778 -219.153994)
		(stroke
			(width 0.06985)
			(type default)
		)
		(layer "In2.Cu")
	)
	(gr_line
		(start 56.804814 -24.965152)
		(end 56.804814 -25.222708)
		(stroke
			(width 0.0635)
			(type default)
		)
		(layer "In2.Cu")
	)
	(gr_line
		(start 56.804814 -24.965152)
		(end 57.289954 -24.480012)
		(stroke
			(width 0.0635)
			(type default)
		)
		(layer "In2.Cu")
	)
	(gr_line
		(start 56.891936 -101.439726)
		(end 56.891936 -101.43998)
		(stroke
			(width 0.06985)
			(type default)
		)
		(layer "In2.Cu")
	)
	(gr_line
		(start 56.891936 -101.439726)
		(end 56.89219 -101.43998)
		(stroke
			(width 0.06985)
			(type default)
		)
		(layer "In2.Cu")
	)
	(gr_line
		(start 56.936894 -101.112574)
		(end 56.95823 -101.11613)
		(stroke
			(width 0.06985)
			(type default)
		)
		(layer "In2.Cu")
	)
	(gr_line
		(start 56.989218 -101.121464)
		(end 57.021476 -101.127052)
		(stroke
			(width 0.06985)
			(type default)
		)
		(layer "In2.Cu")
	)
	(gr_line
		(start 57.021476 -101.127052)
		(end 57.049416 -101.14661)
		(stroke
			(width 0.06985)
			(type default)
		)
		(layer "In2.Cu")
	)
	(gr_line
		(start 57.023762 -214.689436)
		(end 57.0484 -214.647272)
		(stroke
			(width 0.06985)
			(type default)
		)
		(layer "In2.Cu")
	)
	(gr_line
		(start 57.0484 -214.647272)
		(end 57.048654 -214.647272)
		(stroke
			(width 0.06985)
			(type default)
		)
		(layer "In2.Cu")
	)
	(gr_line
		(start 57.048654 -214.596472)
		(end 57.048654 -214.647272)
		(stroke
			(width 0.06985)
			(type default)
		)
		(layer "In2.Cu")
	)
	(gr_arc
		(start 57.06491 -221.712028)
		(mid 57.127631 -222.02735)
		(end 57.30621 -222.294704)
		(stroke
			(width 0.06985)
			(type default)
		)
		(layer "In2.Cu")
	)
	(gr_line
		(start 57.289954 -24.480012)
		(end 57.36844 -24.480012)
		(stroke
			(width 0.0635)
			(type default)
		)
		(layer "In2.Cu")
	)
	(gr_line
		(start 57.4802 -128.4478)
		(end 57.918858 -128.4478)
		(stroke
			(width 0.0635)
			(type default)
		)
		(layer "In2.Cu")
	)
	(gr_line
		(start 57.53862 -127.585978)
		(end 57.830466 -127.585978)
		(stroke
			(width 0.0635)
			(type default)
		)
		(layer "In2.Cu")
	)
	(gr_line
		(start 57.811924 -25.055068)
		(end 57.87644 -24.990552)
		(stroke
			(width 0.0635)
			(type default)
		)
		(layer "In2.Cu")
	)
	(gr_line
		(start 57.830466 -127.585978)
		(end 58.165746 -127.921258)
		(stroke
			(width 0.0635)
			(type default)
		)
		(layer "In2.Cu")
	)
	(gr_line
		(start 57.953402 -19.961606)
		(end 61.454538 -19.961606)
		(stroke
			(width 0.0508)
			(type default)
		)
		(layer "In2.Cu")
	)
	(gr_line
		(start 57.953402 -17.421606)
		(end 61.458094 -17.421606)
		(stroke
			(width 0.0508)
			(type default)
		)
		(layer "In2.Cu")
	)
	(gr_line
		(start 58.165746 -127.921258)
		(end 58.410856 -127.921258)
		(stroke
			(width 0.0635)
			(type default)
		)
		(layer "In2.Cu")
	)
	(gr_line
		(start 58.410856 -127.921258)
		(end 58.426858 -127.93726)
		(stroke
			(width 0.0635)
			(type default)
		)
		(layer "In2.Cu")
	)
	(gr_line
		(start 58.674 -93.4593)
		(end 58.699654 -93.4593)
		(stroke
			(width 0.0635)
			(type default)
		)
		(layer "In2.Cu")
	)
	(gr_line
		(start 59.080654 -200.171558)
		(end 59.091576 -200.156064)
		(stroke
			(width 0.06985)
			(type default)
		)
		(layer "In2.Cu")
	)
	(gr_line
		(start 59.091576 -200.156064)
		(end 59.10707 -200.145142)
		(stroke
			(width 0.06985)
			(type default)
		)
		(layer "In2.Cu")
	)
	(gr_line
		(start 59.129168 -104.720898)
		(end 59.157108 -104.740456)
		(stroke
			(width 0.06985)
			(type default)
		)
		(layer "In2.Cu")
	)
	(gr_line
		(start 59.157108 -104.740456)
		(end 59.190128 -104.746298)
		(stroke
			(width 0.06985)
			(type default)
		)
		(layer "In2.Cu")
	)
	(gr_line
		(start 59.182 -93.69552)
		(end 59.207654 -93.69552)
		(stroke
			(width 0.0635)
			(type default)
		)
		(layer "In2.Cu")
	)
	(gr_line
		(start 59.36488 -79.66075)
		(end 59.394344 -79.6544)
		(stroke
			(width 0.06985)
			(type default)
		)
		(layer "In2.Cu")
	)
	(gr_line
		(start 59.394344 -79.6544)
		(end 59.423808 -79.66075)
		(stroke
			(width 0.06985)
			(type default)
		)
		(layer "In2.Cu")
	)
	(gr_arc
		(start 59.693302 -222.294704)
		(mid 59.871869 -222.027353)
		(end 59.934602 -221.712028)
		(stroke
			(width 0.06985)
			(type default)
		)
		(layer "In2.Cu")
	)
	(gr_line
		(start 59.815222 -103.48595)
		(end 59.843162 -103.505508)
		(stroke
			(width 0.06985)
			(type default)
		)
		(layer "In2.Cu")
	)
	(gr_line
		(start 59.843162 -103.505508)
		(end 59.876182 -103.51135)
		(stroke
			(width 0.06985)
			(type default)
		)
		(layer "In2.Cu")
	)
	(gr_line
		(start 59.954922 -208.717134)
		(end 59.958224 -208.736184)
		(stroke
			(width 0.06985)
			(type default)
		)
		(layer "In2.Cu")
	)
	(gr_line
		(start 59.954922 -208.717134)
		(end 59.958224 -208.698338)
		(stroke
			(width 0.06985)
			(type default)
		)
		(layer "In2.Cu")
	)
	(gr_line
		(start 59.971178 -215.159082)
		(end 59.990736 -215.131142)
		(stroke
			(width 0.06985)
			(type default)
		)
		(layer "In2.Cu")
	)
	(gr_line
		(start 59.990736 -215.131142)
		(end 59.996578 -215.098122)
		(stroke
			(width 0.06985)
			(type default)
		)
		(layer "In2.Cu")
	)
	(gr_line
		(start 60.003436 -26.163524)
		(end 61.766196 -27.926284)
		(stroke
			(width 0.0635)
			(type default)
		)
		(layer "In2.Cu")
	)
	(gr_line
		(start 60.022486 -100.506276)
		(end 60.041282 -100.509578)
		(stroke
			(width 0.06985)
			(type default)
		)
		(layer "In2.Cu")
	)
	(gr_line
		(start 60.041282 -100.509578)
		(end 60.060078 -100.506276)
		(stroke
			(width 0.06985)
			(type default)
		)
		(layer "In2.Cu")
	)
	(gr_arc
		(start 60.264802 -221.712028)
		(mid 60.327484 -222.027371)
		(end 60.506102 -222.294704)
		(stroke
			(width 0.06985)
			(type default)
		)
		(layer "In2.Cu")
	)
	(gr_line
		(start 60.455556 -205.878938)
		(end 60.461398 -205.845918)
		(stroke
			(width 0.06985)
			(type default)
		)
		(layer "In2.Cu")
	)
	(gr_line
		(start 60.461398 -205.845918)
		(end 60.480956 -205.817978)
		(stroke
			(width 0.06985)
			(type default)
		)
		(layer "In2.Cu")
	)
	(gr_line
		(start 60.481718 -202.111102)
		(end 60.49264 -202.095608)
		(stroke
			(width 0.06985)
			(type default)
		)
		(layer "In2.Cu")
	)
	(gr_line
		(start 60.49264 -202.095608)
		(end 60.508134 -202.084686)
		(stroke
			(width 0.06985)
			(type default)
		)
		(layer "In2.Cu")
	)
	(gr_line
		(start 60.576714 -94.936818)
		(end 60.607194 -94.936818)
		(stroke
			(width 0.0635)
			(type default)
		)
		(layer "In2.Cu")
	)
	(gr_line
		(start 60.702698 -211.092796)
		(end 60.702698 -211.09305)
		(stroke
			(width 0.06985)
			(type default)
		)
		(layer "In2.Cu")
	)
	(gr_line
		(start 60.702698 -211.092796)
		(end 60.706 -211.074)
		(stroke
			(width 0.06985)
			(type default)
		)
		(layer "In2.Cu")
	)
	(gr_line
		(start 60.702698 -211.055204)
		(end 60.706 -211.074)
		(stroke
			(width 0.06985)
			(type default)
		)
		(layer "In2.Cu")
	)
	(gr_line
		(start 61.084714 -95.177864)
		(end 61.115194 -95.177864)
		(stroke
			(width 0.0635)
			(type default)
		)
		(layer "In2.Cu")
	)
	(gr_line
		(start 61.19622 -209.274156)
		(end 61.199522 -209.293206)
		(stroke
			(width 0.06985)
			(type default)
		)
		(layer "In2.Cu")
	)
	(gr_line
		(start 61.19622 -209.274156)
		(end 61.199522 -209.25536)
		(stroke
			(width 0.06985)
			(type default)
		)
		(layer "In2.Cu")
	)
	(gr_line
		(start 61.199522 -209.292952)
		(end 61.199522 -209.293206)
		(stroke
			(width 0.06985)
			(type default)
		)
		(layer "In2.Cu")
	)
	(gr_line
		(start 61.454538 -19.961606)
		(end 61.491114 -19.998182)
		(stroke
			(width 0.0508)
			(type default)
		)
		(layer "In2.Cu")
	)
	(gr_line
		(start 61.458094 -17.421606)
		(end 61.49467 -17.458182)
		(stroke
			(width 0.0508)
			(type default)
		)
		(layer "In2.Cu")
	)
	(gr_line
		(start 61.475874 -207.687164)
		(end 61.481716 -207.654144)
		(stroke
			(width 0.06985)
			(type default)
		)
		(layer "In2.Cu")
	)
	(gr_line
		(start 61.481716 -207.654144)
		(end 61.501274 -207.626204)
		(stroke
			(width 0.06985)
			(type default)
		)
		(layer "In2.Cu")
	)
	(gr_line
		(start 61.766196 -27.926284)
		(end 61.766196 -29.558996)
		(stroke
			(width 0.0635)
			(type default)
		)
		(layer "In2.Cu")
	)
	(gr_line
		(start 61.845698 -211.092796)
		(end 61.845698 -211.09305)
		(stroke
			(width 0.06985)
			(type default)
		)
		(layer "In2.Cu")
	)
	(gr_line
		(start 61.845698 -211.092796)
		(end 61.849 -211.074)
		(stroke
			(width 0.06985)
			(type default)
		)
		(layer "In2.Cu")
	)
	(gr_line
		(start 61.845698 -211.055204)
		(end 61.849 -211.074)
		(stroke
			(width 0.06985)
			(type default)
		)
		(layer "In2.Cu")
	)
	(gr_line
		(start 61.925962 -19.998182)
		(end 61.962538 -19.961606)
		(stroke
			(width 0.0508)
			(type default)
		)
		(layer "In2.Cu")
	)
	(gr_line
		(start 61.929518 -17.458182)
		(end 61.966094 -17.421606)
		(stroke
			(width 0.0508)
			(type default)
		)
		(layer "In2.Cu")
	)
	(gr_line
		(start 61.962538 -19.961606)
		(end 65.463674 -19.961606)
		(stroke
			(width 0.0508)
			(type default)
		)
		(layer "In2.Cu")
	)
	(gr_line
		(start 61.966094 -17.421606)
		(end 65.470786 -17.421606)
		(stroke
			(width 0.0508)
			(type default)
		)
		(layer "In2.Cu")
	)
	(gr_line
		(start 61.976 -97.023428)
		(end 62.169294 -96.830134)
		(stroke
			(width 0.0635)
			(type default)
		)
		(layer "In2.Cu")
	)
	(gr_line
		(start 61.976 -95.914718)
		(end 62.169294 -96.108012)
		(stroke
			(width 0.0635)
			(type default)
		)
		(layer "In2.Cu")
	)
	(gr_line
		(start 62.3316 -28.410662)
		(end 62.3316 -29.402278)
		(stroke
			(width 0.0635)
			(type default)
		)
		(layer "In2.Cu")
	)
	(gr_line
		(start 62.3316 -28.410662)
		(end 63.983362 -26.7589)
		(stroke
			(width 0.0635)
			(type default)
		)
		(layer "In2.Cu")
	)
	(gr_line
		(start 62.820296 -105.38587)
		(end 62.844934 -105.390188)
		(stroke
			(width 0.06985)
			(type default)
		)
		(layer "In2.Cu")
	)
	(gr_line
		(start 62.844934 -105.390188)
		(end 62.869318 -105.385108)
		(stroke
			(width 0.06985)
			(type default)
		)
		(layer "In2.Cu")
	)
	(gr_line
		(start 63.074042 -202.114658)
		(end 63.084964 -202.099164)
		(stroke
			(width 0.06985)
			(type default)
		)
		(layer "In2.Cu")
	)
	(gr_line
		(start 63.084964 -202.099164)
		(end 63.100458 -202.088242)
		(stroke
			(width 0.06985)
			(type default)
		)
		(layer "In2.Cu")
	)
	(gr_line
		(start 63.119 -118.11)
		(end 63.509906 -118.19382)
		(stroke
			(width 0.0635)
			(type default)
		)
		(layer "In2.Cu")
	)
	(gr_line
		(start 63.22949 -104.102408)
		(end 63.254128 -104.106726)
		(stroke
			(width 0.06985)
			(type default)
		)
		(layer "In2.Cu")
	)
	(gr_line
		(start 63.254128 -104.106726)
		(end 63.278512 -104.101646)
		(stroke
			(width 0.06985)
			(type default)
		)
		(layer "In2.Cu")
	)
	(gr_line
		(start 63.509906 -118.19382)
		(end 63.940944 -118.19382)
		(stroke
			(width 0.0635)
			(type default)
		)
		(layer "In2.Cu")
	)
	(gr_line
		(start 63.582042 -204.654658)
		(end 63.592964 -204.639164)
		(stroke
			(width 0.06985)
			(type default)
		)
		(layer "In2.Cu")
	)
	(gr_line
		(start 63.592964 -204.639164)
		(end 63.608458 -204.628242)
		(stroke
			(width 0.06985)
			(type default)
		)
		(layer "In2.Cu")
	)
	(gr_line
		(start 63.692532 -99.5299)
		(end 63.711328 -99.526598)
		(stroke
			(width 0.06985)
			(type default)
		)
		(layer "In2.Cu")
	)
	(gr_line
		(start 63.711328 -99.526598)
		(end 63.730124 -99.5299)
		(stroke
			(width 0.06985)
			(type default)
		)
		(layer "In2.Cu")
	)
	(gr_line
		(start 63.940944 -118.19382)
		(end 63.941198 -118.194074)
		(stroke
			(width 0.0635)
			(type default)
		)
		(layer "In2.Cu")
	)
	(gr_line
		(start 63.941198 -118.194074)
		(end 63.983616 -118.194074)
		(stroke
			(width 0.0635)
			(type default)
		)
		(layer "In2.Cu")
	)
	(gr_line
		(start 63.9572 -119.4054)
		(end 64.083184 -118.816628)
		(stroke
			(width 0.0635)
			(type default)
		)
		(layer "In2.Cu")
	)
	(gr_line
		(start 63.983362 -26.7589)
		(end 67.263518 -26.7589)
		(stroke
			(width 0.0635)
			(type default)
		)
		(layer "In2.Cu")
	)
	(gr_line
		(start 64.005714 -116.32946)
		(end 64.338708 -115.996466)
		(stroke
			(width 0.0635)
			(type default)
		)
		(layer "In2.Cu")
	)
	(gr_line
		(start 64.389 -149.987)
		(end 64.472312 -149.903688)
		(stroke
			(width 0.0635)
			(type default)
		)
		(layer "In2.Cu")
	)
	(gr_line
		(start 64.389 -149.987)
		(end 64.52489 -150.12289)
		(stroke
			(width 0.0635)
			(type default)
		)
		(layer "In2.Cu")
	)
	(gr_line
		(start 64.513714 -116.84)
		(end 64.55918 -116.84)
		(stroke
			(width 0.0635)
			(type default)
		)
		(layer "In2.Cu")
	)
	(gr_line
		(start 64.55918 -116.84)
		(end 64.559942 -116.839746)
		(stroke
			(width 0.0635)
			(type default)
		)
		(layer "In2.Cu")
	)
	(gr_line
		(start 64.559942 -116.839746)
		(end 65.403222 -115.996466)
		(stroke
			(width 0.0635)
			(type default)
		)
		(layer "In2.Cu")
	)
	(gr_line
		(start 64.953134 -124.312934)
		(end 65.1002 -124.46)
		(stroke
			(width 0.0635)
			(type default)
		)
		(layer "In2.Cu")
	)
	(gr_line
		(start 64.953134 -123.591066)
		(end 65.1002 -123.444)
		(stroke
			(width 0.0635)
			(type default)
		)
		(layer "In2.Cu")
	)
	(gr_line
		(start 65.015872 -149.61997)
		(end 65.382902 -149.987)
		(stroke
			(width 0.0635)
			(type default)
		)
		(layer "In2.Cu")
	)
	(gr_line
		(start 65.160398 -219.522294)
		(end 65.1637 -219.541344)
		(stroke
			(width 0.06985)
			(type default)
		)
		(layer "In2.Cu")
	)
	(gr_line
		(start 65.160398 -219.522294)
		(end 65.1637 -219.503498)
		(stroke
			(width 0.06985)
			(type default)
		)
		(layer "In2.Cu")
	)
	(gr_line
		(start 65.247012 -150.12289)
		(end 65.382902 -149.987)
		(stroke
			(width 0.0635)
			(type default)
		)
		(layer "In2.Cu")
	)
	(gr_line
		(start 65.288922 -198.736966)
		(end 65.316862 -198.717408)
		(stroke
			(width 0.06985)
			(type default)
		)
		(layer "In2.Cu")
	)
	(gr_line
		(start 65.292986 -122.153934)
		(end 65.3796 -122.240548)
		(stroke
			(width 0.0635)
			(type default)
		)
		(layer "In2.Cu")
	)
	(gr_line
		(start 65.292986 -121.431812)
		(end 65.3796 -121.345198)
		(stroke
			(width 0.0635)
			(type default)
		)
		(layer "In2.Cu")
	)
	(gr_arc
		(start 65.293494 -222.294704)
		(mid 65.472063 -222.027354)
		(end 65.534794 -221.712028)
		(stroke
			(width 0.06985)
			(type default)
		)
		(layer "In2.Cu")
	)
	(gr_line
		(start 65.29959 -25.547574)
		(end 65.509648 -25.757632)
		(stroke
			(width 0.0635)
			(type default)
		)
		(layer "In2.Cu")
	)
	(gr_line
		(start 65.29959 -24.825706)
		(end 65.397634 -24.727662)
		(stroke
			(width 0.0635)
			(type default)
		)
		(layer "In2.Cu")
	)
	(gr_line
		(start 65.316862 -198.717408)
		(end 65.349882 -198.711566)
		(stroke
			(width 0.06985)
			(type default)
		)
		(layer "In2.Cu")
	)
	(gr_line
		(start 65.364868 -213.169246)
		(end 65.36817 -213.188296)
		(stroke
			(width 0.06985)
			(type default)
		)
		(layer "In2.Cu")
	)
	(gr_line
		(start 65.364868 -213.169246)
		(end 65.36817 -213.15045)
		(stroke
			(width 0.06985)
			(type default)
		)
		(layer "In2.Cu")
	)
	(gr_line
		(start 65.36817 -213.188042)
		(end 65.36817 -213.188296)
		(stroke
			(width 0.06985)
			(type default)
		)
		(layer "In2.Cu")
	)
	(gr_line
		(start 65.3796 -122.240548)
		(end 65.3796 -122.335798)
		(stroke
			(width 0.0635)
			(type default)
		)
		(layer "In2.Cu")
	)
	(gr_line
		(start 65.3796 -121.2342)
		(end 65.3796 -121.345198)
		(stroke
			(width 0.0635)
			(type default)
		)
		(layer "In2.Cu")
	)
	(gr_line
		(start 65.397634 -24.727662)
		(end 65.539366 -24.727662)
		(stroke
			(width 0.0635)
			(type default)
		)
		(layer "In2.Cu")
	)
	(gr_line
		(start 65.5828 -206.977996)
		(end 65.618868 -206.926434)
		(stroke
			(width 0.06985)
			(type default)
		)
		(layer "In2.Cu")
	)
	(gr_arc
		(start 65.864994 -221.712028)
		(mid 65.927715 -222.02735)
		(end 66.106294 -222.294704)
		(stroke
			(width 0.06985)
			(type default)
		)
		(layer "In2.Cu")
	)
	(gr_line
		(start 66.045842 -200.026016)
		(end 66.073782 -200.006458)
		(stroke
			(width 0.06985)
			(type default)
		)
		(layer "In2.Cu")
	)
	(gr_line
		(start 66.073782 -200.006458)
		(end 66.106802 -200.000616)
		(stroke
			(width 0.06985)
			(type default)
		)
		(layer "In2.Cu")
	)
	(gr_line
		(start 66.154808 -215.785446)
		(end 66.154808 -215.7857)
		(stroke
			(width 0.06985)
			(type default)
		)
		(layer "In2.Cu")
	)
	(gr_line
		(start 66.154808 -215.785446)
		(end 66.15811 -215.76665)
		(stroke
			(width 0.06985)
			(type default)
		)
		(layer "In2.Cu")
	)
	(gr_line
		(start 66.154808 -215.747854)
		(end 66.15811 -215.76665)
		(stroke
			(width 0.06985)
			(type default)
		)
		(layer "In2.Cu")
	)
	(gr_line
		(start 66.426842 -205.772258)
		(end 66.437764 -205.756764)
		(stroke
			(width 0.06985)
			(type default)
		)
		(layer "In2.Cu")
	)
	(gr_line
		(start 66.437764 -205.756764)
		(end 66.453258 -205.745842)
		(stroke
			(width 0.06985)
			(type default)
		)
		(layer "In2.Cu")
	)
	(gr_line
		(start 66.680334 -81.540858)
		(end 66.709798 -81.547208)
		(stroke
			(width 0.06985)
			(type default)
		)
		(layer "In2.Cu")
	)
	(gr_line
		(start 66.709798 -81.547208)
		(end 66.739262 -81.540858)
		(stroke
			(width 0.06985)
			(type default)
		)
		(layer "In2.Cu")
	)
	(gr_line
		(start 66.79057 -192.89903)
		(end 66.81851 -192.879472)
		(stroke
			(width 0.06985)
			(type default)
		)
		(layer "In2.Cu")
	)
	(gr_line
		(start 66.81851 -192.879472)
		(end 66.85153 -192.87363)
		(stroke
			(width 0.06985)
			(type default)
		)
		(layer "In2.Cu")
	)
	(gr_line
		(start 66.9798 -120.5484)
		(end 67.4624 -121.031)
		(stroke
			(width 0.0635)
			(type default)
		)
		(layer "In2.Cu")
	)
	(gr_line
		(start 67.4624 -121.031)
		(end 68.034154 -121.031)
		(stroke
			(width 0.0635)
			(type default)
		)
		(layer "In2.Cu")
	)
	(gr_line
		(start 68.034154 -121.031)
		(end 68.11899 -120.946164)
		(stroke
			(width 0.0635)
			(type default)
		)
		(layer "In2.Cu")
	)
	(gr_line
		(start 68.034916 -198.573898)
		(end 68.067936 -198.568056)
		(stroke
			(width 0.06985)
			(type default)
		)
		(layer "In2.Cu")
	)
	(gr_line
		(start 68.067936 -198.568056)
		(end 68.095876 -198.548498)
		(stroke
			(width 0.06985)
			(type default)
		)
		(layer "In2.Cu")
	)
	(gr_line
		(start 68.239894 -193.74993)
		(end 68.267834 -193.730372)
		(stroke
			(width 0.06985)
			(type default)
		)
		(layer "In2.Cu")
	)
	(gr_line
		(start 68.267834 -193.730372)
		(end 68.300854 -193.72453)
		(stroke
			(width 0.06985)
			(type default)
		)
		(layer "In2.Cu")
	)
	(gr_arc
		(start 68.493386 -222.294704)
		(mid 68.672013 -222.02737)
		(end 68.734686 -221.712028)
		(stroke
			(width 0.06985)
			(type default)
		)
		(layer "In2.Cu")
	)
	(gr_line
		(start 68.824094 -120.9294)
		(end 69.540882 -120.9294)
		(stroke
			(width 0.0635)
			(type default)
		)
		(layer "In2.Cu")
	)
	(gr_line
		(start 69.004434 -207.612488)
		(end 69.010276 -207.579468)
		(stroke
			(width 0.06985)
			(type default)
		)
		(layer "In2.Cu")
	)
	(gr_line
		(start 69.010276 -207.579468)
		(end 69.029834 -207.551528)
		(stroke
			(width 0.06985)
			(type default)
		)
		(layer "In2.Cu")
	)
	(gr_arc
		(start 69.064886 -221.712028)
		(mid 69.127567 -222.027372)
		(end 69.306186 -222.294704)
		(stroke
			(width 0.06985)
			(type default)
		)
		(layer "In2.Cu")
	)
	(gr_line
		(start 69.347842 -200.609454)
		(end 69.375782 -200.589896)
		(stroke
			(width 0.06985)
			(type default)
		)
		(layer "In2.Cu")
	)
	(gr_line
		(start 69.375782 -200.589896)
		(end 69.408802 -200.584054)
		(stroke
			(width 0.06985)
			(type default)
		)
		(layer "In2.Cu")
	)
	(gr_line
		(start 69.421502 -103.655114)
		(end 69.450966 -103.648764)
		(stroke
			(width 0.06985)
			(type default)
		)
		(layer "In2.Cu")
	)
	(gr_line
		(start 69.450966 -103.648764)
		(end 69.48043 -103.655114)
		(stroke
			(width 0.06985)
			(type default)
		)
		(layer "In2.Cu")
	)
	(gr_line
		(start 69.48043 -216.934542)
		(end 69.48043 -216.934796)
		(stroke
			(width 0.06985)
			(type default)
		)
		(layer "In2.Cu")
	)
	(gr_line
		(start 69.48043 -216.934542)
		(end 69.483732 -216.915746)
		(stroke
			(width 0.06985)
			(type default)
		)
		(layer "In2.Cu")
	)
	(gr_line
		(start 69.48043 -216.89695)
		(end 69.483732 -216.915746)
		(stroke
			(width 0.06985)
			(type default)
		)
		(layer "In2.Cu")
	)
	(gr_line
		(start 69.727318 -102.393242)
		(end 69.756782 -102.386892)
		(stroke
			(width 0.06985)
			(type default)
		)
		(layer "In2.Cu")
	)
	(gr_line
		(start 69.756782 -102.386892)
		(end 69.786246 -102.393242)
		(stroke
			(width 0.06985)
			(type default)
		)
		(layer "In2.Cu")
	)
	(gr_line
		(start 69.946774 -206.242158)
		(end 69.957696 -206.226664)
		(stroke
			(width 0.06985)
			(type default)
		)
		(layer "In2.Cu")
	)
	(gr_line
		(start 69.957696 -206.226664)
		(end 69.97319 -206.215742)
		(stroke
			(width 0.06985)
			(type default)
		)
		(layer "In2.Cu")
	)
	(gr_line
		(start 70.931278 -57.49036)
		(end 71.124572 -57.297066)
		(stroke
			(width 0.0635)
			(type default)
		)
		(layer "In2.Cu")
	)
	(gr_line
		(start 71.08952 -196.048884)
		(end 71.11746 -196.029326)
		(stroke
			(width 0.06985)
			(type default)
		)
		(layer "In2.Cu")
	)
	(gr_line
		(start 71.11746 -196.029326)
		(end 71.15048 -196.023484)
		(stroke
			(width 0.06985)
			(type default)
		)
		(layer "In2.Cu")
	)
	(gr_line
		(start 71.170292 -202.44308)
		(end 71.198232 -202.423522)
		(stroke
			(width 0.06985)
			(type default)
		)
		(layer "In2.Cu")
	)
	(gr_line
		(start 71.198232 -202.423522)
		(end 71.231252 -202.41768)
		(stroke
			(width 0.06985)
			(type default)
		)
		(layer "In2.Cu")
	)
	(gr_arc
		(start 71.7042 -220.0148)
		(mid 71.882827 -219.747466)
		(end 71.9455 -219.432124)
		(stroke
			(width 0.06985)
			(type default)
		)
		(layer "In2.Cu")
	)
	(gr_line
		(start 71.846694 -57.297066)
		(end 72.039988 -57.49036)
		(stroke
			(width 0.0635)
			(type default)
		)
		(layer "In2.Cu")
	)
	(gr_line
		(start 71.876158 -216.244678)
		(end 71.87946 -216.263728)
		(stroke
			(width 0.06985)
			(type default)
		)
		(layer "In2.Cu")
	)
	(gr_line
		(start 71.876158 -216.244678)
		(end 71.87946 -216.225882)
		(stroke
			(width 0.06985)
			(type default)
		)
		(layer "In2.Cu")
	)
	(gr_arc
		(start 72.2757 -219.432124)
		(mid 72.33838 -219.747468)
		(end 72.517 -220.0148)
		(stroke
			(width 0.06985)
			(type default)
		)
		(layer "In2.Cu")
	)
	(gr_line
		(start 72.28078 -93.69552)
		(end 72.306434 -93.69552)
		(stroke
			(width 0.0635)
			(type default)
		)
		(layer "In2.Cu")
	)
	(gr_line
		(start 72.292464 -204.591666)
		(end 72.320404 -204.572108)
		(stroke
			(width 0.06985)
			(type default)
		)
		(layer "In2.Cu")
	)
	(gr_line
		(start 72.320404 -204.572108)
		(end 72.353424 -204.566266)
		(stroke
			(width 0.06985)
			(type default)
		)
		(layer "In2.Cu")
	)
	(gr_line
		(start 72.383142 -217.25255)
		(end 72.383142 -217.252804)
		(stroke
			(width 0.06985)
			(type default)
		)
		(layer "In2.Cu")
	)
	(gr_line
		(start 72.383142 -217.25255)
		(end 72.386444 -217.233754)
		(stroke
			(width 0.06985)
			(type default)
		)
		(layer "In2.Cu")
	)
	(gr_line
		(start 72.383142 -217.214958)
		(end 72.386444 -217.233754)
		(stroke
			(width 0.06985)
			(type default)
		)
		(layer "In2.Cu")
	)
	(gr_line
		(start 72.56018 -192.202562)
		(end 72.5932 -192.19672)
		(stroke
			(width 0.06985)
			(type default)
		)
		(layer "In2.Cu")
	)
	(gr_line
		(start 72.5932 -192.19672)
		(end 72.62114 -192.177162)
		(stroke
			(width 0.06985)
			(type default)
		)
		(layer "In2.Cu")
	)
	(gr_line
		(start 72.78878 -93.4593)
		(end 72.814434 -93.4593)
		(stroke
			(width 0.0635)
			(type default)
		)
		(layer "In2.Cu")
	)
	(gr_line
		(start 72.983598 -209.964782)
		(end 72.98944 -209.931762)
		(stroke
			(width 0.06985)
			(type default)
		)
		(layer "In2.Cu")
	)
	(gr_line
		(start 72.98944 -209.931762)
		(end 73.008998 -209.903822)
		(stroke
			(width 0.06985)
			(type default)
		)
		(layer "In2.Cu")
	)
	(gr_line
		(start 73.411842 -209.328258)
		(end 73.422764 -209.312764)
		(stroke
			(width 0.06985)
			(type default)
		)
		(layer "In2.Cu")
	)
	(gr_line
		(start 73.422764 -209.312764)
		(end 73.438258 -209.301842)
		(stroke
			(width 0.06985)
			(type default)
		)
		(layer "In2.Cu")
	)
	(gr_line
		(start 74.102468 -79.638144)
		(end 74.131932 -79.631794)
		(stroke
			(width 0.06985)
			(type default)
		)
		(layer "In2.Cu")
	)
	(gr_line
		(start 74.131932 -79.631794)
		(end 74.161396 -79.638144)
		(stroke
			(width 0.06985)
			(type default)
		)
		(layer "In2.Cu")
	)
	(gr_line
		(start 74.77506 -190.265558)
		(end 74.803 -190.246)
		(stroke
			(width 0.06985)
			(type default)
		)
		(layer "In2.Cu")
	)
	(gr_line
		(start 74.803 -190.246)
		(end 74.83602 -190.240158)
		(stroke
			(width 0.06985)
			(type default)
		)
		(layer "In2.Cu")
	)
	(gr_line
		(start 75.676252 -105.30967)
		(end 75.705716 -105.31602)
		(stroke
			(width 0.06985)
			(type default)
		)
		(layer "In2.Cu")
	)
	(gr_line
		(start 75.705716 -105.31602)
		(end 75.73518 -105.30967)
		(stroke
			(width 0.06985)
			(type default)
		)
		(layer "In2.Cu")
	)
	(gr_line
		(start 75.725528 -192.415414)
		(end 75.744324 -192.412112)
		(stroke
			(width 0.06985)
			(type default)
		)
		(layer "In2.Cu")
	)
	(gr_line
		(start 75.744324 -192.412112)
		(end 75.76312 -192.415414)
		(stroke
			(width 0.06985)
			(type default)
		)
		(layer "In2.Cu")
	)
	(gr_line
		(start 75.801728 -195.203318)
		(end 75.820524 -195.200016)
		(stroke
			(width 0.06985)
			(type default)
		)
		(layer "In2.Cu")
	)
	(gr_line
		(start 75.820524 -195.200016)
		(end 75.83932 -195.203318)
		(stroke
			(width 0.06985)
			(type default)
		)
		(layer "In2.Cu")
	)
	(gr_line
		(start 75.82281 -104.014016)
		(end 75.852274 -104.020366)
		(stroke
			(width 0.06985)
			(type default)
		)
		(layer "In2.Cu")
	)
	(gr_line
		(start 75.852274 -104.020366)
		(end 75.881738 -104.014016)
		(stroke
			(width 0.06985)
			(type default)
		)
		(layer "In2.Cu")
	)
	(gr_line
		(start 76.099416 -207.438498)
		(end 76.127356 -207.41894)
		(stroke
			(width 0.06985)
			(type default)
		)
		(layer "In2.Cu")
	)
	(gr_line
		(start 76.127356 -207.41894)
		(end 76.160376 -207.413098)
		(stroke
			(width 0.06985)
			(type default)
		)
		(layer "In2.Cu")
	)
	(gr_line
		(start 76.147168 -80.060546)
		(end 76.16698 -80.06461)
		(stroke
			(width 0.06985)
			(type default)
		)
		(layer "In2.Cu")
	)
	(gr_line
		(start 76.16698 -80.06461)
		(end 76.18476 -80.07604)
		(stroke
			(width 0.06985)
			(type default)
		)
		(layer "In2.Cu")
	)
	(gr_line
		(start 76.413868 -117.462808)
		(end 76.49718 -117.54612)
		(stroke
			(width 0.0635)
			(type default)
		)
		(layer "In2.Cu")
	)
	(gr_line
		(start 76.413868 -116.74094)
		(end 76.495148 -116.65966)
		(stroke
			(width 0.0635)
			(type default)
		)
		(layer "In2.Cu")
	)
	(gr_line
		(start 76.5175 -118.01602)
		(end 76.691998 -118.01602)
		(stroke
			(width 0.0635)
			(type default)
		)
		(layer "In2.Cu")
	)
	(gr_line
		(start 76.870814 -80.91551)
		(end 76.888594 -80.92694)
		(stroke
			(width 0.06985)
			(type default)
		)
		(layer "In2.Cu")
	)
	(gr_line
		(start 76.888594 -80.92694)
		(end 76.908406 -80.931004)
		(stroke
			(width 0.06985)
			(type default)
		)
		(layer "In2.Cu")
	)
	(gr_line
		(start 77.0255 -118.401084)
		(end 77.199998 -118.401084)
		(stroke
			(width 0.0635)
			(type default)
		)
		(layer "In2.Cu")
	)
	(gr_line
		(start 77.091794 -189.842394)
		(end 77.11059 -189.839092)
		(stroke
			(width 0.06985)
			(type default)
		)
		(layer "In2.Cu")
	)
	(gr_line
		(start 77.11059 -189.839092)
		(end 77.129386 -189.842394)
		(stroke
			(width 0.06985)
			(type default)
		)
		(layer "In2.Cu")
	)
	(gr_line
		(start 77.158342 -117.812058)
		(end 77.222096 -117.748304)
		(stroke
			(width 0.0635)
			(type default)
		)
		(layer "In2.Cu")
	)
	(gr_line
		(start 77.222096 -117.748304)
		(end 77.856334 -117.748304)
		(stroke
			(width 0.0635)
			(type default)
		)
		(layer "In2.Cu")
	)
	(gr_line
		(start 77.500734 -211.709)
		(end 77.504036 -211.72805)
		(stroke
			(width 0.06985)
			(type default)
		)
		(layer "In2.Cu")
	)
	(gr_line
		(start 77.500734 -211.709)
		(end 77.504036 -211.690204)
		(stroke
			(width 0.06985)
			(type default)
		)
		(layer "In2.Cu")
	)
	(gr_line
		(start 77.775054 -210.152996)
		(end 77.792326 -210.05546)
		(stroke
			(width 0.06985)
			(type default)
		)
		(layer "In2.Cu")
	)
	(gr_line
		(start 77.792326 -210.05546)
		(end 77.873352 -209.998818)
		(stroke
			(width 0.06985)
			(type default)
		)
		(layer "In2.Cu")
	)
	(gr_arc
		(start 78.16977 -219.881704)
		(mid 78.348397 -219.61437)
		(end 78.41107 -219.299028)
		(stroke
			(width 0.06985)
			(type default)
		)
		(layer "In2.Cu")
	)
	(gr_line
		(start 78.219046 -103.179626)
		(end 78.24851 -103.173276)
		(stroke
			(width 0.06985)
			(type default)
		)
		(layer "In2.Cu")
	)
	(gr_line
		(start 78.24851 -103.173276)
		(end 78.277974 -103.179626)
		(stroke
			(width 0.06985)
			(type default)
		)
		(layer "In2.Cu")
	)
	(gr_line
		(start 78.303882 -81.227676)
		(end 78.333346 -81.234026)
		(stroke
			(width 0.06985)
			(type default)
		)
		(layer "In2.Cu")
	)
	(gr_line
		(start 78.333346 -81.234026)
		(end 78.36281 -81.227676)
		(stroke
			(width 0.06985)
			(type default)
		)
		(layer "In2.Cu")
	)
	(gr_line
		(start 78.359 -96.991424)
		(end 78.538578 -96.991424)
		(stroke
			(width 0.0635)
			(type default)
		)
		(layer "In2.Cu")
	)
	(gr_line
		(start 78.43774 -104.397556)
		(end 78.467204 -104.391206)
		(stroke
			(width 0.06985)
			(type default)
		)
		(layer "In2.Cu")
	)
	(gr_line
		(start 78.467204 -104.391206)
		(end 78.496668 -104.397556)
		(stroke
			(width 0.06985)
			(type default)
		)
		(layer "In2.Cu")
	)
	(gr_arc
		(start 78.74127 -219.299028)
		(mid 78.80395 -219.614373)
		(end 78.98257 -219.881704)
		(stroke
			(width 0.06985)
			(type default)
		)
		(layer "In2.Cu")
	)
	(gr_line
		(start 78.76032 -96.4946)
		(end 79.046578 -96.4946)
		(stroke
			(width 0.0635)
			(type default)
		)
		(layer "In2.Cu")
	)
	(gr_line
		(start 78.88605 -138.95705)
		(end 79.121 -139.192)
		(stroke
			(width 0.0635)
			(type default)
		)
		(layer "In2.Cu")
	)
	(gr_line
		(start 79.17434 -94.754192)
		(end 79.5274 -95.107252)
		(stroke
			(width 0.0635)
			(type default)
		)
		(layer "In2.Cu")
	)
	(gr_line
		(start 79.223616 -209.052922)
		(end 79.250286 -209.03438)
		(stroke
			(width 0.06985)
			(type default)
		)
		(layer "In2.Cu")
	)
	(gr_line
		(start 79.250286 -209.03438)
		(end 79.281782 -209.028538)
		(stroke
			(width 0.06985)
			(type default)
		)
		(layer "In2.Cu")
	)
	(gr_line
		(start 79.25943 -138.44651)
		(end 79.556864 -138.743944)
		(stroke
			(width 0.0635)
			(type default)
		)
		(layer "In2.Cu")
	)
	(gr_line
		(start 79.292196 -190.559182)
		(end 79.310992 -190.562484)
		(stroke
			(width 0.06985)
			(type default)
		)
		(layer "In2.Cu")
	)
	(gr_line
		(start 79.295498 -81.029302)
		(end 79.31531 -81.025238)
		(stroke
			(width 0.06985)
			(type default)
		)
		(layer "In2.Cu")
	)
	(gr_line
		(start 79.310992 -190.562484)
		(end 79.330042 -190.559182)
		(stroke
			(width 0.06985)
			(type default)
		)
		(layer "In2.Cu")
	)
	(gr_line
		(start 79.31531 -81.025238)
		(end 79.33309 -81.013808)
		(stroke
			(width 0.06985)
			(type default)
		)
		(layer "In2.Cu")
	)
	(gr_line
		(start 79.556864 -138.764264)
		(end 79.9846 -139.192)
		(stroke
			(width 0.0635)
			(type default)
		)
		(layer "In2.Cu")
	)
	(gr_line
		(start 79.556864 -138.743944)
		(end 79.556864 -138.764264)
		(stroke
			(width 0.0635)
			(type default)
		)
		(layer "In2.Cu")
	)
	(gr_line
		(start 80.201262 -196.307964)
		(end 80.220058 -196.311266)
		(stroke
			(width 0.06985)
			(type default)
		)
		(layer "In2.Cu")
	)
	(gr_line
		(start 80.220058 -196.311266)
		(end 80.238854 -196.307964)
		(stroke
			(width 0.06985)
			(type default)
		)
		(layer "In2.Cu")
	)
	(gr_arc
		(start 81.293462 -222.294704)
		(mid 81.472089 -222.02737)
		(end 81.534762 -221.712028)
		(stroke
			(width 0.06985)
			(type default)
		)
		(layer "In2.Cu")
	)
	(gr_line
		(start 81.293716 -189.8777)
		(end 81.312512 -189.874398)
		(stroke
			(width 0.06985)
			(type default)
		)
		(layer "In2.Cu")
	)
	(gr_line
		(start 81.312512 -189.874398)
		(end 81.331308 -189.8777)
		(stroke
			(width 0.06985)
			(type default)
		)
		(layer "In2.Cu")
	)
	(gr_line
		(start 81.534762 -219.47886)
		(end 81.57083 -219.427298)
		(stroke
			(width 0.06985)
			(type default)
		)
		(layer "In2.Cu")
	)
	(gr_arc
		(start 81.864962 -221.712028)
		(mid 81.927647 -222.027367)
		(end 82.106262 -222.294704)
		(stroke
			(width 0.06985)
			(type default)
		)
		(layer "In2.Cu")
	)
	(gr_line
		(start 82.23377 -193.891916)
		(end 82.252566 -193.895218)
		(stroke
			(width 0.06985)
			(type default)
		)
		(layer "In2.Cu")
	)
	(gr_line
		(start 82.252566 -193.895218)
		(end 82.271362 -193.891916)
		(stroke
			(width 0.06985)
			(type default)
		)
		(layer "In2.Cu")
	)
	(gr_line
		(start 82.576162 -208.758282)
		(end 82.607658 -208.75244)
		(stroke
			(width 0.06985)
			(type default)
		)
		(layer "In2.Cu")
	)
	(gr_line
		(start 82.607658 -208.75244)
		(end 82.634582 -208.733644)
		(stroke
			(width 0.06985)
			(type default)
		)
		(layer "In2.Cu")
	)
	(gr_line
		(start 83.279488 -103.318056)
		(end 83.298284 -103.321358)
		(stroke
			(width 0.06985)
			(type default)
		)
		(layer "In2.Cu")
	)
	(gr_line
		(start 83.291172 -105.75417)
		(end 83.320636 -105.76052)
		(stroke
			(width 0.06985)
			(type default)
		)
		(layer "In2.Cu")
	)
	(gr_line
		(start 83.298284 -103.321358)
		(end 83.31708 -103.318056)
		(stroke
			(width 0.06985)
			(type default)
		)
		(layer "In2.Cu")
	)
	(gr_line
		(start 83.320636 -105.76052)
		(end 83.3501 -105.75417)
		(stroke
			(width 0.06985)
			(type default)
		)
		(layer "In2.Cu")
	)
	(gr_line
		(start 83.45932 -104.618536)
		(end 83.488784 -104.624886)
		(stroke
			(width 0.06985)
			(type default)
		)
		(layer "In2.Cu")
	)
	(gr_line
		(start 83.488784 -104.624886)
		(end 83.518248 -104.618536)
		(stroke
			(width 0.06985)
			(type default)
		)
		(layer "In2.Cu")
	)
	(gr_line
		(start 84.230972 -206.325978)
		(end 84.263992 -206.320136)
		(stroke
			(width 0.06985)
			(type default)
		)
		(layer "In2.Cu")
	)
	(gr_line
		(start 84.263992 -206.320136)
		(end 84.291932 -206.300578)
		(stroke
			(width 0.06985)
			(type default)
		)
		(layer "In2.Cu")
	)
	(gr_arc
		(start 84.493354 -222.294704)
		(mid 84.67191 -222.02735)
		(end 84.734654 -221.712028)
		(stroke
			(width 0.06985)
			(type default)
		)
		(layer "In2.Cu")
	)
	(gr_line
		(start 84.50961 -215.806274)
		(end 84.529168 -215.778334)
		(stroke
			(width 0.06985)
			(type default)
		)
		(layer "In2.Cu")
	)
	(gr_line
		(start 84.529168 -215.778334)
		(end 84.53501 -215.745314)
		(stroke
			(width 0.06985)
			(type default)
		)
		(layer "In2.Cu")
	)
	(gr_line
		(start 84.7598 -208.93786)
		(end 84.795868 -208.886298)
		(stroke
			(width 0.06985)
			(type default)
		)
		(layer "In2.Cu")
	)
	(gr_line
		(start 85.00364 -218.931744)
		(end 85.009482 -218.898724)
		(stroke
			(width 0.06985)
			(type default)
		)
		(layer "In2.Cu")
	)
	(gr_line
		(start 85.009482 -218.898724)
		(end 85.02904 -218.870784)
		(stroke
			(width 0.06985)
			(type default)
		)
		(layer "In2.Cu")
	)
	(gr_line
		(start 85.063838 -76.899516)
		(end 85.110574 -76.869036)
		(stroke
			(width 0.06985)
			(type default)
		)
		(layer "In2.Cu")
	)
	(gr_arc
		(start 85.064854 -221.712028)
		(mid 85.127575 -222.02735)
		(end 85.306154 -222.294704)
		(stroke
			(width 0.06985)
			(type default)
		)
		(layer "In2.Cu")
	)
	(gr_line
		(start 85.524086 -207.84566)
		(end 85.535008 -207.830166)
		(stroke
			(width 0.06985)
			(type default)
		)
		(layer "In2.Cu")
	)
	(gr_line
		(start 85.535008 -207.830166)
		(end 85.550502 -207.819244)
		(stroke
			(width 0.06985)
			(type default)
		)
		(layer "In2.Cu")
	)
	(gr_line
		(start 86.570312 -77.26934)
		(end 86.779608 -77.478636)
		(stroke
			(width 0.06985)
			(type default)
		)
		(layer "In2.Cu")
	)
	(gr_line
		(start 86.570312 -76.798932)
		(end 86.779608 -76.589636)
		(stroke
			(width 0.06985)
			(type default)
		)
		(layer "In2.Cu")
	)
	(gr_line
		(start 87.062564 -102.32136)
		(end 87.08136 -102.318058)
		(stroke
			(width 0.06985)
			(type default)
		)
		(layer "In2.Cu")
	)
	(gr_line
		(start 87.08136 -102.318058)
		(end 87.10041 -102.32136)
		(stroke
			(width 0.06985)
			(type default)
		)
		(layer "In2.Cu")
	)
	(gr_line
		(start 87.186008 -199.939402)
		(end 87.219028 -199.93356)
		(stroke
			(width 0.06985)
			(type default)
		)
		(layer "In2.Cu")
	)
	(gr_line
		(start 87.219028 -199.93356)
		(end 87.246968 -199.914002)
		(stroke
			(width 0.06985)
			(type default)
		)
		(layer "In2.Cu")
	)
	(gr_line
		(start 87.336122 -104.56926)
		(end 87.360506 -104.56418)
		(stroke
			(width 0.06985)
			(type default)
		)
		(layer "In2.Cu")
	)
	(gr_line
		(start 87.360506 -104.56418)
		(end 87.385144 -104.568498)
		(stroke
			(width 0.06985)
			(type default)
		)
		(layer "In2.Cu")
	)
	(gr_line
		(start 87.391748 -191.282066)
		(end 87.410544 -191.285368)
		(stroke
			(width 0.06985)
			(type default)
		)
		(layer "In2.Cu")
	)
	(gr_line
		(start 87.410544 -191.285368)
		(end 87.42934 -191.282066)
		(stroke
			(width 0.06985)
			(type default)
		)
		(layer "In2.Cu")
	)
	(gr_line
		(start 87.601552 -103.412544)
		(end 87.625936 -103.407464)
		(stroke
			(width 0.06985)
			(type default)
		)
		(layer "In2.Cu")
	)
	(gr_line
		(start 87.625936 -103.407464)
		(end 87.650574 -103.411782)
		(stroke
			(width 0.06985)
			(type default)
		)
		(layer "In2.Cu")
	)
	(gr_line
		(start 87.67572 -202.200764)
		(end 87.70747 -202.195176)
		(stroke
			(width 0.06985)
			(type default)
		)
		(layer "In2.Cu")
	)
	(gr_arc
		(start 87.6935 -222.294704)
		(mid 87.872127 -222.02737)
		(end 87.9348 -221.712028)
		(stroke
			(width 0.06985)
			(type default)
		)
		(layer "In2.Cu")
	)
	(gr_line
		(start 87.70747 -202.195176)
		(end 87.734648 -202.176126)
		(stroke
			(width 0.06985)
			(type default)
		)
		(layer "In2.Cu")
	)
	(gr_line
		(start 87.795608 -194.97548)
		(end 87.828628 -194.969638)
		(stroke
			(width 0.06985)
			(type default)
		)
		(layer "In2.Cu")
	)
	(gr_line
		(start 87.828628 -194.969638)
		(end 87.856568 -194.95008)
		(stroke
			(width 0.06985)
			(type default)
		)
		(layer "In2.Cu")
	)
	(gr_line
		(start 87.920322 -215.317578)
		(end 87.93988 -215.289638)
		(stroke
			(width 0.06985)
			(type default)
		)
		(layer "In2.Cu")
	)
	(gr_line
		(start 87.927434 -208.17078)
		(end 87.963502 -208.119218)
		(stroke
			(width 0.06985)
			(type default)
		)
		(layer "In2.Cu")
	)
	(gr_line
		(start 87.93988 -215.289638)
		(end 87.945722 -215.256618)
		(stroke
			(width 0.06985)
			(type default)
		)
		(layer "In2.Cu")
	)
	(gr_line
		(start 88.001348 -196.475604)
		(end 88.034368 -196.469762)
		(stroke
			(width 0.06985)
			(type default)
		)
		(layer "In2.Cu")
	)
	(gr_line
		(start 88.034368 -196.469762)
		(end 88.062308 -196.450204)
		(stroke
			(width 0.06985)
			(type default)
		)
		(layer "In2.Cu")
	)
	(gr_line
		(start 88.242648 -191.138556)
		(end 88.275668 -191.132714)
		(stroke
			(width 0.06985)
			(type default)
		)
		(layer "In2.Cu")
	)
	(gr_line
		(start 88.26246 -192.83553)
		(end 88.29548 -192.829688)
		(stroke
			(width 0.06985)
			(type default)
		)
		(layer "In2.Cu")
	)
	(gr_arc
		(start 88.265 -221.712028)
		(mid 88.327682 -222.027371)
		(end 88.5063 -222.294704)
		(stroke
			(width 0.06985)
			(type default)
		)
		(layer "In2.Cu")
	)
	(gr_line
		(start 88.275668 -191.132714)
		(end 88.303608 -191.113156)
		(stroke
			(width 0.06985)
			(type default)
		)
		(layer "In2.Cu")
	)
	(gr_line
		(start 88.29548 -192.829688)
		(end 88.32342 -192.81013)
		(stroke
			(width 0.06985)
			(type default)
		)
		(layer "In2.Cu")
	)
	(gr_line
		(start 88.307926 -219.142564)
		(end 88.313768 -219.109544)
		(stroke
			(width 0.06985)
			(type default)
		)
		(layer "In2.Cu")
	)
	(gr_line
		(start 88.313768 -219.109544)
		(end 88.333326 -219.081604)
		(stroke
			(width 0.06985)
			(type default)
		)
		(layer "In2.Cu")
	)
	(gr_line
		(start 88.617044 -197.533006)
		(end 88.650064 -197.527164)
		(stroke
			(width 0.06985)
			(type default)
		)
		(layer "In2.Cu")
	)
	(gr_line
		(start 88.650064 -197.527164)
		(end 88.678004 -197.507606)
		(stroke
			(width 0.06985)
			(type default)
		)
		(layer "In2.Cu")
	)
	(gr_line
		(start 88.951308 -206.707994)
		(end 88.96223 -206.6925)
		(stroke
			(width 0.06985)
			(type default)
		)
		(layer "In2.Cu")
	)
	(gr_line
		(start 88.96223 -206.6925)
		(end 88.977724 -206.681578)
		(stroke
			(width 0.06985)
			(type default)
		)
		(layer "In2.Cu")
	)
	(gr_line
		(start 89.370662 -33.47466)
		(end 89.5604 -33.664398)
		(stroke
			(width 0.0635)
			(type default)
		)
		(layer "In2.Cu")
	)
	(gr_line
		(start 89.370662 -32.752538)
		(end 89.5604 -32.5628)
		(stroke
			(width 0.0635)
			(type default)
		)
		(layer "In2.Cu")
	)
	(gr_arc
		(start 90.893392 -222.294704)
		(mid 91.071961 -222.027354)
		(end 91.134692 -221.712028)
		(stroke
			(width 0.06985)
			(type default)
		)
		(layer "In2.Cu")
	)
	(gr_line
		(start 91.0717 -215.746838)
		(end 91.091258 -215.718898)
		(stroke
			(width 0.06985)
			(type default)
		)
		(layer "In2.Cu")
	)
	(gr_line
		(start 91.091258 -215.718898)
		(end 91.0971 -215.685878)
		(stroke
			(width 0.06985)
			(type default)
		)
		(layer "In2.Cu")
	)
	(gr_line
		(start 91.1098 -207.92186)
		(end 91.145868 -207.870298)
		(stroke
			(width 0.06985)
			(type default)
		)
		(layer "In2.Cu")
	)
	(gr_line
		(start 91.375484 -218.59748)
		(end 91.381326 -218.56446)
		(stroke
			(width 0.06985)
			(type default)
		)
		(layer "In2.Cu")
	)
	(gr_line
		(start 91.381326 -218.56446)
		(end 91.400884 -218.53652)
		(stroke
			(width 0.06985)
			(type default)
		)
		(layer "In2.Cu")
	)
	(gr_arc
		(start 91.464892 -221.712028)
		(mid 91.527573 -222.027371)
		(end 91.706192 -222.294704)
		(stroke
			(width 0.06985)
			(type default)
		)
		(layer "In2.Cu")
	)
	(gr_line
		(start 92.67444 -205.687168)
		(end 92.685362 -205.671674)
		(stroke
			(width 0.06985)
			(type default)
		)
		(layer "In2.Cu")
	)
	(gr_line
		(start 92.685362 -205.671674)
		(end 92.700856 -205.660752)
		(stroke
			(width 0.06985)
			(type default)
		)
		(layer "In2.Cu")
	)
	(gr_arc
		(start 93.38945 -183.642)
		(mid 93.568006 -183.374646)
		(end 93.63075 -183.059324)
		(stroke
			(width 0.06985)
			(type default)
		)
		(layer "In2.Cu")
	)
	(gr_line
		(start 93.63075 -182.7022)
		(end 93.63075 -183.059324)
		(stroke
			(width 0.06985)
			(type default)
		)
		(layer "In2.Cu")
	)
	(gr_line
		(start 93.63075 -182.685944)
		(end 93.666818 -182.634382)
		(stroke
			(width 0.06985)
			(type default)
		)
		(layer "In2.Cu")
	)
	(gr_arc
		(start 93.960696 -183.058816)
		(mid 94.02345 -183.374445)
		(end 94.20225 -183.642)
		(stroke
			(width 0.06985)
			(type default)
		)
		(layer "In2.Cu")
	)
	(gr_line
		(start 93.960696 -183.0324)
		(end 93.960696 -183.058816)
		(stroke
			(width 0.06985)
			(type default)
		)
		(layer "In2.Cu")
	)
	(gr_line
		(start 93.960696 -183.0324)
		(end 93.96095 -183.0324)
		(stroke
			(width 0.06985)
			(type default)
		)
		(layer "In2.Cu")
	)
	(gr_line
		(start 94.47149 -214.727282)
		(end 94.491048 -214.699342)
		(stroke
			(width 0.06985)
			(type default)
		)
		(layer "In2.Cu")
	)
	(gr_line
		(start 94.491048 -214.699342)
		(end 94.49689 -214.666322)
		(stroke
			(width 0.06985)
			(type default)
		)
		(layer "In2.Cu")
	)
	(gr_line
		(start 94.692724 -186.6392)
		(end 94.708218 -186.628278)
		(stroke
			(width 0.06985)
			(type default)
		)
		(layer "In2.Cu")
	)
	(gr_line
		(start 94.708218 -186.628278)
		(end 94.71914 -186.612784)
		(stroke
			(width 0.06985)
			(type default)
		)
		(layer "In2.Cu")
	)
	(gr_line
		(start 95.234506 -187.970922)
		(end 95.25 -187.96)
		(stroke
			(width 0.06985)
			(type default)
		)
		(layer "In2.Cu")
	)
	(gr_line
		(start 95.25 -187.96)
		(end 95.260922 -187.944506)
		(stroke
			(width 0.06985)
			(type default)
		)
		(layer "In2.Cu")
	)
	(gr_line
		(start 95.45574 -207.32623)
		(end 95.461582 -207.29321)
		(stroke
			(width 0.06985)
			(type default)
		)
		(layer "In2.Cu")
	)
	(gr_line
		(start 95.461582 -207.29321)
		(end 95.48114 -207.26527)
		(stroke
			(width 0.06985)
			(type default)
		)
		(layer "In2.Cu")
	)
	(gr_line
		(start 95.540068 -213.037166)
		(end 95.54337 -213.056216)
		(stroke
			(width 0.06985)
			(type default)
		)
		(layer "In2.Cu")
	)
	(gr_line
		(start 95.540068 -213.037166)
		(end 95.54337 -213.01837)
		(stroke
			(width 0.06985)
			(type default)
		)
		(layer "In2.Cu")
	)
	(gr_line
		(start 96.130364 -189.156848)
		(end 96.145858 -189.145926)
		(stroke
			(width 0.06985)
			(type default)
		)
		(layer "In2.Cu")
	)
	(gr_line
		(start 96.145858 -189.145926)
		(end 96.15678 -189.130432)
		(stroke
			(width 0.06985)
			(type default)
		)
		(layer "In2.Cu")
	)
	(gr_line
		(start 96.324674 -208.587086)
		(end 96.330516 -208.554066)
		(stroke
			(width 0.06985)
			(type default)
		)
		(layer "In2.Cu")
	)
	(gr_line
		(start 96.330516 -208.554066)
		(end 96.350074 -208.526126)
		(stroke
			(width 0.06985)
			(type default)
		)
		(layer "In2.Cu")
	)
	(gr_line
		(start 96.37903 -178.760882)
		(end 96.389952 -178.745388)
		(stroke
			(width 0.06985)
			(type default)
		)
		(layer "In2.Cu")
	)
	(gr_line
		(start 96.389952 -178.745388)
		(end 96.405446 -178.734466)
		(stroke
			(width 0.06985)
			(type default)
		)
		(layer "In2.Cu")
	)
	(gr_arc
		(start 96.493584 -222.294704)
		(mid 96.672211 -222.02737)
		(end 96.734884 -221.712028)
		(stroke
			(width 0.06985)
			(type default)
		)
		(layer "In2.Cu")
	)
	(gr_arc
		(start 97.065084 -221.712028)
		(mid 97.127805 -222.02735)
		(end 97.306384 -222.294704)
		(stroke
			(width 0.06985)
			(type default)
		)
		(layer "In2.Cu")
	)
	(gr_line
		(start 97.088706 -190.129922)
		(end 97.1042 -190.119)
		(stroke
			(width 0.06985)
			(type default)
		)
		(layer "In2.Cu")
	)
	(gr_line
		(start 97.1042 -190.119)
		(end 97.115122 -190.103506)
		(stroke
			(width 0.06985)
			(type default)
		)
		(layer "In2.Cu")
	)
	(gr_line
		(start 97.135442 -183.16194)
		(end 97.155 -183.134)
		(stroke
			(width 0.06985)
			(type default)
		)
		(layer "In2.Cu")
	)
	(gr_line
		(start 97.139506 -195.590922)
		(end 97.155 -195.58)
		(stroke
			(width 0.06985)
			(type default)
		)
		(layer "In2.Cu")
	)
	(gr_line
		(start 97.14865 -220.295724)
		(end 97.14865 -220.295978)
		(stroke
			(width 0.06985)
			(type default)
		)
		(layer "In2.Cu")
	)
	(gr_line
		(start 97.14865 -220.295724)
		(end 97.151952 -220.276928)
		(stroke
			(width 0.06985)
			(type default)
		)
		(layer "In2.Cu")
	)
	(gr_line
		(start 97.14865 -220.258132)
		(end 97.151952 -220.276928)
		(stroke
			(width 0.06985)
			(type default)
		)
		(layer "In2.Cu")
	)
	(gr_line
		(start 97.155 -195.58)
		(end 97.165922 -195.564506)
		(stroke
			(width 0.06985)
			(type default)
		)
		(layer "In2.Cu")
	)
	(gr_line
		(start 97.155 -183.134)
		(end 97.160842 -183.10098)
		(stroke
			(width 0.06985)
			(type default)
		)
		(layer "In2.Cu")
	)
	(gr_line
		(start 97.17024 -181.14518)
		(end 97.176082 -181.11216)
		(stroke
			(width 0.06985)
			(type default)
		)
		(layer "In2.Cu")
	)
	(gr_line
		(start 97.176082 -181.11216)
		(end 97.19564 -181.08422)
		(stroke
			(width 0.06985)
			(type default)
		)
		(layer "In2.Cu")
	)
	(gr_line
		(start 97.799906 -191.120522)
		(end 97.8154 -191.1096)
		(stroke
			(width 0.06985)
			(type default)
		)
		(layer "In2.Cu")
	)
	(gr_line
		(start 97.8154 -191.1096)
		(end 97.826322 -191.094106)
		(stroke
			(width 0.06985)
			(type default)
		)
		(layer "In2.Cu")
	)
	(gr_line
		(start 98.148648 -196.59854)
		(end 98.164142 -196.587618)
		(stroke
			(width 0.06985)
			(type default)
		)
		(layer "In2.Cu")
	)
	(gr_line
		(start 98.164142 -196.587618)
		(end 98.175064 -196.572124)
		(stroke
			(width 0.06985)
			(type default)
		)
		(layer "In2.Cu")
	)
	(gr_line
		(start 98.213418 -192.235328)
		(end 98.228912 -192.224406)
		(stroke
			(width 0.06985)
			(type default)
		)
		(layer "In2.Cu")
	)
	(gr_line
		(start 98.228912 -192.224406)
		(end 98.239834 -192.208912)
		(stroke
			(width 0.06985)
			(type default)
		)
		(layer "In2.Cu")
	)
	(gr_line
		(start 98.608388 -177.59553)
		(end 98.624898 -177.5841)
		(stroke
			(width 0.06985)
			(type default)
		)
		(layer "In2.Cu")
	)
	(gr_line
		(start 98.624898 -177.5841)
		(end 98.636328 -177.56759)
		(stroke
			(width 0.06985)
			(type default)
		)
		(layer "In2.Cu")
	)
	(gr_line
		(start 98.811842 -205.010258)
		(end 98.822764 -204.994764)
		(stroke
			(width 0.06985)
			(type default)
		)
		(layer "In2.Cu")
	)
	(gr_line
		(start 98.822764 -204.994764)
		(end 98.838258 -204.983842)
		(stroke
			(width 0.06985)
			(type default)
		)
		(layer "In2.Cu")
	)
	(gr_line
		(start 99.044506 -197.241922)
		(end 99.06 -197.231)
		(stroke
			(width 0.06985)
			(type default)
		)
		(layer "In2.Cu")
	)
	(gr_line
		(start 99.04857 -202.17003)
		(end 99.059492 -202.154536)
		(stroke
			(width 0.06985)
			(type default)
		)
		(layer "In2.Cu")
	)
	(gr_line
		(start 99.059492 -202.154536)
		(end 99.074986 -202.143614)
		(stroke
			(width 0.06985)
			(type default)
		)
		(layer "In2.Cu")
	)
	(gr_line
		(start 99.06 -197.231)
		(end 99.070922 -197.215506)
		(stroke
			(width 0.06985)
			(type default)
		)
		(layer "In2.Cu")
	)
	(gr_line
		(start 99.533202 -215.639142)
		(end 99.536504 -215.658192)
		(stroke
			(width 0.06985)
			(type default)
		)
		(layer "In2.Cu")
	)
	(gr_line
		(start 99.533202 -215.639142)
		(end 99.536504 -215.620346)
		(stroke
			(width 0.06985)
			(type default)
		)
		(layer "In2.Cu")
	)
	(gr_line
		(start 99.578668 -198.402194)
		(end 99.594162 -198.391272)
		(stroke
			(width 0.06985)
			(type default)
		)
		(layer "In2.Cu")
	)
	(gr_line
		(start 99.594162 -198.391272)
		(end 99.605084 -198.375778)
		(stroke
			(width 0.06985)
			(type default)
		)
		(layer "In2.Cu")
	)
	(gr_arc
		(start 99.693476 -222.294704)
		(mid 99.872103 -222.02737)
		(end 99.934776 -221.712028)
		(stroke
			(width 0.06985)
			(type default)
		)
		(layer "In2.Cu")
	)
	(gr_line
		(start 99.724464 -187.806838)
		(end 99.735386 -187.791344)
		(stroke
			(width 0.06985)
			(type default)
		)
		(layer "In2.Cu")
	)
	(gr_line
		(start 99.724718 -189.51194)
		(end 99.734878 -189.497716)
		(stroke
			(width 0.06985)
			(type default)
		)
		(layer "In2.Cu")
	)
	(gr_line
		(start 99.734878 -189.497716)
		(end 99.735132 -189.497462)
		(stroke
			(width 0.06985)
			(type default)
		)
		(layer "In2.Cu")
	)
	(gr_line
		(start 99.735132 -189.497462)
		(end 99.749356 -189.487302)
		(stroke
			(width 0.06985)
			(type default)
		)
		(layer "In2.Cu")
	)
	(gr_line
		(start 99.735386 -187.791344)
		(end 99.75088 -187.780422)
		(stroke
			(width 0.06985)
			(type default)
		)
		(layer "In2.Cu")
	)
	(gr_line
		(start 99.89566 -208.667858)
		(end 99.931728 -208.616296)
		(stroke
			(width 0.06985)
			(type default)
		)
		(layer "In2.Cu")
	)
	(gr_line
		(start 100.080064 -193.27495)
		(end 100.090986 -193.259202)
		(stroke
			(width 0.06985)
			(type default)
		)
		(layer "In2.Cu")
	)
	(gr_line
		(start 100.090986 -193.259202)
		(end 100.105972 -193.248534)
		(stroke
			(width 0.06985)
			(type default)
		)
		(layer "In2.Cu")
	)
	(gr_arc
		(start 100.264976 -221.712028)
		(mid 100.327656 -222.027372)
		(end 100.506276 -222.294704)
		(stroke
			(width 0.06985)
			(type default)
		)
		(layer "In2.Cu")
	)
	(gr_line
		(start 100.314506 -199.146922)
		(end 100.33 -199.136)
		(stroke
			(width 0.06985)
			(type default)
		)
		(layer "In2.Cu")
	)
	(gr_line
		(start 100.33 -199.136)
		(end 100.340922 -199.120506)
		(stroke
			(width 0.06985)
			(type default)
		)
		(layer "In2.Cu")
	)
	(gr_line
		(start 100.462842 -182.404258)
		(end 100.473764 -182.388764)
		(stroke
			(width 0.06985)
			(type default)
		)
		(layer "In2.Cu")
	)
	(gr_line
		(start 100.473764 -182.388764)
		(end 100.489258 -182.377842)
		(stroke
			(width 0.06985)
			(type default)
		)
		(layer "In2.Cu")
	)
	(gr_line
		(start 100.539296 -194.542156)
		(end 100.550726 -194.525646)
		(stroke
			(width 0.06985)
			(type default)
		)
		(layer "In2.Cu")
	)
	(gr_line
		(start 100.550726 -194.525646)
		(end 100.567236 -194.514216)
		(stroke
			(width 0.06985)
			(type default)
		)
		(layer "In2.Cu")
	)
	(gr_line
		(start 100.553266 -190.150496)
		(end 100.564188 -190.135002)
		(stroke
			(width 0.06985)
			(type default)
		)
		(layer "In2.Cu")
	)
	(gr_line
		(start 100.564188 -190.135002)
		(end 100.579682 -190.12408)
		(stroke
			(width 0.06985)
			(type default)
		)
		(layer "In2.Cu")
	)
	(gr_line
		(start 100.566982 -219.636594)
		(end 100.566982 -219.636848)
		(stroke
			(width 0.06985)
			(type default)
		)
		(layer "In2.Cu")
	)
	(gr_line
		(start 100.566982 -219.636594)
		(end 100.570284 -219.617798)
		(stroke
			(width 0.06985)
			(type default)
		)
		(layer "In2.Cu")
	)
	(gr_line
		(start 100.566982 -219.599002)
		(end 100.570284 -219.617798)
		(stroke
			(width 0.06985)
			(type default)
		)
		(layer "In2.Cu")
	)
	(gr_line
		(start 101.310948 -203.65593)
		(end 101.326442 -203.645008)
		(stroke
			(width 0.06985)
			(type default)
		)
		(layer "In2.Cu")
	)
	(gr_line
		(start 101.325172 -200.025254)
		(end 101.340666 -200.014332)
		(stroke
			(width 0.06985)
			(type default)
		)
		(layer "In2.Cu")
	)
	(gr_line
		(start 101.326442 -203.645008)
		(end 101.337364 -203.629514)
		(stroke
			(width 0.06985)
			(type default)
		)
		(layer "In2.Cu")
	)
	(gr_line
		(start 101.340666 -200.014332)
		(end 101.351588 -199.998838)
		(stroke
			(width 0.06985)
			(type default)
		)
		(layer "In2.Cu")
	)
	(gr_line
		(start 101.34854 -195.309236)
		(end 101.358446 -195.295266)
		(stroke
			(width 0.06985)
			(type default)
		)
		(layer "In2.Cu")
	)
	(gr_line
		(start 101.358446 -195.295266)
		(end 101.372416 -195.285614)
		(stroke
			(width 0.06985)
			(type default)
		)
		(layer "In2.Cu")
	)
	(gr_line
		(start 101.463094 -183.317642)
		(end 101.474016 -183.302148)
		(stroke
			(width 0.06985)
			(type default)
		)
		(layer "In2.Cu")
	)
	(gr_line
		(start 101.474016 -183.302148)
		(end 101.48951 -183.291226)
		(stroke
			(width 0.06985)
			(type default)
		)
		(layer "In2.Cu")
	)
	(gr_line
		(start 101.71938 -196.57568)
		(end 101.730302 -196.560186)
		(stroke
			(width 0.06985)
			(type default)
		)
		(layer "In2.Cu")
	)
	(gr_line
		(start 101.730302 -196.560186)
		(end 101.745796 -196.549264)
		(stroke
			(width 0.06985)
			(type default)
		)
		(layer "In2.Cu")
	)
	(gr_line
		(start 101.881686 -200.581768)
		(end 101.89718 -200.570846)
		(stroke
			(width 0.06985)
			(type default)
		)
		(layer "In2.Cu")
	)
	(gr_line
		(start 101.89718 -200.570846)
		(end 101.908102 -200.555352)
		(stroke
			(width 0.06985)
			(type default)
		)
		(layer "In2.Cu")
	)
	(gr_line
		(start 101.9302 -39.80561)
		(end 102.139496 -39.596314)
		(stroke
			(width 0.06985)
			(type default)
		)
		(layer "In2.Cu")
	)
	(gr_line
		(start 101.9302 -38.91661)
		(end 102.139496 -39.125906)
		(stroke
			(width 0.06985)
			(type default)
		)
		(layer "In2.Cu")
	)
	(gr_line
		(start 102.399846 -177.17262)
		(end 102.410768 -177.157126)
		(stroke
			(width 0.06985)
			(type default)
		)
		(layer "In2.Cu")
	)
	(gr_line
		(start 102.410768 -177.157126)
		(end 102.426262 -177.146204)
		(stroke
			(width 0.06985)
			(type default)
		)
		(layer "In2.Cu")
	)
	(gr_line
		(start 102.5144 -37.094668)
		(end 102.723696 -36.885372)
		(stroke
			(width 0.06985)
			(type default)
		)
		(layer "In2.Cu")
	)
	(gr_line
		(start 102.5144 -36.205668)
		(end 102.723696 -36.414964)
		(stroke
			(width 0.06985)
			(type default)
		)
		(layer "In2.Cu")
	)
	(gr_line
		(start 102.554786 -197.704202)
		(end 102.565708 -197.688708)
		(stroke
			(width 0.06985)
			(type default)
		)
		(layer "In2.Cu")
	)
	(gr_line
		(start 102.565708 -197.688708)
		(end 102.581202 -197.677786)
		(stroke
			(width 0.06985)
			(type default)
		)
		(layer "In2.Cu")
	)
	(gr_arc
		(start 102.62616 -81.005172)
		(mid 102.725243 -81.244428)
		(end 102.964488 -81.3435)
		(stroke
			(width 0.06985)
			(type default)
		)
		(layer "In2.Cu")
	)
	(gr_line
		(start 102.62616 -81.0006)
		(end 102.62616 -81.005172)
		(stroke
			(width 0.06985)
			(type default)
		)
		(layer "In2.Cu")
	)
	(gr_line
		(start 102.787196 -215.914478)
		(end 102.790498 -215.933528)
		(stroke
			(width 0.06985)
			(type default)
		)
		(layer "In2.Cu")
	)
	(gr_line
		(start 102.787196 -215.914478)
		(end 102.790498 -215.895682)
		(stroke
			(width 0.06985)
			(type default)
		)
		(layer "In2.Cu")
	)
	(gr_arc
		(start 102.893368 -222.294704)
		(mid 103.071995 -222.02737)
		(end 103.134668 -221.712028)
		(stroke
			(width 0.06985)
			(type default)
		)
		(layer "In2.Cu")
	)
	(gr_line
		(start 102.92969 -198.52005)
		(end 102.940612 -198.504556)
		(stroke
			(width 0.06985)
			(type default)
		)
		(layer "In2.Cu")
	)
	(gr_line
		(start 102.940612 -198.504556)
		(end 102.956106 -198.493634)
		(stroke
			(width 0.06985)
			(type default)
		)
		(layer "In2.Cu")
	)
	(gr_arc
		(start 103.07066 -81.6737)
		(mid 102.756377 -81.803905)
		(end 102.62616 -82.1182)
		(stroke
			(width 0.06985)
			(type default)
		)
		(layer "In2.Cu")
	)
	(gr_line
		(start 103.440484 -207.80248)
		(end 103.446326 -207.76946)
		(stroke
			(width 0.06985)
			(type default)
		)
		(layer "In2.Cu")
	)
	(gr_line
		(start 103.446326 -207.76946)
		(end 103.465884 -207.74152)
		(stroke
			(width 0.06985)
			(type default)
		)
		(layer "In2.Cu")
	)
	(gr_arc
		(start 103.464868 -221.712028)
		(mid 103.527548 -222.027373)
		(end 103.706168 -222.294704)
		(stroke
			(width 0.06985)
			(type default)
		)
		(layer "In2.Cu")
	)
	(gr_line
		(start 103.746046 -219.486226)
		(end 103.746046 -219.48648)
		(stroke
			(width 0.06985)
			(type default)
		)
		(layer "In2.Cu")
	)
	(gr_line
		(start 103.746046 -219.486226)
		(end 103.749348 -219.46743)
		(stroke
			(width 0.06985)
			(type default)
		)
		(layer "In2.Cu")
	)
	(gr_line
		(start 103.746046 -219.448634)
		(end 103.749348 -219.46743)
		(stroke
			(width 0.06985)
			(type default)
		)
		(layer "In2.Cu")
	)
	(gr_line
		(start 104.023922 -199.215502)
		(end 104.034844 -199.200008)
		(stroke
			(width 0.06985)
			(type default)
		)
		(layer "In2.Cu")
	)
	(gr_line
		(start 104.034844 -199.200008)
		(end 104.050338 -199.189086)
		(stroke
			(width 0.06985)
			(type default)
		)
		(layer "In2.Cu")
	)
	(gr_line
		(start 105.0036 -77.772514)
		(end 105.0036 -77.881734)
		(stroke
			(width 0.06985)
			(type default)
		)
		(layer "In2.Cu")
	)
	(gr_line
		(start 105.0036 -76.578714)
		(end 105.0036 -76.687934)
		(stroke
			(width 0.06985)
			(type default)
		)
		(layer "In2.Cu")
	)
	(gr_line
		(start 105.0036 -75.384914)
		(end 105.0036 -75.494134)
		(stroke
			(width 0.06985)
			(type default)
		)
		(layer "In2.Cu")
	)
	(gr_line
		(start 105.33634 -78.211934)
		(end 105.5116 -78.036674)
		(stroke
			(width 0.06985)
			(type default)
		)
		(layer "In2.Cu")
	)
	(gr_line
		(start 105.33634 -77.442314)
		(end 105.5116 -77.617574)
		(stroke
			(width 0.06985)
			(type default)
		)
		(layer "In2.Cu")
	)
	(gr_line
		(start 105.33634 -77.018134)
		(end 105.5116 -76.842874)
		(stroke
			(width 0.06985)
			(type default)
		)
		(layer "In2.Cu")
	)
	(gr_line
		(start 105.33634 -76.248514)
		(end 105.5116 -76.423774)
		(stroke
			(width 0.06985)
			(type default)
		)
		(layer "In2.Cu")
	)
	(gr_line
		(start 105.33634 -75.824334)
		(end 105.5116 -75.649074)
		(stroke
			(width 0.06985)
			(type default)
		)
		(layer "In2.Cu")
	)
	(gr_line
		(start 105.33634 -75.054714)
		(end 105.5116 -75.229974)
		(stroke
			(width 0.06985)
			(type default)
		)
		(layer "In2.Cu")
	)
	(gr_line
		(start 105.5116 -77.617574)
		(end 105.5116 -78.036674)
		(stroke
			(width 0.06985)
			(type default)
		)
		(layer "In2.Cu")
	)
	(gr_line
		(start 105.5116 -76.423774)
		(end 105.5116 -76.842874)
		(stroke
			(width 0.06985)
			(type default)
		)
		(layer "In2.Cu")
	)
	(gr_line
		(start 105.5116 -75.229974)
		(end 105.5116 -75.649074)
		(stroke
			(width 0.06985)
			(type default)
		)
		(layer "In2.Cu")
	)
	(gr_line
		(start 105.804208 -200.229724)
		(end 105.81513 -200.21423)
		(stroke
			(width 0.06985)
			(type default)
		)
		(layer "In2.Cu")
	)
	(gr_line
		(start 105.81513 -200.21423)
		(end 105.830624 -200.203308)
		(stroke
			(width 0.06985)
			(type default)
		)
		(layer "In2.Cu")
	)
	(gr_line
		(start 105.921556 -216.012014)
		(end 105.924858 -216.031064)
		(stroke
			(width 0.06985)
			(type default)
		)
		(layer "In2.Cu")
	)
	(gr_line
		(start 105.921556 -216.012014)
		(end 105.924858 -215.993218)
		(stroke
			(width 0.06985)
			(type default)
		)
		(layer "In2.Cu")
	)
	(gr_arc
		(start 106.093514 -222.294704)
		(mid 106.272141 -222.02737)
		(end 106.334814 -221.712028)
		(stroke
			(width 0.06985)
			(type default)
		)
		(layer "In2.Cu")
	)
	(gr_arc
		(start 106.665014 -221.712028)
		(mid 106.727696 -222.02737)
		(end 106.906314 -222.294704)
		(stroke
			(width 0.06985)
			(type default)
		)
		(layer "In2.Cu")
	)
	(gr_line
		(start 106.903266 -219.714318)
		(end 106.903266 -219.714572)
		(stroke
			(width 0.06985)
			(type default)
		)
		(layer "In2.Cu")
	)
	(gr_line
		(start 106.903266 -219.714318)
		(end 106.906568 -219.695522)
		(stroke
			(width 0.06985)
			(type default)
		)
		(layer "In2.Cu")
	)
	(gr_line
		(start 106.903266 -219.676726)
		(end 106.906568 -219.695522)
		(stroke
			(width 0.06985)
			(type default)
		)
		(layer "In2.Cu")
	)
	(gr_line
		(start 107.023154 -206.040736)
		(end 107.028996 -206.007716)
		(stroke
			(width 0.06985)
			(type default)
		)
		(layer "In2.Cu")
	)
	(gr_line
		(start 107.028996 -206.007716)
		(end 107.048554 -205.979776)
		(stroke
			(width 0.06985)
			(type default)
		)
		(layer "In2.Cu")
	)
	(gr_line
		(start 107.410504 -51.864514)
		(end 107.410504 -51.86553)
		(stroke
			(width 0.0635)
			(type default)
		)
		(layer "In2.Cu")
	)
	(gr_line
		(start 107.410504 -51.864514)
		(end 107.60329 -51.671728)
		(stroke
			(width 0.0635)
			(type default)
		)
		(layer "In2.Cu")
	)
	(gr_line
		(start 107.410504 -50.75682)
		(end 107.60329 -50.949606)
		(stroke
			(width 0.0635)
			(type default)
		)
		(layer "In2.Cu")
	)
	(gr_line
		(start 108.797344 -200.127108)
		(end 108.808266 -200.111614)
		(stroke
			(width 0.06985)
			(type default)
		)
		(layer "In2.Cu")
	)
	(gr_line
		(start 108.808266 -200.111614)
		(end 108.82376 -200.100692)
		(stroke
			(width 0.06985)
			(type default)
		)
		(layer "In2.Cu")
	)
	(gr_line
		(start 110.1344 -97.0026)
		(end 110.247938 -96.889062)
		(stroke
			(width 0.0635)
			(type default)
		)
		(layer "In2.Cu")
	)
	(gr_line
		(start 110.530894 -42.390568)
		(end 110.60176 -42.461434)
		(stroke
			(width 0.0635)
			(type default)
		)
		(layer "In2.Cu")
	)
	(gr_line
		(start 111.099854 -200.193148)
		(end 111.110776 -200.177654)
		(stroke
			(width 0.06985)
			(type default)
		)
		(layer "In2.Cu")
	)
	(gr_line
		(start 111.110776 -200.177654)
		(end 111.12627 -200.166732)
		(stroke
			(width 0.06985)
			(type default)
		)
		(layer "In2.Cu")
	)
	(gr_line
		(start 111.323628 -42.461434)
		(end 111.394494 -42.390568)
		(stroke
			(width 0.0635)
			(type default)
		)
		(layer "In2.Cu")
	)
	(gr_line
		(start 115.951 -43.124882)
		(end 116.144294 -42.931588)
		(stroke
			(width 0.0635)
			(type default)
		)
		(layer "In2.Cu")
	)
	(gr_line
		(start 115.951 -42.016172)
		(end 116.144294 -42.209466)
		(stroke
			(width 0.0635)
			(type default)
		)
		(layer "In2.Cu")
	)
	(gr_line
		(start 116.654326 -107.857544)
		(end 116.673884 -107.8611)
		(stroke
			(width 0.06985)
			(type default)
		)
		(layer "In2.Cu")
	)
	(gr_line
		(start 116.673884 -107.8611)
		(end 116.692934 -107.85729)
		(stroke
			(width 0.06985)
			(type default)
		)
		(layer "In2.Cu")
	)
	(gr_line
		(start 117.38102 -110.19282)
		(end 117.405658 -110.197138)
		(stroke
			(width 0.06985)
			(type default)
		)
		(layer "In2.Cu")
	)
	(gr_line
		(start 117.405658 -110.197138)
		(end 117.430042 -110.192058)
		(stroke
			(width 0.06985)
			(type default)
		)
		(layer "In2.Cu")
	)
	(gr_line
		(start 117.463824 -109.004608)
		(end 117.488462 -109.008926)
		(stroke
			(width 0.06985)
			(type default)
		)
		(layer "In2.Cu")
	)
	(gr_line
		(start 117.488462 -109.008926)
		(end 117.512846 -109.003846)
		(stroke
			(width 0.06985)
			(type default)
		)
		(layer "In2.Cu")
	)
	(gr_line
		(start 118.366032 -33.989264)
		(end 118.405402 -33.980882)
		(stroke
			(width 0.06985)
			(type default)
		)
		(layer "In2.Cu")
	)
	(gr_line
		(start 118.405402 -33.980882)
		(end 118.444264 -33.99155)
		(stroke
			(width 0.06985)
			(type default)
		)
		(layer "In2.Cu")
	)
	(gr_line
		(start 119.802656 -36.135564)
		(end 119.842534 -36.127182)
		(stroke
			(width 0.06985)
			(type default)
		)
		(layer "In2.Cu")
	)
	(gr_line
		(start 119.842534 -36.127182)
		(end 119.881904 -36.13785)
		(stroke
			(width 0.06985)
			(type default)
		)
		(layer "In2.Cu")
	)
	(gr_line
		(start 120.303798 -84.804504)
		(end 120.378982 -84.72932)
		(stroke
			(width 0.0635)
			(type default)
		)
		(layer "In2.Cu")
	)
	(gr_line
		(start 121.038874 -103.023924)
		(end 121.165112 -102.897686)
		(stroke
			(width 0.0635)
			(type default)
		)
		(layer "In2.Cu")
	)
	(gr_line
		(start 121.0564 -90.3732)
		(end 121.127266 -90.302334)
		(stroke
			(width 0.0635)
			(type default)
		)
		(layer "In2.Cu")
	)
	(gr_line
		(start 121.101104 -84.72932)
		(end 121.167398 -84.795614)
		(stroke
			(width 0.0635)
			(type default)
		)
		(layer "In2.Cu")
	)
	(gr_line
		(start 121.273062 -109.03712)
		(end 121.302526 -109.03077)
		(stroke
			(width 0.06985)
			(type default)
		)
		(layer "In2.Cu")
	)
	(gr_line
		(start 121.302526 -109.03077)
		(end 121.33199 -109.03712)
		(stroke
			(width 0.06985)
			(type default)
		)
		(layer "In2.Cu")
	)
	(gr_line
		(start 121.632472 -106.470958)
		(end 121.661936 -106.464608)
		(stroke
			(width 0.06985)
			(type default)
		)
		(layer "In2.Cu")
	)
	(gr_line
		(start 121.661936 -106.464608)
		(end 121.6914 -106.470958)
		(stroke
			(width 0.06985)
			(type default)
		)
		(layer "In2.Cu")
	)
	(gr_line
		(start 121.758456 -107.76331)
		(end 121.78792 -107.75696)
		(stroke
			(width 0.06985)
			(type default)
		)
		(layer "In2.Cu")
	)
	(gr_line
		(start 121.78792 -107.75696)
		(end 121.817384 -107.76331)
		(stroke
			(width 0.06985)
			(type default)
		)
		(layer "In2.Cu")
	)
	(gr_line
		(start 121.849134 -90.302334)
		(end 121.92 -90.3732)
		(stroke
			(width 0.0635)
			(type default)
		)
		(layer "In2.Cu")
	)
	(gr_line
		(start 121.887234 -102.897686)
		(end 122.013472 -103.023924)
		(stroke
			(width 0.0635)
			(type default)
		)
		(layer "In2.Cu")
	)
	(gr_line
		(start 123.649232 -141.269466)
		(end 123.660154 -141.253972)
		(stroke
			(width 0.06985)
			(type default)
		)
		(layer "In2.Cu")
	)
	(gr_line
		(start 123.660154 -141.253972)
		(end 123.675648 -141.24305)
		(stroke
			(width 0.06985)
			(type default)
		)
		(layer "In2.Cu")
	)
	(gr_line
		(start 124.31649 -142.351252)
		(end 124.327412 -142.335758)
		(stroke
			(width 0.06985)
			(type default)
		)
		(layer "In2.Cu")
	)
	(gr_line
		(start 124.327412 -142.335758)
		(end 124.342906 -142.324836)
		(stroke
			(width 0.06985)
			(type default)
		)
		(layer "In2.Cu")
	)
	(gr_line
		(start 126.429262 -110.45825)
		(end 126.458726 -110.4646)
		(stroke
			(width 0.06985)
			(type default)
		)
		(layer "In2.Cu")
	)
	(gr_line
		(start 126.458726 -110.4646)
		(end 126.48819 -110.45825)
		(stroke
			(width 0.06985)
			(type default)
		)
		(layer "In2.Cu")
	)
	(gr_line
		(start 127.197612 -107.97921)
		(end 127.227076 -107.98556)
		(stroke
			(width 0.06985)
			(type default)
		)
		(layer "In2.Cu")
	)
	(gr_line
		(start 127.227076 -107.98556)
		(end 127.25654 -107.97921)
		(stroke
			(width 0.06985)
			(type default)
		)
		(layer "In2.Cu")
	)
	(gr_line
		(start 127.267462 -109.25937)
		(end 127.296926 -109.26572)
		(stroke
			(width 0.06985)
			(type default)
		)
		(layer "In2.Cu")
	)
	(gr_line
		(start 127.296926 -109.26572)
		(end 127.32639 -109.25937)
		(stroke
			(width 0.06985)
			(type default)
		)
		(layer "In2.Cu")
	)
	(gr_line
		(start 131.138168 -37.859716)
		(end 131.17703 -37.870384)
		(stroke
			(width 0.06985)
			(type default)
		)
		(layer "In2.Cu")
	)
	(gr_line
		(start 131.17703 -37.870384)
		(end 131.2164 -37.862002)
		(stroke
			(width 0.06985)
			(type default)
		)
		(layer "In2.Cu")
	)
	(gr_arc
		(start 131.390644 -41.9862)
		(mid 131.642063 -41.882032)
		(end 131.746244 -41.6306)
		(stroke
			(width 0.06985)
			(type default)
		)
		(layer "In2.Cu")
	)
	(gr_arc
		(start 131.746244 -42.693844)
		(mid 131.635709 -42.426922)
		(end 131.3688 -42.3164)
		(stroke
			(width 0.06985)
			(type default)
		)
		(layer "In2.Cu")
	)
	(gr_line
		(start 131.746244 -42.693844)
		(end 131.746244 -42.7228)
		(stroke
			(width 0.06985)
			(type default)
		)
		(layer "In2.Cu")
	)
	(gr_line
		(start 131.746244 -41.6052)
		(end 131.746244 -41.6306)
		(stroke
			(width 0.06985)
			(type default)
		)
		(layer "In2.Cu")
	)
	(gr_line
		(start 131.81203 -25.989788)
		(end 131.816348 -25.96515)
		(stroke
			(width 0.06985)
			(type default)
		)
		(layer "In2.Cu")
	)
	(gr_line
		(start 131.81203 -25.989788)
		(end 131.817364 -26.014934)
		(stroke
			(width 0.06985)
			(type default)
		)
		(layer "In2.Cu")
	)
	(gr_line
		(start 131.82092 -20.60575)
		(end 131.826762 -20.57273)
		(stroke
			(width 0.06985)
			(type default)
		)
		(layer "In2.Cu")
	)
	(gr_line
		(start 131.826762 -20.57273)
		(end 131.84632 -20.54479)
		(stroke
			(width 0.06985)
			(type default)
		)
		(layer "In2.Cu")
	)
	(gr_line
		(start 131.901946 -26.411428)
		(end 131.90601 -26.43124)
		(stroke
			(width 0.06985)
			(type default)
		)
		(layer "In2.Cu")
	)
	(gr_line
		(start 131.90601 -26.43124)
		(end 131.91744 -26.44902)
		(stroke
			(width 0.06985)
			(type default)
		)
		(layer "In2.Cu")
	)
	(gr_line
		(start 131.968748 -39.781226)
		(end 132.008118 -39.791894)
		(stroke
			(width 0.06985)
			(type default)
		)
		(layer "In2.Cu")
	)
	(gr_line
		(start 132.008118 -39.791894)
		(end 132.047996 -39.783512)
		(stroke
			(width 0.06985)
			(type default)
		)
		(layer "In2.Cu")
	)
	(gr_line
		(start 132.361432 -27.133042)
		(end 132.377688 -27.157934)
		(stroke
			(width 0.06985)
			(type default)
		)
		(layer "In2.Cu")
	)
	(gr_line
		(start 132.377688 -27.157934)
		(end 132.40258 -27.17419)
		(stroke
			(width 0.06985)
			(type default)
		)
		(layer "In2.Cu")
	)
	(gr_line
		(start 132.398262 -24.56815)
		(end 132.398262 -24.568404)
		(stroke
			(width 0.06985)
			(type default)
		)
		(layer "In2.Cu")
	)
	(gr_line
		(start 132.398262 -24.56815)
		(end 132.401564 -24.549354)
		(stroke
			(width 0.06985)
			(type default)
		)
		(layer "In2.Cu")
	)
	(gr_line
		(start 132.398262 -24.530558)
		(end 132.401564 -24.549354)
		(stroke
			(width 0.06985)
			(type default)
		)
		(layer "In2.Cu")
	)
	(gr_line
		(start 132.491988 -19.622516)
		(end 132.50291 -19.607022)
		(stroke
			(width 0.06985)
			(type default)
		)
		(layer "In2.Cu")
	)
	(gr_line
		(start 132.50291 -19.607022)
		(end 132.518404 -19.5961)
		(stroke
			(width 0.06985)
			(type default)
		)
		(layer "In2.Cu")
	)
	(gr_line
		(start 133.499606 -18.90903)
		(end 133.578854 -18.853658)
		(stroke
			(width 0.06985)
			(type default)
		)
		(layer "In2.Cu")
	)
	(gr_line
		(start 133.578854 -18.853658)
		(end 133.673596 -18.870422)
		(stroke
			(width 0.06985)
			(type default)
		)
		(layer "In2.Cu")
	)
	(gr_line
		(start 134.168388 -38.994842)
		(end 134.197852 -38.988492)
		(stroke
			(width 0.06985)
			(type default)
		)
		(layer "In2.Cu")
	)
	(gr_line
		(start 134.173976 -106.508296)
		(end 134.193788 -106.504232)
		(stroke
			(width 0.06985)
			(type default)
		)
		(layer "In2.Cu")
	)
	(gr_line
		(start 134.193788 -106.504232)
		(end 134.211568 -106.492802)
		(stroke
			(width 0.06985)
			(type default)
		)
		(layer "In2.Cu")
	)
	(gr_line
		(start 134.197852 -38.988492)
		(end 134.227316 -38.994842)
		(stroke
			(width 0.06985)
			(type default)
		)
		(layer "In2.Cu")
	)
	(gr_line
		(start 134.412228 -107.75315)
		(end 134.43204 -107.749086)
		(stroke
			(width 0.06985)
			(type default)
		)
		(layer "In2.Cu")
	)
	(gr_line
		(start 134.43204 -107.749086)
		(end 134.44982 -107.737656)
		(stroke
			(width 0.06985)
			(type default)
		)
		(layer "In2.Cu")
	)
	(gr_line
		(start 134.72033 -19.39036)
		(end 134.739126 -19.393662)
		(stroke
			(width 0.06985)
			(type default)
		)
		(layer "In2.Cu")
	)
	(gr_line
		(start 134.739126 -19.393662)
		(end 134.757922 -19.39036)
		(stroke
			(width 0.06985)
			(type default)
		)
		(layer "In2.Cu")
	)
	(gr_line
		(start 135.17245 -28.970986)
		(end 135.19023 -28.982416)
		(stroke
			(width 0.06985)
			(type default)
		)
		(layer "In2.Cu")
	)
	(gr_line
		(start 135.173212 -12.730734)
		(end 135.208264 -12.75207)
		(stroke
			(width 0.06985)
			(type default)
		)
		(layer "In2.Cu")
	)
	(gr_line
		(start 135.19023 -28.982416)
		(end 135.210042 -28.98648)
		(stroke
			(width 0.06985)
			(type default)
		)
		(layer "In2.Cu")
	)
	(gr_line
		(start 135.298434 -12.806934)
		(end 135.320532 -12.82065)
		(stroke
			(width 0.06985)
			(type default)
		)
		(layer "In2.Cu")
	)
	(gr_arc
		(start 135.349234 -12.439396)
		(mid 135.380497 -12.467205)
		(end 135.414766 -12.491212)
		(stroke
			(width 0.06985)
			(type default)
		)
		(layer "In2.Cu")
	)
	(gr_line
		(start 135.38454 -17.729962)
		(end 135.889492 -17.729962)
		(stroke
			(width 0.06985)
			(type default)
		)
		(layer "In2.Cu")
	)
	(gr_arc
		(start 135.38454 -13.930122)
		(mid 135.536423 -13.900004)
		(end 135.66521 -13.814044)
		(stroke
			(width 0.06985)
			(type default)
		)
		(layer "In2.Cu")
	)
	(gr_arc
		(start 135.436102 -12.504166)
		(mid 135.457987 -12.516737)
		(end 135.480552 -12.528042)
		(stroke
			(width 0.06985)
			(type default)
		)
		(layer "In2.Cu")
	)
	(gr_line
		(start 135.453882 -106.691684)
		(end 136.035796 -106.313986)
		(stroke
			(width 0.06985)
			(type default)
		)
		(layer "In2.Cu")
	)
	(gr_arc
		(start 135.459978 -12.88034)
		(mid 135.392297 -12.845726)
		(end 135.320532 -12.82065)
		(stroke
			(width 0.06985)
			(type default)
		)
		(layer "In2.Cu")
	)
	(gr_line
		(start 135.480552 -12.528042)
		(end 135.531352 -12.55141)
		(stroke
			(width 0.06985)
			(type default)
		)
		(layer "In2.Cu")
	)
	(gr_arc
		(start 135.489188 -12.89939)
		(mid 135.474733 -12.889636)
		(end 135.459978 -12.88034)
		(stroke
			(width 0.06985)
			(type default)
		)
		(layer "In2.Cu")
	)
	(gr_line
		(start 135.531352 -12.55141)
		(end 135.616188 -12.587986)
		(stroke
			(width 0.06985)
			(type default)
		)
		(layer "In2.Cu")
	)
	(gr_arc
		(start 135.533638 -12.93368)
		(mid 135.511848 -12.915971)
		(end 135.489188 -12.89939)
		(stroke
			(width 0.06985)
			(type default)
		)
		(layer "In2.Cu")
	)
	(gr_line
		(start 135.533638 -12.93368)
		(end 135.683752 -13.083794)
		(stroke
			(width 0.06985)
			(type default)
		)
		(layer "In2.Cu")
	)
	(gr_line
		(start 135.60298 -106.991658)
		(end 135.84555 -107.04322)
		(stroke
			(width 0.06985)
			(type default)
		)
		(layer "In2.Cu")
	)
	(gr_line
		(start 135.616188 -12.587986)
		(end 135.624824 -12.593574)
		(stroke
			(width 0.06985)
			(type default)
		)
		(layer "In2.Cu")
	)
	(gr_line
		(start 135.624824 -12.593574)
		(end 135.771382 -12.611354)
		(stroke
			(width 0.06985)
			(type default)
		)
		(layer "In2.Cu")
	)
	(gr_arc
		(start 135.66521 -13.814044)
		(mid 135.775158 -13.649495)
		(end 135.8138 -13.455396)
		(stroke
			(width 0.06985)
			(type default)
		)
		(layer "In2.Cu")
	)
	(gr_line
		(start 135.769604 -28.76804)
		(end 135.789416 -28.772104)
		(stroke
			(width 0.06985)
			(type default)
		)
		(layer "In2.Cu")
	)
	(gr_line
		(start 135.771382 -12.611354)
		(end 135.967724 -12.611354)
		(stroke
			(width 0.06985)
			(type default)
		)
		(layer "In2.Cu")
	)
	(gr_line
		(start 135.789416 -28.772104)
		(end 135.807196 -28.783534)
		(stroke
			(width 0.06985)
			(type default)
		)
		(layer "In2.Cu")
	)
	(gr_arc
		(start 135.8138 -13.397738)
		(mid 135.780003 -13.22783)
		(end 135.683752 -13.083794)
		(stroke
			(width 0.06985)
			(type default)
		)
		(layer "In2.Cu")
	)
	(gr_line
		(start 135.8138 -13.397738)
		(end 135.8138 -13.455396)
		(stroke
			(width 0.06985)
			(type default)
		)
		(layer "In2.Cu")
	)
	(gr_line
		(start 135.84555 -107.04322)
		(end 136.197086 -106.814874)
		(stroke
			(width 0.06985)
			(type default)
		)
		(layer "In2.Cu")
	)
	(gr_line
		(start 135.935466 -108.450126)
		(end 135.955278 -108.446062)
		(stroke
			(width 0.06985)
			(type default)
		)
		(layer "In2.Cu")
	)
	(gr_line
		(start 135.955278 -108.446062)
		(end 135.973058 -108.434632)
		(stroke
			(width 0.06985)
			(type default)
		)
		(layer "In2.Cu")
	)
	(gr_arc
		(start 135.967724 -12.611354)
		(mid 136.057833 -12.584646)
		(end 136.134348 -12.530074)
		(stroke
			(width 0.06985)
			(type default)
		)
		(layer "In2.Cu")
	)
	(gr_arc
		(start 135.981948 -16.79702)
		(mid 136.02073 -16.992223)
		(end 136.1313 -17.1577)
		(stroke
			(width 0.06985)
			(type default)
		)
		(layer "In2.Cu")
	)
	(gr_line
		(start 135.981948 -16.6624)
		(end 135.981948 -16.79702)
		(stroke
			(width 0.06985)
			(type default)
		)
		(layer "In2.Cu")
	)
	(gr_arc
		(start 136.109202 -16.355568)
		(mid 136.015076 -16.496335)
		(end 135.981948 -16.6624)
		(stroke
			(width 0.06985)
			(type default)
		)
		(layer "In2.Cu")
	)
	(gr_line
		(start 136.109202 -16.355568)
		(end 136.134348 -16.330168)
		(stroke
			(width 0.06985)
			(type default)
		)
		(layer "In2.Cu")
	)
	(gr_line
		(start 136.1313 -17.1577)
		(end 136.475978 -17.502378)
		(stroke
			(width 0.06985)
			(type default)
		)
		(layer "In2.Cu")
	)
	(gr_line
		(start 136.182608 -19.139154)
		(end 136.255506 -19.1262)
		(stroke
			(width 0.06985)
			(type default)
		)
		(layer "In2.Cu")
	)
	(gr_line
		(start 136.197086 -106.814874)
		(end 136.248648 -106.572304)
		(stroke
			(width 0.06985)
			(type default)
		)
		(layer "In2.Cu")
	)
	(gr_line
		(start 136.455404 -106.041444)
		(end 137.037064 -105.663746)
		(stroke
			(width 0.06985)
			(type default)
		)
		(layer "In2.Cu")
	)
	(gr_arc
		(start 136.477502 -17.971262)
		(mid 136.207272 -17.792675)
		(end 135.889492 -17.729962)
		(stroke
			(width 0.06985)
			(type default)
		)
		(layer "In2.Cu")
	)
	(gr_line
		(start 136.604248 -106.341418)
		(end 136.846818 -106.39298)
		(stroke
			(width 0.06985)
			(type default)
		)
		(layer "In2.Cu")
	)
	(gr_line
		(start 136.817862 -96.528636)
		(end 137.0076 -96.718374)
		(stroke
			(width 0.0635)
			(type default)
		)
		(layer "In2.Cu")
	)
	(gr_line
		(start 136.817862 -95.806514)
		(end 137.0076 -95.616776)
		(stroke
			(width 0.0635)
			(type default)
		)
		(layer "In2.Cu")
	)
	(gr_line
		(start 136.846818 -106.39298)
		(end 137.198354 -106.164634)
		(stroke
			(width 0.06985)
			(type default)
		)
		(layer "In2.Cu")
	)
	(gr_arc
		(start 136.893554 -222.294704)
		(mid 137.072181 -222.02737)
		(end 137.134854 -221.712028)
		(stroke
			(width 0.06985)
			(type default)
		)
		(layer "In2.Cu")
	)
	(gr_line
		(start 137.134854 -219.652596)
		(end 137.170922 -219.601034)
		(stroke
			(width 0.06985)
			(type default)
		)
		(layer "In2.Cu")
	)
	(gr_line
		(start 137.198354 -106.164634)
		(end 137.249916 -105.922064)
		(stroke
			(width 0.06985)
			(type default)
		)
		(layer "In2.Cu")
	)
	(gr_arc
		(start 137.354564 -12.875768)
		(mid 137.366624 -12.905872)
		(end 137.381488 -12.934696)
		(stroke
			(width 0.06985)
			(type default)
		)
		(layer "In2.Cu")
	)
	(gr_line
		(start 137.456672 -105.391204)
		(end 138.038332 -105.013506)
		(stroke
			(width 0.06985)
			(type default)
		)
		(layer "In2.Cu")
	)
	(gr_arc
		(start 137.465054 -221.712028)
		(mid 137.527775 -222.02735)
		(end 137.706354 -222.294704)
		(stroke
			(width 0.06985)
			(type default)
		)
		(layer "In2.Cu")
	)
	(gr_line
		(start 137.605516 -105.691178)
		(end 137.848086 -105.74274)
		(stroke
			(width 0.06985)
			(type default)
		)
		(layer "In2.Cu")
	)
	(gr_line
		(start 137.634472 -17.729962)
		(end 137.955528 -17.729962)
		(stroke
			(width 0.06985)
			(type default)
		)
		(layer "In2.Cu")
	)
	(gr_arc
		(start 137.805922 -13.051028)
		(mid 138.002511 -13.250299)
		(end 138.282426 -13.252196)
		(stroke
			(width 0.06985)
			(type default)
		)
		(layer "In2.Cu")
	)
	(gr_line
		(start 137.805922 -13.050774)
		(end 137.805922 -13.051028)
		(stroke
			(width 0.06985)
			(type default)
		)
		(layer "In2.Cu")
	)
	(gr_line
		(start 137.848086 -105.74274)
		(end 138.199622 -105.514648)
		(stroke
			(width 0.06985)
			(type default)
		)
		(layer "In2.Cu")
	)
	(gr_line
		(start 138.199622 -105.514648)
		(end 138.251184 -105.271824)
		(stroke
			(width 0.06985)
			(type default)
		)
		(layer "In2.Cu")
	)
	(gr_arc
		(start 138.237214 -16.835882)
		(mid 138.304322 -17.064882)
		(end 138.4427 -17.2593)
		(stroke
			(width 0.06985)
			(type default)
		)
		(layer "In2.Cu")
	)
	(gr_line
		(start 138.237214 -16.685768)
		(end 138.237214 -16.835882)
		(stroke
			(width 0.06985)
			(type default)
		)
		(layer "In2.Cu")
	)
	(gr_line
		(start 138.282426 -13.252196)
		(end 138.28268 -13.251942)
		(stroke
			(width 0.06985)
			(type default)
		)
		(layer "In2.Cu")
	)
	(gr_arc
		(start 138.28268 -13.251942)
		(mid 138.482071 -13.055424)
		(end 138.484102 -12.775438)
		(stroke
			(width 0.06985)
			(type default)
		)
		(layer "In2.Cu")
	)
	(gr_arc
		(start 138.384534 -16.330168)
		(mid 138.275514 -16.493315)
		(end 138.237214 -16.685768)
		(stroke
			(width 0.06985)
			(type default)
		)
		(layer "In2.Cu")
	)
	(gr_line
		(start 138.384534 -12.530074)
		(end 138.484102 -12.775438)
		(stroke
			(width 0.06985)
			(type default)
		)
		(layer "In2.Cu")
	)
	(gr_line
		(start 138.4427 -17.2593)
		(end 138.791442 -17.608042)
		(stroke
			(width 0.06985)
			(type default)
		)
		(layer "In2.Cu")
	)
	(gr_line
		(start 138.457432 -104.741472)
		(end 139.039346 -104.363266)
		(stroke
			(width 0.06985)
			(type default)
		)
		(layer "In2.Cu")
	)
	(gr_line
		(start 138.606276 -105.041192)
		(end 138.849354 -105.0925)
		(stroke
			(width 0.06985)
			(type default)
		)
		(layer "In2.Cu")
	)
	(gr_line
		(start 138.849354 -105.0925)
		(end 139.20089 -104.864408)
		(stroke
			(width 0.06985)
			(type default)
		)
		(layer "In2.Cu")
	)
	(gr_line
		(start 139.20089 -104.864408)
		(end 139.252198 -104.621584)
		(stroke
			(width 0.06985)
			(type default)
		)
		(layer "In2.Cu")
	)
	(gr_line
		(start 139.413996 -11.51509)
		(end 139.414758 -11.525758)
		(stroke
			(width 0.06985)
			(type default)
		)
		(layer "In2.Cu")
	)
	(gr_line
		(start 139.414758 -11.525758)
		(end 139.418568 -11.53541)
		(stroke
			(width 0.06985)
			(type default)
		)
		(layer "In2.Cu")
	)
	(gr_arc
		(start 139.4206 -15.7226)
		(mid 139.29816 -15.602146)
		(end 139.164314 -15.494508)
		(stroke
			(width 0.06985)
			(type default)
		)
		(layer "In2.Cu")
	)
	(gr_line
		(start 139.58697 -36.963858)
		(end 139.634468 -36.994846)
		(stroke
			(width 0.06985)
			(type default)
		)
		(layer "In2.Cu")
	)
	(gr_line
		(start 140.004292 -24.284178)
		(end 140.007594 -24.303228)
		(stroke
			(width 0.06985)
			(type default)
		)
		(layer "In2.Cu")
	)
	(gr_line
		(start 140.004292 -24.284178)
		(end 140.007594 -24.265128)
		(stroke
			(width 0.06985)
			(type default)
		)
		(layer "In2.Cu")
	)
	(gr_line
		(start 140.007594 -31.510732)
		(end 140.032486 -31.526988)
		(stroke
			(width 0.06985)
			(type default)
		)
		(layer "In2.Cu")
	)
	(gr_line
		(start 140.032486 -31.526988)
		(end 140.048742 -31.55188)
		(stroke
			(width 0.06985)
			(type default)
		)
		(layer "In2.Cu")
	)
	(gr_arc
		(start 140.0937 -222.294704)
		(mid 140.272327 -222.02737)
		(end 140.335 -221.712028)
		(stroke
			(width 0.06985)
			(type default)
		)
		(layer "In2.Cu")
	)
	(gr_line
		(start 140.10386 -18.920206)
		(end 140.11529 -18.984468)
		(stroke
			(width 0.06985)
			(type default)
		)
		(layer "In2.Cu")
	)
	(gr_line
		(start 140.1826 -16.4846)
		(end 140.185394 -16.488664)
		(stroke
			(width 0.06985)
			(type default)
		)
		(layer "In2.Cu")
	)
	(gr_line
		(start 140.30071 -215.70696)
		(end 140.320268 -215.67902)
		(stroke
			(width 0.06985)
			(type default)
		)
		(layer "In2.Cu")
	)
	(gr_line
		(start 140.3096 -209.358992)
		(end 140.345668 -209.30743)
		(stroke
			(width 0.06985)
			(type default)
		)
		(layer "In2.Cu")
	)
	(gr_line
		(start 140.320268 -215.67902)
		(end 140.32611 -215.646)
		(stroke
			(width 0.06985)
			(type default)
		)
		(layer "In2.Cu")
	)
	(gr_line
		(start 140.335 -220.094048)
		(end 140.37183 -220.04147)
		(stroke
			(width 0.06985)
			(type default)
		)
		(layer "In2.Cu")
	)
	(gr_arc
		(start 140.6652 -221.712028)
		(mid 140.727882 -222.027371)
		(end 140.9065 -222.294704)
		(stroke
			(width 0.06985)
			(type default)
		)
		(layer "In2.Cu")
	)
	(gr_line
		(start 140.680694 -32.52089)
		(end 140.719048 -32.559244)
		(stroke
			(width 0.06985)
			(type default)
		)
		(layer "In2.Cu")
	)
	(gr_line
		(start 140.691108 -22.288754)
		(end 140.691108 -22.289008)
		(stroke
			(width 0.06985)
			(type default)
		)
		(layer "In2.Cu")
	)
	(gr_line
		(start 140.691108 -22.288754)
		(end 140.69441 -22.269704)
		(stroke
			(width 0.06985)
			(type default)
		)
		(layer "In2.Cu")
	)
	(gr_line
		(start 140.691108 -22.250908)
		(end 140.69441 -22.269704)
		(stroke
			(width 0.06985)
			(type default)
		)
		(layer "In2.Cu")
	)
	(gr_line
		(start 140.719048 -32.559244)
		(end 140.719048 -32.6136)
		(stroke
			(width 0.06985)
			(type default)
		)
		(layer "In2.Cu")
	)
	(gr_line
		(start 141.19987 -36.472114)
		(end 141.203934 -36.491926)
		(stroke
			(width 0.06985)
			(type default)
		)
		(layer "In2.Cu")
	)
	(gr_line
		(start 141.203934 -36.491926)
		(end 141.215364 -36.509706)
		(stroke
			(width 0.06985)
			(type default)
		)
		(layer "In2.Cu")
	)
	(gr_line
		(start 141.255242 -24.693372)
		(end 141.261592 -24.722836)
		(stroke
			(width 0.06985)
			(type default)
		)
		(layer "In2.Cu")
	)
	(gr_line
		(start 141.255242 -24.693372)
		(end 141.261846 -24.662638)
		(stroke
			(width 0.06985)
			(type default)
		)
		(layer "In2.Cu")
	)
	(gr_line
		(start 141.405102 -18.302224)
		(end 141.42212 -18.327624)
		(stroke
			(width 0.06985)
			(type default)
		)
		(layer "In2.Cu")
	)
	(gr_line
		(start 141.42212 -18.327624)
		(end 141.4272 -18.35658)
		(stroke
			(width 0.06985)
			(type default)
		)
		(layer "In2.Cu")
	)
	(gr_line
		(start 141.424406 -101.414326)
		(end 141.448028 -101.399086)
		(stroke
			(width 0.06985)
			(type default)
		)
		(layer "In2.Cu")
	)
	(gr_line
		(start 141.448028 -101.399086)
		(end 141.475206 -101.39426)
		(stroke
			(width 0.06985)
			(type default)
		)
		(layer "In2.Cu")
	)
	(gr_line
		(start 141.822678 -102.555548)
		(end 141.8463 -102.540308)
		(stroke
			(width 0.06985)
			(type default)
		)
		(layer "In2.Cu")
	)
	(gr_line
		(start 141.8463 -102.540308)
		(end 141.873478 -102.535482)
		(stroke
			(width 0.06985)
			(type default)
		)
		(layer "In2.Cu")
	)
	(gr_line
		(start 141.965172 -28.032202)
		(end 141.969236 -28.052014)
		(stroke
			(width 0.06985)
			(type default)
		)
		(layer "In2.Cu")
	)
	(gr_line
		(start 141.969236 -28.052014)
		(end 141.980666 -28.069794)
		(stroke
			(width 0.06985)
			(type default)
		)
		(layer "In2.Cu")
	)
	(gr_line
		(start 141.976856 -40.641778)
		(end 141.996668 -40.645842)
		(stroke
			(width 0.06985)
			(type default)
		)
		(layer "In2.Cu")
	)
	(gr_line
		(start 141.996668 -40.645842)
		(end 142.014448 -40.657272)
		(stroke
			(width 0.06985)
			(type default)
		)
		(layer "In2.Cu")
	)
	(gr_line
		(start 142.029434 -37.76345)
		(end 142.04569 -37.788342)
		(stroke
			(width 0.06985)
			(type default)
		)
		(layer "In2.Cu")
	)
	(gr_line
		(start 142.04569 -37.788342)
		(end 142.070582 -37.804598)
		(stroke
			(width 0.06985)
			(type default)
		)
		(layer "In2.Cu")
	)
	(gr_line
		(start 142.063216 -35.959796)
		(end 142.068042 -35.986974)
		(stroke
			(width 0.06985)
			(type default)
		)
		(layer "In2.Cu")
	)
	(gr_line
		(start 142.066772 -15.724886)
		(end 142.08633 -15.752826)
		(stroke
			(width 0.06985)
			(type default)
		)
		(layer "In2.Cu")
	)
	(gr_line
		(start 142.068042 -35.986974)
		(end 142.083282 -36.010596)
		(stroke
			(width 0.06985)
			(type default)
		)
		(layer "In2.Cu")
	)
	(gr_line
		(start 142.08633 -15.752826)
		(end 142.092172 -15.785846)
		(stroke
			(width 0.06985)
			(type default)
		)
		(layer "In2.Cu")
	)
	(gr_line
		(start 142.10792 -22.271228)
		(end 142.113 -22.246844)
		(stroke
			(width 0.06985)
			(type default)
		)
		(layer "In2.Cu")
	)
	(gr_line
		(start 142.108682 -22.22246)
		(end 142.113 -22.246844)
		(stroke
			(width 0.06985)
			(type default)
		)
		(layer "In2.Cu")
	)
	(gr_line
		(start 142.108682 -22.221952)
		(end 142.108682 -22.222206)
		(stroke
			(width 0.06985)
			(type default)
		)
		(layer "In2.Cu")
	)
	(gr_line
		(start 142.671546 -25.557734)
		(end 142.674848 -25.576784)
		(stroke
			(width 0.06985)
			(type default)
		)
		(layer "In2.Cu")
	)
	(gr_line
		(start 142.671546 -25.557734)
		(end 142.674848 -25.538938)
		(stroke
			(width 0.06985)
			(type default)
		)
		(layer "In2.Cu")
	)
	(gr_line
		(start 142.674848 -25.57653)
		(end 142.674848 -25.576784)
		(stroke
			(width 0.06985)
			(type default)
		)
		(layer "In2.Cu")
	)
	(gr_line
		(start 142.709392 -103.667052)
		(end 142.732252 -103.65232)
		(stroke
			(width 0.06985)
			(type default)
		)
		(layer "In2.Cu")
	)
	(gr_line
		(start 142.732252 -103.65232)
		(end 142.759176 -103.647494)
		(stroke
			(width 0.06985)
			(type default)
		)
		(layer "In2.Cu")
	)
	(gr_line
		(start 142.850362 -26.572718)
		(end 142.855188 -26.599642)
		(stroke
			(width 0.06985)
			(type default)
		)
		(layer "In2.Cu")
	)
	(gr_line
		(start 142.855188 -26.599642)
		(end 142.86992 -26.622502)
		(stroke
			(width 0.06985)
			(type default)
		)
		(layer "In2.Cu")
	)
	(gr_line
		(start 142.897352 -37.263832)
		(end 142.913608 -37.288724)
		(stroke
			(width 0.06985)
			(type default)
		)
		(layer "In2.Cu")
	)
	(gr_line
		(start 142.913608 -37.288724)
		(end 142.9385 -37.30498)
		(stroke
			(width 0.06985)
			(type default)
		)
		(layer "In2.Cu")
	)
	(gr_line
		(start 143.194278 -29.33192)
		(end 143.205708 -29.3497)
		(stroke
			(width 0.06985)
			(type default)
		)
		(layer "In2.Cu")
	)
	(gr_line
		(start 143.205708 -29.3497)
		(end 143.209772 -29.369512)
		(stroke
			(width 0.06985)
			(type default)
		)
		(layer "In2.Cu")
	)
	(gr_arc
		(start 143.293592 -222.294704)
		(mid 143.472219 -222.02737)
		(end 143.534892 -221.712028)
		(stroke
			(width 0.06985)
			(type default)
		)
		(layer "In2.Cu")
	)
	(gr_line
		(start 143.339312 -216.379298)
		(end 143.35887 -216.351358)
		(stroke
			(width 0.06985)
			(type default)
		)
		(layer "In2.Cu")
	)
	(gr_line
		(start 143.35887 -216.351358)
		(end 143.364712 -216.318338)
		(stroke
			(width 0.06985)
			(type default)
		)
		(layer "In2.Cu")
	)
	(gr_line
		(start 143.407892 -23.285704)
		(end 143.407892 -23.285958)
		(stroke
			(width 0.06985)
			(type default)
		)
		(layer "In2.Cu")
	)
	(gr_line
		(start 143.407892 -23.285704)
		(end 143.411194 -23.266908)
		(stroke
			(width 0.06985)
			(type default)
		)
		(layer "In2.Cu")
	)
	(gr_line
		(start 143.407892 -23.248112)
		(end 143.411194 -23.266908)
		(stroke
			(width 0.06985)
			(type default)
		)
		(layer "In2.Cu")
	)
	(gr_line
		(start 143.516096 -11.627104)
		(end 143.602202 -11.540998)
		(stroke
			(width 0.06985)
			(type default)
		)
		(layer "In2.Cu")
	)
	(gr_line
		(start 143.534892 -219.329508)
		(end 143.571722 -219.27693)
		(stroke
			(width 0.06985)
			(type default)
		)
		(layer "In2.Cu")
	)
	(gr_line
		(start 143.749522 -11.86053)
		(end 143.834104 -11.775948)
		(stroke
			(width 0.06985)
			(type default)
		)
		(layer "In2.Cu")
	)
	(gr_line
		(start 143.805656 -28.063444)
		(end 143.839692 -28.115768)
		(stroke
			(width 0.06985)
			(type default)
		)
		(layer "In2.Cu")
	)
	(gr_line
		(start 143.817594 -207.50403)
		(end 143.823436 -207.47101)
		(stroke
			(width 0.06985)
			(type default)
		)
		(layer "In2.Cu")
	)
	(gr_line
		(start 143.823436 -207.47101)
		(end 143.842994 -207.44307)
		(stroke
			(width 0.06985)
			(type default)
		)
		(layer "In2.Cu")
	)
	(gr_line
		(start 143.839692 -28.115768)
		(end 143.896334 -28.139644)
		(stroke
			(width 0.06985)
			(type default)
		)
		(layer "In2.Cu")
	)
	(gr_arc
		(start 143.865092 -221.712028)
		(mid 143.927773 -222.027371)
		(end 144.106392 -222.294704)
		(stroke
			(width 0.06985)
			(type default)
		)
		(layer "In2.Cu")
	)
	(gr_line
		(start 144.152366 -35.39363)
		(end 144.15643 -35.413442)
		(stroke
			(width 0.06985)
			(type default)
		)
		(layer "In2.Cu")
	)
	(gr_line
		(start 144.15643 -35.413442)
		(end 144.16786 -35.431222)
		(stroke
			(width 0.06985)
			(type default)
		)
		(layer "In2.Cu")
	)
	(gr_line
		(start 144.246346 -204.779372)
		(end 144.2466 -204.779372)
		(stroke
			(width 0.06985)
			(type default)
		)
		(layer "In2.Cu")
	)
	(gr_line
		(start 144.2466 -204.779372)
		(end 144.247108 -204.778864)
		(stroke
			(width 0.06985)
			(type default)
		)
		(layer "In2.Cu")
	)
	(gr_line
		(start 144.247108 -204.778864)
		(end 144.248378 -204.777086)
		(stroke
			(width 0.06985)
			(type default)
		)
		(layer "In2.Cu")
	)
	(gr_line
		(start 144.931384 -36.606988)
		(end 144.94764 -36.63188)
		(stroke
			(width 0.06985)
			(type default)
		)
		(layer "In2.Cu")
	)
	(gr_line
		(start 144.94764 -36.63188)
		(end 144.972532 -36.648136)
		(stroke
			(width 0.06985)
			(type default)
		)
		(layer "In2.Cu")
	)
	(gr_line
		(start 145.732246 -43.465496)
		(end 145.75155 -43.477942)
		(stroke
			(width 0.06985)
			(type default)
		)
		(layer "In2.Cu")
	)
	(gr_line
		(start 145.75155 -43.477942)
		(end 145.774156 -43.482768)
		(stroke
			(width 0.06985)
			(type default)
		)
		(layer "In2.Cu")
	)
	(gr_line
		(start 145.837402 -37.20973)
		(end 145.855182 -37.22116)
		(stroke
			(width 0.06985)
			(type default)
		)
		(layer "In2.Cu")
	)
	(gr_line
		(start 145.855182 -37.22116)
		(end 145.874994 -37.225224)
		(stroke
			(width 0.06985)
			(type default)
		)
		(layer "In2.Cu")
	)
	(gr_line
		(start 146.304254 -12.877546)
		(end 146.574764 -13.008356)
		(stroke
			(width 0.06985)
			(type default)
		)
		(layer "In2.Cu")
	)
	(gr_line
		(start 146.307302 -40.555672)
		(end 146.32559 -40.567864)
		(stroke
			(width 0.06985)
			(type default)
		)
		(layer "In2.Cu")
	)
	(gr_line
		(start 146.32559 -40.567864)
		(end 146.34718 -40.572182)
		(stroke
			(width 0.06985)
			(type default)
		)
		(layer "In2.Cu")
	)
	(gr_arc
		(start 146.384518 -13.930122)
		(mid 146.838761 -13.543344)
		(end 146.574764 -13.008356)
		(stroke
			(width 0.06985)
			(type default)
		)
		(layer "In2.Cu")
	)
	(gr_line
		(start 146.485864 -41.838626)
		(end 146.505168 -41.851072)
		(stroke
			(width 0.06985)
			(type default)
		)
		(layer "In2.Cu")
	)
	(gr_line
		(start 146.493738 -222.294704)
		(end 146.676364 -222.111824)
		(stroke
			(width 0.06985)
			(type default)
		)
		(layer "In2.Cu")
	)
	(gr_line
		(start 146.505168 -41.851072)
		(end 146.527774 -41.855898)
		(stroke
			(width 0.06985)
			(type default)
		)
		(layer "In2.Cu")
	)
	(gr_arc
		(start 146.676364 -222.111824)
		(mid 146.719741 -222.047045)
		(end 146.735038 -221.9706)
		(stroke
			(width 0.06985)
			(type default)
		)
		(layer "In2.Cu")
	)
	(gr_line
		(start 146.676364 -215.418924)
		(end 146.695922 -215.390984)
		(stroke
			(width 0.06985)
			(type default)
		)
		(layer "In2.Cu")
	)
	(gr_line
		(start 146.695922 -215.390984)
		(end 146.701764 -215.357964)
		(stroke
			(width 0.06985)
			(type default)
		)
		(layer "In2.Cu")
	)
	(gr_line
		(start 146.735038 -221.381828)
		(end 146.735038 -221.9706)
		(stroke
			(width 0.06985)
			(type default)
		)
		(layer "In2.Cu")
	)
	(gr_line
		(start 146.735038 -219.334588)
		(end 146.771106 -219.283026)
		(stroke
			(width 0.06985)
			(type default)
		)
		(layer "In2.Cu")
	)
	(gr_line
		(start 146.82724 -39.82847)
		(end 146.846544 -39.84117)
		(stroke
			(width 0.06985)
			(type default)
		)
		(layer "In2.Cu")
	)
	(gr_line
		(start 146.846544 -39.84117)
		(end 146.86915 -39.845742)
		(stroke
			(width 0.06985)
			(type default)
		)
		(layer "In2.Cu")
	)
	(gr_line
		(start 146.969988 -16.984472)
		(end 147.256754 -17.271238)
		(stroke
			(width 0.06985)
			(type default)
		)
		(layer "In2.Cu")
	)
	(gr_line
		(start 147.064984 -221.712028)
		(end 147.065238 -221.712028)
		(stroke
			(width 0.06985)
			(type default)
		)
		(layer "In2.Cu")
	)
	(gr_arc
		(start 147.064984 -221.712028)
		(mid 147.127764 -222.027412)
		(end 147.306538 -222.294704)
		(stroke
			(width 0.06985)
			(type default)
		)
		(layer "In2.Cu")
	)
	(gr_arc
		(start 147.134326 -16.330168)
		(mid 146.866785 -16.610745)
		(end 146.969988 -16.984472)
		(stroke
			(width 0.06985)
			(type default)
		)
		(layer "In2.Cu")
	)
	(gr_arc
		(start 147.258278 -17.740376)
		(mid 146.823528 -17.557277)
		(end 146.384518 -17.729962)
		(stroke
			(width 0.06985)
			(type default)
		)
		(layer "In2.Cu")
	)
	(gr_line
		(start 147.447508 -37.559488)
		(end 147.476972 -37.565838)
		(stroke
			(width 0.06985)
			(type default)
		)
		(layer "In2.Cu")
	)
	(gr_line
		(start 147.470368 -204.659992)
		(end 147.47621 -204.626972)
		(stroke
			(width 0.06985)
			(type default)
		)
		(layer "In2.Cu")
	)
	(gr_line
		(start 147.47621 -204.626972)
		(end 147.495768 -204.599032)
		(stroke
			(width 0.06985)
			(type default)
		)
		(layer "In2.Cu")
	)
	(gr_line
		(start 147.476972 -37.565838)
		(end 147.506436 -37.559488)
		(stroke
			(width 0.06985)
			(type default)
		)
		(layer "In2.Cu")
	)
	(gr_line
		(start 147.738846 -18.43405)
		(end 147.756118 -18.460974)
		(stroke
			(width 0.06985)
			(type default)
		)
		(layer "In2.Cu")
	)
	(gr_line
		(start 147.756118 -18.460974)
		(end 147.782788 -18.478246)
		(stroke
			(width 0.06985)
			(type default)
		)
		(layer "In2.Cu")
	)
	(gr_line
		(start 147.8026 -125.897894)
		(end 148.390102 -125.486668)
		(stroke
			(width 0.06985)
			(type default)
		)
		(layer "In2.Cu")
	)
	(gr_line
		(start 147.8534 -102.74935)
		(end 147.872196 -102.746048)
		(stroke
			(width 0.06985)
			(type default)
		)
		(layer "In2.Cu")
	)
	(gr_line
		(start 147.872196 -102.746048)
		(end 147.890992 -102.74935)
		(stroke
			(width 0.06985)
			(type default)
		)
		(layer "In2.Cu")
	)
	(gr_line
		(start 147.963636 -126.191518)
		(end 148.222208 -126.237238)
		(stroke
			(width 0.06985)
			(type default)
		)
		(layer "In2.Cu")
	)
	(gr_line
		(start 148.222208 -126.237238)
		(end 148.565616 -125.996954)
		(stroke
			(width 0.06985)
			(type default)
		)
		(layer "In2.Cu")
	)
	(gr_line
		(start 148.322538 -12.831826)
		(end 148.322792 -12.831572)
		(stroke
			(width 0.06985)
			(type default)
		)
		(layer "In2.Cu")
	)
	(gr_line
		(start 148.389848 -18.8722)
		(end 148.391372 -18.873216)
		(stroke
			(width 0.06985)
			(type default)
		)
		(layer "In2.Cu")
	)
	(gr_line
		(start 148.391372 -18.873216)
		(end 148.392642 -18.873724)
		(stroke
			(width 0.06985)
			(type default)
		)
		(layer "In2.Cu")
	)
	(gr_line
		(start 148.50999 -101.365304)
		(end 148.528786 -101.362002)
		(stroke
			(width 0.06985)
			(type default)
		)
		(layer "In2.Cu")
	)
	(gr_line
		(start 148.528786 -101.362002)
		(end 148.547582 -101.365304)
		(stroke
			(width 0.06985)
			(type default)
		)
		(layer "In2.Cu")
	)
	(gr_line
		(start 148.565616 -125.996954)
		(end 148.611082 -125.738382)
		(stroke
			(width 0.06985)
			(type default)
		)
		(layer "In2.Cu")
	)
	(gr_line
		(start 148.575522 -100.142294)
		(end 148.594318 -100.138992)
		(stroke
			(width 0.06985)
			(type default)
		)
		(layer "In2.Cu")
	)
	(gr_line
		(start 148.594318 -100.138992)
		(end 148.613114 -100.142294)
		(stroke
			(width 0.06985)
			(type default)
		)
		(layer "In2.Cu")
	)
	(gr_arc
		(start 148.63445 -13.930122)
		(mid 148.569698 -13.522396)
		(end 148.45538 -13.125704)
		(stroke
			(width 0.06985)
			(type default)
		)
		(layer "In2.Cu")
	)
	(gr_arc
		(start 148.75891 -17.6784)
		(mid 148.691543 -17.691791)
		(end 148.63445 -17.729962)
		(stroke
			(width 0.06985)
			(type default)
		)
		(layer "In2.Cu")
	)
	(gr_line
		(start 148.75891 -17.6784)
		(end 149.205188 -17.6784)
		(stroke
			(width 0.06985)
			(type default)
		)
		(layer "In2.Cu")
	)
	(gr_arc
		(start 148.76653 -13.015214)
		(mid 149.242349 -13.241422)
		(end 149.468332 -12.765532)
		(stroke
			(width 0.06985)
			(type default)
		)
		(layer "In2.Cu")
	)
	(gr_line
		(start 148.76653 -13.01496)
		(end 148.76653 -13.015214)
		(stroke
			(width 0.06985)
			(type default)
		)
		(layer "In2.Cu")
	)
	(gr_line
		(start 148.797264 -125.20168)
		(end 149.384258 -124.790708)
		(stroke
			(width 0.06985)
			(type default)
		)
		(layer "In2.Cu")
	)
	(gr_line
		(start 148.943568 -101.772974)
		(end 149.085808 -101.976174)
		(stroke
			(width 0.06985)
			(type default)
		)
		(layer "In2.Cu")
	)
	(gr_line
		(start 148.958046 -125.495304)
		(end 149.216618 -125.54077)
		(stroke
			(width 0.06985)
			(type default)
		)
		(layer "In2.Cu")
	)
	(gr_line
		(start 149.038056 -101.451664)
		(end 149.723602 -101.572568)
		(stroke
			(width 0.06985)
			(type default)
		)
		(layer "In2.Cu")
	)
	(gr_line
		(start 149.085808 -101.976174)
		(end 149.498558 -102.049072)
		(stroke
			(width 0.06985)
			(type default)
		)
		(layer "In2.Cu")
	)
	(gr_line
		(start 149.216618 -125.54077)
		(end 149.560026 -125.300486)
		(stroke
			(width 0.06985)
			(type default)
		)
		(layer "In2.Cu")
	)
	(gr_arc
		(start 149.219666 -16.903446)
		(mid 149.255648 -17.084338)
		(end 149.358096 -17.23771)
		(stroke
			(width 0.06985)
			(type default)
		)
		(layer "In2.Cu")
	)
	(gr_line
		(start 149.219666 -16.728186)
		(end 149.219666 -16.903446)
		(stroke
			(width 0.06985)
			(type default)
		)
		(layer "In2.Cu")
	)
	(gr_line
		(start 149.29993 -103.335582)
		(end 149.450552 -103.55072)
		(stroke
			(width 0.06985)
			(type default)
		)
		(layer "In2.Cu")
	)
	(gr_line
		(start 149.358096 -17.23771)
		(end 149.563328 -17.442688)
		(stroke
			(width 0.06985)
			(type default)
		)
		(layer "In2.Cu")
	)
	(gr_arc
		(start 149.384512 -16.330168)
		(mid 149.262494 -16.51278)
		(end 149.219666 -16.728186)
		(stroke
			(width 0.06985)
			(type default)
		)
		(layer "In2.Cu")
	)
	(gr_line
		(start 149.384512 -12.530074)
		(end 149.468332 -12.765532)
		(stroke
			(width 0.06985)
			(type default)
		)
		(layer "In2.Cu")
	)
	(gr_line
		(start 149.392894 -103.014018)
		(end 150.10003 -103.138732)
		(stroke
			(width 0.06985)
			(type default)
		)
		(layer "In2.Cu")
	)
	(gr_line
		(start 149.450552 -103.55072)
		(end 149.863302 -103.623618)
		(stroke
			(width 0.06985)
			(type default)
		)
		(layer "In2.Cu")
	)
	(gr_line
		(start 149.498558 -102.049072)
		(end 149.701758 -101.906578)
		(stroke
			(width 0.06985)
			(type default)
		)
		(layer "In2.Cu")
	)
	(gr_line
		(start 149.560026 -125.300486)
		(end 149.605746 -125.041914)
		(stroke
			(width 0.06985)
			(type default)
		)
		(layer "In2.Cu")
	)
	(gr_arc
		(start 149.69363 -222.294704)
		(mid 149.872257 -222.02737)
		(end 149.93493 -221.712028)
		(stroke
			(width 0.06985)
			(type default)
		)
		(layer "In2.Cu")
	)
	(gr_line
		(start 149.791928 -124.505212)
		(end 150.37816 -124.094748)
		(stroke
			(width 0.06985)
			(type default)
		)
		(layer "In2.Cu")
	)
	(gr_line
		(start 149.863302 -103.623618)
		(end 150.078186 -103.472996)
		(stroke
			(width 0.06985)
			(type default)
		)
		(layer "In2.Cu")
	)
	(gr_line
		(start 149.93493 -220.052392)
		(end 149.97176 -219.999814)
		(stroke
			(width 0.06985)
			(type default)
		)
		(layer "In2.Cu")
	)
	(gr_line
		(start 149.95271 -124.798836)
		(end 150.211282 -124.844556)
		(stroke
			(width 0.06985)
			(type default)
		)
		(layer "In2.Cu")
	)
	(gr_line
		(start 149.97938 -215.276938)
		(end 149.998938 -215.248998)
		(stroke
			(width 0.06985)
			(type default)
		)
		(layer "In2.Cu")
	)
	(gr_line
		(start 149.998938 -215.248998)
		(end 150.00478 -215.215978)
		(stroke
			(width 0.06985)
			(type default)
		)
		(layer "In2.Cu")
	)
	(gr_line
		(start 150.11908 -101.980238)
		(end 150.26132 -102.183438)
		(stroke
			(width 0.06985)
			(type default)
		)
		(layer "In2.Cu")
	)
	(gr_line
		(start 150.143972 -19.110706)
		(end 150.1902 -19.1262)
		(stroke
			(width 0.06985)
			(type default)
		)
		(layer "In2.Cu")
	)
	(gr_line
		(start 150.1902 -19.1262)
		(end 150.222712 -19.162522)
		(stroke
			(width 0.06985)
			(type default)
		)
		(layer "In2.Cu")
	)
	(gr_line
		(start 150.211282 -124.844556)
		(end 150.55469 -124.604018)
		(stroke
			(width 0.06985)
			(type default)
		)
		(layer "In2.Cu")
	)
	(gr_line
		(start 150.211282 -101.65842)
		(end 150.90013 -101.779832)
		(stroke
			(width 0.06985)
			(type default)
		)
		(layer "In2.Cu")
	)
	(gr_line
		(start 150.26132 -102.183438)
		(end 150.67407 -102.256336)
		(stroke
			(width 0.06985)
			(type default)
		)
		(layer "In2.Cu")
	)
	(gr_arc
		(start 150.26513 -221.712028)
		(mid 150.327813 -222.027369)
		(end 150.50643 -222.294704)
		(stroke
			(width 0.06985)
			(type default)
		)
		(layer "In2.Cu")
	)
	(gr_line
		(start 150.430484 -203.76388)
		(end 150.436326 -203.73086)
		(stroke
			(width 0.06985)
			(type default)
		)
		(layer "In2.Cu")
	)
	(gr_line
		(start 150.436326 -203.73086)
		(end 150.455884 -203.70292)
		(stroke
			(width 0.06985)
			(type default)
		)
		(layer "In2.Cu")
	)
	(gr_line
		(start 150.55469 -124.604018)
		(end 150.600156 -124.345446)
		(stroke
			(width 0.06985)
			(type default)
		)
		(layer "In2.Cu")
	)
	(gr_line
		(start 150.67407 -102.256336)
		(end 150.87727 -102.113842)
		(stroke
			(width 0.06985)
			(type default)
		)
		(layer "In2.Cu")
	)
	(gr_line
		(start 150.71471 -16.562578)
		(end 150.71852 -16.567912)
		(stroke
			(width 0.06985)
			(type default)
		)
		(layer "In2.Cu")
	)
	(gr_line
		(start 150.71852 -16.567912)
		(end 150.7236 -16.57223)
		(stroke
			(width 0.06985)
			(type default)
		)
		(layer "In2.Cu")
	)
	(gr_line
		(start 150.817072 -24.074628)
		(end 150.820374 -24.093932)
		(stroke
			(width 0.06985)
			(type default)
		)
		(layer "In2.Cu")
	)
	(gr_line
		(start 150.817072 -24.074628)
		(end 150.820374 -24.055832)
		(stroke
			(width 0.06985)
			(type default)
		)
		(layer "In2.Cu")
	)
	(gr_line
		(start 150.841964 -19.853148)
		(end 150.855934 -19.868642)
		(stroke
			(width 0.06985)
			(type default)
		)
		(layer "In2.Cu")
	)
	(gr_line
		(start 150.855934 -19.868642)
		(end 150.863554 -19.888962)
		(stroke
			(width 0.06985)
			(type default)
		)
		(layer "In2.Cu")
	)
	(gr_line
		(start 150.908512 -103.6193)
		(end 151.05888 -103.834438)
		(stroke
			(width 0.06985)
			(type default)
		)
		(layer "In2.Cu")
	)
	(gr_line
		(start 151.002238 -103.297736)
		(end 151.70912 -103.42245)
		(stroke
			(width 0.06985)
			(type default)
		)
		(layer "In2.Cu")
	)
	(gr_line
		(start 151.05888 -103.834438)
		(end 151.47163 -103.907082)
		(stroke
			(width 0.06985)
			(type default)
		)
		(layer "In2.Cu")
	)
	(gr_line
		(start 151.17445 -36.442142)
		(end 151.203914 -36.435792)
		(stroke
			(width 0.06985)
			(type default)
		)
		(layer "In2.Cu")
	)
	(gr_line
		(start 151.203914 -36.435792)
		(end 151.233378 -36.442142)
		(stroke
			(width 0.06985)
			(type default)
		)
		(layer "In2.Cu")
	)
	(gr_line
		(start 151.294592 -102.187502)
		(end 151.437086 -102.390956)
		(stroke
			(width 0.06985)
			(type default)
		)
		(layer "In2.Cu")
	)
	(gr_line
		(start 151.385778 -101.86543)
		(end 152.075896 -101.987096)
		(stroke
			(width 0.06985)
			(type default)
		)
		(layer "In2.Cu")
	)
	(gr_line
		(start 151.420322 -22.556978)
		(end 151.420322 -22.557232)
		(stroke
			(width 0.06985)
			(type default)
		)
		(layer "In2.Cu")
	)
	(gr_line
		(start 151.420322 -22.556978)
		(end 151.423624 -22.538182)
		(stroke
			(width 0.06985)
			(type default)
		)
		(layer "In2.Cu")
	)
	(gr_line
		(start 151.420322 -22.519386)
		(end 151.423624 -22.538182)
		(stroke
			(width 0.06985)
			(type default)
		)
		(layer "In2.Cu")
	)
	(gr_line
		(start 151.437086 -102.390956)
		(end 151.849836 -102.4636)
		(stroke
			(width 0.06985)
			(type default)
		)
		(layer "In2.Cu")
	)
	(gr_line
		(start 151.47163 -103.907082)
		(end 151.686768 -103.75646)
		(stroke
			(width 0.06985)
			(type default)
		)
		(layer "In2.Cu")
	)
	(gr_line
		(start 151.504396 -16.78432)
		(end 151.509476 -16.788638)
		(stroke
			(width 0.06985)
			(type default)
		)
		(layer "In2.Cu")
	)
	(gr_line
		(start 151.509476 -16.788638)
		(end 151.512778 -16.793718)
		(stroke
			(width 0.06985)
			(type default)
		)
		(layer "In2.Cu")
	)
	(gr_line
		(start 151.550878 -28.242006)
		(end 151.556466 -28.273502)
		(stroke
			(width 0.06985)
			(type default)
		)
		(layer "In2.Cu")
	)
	(gr_line
		(start 151.556466 -28.273502)
		(end 151.575008 -28.300172)
		(stroke
			(width 0.06985)
			(type default)
		)
		(layer "In2.Cu")
	)
	(gr_line
		(start 151.849836 -102.4636)
		(end 152.053036 -102.321106)
		(stroke
			(width 0.06985)
			(type default)
		)
		(layer "In2.Cu")
	)
	(gr_line
		(start 151.868378 -23.902924)
		(end 151.87168 -23.92172)
		(stroke
			(width 0.06985)
			(type default)
		)
		(layer "In2.Cu")
	)
	(gr_line
		(start 151.868378 -23.902924)
		(end 151.87168 -23.884128)
		(stroke
			(width 0.06985)
			(type default)
		)
		(layer "In2.Cu")
	)
	(gr_line
		(start 151.87168 -23.883874)
		(end 151.87168 -23.884128)
		(stroke
			(width 0.06985)
			(type default)
		)
		(layer "In2.Cu")
	)
	(gr_line
		(start 151.92502 -19.722846)
		(end 151.93645 -19.787108)
		(stroke
			(width 0.06985)
			(type default)
		)
		(layer "In2.Cu")
	)
	(gr_line
		(start 151.968962 -28.865576)
		(end 151.982932 -28.885642)
		(stroke
			(width 0.06985)
			(type default)
		)
		(layer "In2.Cu")
	)
	(gr_line
		(start 151.982932 -28.885642)
		(end 152.002744 -28.89885)
		(stroke
			(width 0.06985)
			(type default)
		)
		(layer "In2.Cu")
	)
	(gr_line
		(start 152.429972 -22.623018)
		(end 152.433274 -22.604222)
		(stroke
			(width 0.06985)
			(type default)
		)
		(layer "In2.Cu")
	)
	(gr_line
		(start 152.429972 -22.585172)
		(end 152.433274 -22.604222)
		(stroke
			(width 0.06985)
			(type default)
		)
		(layer "In2.Cu")
	)
	(gr_line
		(start 152.459182 -47.703994)
		(end 152.515062 -47.703994)
		(stroke
			(width 0.0635)
			(type default)
		)
		(layer "In2.Cu")
	)
	(gr_line
		(start 152.470358 -102.394766)
		(end 152.612852 -102.59822)
		(stroke
			(width 0.06985)
			(type default)
		)
		(layer "In2.Cu")
	)
	(gr_line
		(start 152.481026 -27.377898)
		(end 152.486868 -27.410918)
		(stroke
			(width 0.06985)
			(type default)
		)
		(layer "In2.Cu")
	)
	(gr_line
		(start 152.486868 -27.410918)
		(end 152.506426 -27.438858)
		(stroke
			(width 0.06985)
			(type default)
		)
		(layer "In2.Cu")
	)
	(gr_line
		(start 152.563322 -102.073202)
		(end 153.250392 -102.19436)
		(stroke
			(width 0.06985)
			(type default)
		)
		(layer "In2.Cu")
	)
	(gr_line
		(start 152.612852 -102.59822)
		(end 153.025602 -102.670864)
		(stroke
			(width 0.06985)
			(type default)
		)
		(layer "In2.Cu")
	)
	(gr_line
		(start 152.745948 -30.261814)
		(end 152.763728 -30.265878)
		(stroke
			(width 0.06985)
			(type default)
		)
		(layer "In2.Cu")
	)
	(gr_line
		(start 152.763728 -30.265878)
		(end 152.779476 -30.276038)
		(stroke
			(width 0.06985)
			(type default)
		)
		(layer "In2.Cu")
	)
	(gr_line
		(start 152.823418 -18.664936)
		(end 152.842976 -18.692876)
		(stroke
			(width 0.06985)
			(type default)
		)
		(layer "In2.Cu")
	)
	(gr_line
		(start 152.842976 -18.692876)
		(end 152.848818 -18.725896)
		(stroke
			(width 0.06985)
			(type default)
		)
		(layer "In2.Cu")
	)
	(gr_arc
		(start 152.893776 -222.294704)
		(mid 153.072403 -222.02737)
		(end 153.135076 -221.712028)
		(stroke
			(width 0.06985)
			(type default)
		)
		(layer "In2.Cu")
	)
	(gr_line
		(start 152.967182 -47.97044)
		(end 153.023062 -47.97044)
		(stroke
			(width 0.0635)
			(type default)
		)
		(layer "In2.Cu")
	)
	(gr_line
		(start 153.023316 -216.2175)
		(end 153.042874 -216.18956)
		(stroke
			(width 0.06985)
			(type default)
		)
		(layer "In2.Cu")
	)
	(gr_line
		(start 153.025602 -102.670864)
		(end 153.228548 -102.52837)
		(stroke
			(width 0.06985)
			(type default)
		)
		(layer "In2.Cu")
	)
	(gr_line
		(start 153.042874 -216.18956)
		(end 153.048716 -216.15654)
		(stroke
			(width 0.06985)
			(type default)
		)
		(layer "In2.Cu")
	)
	(gr_line
		(start 153.135076 -220.21038)
		(end 153.171144 -220.158818)
		(stroke
			(width 0.06985)
			(type default)
		)
		(layer "In2.Cu")
	)
	(gr_line
		(start 153.162254 -209.532474)
		(end 153.198322 -209.480912)
		(stroke
			(width 0.06985)
			(type default)
		)
		(layer "In2.Cu")
	)
	(gr_line
		(start 153.221436 -104.027224)
		(end 153.372058 -104.242362)
		(stroke
			(width 0.06985)
			(type default)
		)
		(layer "In2.Cu")
	)
	(gr_line
		(start 153.240232 -26.585926)
		(end 153.246074 -26.618946)
		(stroke
			(width 0.06985)
			(type default)
		)
		(layer "In2.Cu")
	)
	(gr_line
		(start 153.246074 -26.618946)
		(end 153.265632 -26.646886)
		(stroke
			(width 0.06985)
			(type default)
		)
		(layer "In2.Cu")
	)
	(gr_line
		(start 153.300938 -47.97044)
		(end 153.356818 -47.97044)
		(stroke
			(width 0.0635)
			(type default)
		)
		(layer "In2.Cu")
	)
	(gr_line
		(start 153.314908 -103.70566)
		(end 154.023568 -103.830628)
		(stroke
			(width 0.06985)
			(type default)
		)
		(layer "In2.Cu")
	)
	(gr_line
		(start 153.372058 -104.242362)
		(end 153.784808 -104.315006)
		(stroke
			(width 0.06985)
			(type default)
		)
		(layer "In2.Cu")
	)
	(gr_arc
		(start 153.465276 -221.712028)
		(mid 153.527956 -222.027372)
		(end 153.706576 -222.294704)
		(stroke
			(width 0.06985)
			(type default)
		)
		(layer "In2.Cu")
	)
	(gr_line
		(start 153.472896 -28.819856)
		(end 153.483818 -28.83535)
		(stroke
			(width 0.06985)
			(type default)
		)
		(layer "In2.Cu")
	)
	(gr_line
		(start 153.483818 -28.83535)
		(end 153.499312 -28.846272)
		(stroke
			(width 0.06985)
			(type default)
		)
		(layer "In2.Cu")
	)
	(gr_line
		(start 153.66111 -36.958524)
		(end 153.680922 -36.962588)
		(stroke
			(width 0.06985)
			(type default)
		)
		(layer "In2.Cu")
	)
	(gr_line
		(start 153.680922 -36.962588)
		(end 153.698702 -36.974018)
		(stroke
			(width 0.06985)
			(type default)
		)
		(layer "In2.Cu")
	)
	(gr_line
		(start 153.755344 -17.755616)
		(end 153.768298 -17.776444)
		(stroke
			(width 0.06985)
			(type default)
		)
		(layer "In2.Cu")
	)
	(gr_line
		(start 153.768298 -17.776444)
		(end 153.772616 -17.800828)
		(stroke
			(width 0.06985)
			(type default)
		)
		(layer "In2.Cu")
	)
	(gr_line
		(start 153.784808 -104.315006)
		(end 153.999946 -104.164384)
		(stroke
			(width 0.06985)
			(type default)
		)
		(layer "In2.Cu")
	)
	(gr_line
		(start 153.795222 -219.267278)
		(end 153.806144 -219.251784)
		(stroke
			(width 0.06985)
			(type default)
		)
		(layer "In2.Cu")
	)
	(gr_line
		(start 153.806144 -219.251784)
		(end 153.821638 -219.240862)
		(stroke
			(width 0.06985)
			(type default)
		)
		(layer "In2.Cu")
	)
	(gr_line
		(start 153.808938 -47.703994)
		(end 153.864818 -47.703994)
		(stroke
			(width 0.0635)
			(type default)
		)
		(layer "In2.Cu")
	)
	(gr_line
		(start 153.8478 -25.1714)
		(end 153.848054 -25.15616)
		(stroke
			(width 0.06985)
			(type default)
		)
		(layer "In2.Cu")
	)
	(gr_line
		(start 153.8478 -25.1714)
		(end 153.852372 -25.18537)
		(stroke
			(width 0.06985)
			(type default)
		)
		(layer "In2.Cu")
	)
	(gr_line
		(start 153.848054 -25.155906)
		(end 153.848054 -25.15616)
		(stroke
			(width 0.06985)
			(type default)
		)
		(layer "In2.Cu")
	)
	(gr_line
		(start 154.285696 -26.510234)
		(end 154.28849 -26.518616)
		(stroke
			(width 0.06985)
			(type default)
		)
		(layer "In2.Cu")
	)
	(gr_line
		(start 154.28849 -26.518616)
		(end 154.293824 -26.526236)
		(stroke
			(width 0.06985)
			(type default)
		)
		(layer "In2.Cu")
	)
	(gr_line
		(start 154.417268 -104.238044)
		(end 154.567636 -104.453182)
		(stroke
			(width 0.06985)
			(type default)
		)
		(layer "In2.Cu")
	)
	(gr_line
		(start 154.446732 -21.62302)
		(end 154.449526 -21.638514)
		(stroke
			(width 0.06985)
			(type default)
		)
		(layer "In2.Cu")
	)
	(gr_line
		(start 154.44724 -21.651722)
		(end 154.449526 -21.638514)
		(stroke
			(width 0.06985)
			(type default)
		)
		(layer "In2.Cu")
	)
	(gr_line
		(start 154.480768 -28.38196)
		(end 154.494484 -28.401518)
		(stroke
			(width 0.06985)
			(type default)
		)
		(layer "In2.Cu")
	)
	(gr_line
		(start 154.494484 -28.401518)
		(end 154.514296 -28.414472)
		(stroke
			(width 0.06985)
			(type default)
		)
		(layer "In2.Cu")
	)
	(gr_line
		(start 154.510232 -103.916226)
		(end 155.218384 -104.041194)
		(stroke
			(width 0.06985)
			(type default)
		)
		(layer "In2.Cu")
	)
	(gr_line
		(start 154.567636 -104.453182)
		(end 154.980386 -104.525826)
		(stroke
			(width 0.06985)
			(type default)
		)
		(layer "In2.Cu")
	)
	(gr_line
		(start 154.94508 -31.682436)
		(end 154.969972 -31.698692)
		(stroke
			(width 0.06985)
			(type default)
		)
		(layer "In2.Cu")
	)
	(gr_line
		(start 154.969972 -31.698692)
		(end 154.986228 -31.723584)
		(stroke
			(width 0.06985)
			(type default)
		)
		(layer "In2.Cu")
	)
	(gr_line
		(start 154.980386 -104.525826)
		(end 155.195524 -104.375204)
		(stroke
			(width 0.06985)
			(type default)
		)
		(layer "In2.Cu")
	)
	(gr_line
		(start 155.026868 -27.573478)
		(end 155.03779 -27.588972)
		(stroke
			(width 0.06985)
			(type default)
		)
		(layer "In2.Cu")
	)
	(gr_line
		(start 155.03779 -27.588972)
		(end 155.053284 -27.599894)
		(stroke
			(width 0.06985)
			(type default)
		)
		(layer "In2.Cu")
	)
	(gr_line
		(start 155.07843 -101.617526)
		(end 155.783788 -101.741732)
		(stroke
			(width 0.06985)
			(type default)
		)
		(layer "In2.Cu")
	)
	(gr_line
		(start 155.096718 -101.283262)
		(end 155.314904 -101.130354)
		(stroke
			(width 0.06985)
			(type default)
		)
		(layer "In2.Cu")
	)
	(gr_line
		(start 155.25369 -35.104324)
		(end 155.26004 -35.07486)
		(stroke
			(width 0.06985)
			(type default)
		)
		(layer "In2.Cu")
	)
	(gr_line
		(start 155.25369 -35.104324)
		(end 155.260294 -35.135058)
		(stroke
			(width 0.06985)
			(type default)
		)
		(layer "In2.Cu")
	)
	(gr_line
		(start 155.314904 -101.130354)
		(end 155.727654 -101.203252)
		(stroke
			(width 0.06985)
			(type default)
		)
		(layer "In2.Cu")
	)
	(gr_line
		(start 155.323286 -30.122876)
		(end 155.34513 -30.138116)
		(stroke
			(width 0.06985)
			(type default)
		)
		(layer "In2.Cu")
	)
	(gr_line
		(start 155.34513 -30.138116)
		(end 155.371292 -30.143704)
		(stroke
			(width 0.06985)
			(type default)
		)
		(layer "In2.Cu")
	)
	(gr_line
		(start 155.403296 -32.365696)
		(end 155.414726 -32.383476)
		(stroke
			(width 0.06985)
			(type default)
		)
		(layer "In2.Cu")
	)
	(gr_line
		(start 155.414726 -32.383476)
		(end 155.41879 -32.403288)
		(stroke
			(width 0.06985)
			(type default)
		)
		(layer "In2.Cu")
	)
	(gr_line
		(start 155.54325 -36.46805)
		(end 155.547568 -36.48837)
		(stroke
			(width 0.06985)
			(type default)
		)
		(layer "In2.Cu")
	)
	(gr_line
		(start 155.547568 -36.48837)
		(end 155.558998 -36.50615)
		(stroke
			(width 0.06985)
			(type default)
		)
		(layer "In2.Cu")
	)
	(gr_line
		(start 155.727654 -101.203252)
		(end 155.880308 -101.421438)
		(stroke
			(width 0.06985)
			(type default)
		)
		(layer "In2.Cu")
	)
	(gr_line
		(start 155.785566 -34.190432)
		(end 155.79217 -34.159698)
		(stroke
			(width 0.06985)
			(type default)
		)
		(layer "In2.Cu")
	)
	(gr_line
		(start 155.78582 -34.130234)
		(end 155.79217 -34.159698)
		(stroke
			(width 0.06985)
			(type default)
		)
		(layer "In2.Cu")
	)
	(gr_line
		(start 155.890214 -31.091632)
		(end 155.914598 -31.107888)
		(stroke
			(width 0.06985)
			(type default)
		)
		(layer "In2.Cu")
	)
	(gr_line
		(start 155.914598 -31.107888)
		(end 155.930854 -31.13278)
		(stroke
			(width 0.06985)
			(type default)
		)
		(layer "In2.Cu")
	)
	(gr_line
		(start 156.045662 -29.409136)
		(end 156.063442 -29.420566)
		(stroke
			(width 0.06985)
			(type default)
		)
		(layer "In2.Cu")
	)
	(gr_line
		(start 156.063442 -29.420566)
		(end 156.083254 -29.42463)
		(stroke
			(width 0.06985)
			(type default)
		)
		(layer "In2.Cu")
	)
	(gr_arc
		(start 156.093668 -222.294704)
		(mid 156.272295 -222.02737)
		(end 156.334968 -221.712028)
		(stroke
			(width 0.06985)
			(type default)
		)
		(layer "In2.Cu")
	)
	(gr_line
		(start 156.27604 -101.828854)
		(end 156.986478 -101.954076)
		(stroke
			(width 0.06985)
			(type default)
		)
		(layer "In2.Cu")
	)
	(gr_line
		(start 156.297376 -101.494844)
		(end 156.515562 -101.34219)
		(stroke
			(width 0.06985)
			(type default)
		)
		(layer "In2.Cu")
	)
	(gr_line
		(start 156.334968 -220.523054)
		(end 156.371036 -220.471492)
		(stroke
			(width 0.06985)
			(type default)
		)
		(layer "In2.Cu")
	)
	(gr_line
		(start 156.513784 -37.976048)
		(end 156.529786 -38.000686)
		(stroke
			(width 0.06985)
			(type default)
		)
		(layer "In2.Cu")
	)
	(gr_line
		(start 156.515562 -101.34219)
		(end 156.928312 -101.415088)
		(stroke
			(width 0.06985)
			(type default)
		)
		(layer "In2.Cu")
	)
	(gr_line
		(start 156.529786 -38.000686)
		(end 156.554424 -38.016688)
		(stroke
			(width 0.06985)
			(type default)
		)
		(layer "In2.Cu")
	)
	(gr_arc
		(start 156.665168 -221.712028)
		(mid 156.727848 -222.027373)
		(end 156.906468 -222.294704)
		(stroke
			(width 0.06985)
			(type default)
		)
		(layer "In2.Cu")
	)
	(gr_line
		(start 156.75483 -32.401764)
		(end 156.76626 -32.419544)
		(stroke
			(width 0.06985)
			(type default)
		)
		(layer "In2.Cu")
	)
	(gr_line
		(start 156.76626 -32.419544)
		(end 156.770324 -32.439356)
		(stroke
			(width 0.06985)
			(type default)
		)
		(layer "In2.Cu")
	)
	(gr_line
		(start 156.808678 -104.659684)
		(end 156.959046 -104.874822)
		(stroke
			(width 0.06985)
			(type default)
		)
		(layer "In2.Cu")
	)
	(gr_line
		(start 156.90215 -104.33812)
		(end 157.609286 -104.462834)
		(stroke
			(width 0.06985)
			(type default)
		)
		(layer "In2.Cu")
	)
	(gr_line
		(start 156.928312 -101.415088)
		(end 157.080966 -101.63302)
		(stroke
			(width 0.06985)
			(type default)
		)
		(layer "In2.Cu")
	)
	(gr_line
		(start 156.959046 -104.874822)
		(end 157.371796 -104.947466)
		(stroke
			(width 0.06985)
			(type default)
		)
		(layer "In2.Cu")
	)
	(gr_line
		(start 157.185106 -219.30868)
		(end 157.196028 -219.293186)
		(stroke
			(width 0.06985)
			(type default)
		)
		(layer "In2.Cu")
	)
	(gr_line
		(start 157.196028 -219.293186)
		(end 157.211522 -219.282264)
		(stroke
			(width 0.06985)
			(type default)
		)
		(layer "In2.Cu")
	)
	(gr_line
		(start 157.23235 -13.449046)
		(end 157.245812 -13.476224)
		(stroke
			(width 0.06985)
			(type default)
		)
		(layer "In2.Cu")
	)
	(gr_arc
		(start 157.268164 -13.532612)
		(mid 157.25825 -13.503918)
		(end 157.245812 -13.476224)
		(stroke
			(width 0.06985)
			(type default)
		)
		(layer "In2.Cu")
	)
	(gr_line
		(start 157.268164 -13.532612)
		(end 157.384496 -13.930122)
		(stroke
			(width 0.06985)
			(type default)
		)
		(layer "In2.Cu")
	)
	(gr_line
		(start 157.342332 -36.717732)
		(end 157.346396 -36.737544)
		(stroke
			(width 0.06985)
			(type default)
		)
		(layer "In2.Cu")
	)
	(gr_line
		(start 157.346396 -36.737544)
		(end 157.357826 -36.755324)
		(stroke
			(width 0.06985)
			(type default)
		)
		(layer "In2.Cu")
	)
	(gr_arc
		(start 157.371542 -13.03147)
		(mid 157.215467 -13.211439)
		(end 157.23235 -13.449046)
		(stroke
			(width 0.06985)
			(type default)
		)
		(layer "In2.Cu")
	)
	(gr_line
		(start 157.371542 -13.03147)
		(end 157.371796 -13.031216)
		(stroke
			(width 0.06985)
			(type default)
		)
		(layer "In2.Cu")
	)
	(gr_line
		(start 157.371796 -104.947466)
		(end 157.58668 -104.796844)
		(stroke
			(width 0.06985)
			(type default)
		)
		(layer "In2.Cu")
	)
	(gr_line
		(start 157.477968 -102.04069)
		(end 158.186374 -102.165658)
		(stroke
			(width 0.06985)
			(type default)
		)
		(layer "In2.Cu")
	)
	(gr_line
		(start 157.498034 -101.70668)
		(end 157.71622 -101.554026)
		(stroke
			(width 0.06985)
			(type default)
		)
		(layer "In2.Cu")
	)
	(gr_line
		(start 157.71622 -101.554026)
		(end 158.12897 -101.626924)
		(stroke
			(width 0.06985)
			(type default)
		)
		(layer "In2.Cu")
	)
	(gr_arc
		(start 157.789626 -13.170154)
		(mid 157.609483 -13.014123)
		(end 157.371796 -13.031216)
		(stroke
			(width 0.06985)
			(type default)
		)
		(layer "In2.Cu")
	)
	(gr_line
		(start 157.789626 -13.170154)
		(end 157.803596 -13.19784)
		(stroke
			(width 0.06985)
			(type default)
		)
		(layer "In2.Cu")
	)
	(gr_line
		(start 157.814518 -37.458396)
		(end 157.83052 -37.483034)
		(stroke
			(width 0.06985)
			(type default)
		)
		(layer "In2.Cu")
	)
	(gr_line
		(start 157.83052 -37.483034)
		(end 157.855412 -37.49929)
		(stroke
			(width 0.06985)
			(type default)
		)
		(layer "In2.Cu")
	)
	(gr_line
		(start 158.004256 -104.870504)
		(end 158.154878 -105.085642)
		(stroke
			(width 0.06985)
			(type default)
		)
		(layer "In2.Cu")
	)
	(gr_arc
		(start 158.023052 -17.530572)
		(mid 157.643464 -17.437054)
		(end 157.384496 -17.729962)
		(stroke
			(width 0.06985)
			(type default)
		)
		(layer "In2.Cu")
	)
	(gr_line
		(start 158.098744 -104.549194)
		(end 158.80588 -104.673908)
		(stroke
			(width 0.06985)
			(type default)
		)
		(layer "In2.Cu")
	)
	(gr_line
		(start 158.12897 -101.626924)
		(end 158.281624 -101.844856)
		(stroke
			(width 0.06985)
			(type default)
		)
		(layer "In2.Cu")
	)
	(gr_arc
		(start 158.134558 -16.330168)
		(mid 158.091524 -16.902079)
		(end 158.365698 -17.405858)
		(stroke
			(width 0.06985)
			(type default)
		)
		(layer "In2.Cu")
	)
	(gr_arc
		(start 158.134558 -12.530074)
		(mid 158.055376 -12.805283)
		(end 158.116524 -13.085064)
		(stroke
			(width 0.06985)
			(type default)
		)
		(layer "In2.Cu")
	)
	(gr_line
		(start 158.154878 -105.085642)
		(end 158.567628 -105.158286)
		(stroke
			(width 0.06985)
			(type default)
		)
		(layer "In2.Cu")
	)
	(gr_line
		(start 158.202884 -192.638934)
		(end 158.213806 -192.62344)
		(stroke
			(width 0.06985)
			(type default)
		)
		(layer "In2.Cu")
	)
	(gr_line
		(start 158.213806 -192.62344)
		(end 158.2293 -192.612518)
		(stroke
			(width 0.06985)
			(type default)
		)
		(layer "In2.Cu")
	)
	(gr_line
		(start 158.567628 -105.158286)
		(end 158.782512 -105.007918)
		(stroke
			(width 0.06985)
			(type default)
		)
		(layer "In2.Cu")
	)
	(gr_line
		(start 158.887668 -216.097104)
		(end 158.903162 -216.086182)
		(stroke
			(width 0.06985)
			(type default)
		)
		(layer "In2.Cu")
	)
	(gr_line
		(start 158.903162 -216.086182)
		(end 158.914084 -216.070688)
		(stroke
			(width 0.06985)
			(type default)
		)
		(layer "In2.Cu")
	)
	(gr_line
		(start 158.9405 -18.725388)
		(end 158.9532 -18.7452)
		(stroke
			(width 0.06985)
			(type default)
		)
		(layer "In2.Cu")
	)
	(gr_line
		(start 158.9532 -18.7452)
		(end 158.97225 -18.758916)
		(stroke
			(width 0.06985)
			(type default)
		)
		(layer "In2.Cu")
	)
	(gr_line
		(start 159.200088 -105.081324)
		(end 159.350456 -105.296462)
		(stroke
			(width 0.06985)
			(type default)
		)
		(layer "In2.Cu")
	)
	(gr_arc
		(start 159.29356 -222.294704)
		(mid 159.472187 -222.02737)
		(end 159.53486 -221.712028)
		(stroke
			(width 0.06985)
			(type default)
		)
		(layer "In2.Cu")
	)
	(gr_line
		(start 159.29356 -104.75976)
		(end 160.00095 -104.884474)
		(stroke
			(width 0.06985)
			(type default)
		)
		(layer "In2.Cu")
	)
	(gr_line
		(start 159.350456 -105.296462)
		(end 159.763206 -105.369106)
		(stroke
			(width 0.06985)
			(type default)
		)
		(layer "In2.Cu")
	)
	(gr_line
		(start 159.486092 -19.129502)
		(end 159.51073 -19.147282)
		(stroke
			(width 0.06985)
			(type default)
		)
		(layer "In2.Cu")
	)
	(gr_line
		(start 159.495998 -215.2396)
		(end 159.515556 -215.21166)
		(stroke
			(width 0.06985)
			(type default)
		)
		(layer "In2.Cu")
	)
	(gr_line
		(start 159.51073 -19.147282)
		(end 159.540448 -19.153378)
		(stroke
			(width 0.06985)
			(type default)
		)
		(layer "In2.Cu")
	)
	(gr_line
		(start 159.512 -208.926938)
		(end 159.548068 -208.875376)
		(stroke
			(width 0.06985)
			(type default)
		)
		(layer "In2.Cu")
	)
	(gr_line
		(start 159.515556 -215.21166)
		(end 159.521398 -215.17864)
		(stroke
			(width 0.06985)
			(type default)
		)
		(layer "In2.Cu")
	)
	(gr_line
		(start 159.53486 -220.037406)
		(end 159.570928 -219.985844)
		(stroke
			(width 0.06985)
			(type default)
		)
		(layer "In2.Cu")
	)
	(gr_line
		(start 159.763206 -105.369106)
		(end 159.97809 -105.218738)
		(stroke
			(width 0.06985)
			(type default)
		)
		(layer "In2.Cu")
	)
	(gr_arc
		(start 159.86506 -221.712028)
		(mid 159.927745 -222.027368)
		(end 160.10636 -222.294704)
		(stroke
			(width 0.06985)
			(type default)
		)
		(layer "In2.Cu")
	)
	(gr_line
		(start 159.957516 -41.43248)
		(end 159.975296 -41.44391)
		(stroke
			(width 0.06985)
			(type default)
		)
		(layer "In2.Cu")
	)
	(gr_line
		(start 159.975296 -41.44391)
		(end 159.995108 -41.447974)
		(stroke
			(width 0.06985)
			(type default)
		)
		(layer "In2.Cu")
	)
	(gr_line
		(start 160.025842 -219.335858)
		(end 160.036764 -219.320364)
		(stroke
			(width 0.06985)
			(type default)
		)
		(layer "In2.Cu")
	)
	(gr_line
		(start 160.036764 -219.320364)
		(end 160.052258 -219.309442)
		(stroke
			(width 0.06985)
			(type default)
		)
		(layer "In2.Cu")
	)
	(gr_arc
		(start 160.163256 -13.615162)
		(mid 159.776244 -13.566871)
		(end 159.634428 -13.930122)
		(stroke
			(width 0.06985)
			(type default)
		)
		(layer "In2.Cu")
	)
	(gr_arc
		(start 160.185862 -13.00734)
		(mid 160.215841 -13.157996)
		(end 160.301178 -13.285724)
		(stroke
			(width 0.06985)
			(type default)
		)
		(layer "In2.Cu")
	)
	(gr_line
		(start 160.185862 -12.949428)
		(end 160.185862 -13.00734)
		(stroke
			(width 0.06985)
			(type default)
		)
		(layer "In2.Cu")
	)
	(gr_arc
		(start 160.295082 -17.53108)
		(mid 159.90144 -17.420254)
		(end 159.634428 -17.729962)
		(stroke
			(width 0.06985)
			(type default)
		)
		(layer "In2.Cu")
	)
	(gr_arc
		(start 160.342072 -12.572492)
		(mid 160.226542 -12.745448)
		(end 160.185862 -12.949428)
		(stroke
			(width 0.06985)
			(type default)
		)
		(layer "In2.Cu")
	)
	(gr_line
		(start 160.342072 -12.572492)
		(end 160.38449 -12.530074)
		(stroke
			(width 0.06985)
			(type default)
		)
		(layer "In2.Cu")
	)
	(gr_line
		(start 160.413954 -40.523922)
		(end 160.431734 -40.535352)
		(stroke
			(width 0.06985)
			(type default)
		)
		(layer "In2.Cu")
	)
	(gr_line
		(start 160.431734 -40.535352)
		(end 160.452054 -40.53967)
		(stroke
			(width 0.06985)
			(type default)
		)
		(layer "In2.Cu")
	)
	(gr_line
		(start 160.541462 -17.310608)
		(end 160.541462 -17.310862)
		(stroke
			(width 0.06985)
			(type default)
		)
		(layer "In2.Cu")
	)
	(gr_line
		(start 160.821624 -105.367328)
		(end 160.971992 -105.582212)
		(stroke
			(width 0.06985)
			(type default)
		)
		(layer "In2.Cu")
	)
	(gr_line
		(start 160.915096 -105.045764)
		(end 161.622232 -105.170478)
		(stroke
			(width 0.06985)
			(type default)
		)
		(layer "In2.Cu")
	)
	(gr_line
		(start 160.971992 -105.582212)
		(end 161.384742 -105.65511)
		(stroke
			(width 0.06985)
			(type default)
		)
		(layer "In2.Cu")
	)
	(gr_line
		(start 161.018982 -19.117564)
		(end 161.0614 -19.1262)
		(stroke
			(width 0.06985)
			(type default)
		)
		(layer "In2.Cu")
	)
	(gr_line
		(start 161.046922 -15.296896)
		(end 161.074608 -15.305278)
		(stroke
			(width 0.06985)
			(type default)
		)
		(layer "In2.Cu")
	)
	(gr_line
		(start 161.0614 -19.1262)
		(end 161.094928 -19.15414)
		(stroke
			(width 0.06985)
			(type default)
		)
		(layer "In2.Cu")
	)
	(gr_line
		(start 161.074608 -15.305278)
		(end 161.096452 -15.32382)
		(stroke
			(width 0.06985)
			(type default)
		)
		(layer "In2.Cu")
	)
	(gr_line
		(start 161.224976 -39.686738)
		(end 161.242756 -39.698168)
		(stroke
			(width 0.06985)
			(type default)
		)
		(layer "In2.Cu")
	)
	(gr_line
		(start 161.242756 -39.698168)
		(end 161.262568 -39.702232)
		(stroke
			(width 0.06985)
			(type default)
		)
		(layer "In2.Cu")
	)
	(gr_line
		(start 161.309304 -218.429078)
		(end 161.337244 -218.40952)
		(stroke
			(width 0.06985)
			(type default)
		)
		(layer "In2.Cu")
	)
	(gr_line
		(start 161.337244 -218.40952)
		(end 161.370264 -218.403678)
		(stroke
			(width 0.06985)
			(type default)
		)
		(layer "In2.Cu")
	)
	(gr_line
		(start 161.384742 -105.65511)
		(end 161.59988 -105.504488)
		(stroke
			(width 0.06985)
			(type default)
		)
		(layer "In2.Cu")
	)
	(gr_line
		(start 161.6583 -19.623532)
		(end 161.671 -19.6342)
		(stroke
			(width 0.06985)
			(type default)
		)
		(layer "In2.Cu")
	)
	(gr_line
		(start 161.671 -19.6342)
		(end 161.679636 -19.648678)
		(stroke
			(width 0.06985)
			(type default)
		)
		(layer "In2.Cu")
	)
	(gr_line
		(start 161.693352 -24.518366)
		(end 161.699956 -24.485346)
		(stroke
			(width 0.06985)
			(type default)
		)
		(layer "In2.Cu")
	)
	(gr_line
		(start 161.693352 -24.518366)
		(end 161.70148 -24.550878)
		(stroke
			(width 0.06985)
			(type default)
		)
		(layer "In2.Cu")
	)
	(gr_line
		(start 161.731706 -216.520522)
		(end 161.7472 -216.5096)
		(stroke
			(width 0.06985)
			(type default)
		)
		(layer "In2.Cu")
	)
	(gr_line
		(start 161.7472 -216.5096)
		(end 161.758122 -216.494106)
		(stroke
			(width 0.06985)
			(type default)
		)
		(layer "In2.Cu")
	)
	(gr_line
		(start 162.15868 -20.45843)
		(end 162.16757 -20.473416)
		(stroke
			(width 0.06985)
			(type default)
		)
		(layer "In2.Cu")
	)
	(gr_line
		(start 162.16757 -20.473416)
		(end 162.170618 -20.489672)
		(stroke
			(width 0.06985)
			(type default)
		)
		(layer "In2.Cu")
	)
	(gr_line
		(start 162.205162 -39.903146)
		(end 162.235642 -39.909496)
		(stroke
			(width 0.06985)
			(type default)
		)
		(layer "In2.Cu")
	)
	(gr_line
		(start 162.214814 -26.62174)
		(end 162.21964 -26.64206)
		(stroke
			(width 0.06985)
			(type default)
		)
		(layer "In2.Cu")
	)
	(gr_line
		(start 162.21964 -26.64206)
		(end 162.231578 -26.658824)
		(stroke
			(width 0.06985)
			(type default)
		)
		(layer "In2.Cu")
	)
	(gr_line
		(start 162.235642 -39.909496)
		(end 162.265106 -39.903146)
		(stroke
			(width 0.06985)
			(type default)
		)
		(layer "In2.Cu")
	)
	(gr_line
		(start 162.48761 -22.20722)
		(end 162.492436 -22.183344)
		(stroke
			(width 0.06985)
			(type default)
		)
		(layer "In2.Cu")
	)
	(gr_line
		(start 162.487864 -22.15896)
		(end 162.492436 -22.183344)
		(stroke
			(width 0.06985)
			(type default)
		)
		(layer "In2.Cu")
	)
	(gr_line
		(start 162.582352 -139.303252)
		(end 162.597846 -139.29233)
		(stroke
			(width 0.06985)
			(type default)
		)
		(layer "In2.Cu")
	)
	(gr_line
		(start 162.597084 -27.180794)
		(end 162.60953 -27.198574)
		(stroke
			(width 0.06985)
			(type default)
		)
		(layer "In2.Cu")
	)
	(gr_line
		(start 162.597846 -139.29233)
		(end 162.608768 -139.276836)
		(stroke
			(width 0.06985)
			(type default)
		)
		(layer "In2.Cu")
	)
	(gr_line
		(start 162.60953 -27.198574)
		(end 162.627056 -27.210258)
		(stroke
			(width 0.06985)
			(type default)
		)
		(layer "In2.Cu")
	)
	(gr_line
		(start 162.732212 -16.718026)
		(end 162.733736 -16.719296)
		(stroke
			(width 0.06985)
			(type default)
		)
		(layer "In2.Cu")
	)
	(gr_line
		(start 162.733736 -16.719296)
		(end 162.735006 -16.721074)
		(stroke
			(width 0.06985)
			(type default)
		)
		(layer "In2.Cu")
	)
	(gr_line
		(start 162.875976 -19.647154)
		(end 162.922204 -19.693382)
		(stroke
			(width 0.06985)
			(type default)
		)
		(layer "In2.Cu")
	)
	(gr_line
		(start 162.922204 -19.693382)
		(end 162.933634 -19.757644)
		(stroke
			(width 0.06985)
			(type default)
		)
		(layer "In2.Cu")
	)
	(gr_line
		(start 163.420044 -15.674848)
		(end 163.435538 -15.68577)
		(stroke
			(width 0.06985)
			(type default)
		)
		(layer "In2.Cu")
	)
	(gr_line
		(start 163.435538 -15.68577)
		(end 163.44646 -15.701264)
		(stroke
			(width 0.06985)
			(type default)
		)
		(layer "In2.Cu")
	)
	(gr_line
		(start 163.567364 -25.261062)
		(end 163.573206 -25.294082)
		(stroke
			(width 0.06985)
			(type default)
		)
		(layer "In2.Cu")
	)
	(gr_line
		(start 163.573206 -25.294082)
		(end 163.592764 -25.322022)
		(stroke
			(width 0.06985)
			(type default)
		)
		(layer "In2.Cu")
	)
	(gr_line
		(start 163.577778 -39.624)
		(end 163.59759 -39.619936)
		(stroke
			(width 0.06985)
			(type default)
		)
		(layer "In2.Cu")
	)
	(gr_line
		(start 163.59759 -39.619936)
		(end 163.61537 -39.608506)
		(stroke
			(width 0.06985)
			(type default)
		)
		(layer "In2.Cu")
	)
	(gr_line
		(start 163.653216 -18.031968)
		(end 163.672774 -18.059908)
		(stroke
			(width 0.06985)
			(type default)
		)
		(layer "In2.Cu")
	)
	(gr_line
		(start 163.672774 -18.059908)
		(end 163.678616 -18.092928)
		(stroke
			(width 0.06985)
			(type default)
		)
		(layer "In2.Cu")
	)
	(gr_line
		(start 163.691824 -103.1367)
		(end 163.71062 -103.140002)
		(stroke
			(width 0.06985)
			(type default)
		)
		(layer "In2.Cu")
	)
	(gr_line
		(start 163.71062 -103.140002)
		(end 163.729416 -103.1367)
		(stroke
			(width 0.06985)
			(type default)
		)
		(layer "In2.Cu")
	)
	(gr_line
		(start 163.733988 -134.621524)
		(end 163.749482 -134.610602)
		(stroke
			(width 0.06985)
			(type default)
		)
		(layer "In2.Cu")
	)
	(gr_line
		(start 163.749482 -134.610602)
		(end 163.760404 -134.595108)
		(stroke
			(width 0.06985)
			(type default)
		)
		(layer "In2.Cu")
	)
	(gr_line
		(start 163.950396 -105.91673)
		(end 163.969192 -105.920032)
		(stroke
			(width 0.06985)
			(type default)
		)
		(layer "In2.Cu")
	)
	(gr_line
		(start 163.969192 -105.920032)
		(end 163.987988 -105.91673)
		(stroke
			(width 0.06985)
			(type default)
		)
		(layer "In2.Cu")
	)
	(gr_line
		(start 164.030914 -39.338504)
		(end 164.055806 -39.322248)
		(stroke
			(width 0.06985)
			(type default)
		)
		(layer "In2.Cu")
	)
	(gr_line
		(start 164.04971 -47.350426)
		(end 164.08019 -47.356776)
		(stroke
			(width 0.06985)
			(type default)
		)
		(layer "In2.Cu")
	)
	(gr_line
		(start 164.055806 -39.322248)
		(end 164.072062 -39.297356)
		(stroke
			(width 0.06985)
			(type default)
		)
		(layer "In2.Cu")
	)
	(gr_line
		(start 164.08019 -47.356776)
		(end 164.110162 -47.350426)
		(stroke
			(width 0.06985)
			(type default)
		)
		(layer "In2.Cu")
	)
	(gr_line
		(start 164.099748 -104.442768)
		(end 164.118544 -104.44607)
		(stroke
			(width 0.06985)
			(type default)
		)
		(layer "In2.Cu")
	)
	(gr_line
		(start 164.118544 -104.44607)
		(end 164.13734 -104.442768)
		(stroke
			(width 0.06985)
			(type default)
		)
		(layer "In2.Cu")
	)
	(gr_line
		(start 164.215318 -218.237562)
		(end 164.248338 -218.23172)
		(stroke
			(width 0.06985)
			(type default)
		)
		(layer "In2.Cu")
	)
	(gr_line
		(start 164.248338 -218.23172)
		(end 164.276278 -218.212162)
		(stroke
			(width 0.06985)
			(type default)
		)
		(layer "In2.Cu")
	)
	(gr_line
		(start 164.378386 -212.751924)
		(end 164.397944 -212.723984)
		(stroke
			(width 0.06985)
			(type default)
		)
		(layer "In2.Cu")
	)
	(gr_line
		(start 164.397944 -212.723984)
		(end 164.403786 -212.690964)
		(stroke
			(width 0.06985)
			(type default)
		)
		(layer "In2.Cu")
	)
	(gr_line
		(start 164.554916 -45.670978)
		(end 164.585396 -45.677328)
		(stroke
			(width 0.06985)
			(type default)
		)
		(layer "In2.Cu")
	)
	(gr_line
		(start 164.585396 -45.677328)
		(end 164.615368 -45.670978)
		(stroke
			(width 0.06985)
			(type default)
		)
		(layer "In2.Cu")
	)
	(gr_line
		(start 164.588444 -25.155652)
		(end 164.594286 -25.188672)
		(stroke
			(width 0.06985)
			(type default)
		)
		(layer "In2.Cu")
	)
	(gr_line
		(start 164.593778 -42.425874)
		(end 164.621718 -42.431716)
		(stroke
			(width 0.06985)
			(type default)
		)
		(layer "In2.Cu")
	)
	(gr_line
		(start 164.594286 -25.188672)
		(end 164.613844 -25.216612)
		(stroke
			(width 0.06985)
			(type default)
		)
		(layer "In2.Cu")
	)
	(gr_line
		(start 164.6047 -43.422824)
		(end 164.629084 -43.427904)
		(stroke
			(width 0.06985)
			(type default)
		)
		(layer "In2.Cu")
	)
	(gr_line
		(start 164.609526 -31.770574)
		(end 164.629338 -31.774638)
		(stroke
			(width 0.06985)
			(type default)
		)
		(layer "In2.Cu")
	)
	(gr_line
		(start 164.621718 -42.431716)
		(end 164.649658 -42.426128)
		(stroke
			(width 0.06985)
			(type default)
		)
		(layer "In2.Cu")
	)
	(gr_line
		(start 164.629084 -43.427904)
		(end 164.653214 -43.423078)
		(stroke
			(width 0.06985)
			(type default)
		)
		(layer "In2.Cu")
	)
	(gr_line
		(start 164.629338 -31.774638)
		(end 164.647118 -31.786068)
		(stroke
			(width 0.06985)
			(type default)
		)
		(layer "In2.Cu")
	)
	(gr_line
		(start 164.64026 -17.40662)
		(end 164.659818 -17.43456)
		(stroke
			(width 0.06985)
			(type default)
		)
		(layer "In2.Cu")
	)
	(gr_line
		(start 164.659818 -17.43456)
		(end 164.66566 -17.46758)
		(stroke
			(width 0.06985)
			(type default)
		)
		(layer "In2.Cu")
	)
	(gr_line
		(start 164.733478 -44.393612)
		(end 164.75964 -44.398946)
		(stroke
			(width 0.06985)
			(type default)
		)
		(layer "In2.Cu")
	)
	(gr_line
		(start 164.75964 -44.398946)
		(end 164.785548 -44.393612)
		(stroke
			(width 0.06985)
			(type default)
		)
		(layer "In2.Cu")
	)
	(gr_line
		(start 164.77488 -38.215316)
		(end 164.78631 -38.197536)
		(stroke
			(width 0.06985)
			(type default)
		)
		(layer "In2.Cu")
	)
	(gr_line
		(start 164.78631 -38.197536)
		(end 164.790374 -38.177724)
		(stroke
			(width 0.06985)
			(type default)
		)
		(layer "In2.Cu")
	)
	(gr_line
		(start 164.823394 -36.434268)
		(end 164.827966 -36.412932)
		(stroke
			(width 0.06985)
			(type default)
		)
		(layer "In2.Cu")
	)
	(gr_line
		(start 164.827966 -36.412932)
		(end 164.839904 -36.39439)
		(stroke
			(width 0.06985)
			(type default)
		)
		(layer "In2.Cu")
	)
	(gr_arc
		(start 164.893752 -222.294704)
		(mid 165.072309 -222.027351)
		(end 165.135052 -221.712028)
		(stroke
			(width 0.06985)
			(type default)
		)
		(layer "In2.Cu")
	)
	(gr_line
		(start 165.072568 -41.521126)
		(end 165.10127 -41.527222)
		(stroke
			(width 0.06985)
			(type default)
		)
		(layer "In2.Cu")
	)
	(gr_line
		(start 165.10127 -41.527222)
		(end 165.129464 -41.521126)
		(stroke
			(width 0.06985)
			(type default)
		)
		(layer "In2.Cu")
	)
	(gr_line
		(start 165.135052 -220.454728)
		(end 165.171882 -220.40215)
		(stroke
			(width 0.06985)
			(type default)
		)
		(layer "In2.Cu")
	)
	(gr_line
		(start 165.138354 -22.050756)
		(end 165.144196 -22.083776)
		(stroke
			(width 0.06985)
			(type default)
		)
		(layer "In2.Cu")
	)
	(gr_line
		(start 165.144196 -22.083776)
		(end 165.163754 -22.111716)
		(stroke
			(width 0.06985)
			(type default)
		)
		(layer "In2.Cu")
	)
	(gr_line
		(start 165.231572 -35.791648)
		(end 165.247574 -35.76701)
		(stroke
			(width 0.06985)
			(type default)
		)
		(layer "In2.Cu")
	)
	(gr_line
		(start 165.247574 -35.76701)
		(end 165.271958 -35.751262)
		(stroke
			(width 0.06985)
			(type default)
		)
		(layer "In2.Cu")
	)
	(gr_line
		(start 165.270688 -27.718512)
		(end 165.28161 -27.734006)
		(stroke
			(width 0.06985)
			(type default)
		)
		(layer "In2.Cu")
	)
	(gr_line
		(start 165.28161 -27.734006)
		(end 165.297104 -27.744928)
		(stroke
			(width 0.06985)
			(type default)
		)
		(layer "In2.Cu")
	)
	(gr_line
		(start 165.311836 -201.219562)
		(end 165.331394 -201.191622)
		(stroke
			(width 0.06985)
			(type default)
		)
		(layer "In2.Cu")
	)
	(gr_line
		(start 165.316916 -31.049722)
		(end 165.336728 -31.053786)
		(stroke
			(width 0.06985)
			(type default)
		)
		(layer "In2.Cu")
	)
	(gr_line
		(start 165.331394 -201.191622)
		(end 165.337236 -201.158602)
		(stroke
			(width 0.06985)
			(type default)
		)
		(layer "In2.Cu")
	)
	(gr_line
		(start 165.336728 -31.053786)
		(end 165.354508 -31.065216)
		(stroke
			(width 0.06985)
			(type default)
		)
		(layer "In2.Cu")
	)
	(gr_line
		(start 165.411404 -103.882698)
		(end 166.095426 -103.762048)
		(stroke
			(width 0.06985)
			(type default)
		)
		(layer "In2.Cu")
	)
	(gr_line
		(start 165.411912 -22.4663)
		(end 165.422834 -22.481794)
		(stroke
			(width 0.06985)
			(type default)
		)
		(layer "In2.Cu")
	)
	(gr_line
		(start 165.422834 -22.481794)
		(end 165.438328 -22.492716)
		(stroke
			(width 0.06985)
			(type default)
		)
		(layer "In2.Cu")
	)
	(gr_line
		(start 165.431724 -104.216962)
		(end 165.634924 -104.359202)
		(stroke
			(width 0.06985)
			(type default)
		)
		(layer "In2.Cu")
	)
	(gr_arc
		(start 165.465252 -221.712028)
		(mid 165.527973 -222.02735)
		(end 165.706552 -222.294704)
		(stroke
			(width 0.06985)
			(type default)
		)
		(layer "In2.Cu")
	)
	(gr_line
		(start 165.497764 -142.148052)
		(end 165.513258 -142.13713)
		(stroke
			(width 0.06985)
			(type default)
		)
		(layer "In2.Cu")
	)
	(gr_line
		(start 165.513258 -142.13713)
		(end 165.52418 -142.121636)
		(stroke
			(width 0.06985)
			(type default)
		)
		(layer "In2.Cu")
	)
	(gr_line
		(start 165.54069 -30.155642)
		(end 165.560502 -30.159706)
		(stroke
			(width 0.06985)
			(type default)
		)
		(layer "In2.Cu")
	)
	(gr_line
		(start 165.560502 -30.159706)
		(end 165.578282 -30.171136)
		(stroke
			(width 0.06985)
			(type default)
		)
		(layer "In2.Cu")
	)
	(gr_line
		(start 165.634924 -104.359202)
		(end 166.047674 -104.286558)
		(stroke
			(width 0.06985)
			(type default)
		)
		(layer "In2.Cu")
	)
	(gr_line
		(start 165.70198 -203.426314)
		(end 165.707822 -203.393294)
		(stroke
			(width 0.06985)
			(type default)
		)
		(layer "In2.Cu")
	)
	(gr_line
		(start 165.707822 -203.393294)
		(end 165.72738 -203.365354)
		(stroke
			(width 0.06985)
			(type default)
		)
		(layer "In2.Cu")
	)
	(gr_line
		(start 165.882574 -22.803612)
		(end 165.910514 -22.82317)
		(stroke
			(width 0.06985)
			(type default)
		)
		(layer "In2.Cu")
	)
	(gr_line
		(start 165.910514 -22.82317)
		(end 165.943534 -22.829012)
		(stroke
			(width 0.06985)
			(type default)
		)
		(layer "In2.Cu")
	)
	(gr_line
		(start 165.966902 -27.14879)
		(end 165.977824 -27.164284)
		(stroke
			(width 0.06985)
			(type default)
		)
		(layer "In2.Cu")
	)
	(gr_line
		(start 165.977824 -27.164284)
		(end 165.993318 -27.175206)
		(stroke
			(width 0.06985)
			(type default)
		)
		(layer "In2.Cu")
	)
	(gr_line
		(start 166.047674 -104.286558)
		(end 166.190168 -104.083104)
		(stroke
			(width 0.06985)
			(type default)
		)
		(layer "In2.Cu")
	)
	(gr_line
		(start 166.110412 -35.206686)
		(end 166.128192 -35.195256)
		(stroke
			(width 0.06985)
			(type default)
		)
		(layer "In2.Cu")
	)
	(gr_line
		(start 166.128192 -35.195256)
		(end 166.148004 -35.191192)
		(stroke
			(width 0.06985)
			(type default)
		)
		(layer "In2.Cu")
	)
	(gr_line
		(start 166.253922 -218.85656)
		(end 166.264844 -218.841066)
		(stroke
			(width 0.06985)
			(type default)
		)
		(layer "In2.Cu")
	)
	(gr_line
		(start 166.264844 -218.841066)
		(end 166.280338 -218.830144)
		(stroke
			(width 0.06985)
			(type default)
		)
		(layer "In2.Cu")
	)
	(gr_line
		(start 166.33317 -138.290554)
		(end 166.348664 -138.279632)
		(stroke
			(width 0.06985)
			(type default)
		)
		(layer "In2.Cu")
	)
	(gr_line
		(start 166.348664 -138.279632)
		(end 166.359586 -138.264138)
		(stroke
			(width 0.06985)
			(type default)
		)
		(layer "In2.Cu")
	)
	(gr_line
		(start 166.492428 -192.704466)
		(end 166.49827 -192.671446)
		(stroke
			(width 0.06985)
			(type default)
		)
		(layer "In2.Cu")
	)
	(gr_line
		(start 166.49827 -192.671446)
		(end 166.517828 -192.643506)
		(stroke
			(width 0.06985)
			(type default)
		)
		(layer "In2.Cu")
	)
	(gr_line
		(start 166.588948 -103.67518)
		(end 167.269414 -103.555292)
		(stroke
			(width 0.06985)
			(type default)
		)
		(layer "In2.Cu")
	)
	(gr_line
		(start 166.60749 -104.009698)
		(end 166.81069 -104.151938)
		(stroke
			(width 0.06985)
			(type default)
		)
		(layer "In2.Cu")
	)
	(gr_line
		(start 166.708836 -22.963632)
		(end 166.723822 -22.966426)
		(stroke
			(width 0.06985)
			(type default)
		)
		(layer "In2.Cu")
	)
	(gr_line
		(start 166.723822 -22.966426)
		(end 166.739316 -22.963886)
		(stroke
			(width 0.06985)
			(type default)
		)
		(layer "In2.Cu")
	)
	(gr_line
		(start 166.81069 -104.151938)
		(end 167.22344 -104.079294)
		(stroke
			(width 0.06985)
			(type default)
		)
		(layer "In2.Cu")
	)
	(gr_line
		(start 167.125396 -216.216992)
		(end 167.14089 -216.20607)
		(stroke
			(width 0.06985)
			(type default)
		)
		(layer "In2.Cu")
	)
	(gr_line
		(start 167.14089 -216.20607)
		(end 167.151812 -216.190576)
		(stroke
			(width 0.06985)
			(type default)
		)
		(layer "In2.Cu")
	)
	(gr_line
		(start 167.22344 -104.079294)
		(end 167.36568 -103.876094)
		(stroke
			(width 0.06985)
			(type default)
		)
		(layer "In2.Cu")
	)
	(gr_line
		(start 167.614854 -34.879026)
		(end 167.642794 -34.873184)
		(stroke
			(width 0.06985)
			(type default)
		)
		(layer "In2.Cu")
	)
	(gr_line
		(start 167.642794 -34.873184)
		(end 167.670734 -34.878772)
		(stroke
			(width 0.06985)
			(type default)
		)
		(layer "In2.Cu")
	)
	(gr_line
		(start 167.762936 -103.468424)
		(end 168.445688 -103.348028)
		(stroke
			(width 0.06985)
			(type default)
		)
		(layer "In2.Cu")
	)
	(gr_line
		(start 167.782748 -103.802434)
		(end 167.986202 -103.944674)
		(stroke
			(width 0.06985)
			(type default)
		)
		(layer "In2.Cu")
	)
	(gr_line
		(start 167.986202 -103.944674)
		(end 168.398952 -103.87203)
		(stroke
			(width 0.06985)
			(type default)
		)
		(layer "In2.Cu")
	)
	(gr_arc
		(start 168.093644 -222.294704)
		(mid 168.272202 -222.027351)
		(end 168.334944 -221.712028)
		(stroke
			(width 0.06985)
			(type default)
		)
		(layer "In2.Cu")
	)
	(gr_line
		(start 168.232328 -13.449046)
		(end 168.24579 -13.476224)
		(stroke
			(width 0.06985)
			(type default)
		)
		(layer "In2.Cu")
	)
	(gr_line
		(start 168.24071 -34.513774)
		(end 168.264332 -34.529014)
		(stroke
			(width 0.06985)
			(type default)
		)
		(layer "In2.Cu")
	)
	(gr_line
		(start 168.259506 -185.993024)
		(end 168.275 -185.982102)
		(stroke
			(width 0.06985)
			(type default)
		)
		(layer "In2.Cu")
	)
	(gr_line
		(start 168.264332 -34.529014)
		(end 168.291764 -34.53384)
		(stroke
			(width 0.06985)
			(type default)
		)
		(layer "In2.Cu")
	)
	(gr_arc
		(start 168.268142 -13.532612)
		(mid 168.258228 -13.503918)
		(end 168.24579 -13.476224)
		(stroke
			(width 0.06985)
			(type default)
		)
		(layer "In2.Cu")
	)
	(gr_line
		(start 168.268142 -13.532612)
		(end 168.384474 -13.930122)
		(stroke
			(width 0.06985)
			(type default)
		)
		(layer "In2.Cu")
	)
	(gr_line
		(start 168.275 -185.982102)
		(end 168.285922 -185.966608)
		(stroke
			(width 0.06985)
			(type default)
		)
		(layer "In2.Cu")
	)
	(gr_line
		(start 168.294558 -209.9945)
		(end 168.29786 -210.01355)
		(stroke
			(width 0.06985)
			(type default)
		)
		(layer "In2.Cu")
	)
	(gr_line
		(start 168.294558 -209.9945)
		(end 168.29786 -209.975704)
		(stroke
			(width 0.06985)
			(type default)
		)
		(layer "In2.Cu")
	)
	(gr_line
		(start 168.326308 -141.872716)
		(end 168.341802 -141.861794)
		(stroke
			(width 0.06985)
			(type default)
		)
		(layer "In2.Cu")
	)
	(gr_line
		(start 168.334944 -220.409262)
		(end 168.371012 -220.3577)
		(stroke
			(width 0.06985)
			(type default)
		)
		(layer "In2.Cu")
	)
	(gr_line
		(start 168.341802 -141.861794)
		(end 168.352724 -141.8463)
		(stroke
			(width 0.06985)
			(type default)
		)
		(layer "In2.Cu")
	)
	(gr_arc
		(start 168.369742 -13.027914)
		(mid 168.213893 -13.21005)
		(end 168.232328 -13.449046)
		(stroke
			(width 0.06985)
			(type default)
		)
		(layer "In2.Cu")
	)
	(gr_line
		(start 168.369742 -13.027914)
		(end 168.369996 -13.02766)
		(stroke
			(width 0.06985)
			(type default)
		)
		(layer "In2.Cu")
	)
	(gr_line
		(start 168.384474 -17.729962)
		(end 168.602406 -17.323054)
		(stroke
			(width 0.06985)
			(type default)
		)
		(layer "In2.Cu")
	)
	(gr_line
		(start 168.396158 -214.413592)
		(end 168.415716 -214.385652)
		(stroke
			(width 0.06985)
			(type default)
		)
		(layer "In2.Cu")
	)
	(gr_line
		(start 168.398952 -103.87203)
		(end 168.541446 -103.66883)
		(stroke
			(width 0.06985)
			(type default)
		)
		(layer "In2.Cu")
	)
	(gr_line
		(start 168.415716 -214.385652)
		(end 168.421558 -214.352632)
		(stroke
			(width 0.06985)
			(type default)
		)
		(layer "In2.Cu")
	)
	(gr_line
		(start 168.627298 -33.584388)
		(end 168.65092 -33.599628)
		(stroke
			(width 0.06985)
			(type default)
		)
		(layer "In2.Cu")
	)
	(gr_line
		(start 168.65092 -33.599628)
		(end 168.678098 -33.604454)
		(stroke
			(width 0.06985)
			(type default)
		)
		(layer "In2.Cu")
	)
	(gr_arc
		(start 168.665144 -221.712028)
		(mid 168.727865 -222.02735)
		(end 168.906444 -222.294704)
		(stroke
			(width 0.06985)
			(type default)
		)
		(layer "In2.Cu")
	)
	(gr_line
		(start 168.715436 -32.602424)
		(end 168.739058 -32.617664)
		(stroke
			(width 0.06985)
			(type default)
		)
		(layer "In2.Cu")
	)
	(gr_line
		(start 168.739058 -32.617664)
		(end 168.766236 -32.62249)
		(stroke
			(width 0.06985)
			(type default)
		)
		(layer "In2.Cu")
	)
	(gr_arc
		(start 168.789604 -13.170154)
		(mid 168.60957 -13.011208)
		(end 168.369996 -13.02766)
		(stroke
			(width 0.06985)
			(type default)
		)
		(layer "In2.Cu")
	)
	(gr_line
		(start 168.789604 -13.170154)
		(end 168.955466 -13.501624)
		(stroke
			(width 0.06985)
			(type default)
		)
		(layer "In2.Cu")
	)
	(gr_arc
		(start 168.80459 -17.24152)
		(mid 168.688702 -17.245619)
		(end 168.602406 -17.323054)
		(stroke
			(width 0.06985)
			(type default)
		)
		(layer "In2.Cu")
	)
	(gr_arc
		(start 168.903396 -16.761206)
		(mid 168.89278 -16.867657)
		(end 168.960546 -16.950436)
		(stroke
			(width 0.06985)
			(type default)
		)
		(layer "In2.Cu")
	)
	(gr_line
		(start 168.903396 -16.761206)
		(end 169.134536 -16.330168)
		(stroke
			(width 0.06985)
			(type default)
		)
		(layer "In2.Cu")
	)
	(gr_line
		(start 168.906698 -211.600796)
		(end 168.906698 -211.60105)
		(stroke
			(width 0.06985)
			(type default)
		)
		(layer "In2.Cu")
	)
	(gr_line
		(start 168.906698 -211.600796)
		(end 168.91 -211.582)
		(stroke
			(width 0.06985)
			(type default)
		)
		(layer "In2.Cu")
	)
	(gr_line
		(start 168.906698 -211.563204)
		(end 168.91 -211.582)
		(stroke
			(width 0.06985)
			(type default)
		)
		(layer "In2.Cu")
	)
	(gr_line
		(start 168.936162 -103.26116)
		(end 169.62247 -103.140256)
		(stroke
			(width 0.06985)
			(type default)
		)
		(layer "In2.Cu")
	)
	(gr_line
		(start 168.955466 -13.501624)
		(end 169.017442 -13.586206)
		(stroke
			(width 0.06985)
			(type default)
		)
		(layer "In2.Cu")
	)
	(gr_line
		(start 168.958514 -103.59517)
		(end 169.161968 -103.73741)
		(stroke
			(width 0.06985)
			(type default)
		)
		(layer "In2.Cu")
	)
	(gr_line
		(start 169.040048 -13.616686)
		(end 169.041064 -13.61821)
		(stroke
			(width 0.06985)
			(type default)
		)
		(layer "In2.Cu")
	)
	(gr_arc
		(start 169.134536 -12.530074)
		(mid 169.145987 -12.797499)
		(end 169.180256 -13.062966)
		(stroke
			(width 0.06985)
			(type default)
		)
		(layer "In2.Cu")
	)
	(gr_line
		(start 169.159682 -142.507208)
		(end 169.175176 -142.496286)
		(stroke
			(width 0.06985)
			(type default)
		)
		(layer "In2.Cu")
	)
	(gr_line
		(start 169.161968 -103.73741)
		(end 169.574718 -103.664766)
		(stroke
			(width 0.06985)
			(type default)
		)
		(layer "In2.Cu")
	)
	(gr_line
		(start 169.175176 -142.496286)
		(end 169.186098 -142.480792)
		(stroke
			(width 0.06985)
			(type default)
		)
		(layer "In2.Cu")
	)
	(gr_arc
		(start 169.180256 -13.062966)
		(mid 169.228268 -13.24718)
		(end 169.30624 -13.420852)
		(stroke
			(width 0.06985)
			(type default)
		)
		(layer "In2.Cu")
	)
	(gr_line
		(start 169.256202 -219.093034)
		(end 169.267124 -219.07754)
		(stroke
			(width 0.06985)
			(type default)
		)
		(layer "In2.Cu")
	)
	(gr_line
		(start 169.260774 -22.213316)
		(end 169.276268 -22.210776)
		(stroke
			(width 0.06985)
			(type default)
		)
		(layer "In2.Cu")
	)
	(gr_line
		(start 169.267124 -219.07754)
		(end 169.282618 -219.066618)
		(stroke
			(width 0.06985)
			(type default)
		)
		(layer "In2.Cu")
	)
	(gr_line
		(start 169.276268 -22.210776)
		(end 169.291254 -22.21357)
		(stroke
			(width 0.06985)
			(type default)
		)
		(layer "In2.Cu")
	)
	(gr_line
		(start 169.30624 -13.420852)
		(end 169.307256 -13.422376)
		(stroke
			(width 0.06985)
			(type default)
		)
		(layer "In2.Cu")
	)
	(gr_line
		(start 169.427398 -31.744158)
		(end 169.457624 -31.749492)
		(stroke
			(width 0.06985)
			(type default)
		)
		(layer "In2.Cu")
	)
	(gr_line
		(start 169.574718 -103.664766)
		(end 169.717212 -103.461566)
		(stroke
			(width 0.06985)
			(type default)
		)
		(layer "In2.Cu")
	)
	(gr_line
		(start 169.670984 -30.807152)
		(end 169.698924 -30.82671)
		(stroke
			(width 0.06985)
			(type default)
		)
		(layer "In2.Cu")
	)
	(gr_line
		(start 169.698924 -30.82671)
		(end 169.731944 -30.832552)
		(stroke
			(width 0.06985)
			(type default)
		)
		(layer "In2.Cu")
	)
	(gr_line
		(start 169.776394 -17.775174)
		(end 169.784522 -17.784318)
		(stroke
			(width 0.06985)
			(type default)
		)
		(layer "In2.Cu")
	)
	(gr_line
		(start 169.77995 -14.621764)
		(end 169.79773 -14.646402)
		(stroke
			(width 0.06985)
			(type default)
		)
		(layer "In2.Cu")
	)
	(gr_line
		(start 169.784522 -17.784318)
		(end 169.789602 -17.795494)
		(stroke
			(width 0.06985)
			(type default)
		)
		(layer "In2.Cu")
	)
	(gr_line
		(start 169.79773 -14.646402)
		(end 169.797984 -14.646148)
		(stroke
			(width 0.06985)
			(type default)
		)
		(layer "In2.Cu")
	)
	(gr_line
		(start 169.797984 -14.646148)
		(end 169.822622 -14.660118)
		(stroke
			(width 0.06985)
			(type default)
		)
		(layer "In2.Cu")
	)
	(gr_line
		(start 169.82186 -18.681954)
		(end 169.841672 -18.726404)
		(stroke
			(width 0.06985)
			(type default)
		)
		(layer "In2.Cu")
	)
	(gr_line
		(start 169.841672 -18.726404)
		(end 169.881042 -18.754598)
		(stroke
			(width 0.06985)
			(type default)
		)
		(layer "In2.Cu")
	)
	(gr_line
		(start 169.849292 -29.87548)
		(end 169.877232 -29.895038)
		(stroke
			(width 0.06985)
			(type default)
		)
		(layer "In2.Cu")
	)
	(gr_line
		(start 169.852086 -14.677136)
		(end 169.858944 -14.6812)
		(stroke
			(width 0.06985)
			(type default)
		)
		(layer "In2.Cu")
	)
	(gr_line
		(start 169.877232 -29.895038)
		(end 169.910252 -29.90088)
		(stroke
			(width 0.06985)
			(type default)
		)
		(layer "In2.Cu")
	)
	(gr_line
		(start 169.969688 -200.4949)
		(end 169.97553 -200.46188)
		(stroke
			(width 0.06985)
			(type default)
		)
		(layer "In2.Cu")
	)
	(gr_line
		(start 169.97553 -200.46188)
		(end 169.995088 -200.43394)
		(stroke
			(width 0.06985)
			(type default)
		)
		(layer "In2.Cu")
	)
	(gr_line
		(start 170.123612 -216.54262)
		(end 170.139106 -216.531698)
		(stroke
			(width 0.06985)
			(type default)
		)
		(layer "In2.Cu")
	)
	(gr_line
		(start 170.139106 -216.531698)
		(end 170.150028 -216.516204)
		(stroke
			(width 0.06985)
			(type default)
		)
		(layer "In2.Cu")
	)
	(gr_line
		(start 170.361102 -144.458944)
		(end 170.376596 -144.448022)
		(stroke
			(width 0.06985)
			(type default)
		)
		(layer "In2.Cu")
	)
	(gr_line
		(start 170.376596 -144.448022)
		(end 170.387518 -144.432528)
		(stroke
			(width 0.06985)
			(type default)
		)
		(layer "In2.Cu")
	)
	(gr_line
		(start 170.471084 -19.178778)
		(end 170.497246 -19.197574)
		(stroke
			(width 0.06985)
			(type default)
		)
		(layer "In2.Cu")
	)
	(gr_line
		(start 170.497246 -19.197574)
		(end 170.528996 -19.203924)
		(stroke
			(width 0.06985)
			(type default)
		)
		(layer "In2.Cu")
	)
	(gr_arc
		(start 170.676062 -13.829538)
		(mid 170.645245 -13.875691)
		(end 170.634406 -13.930122)
		(stroke
			(width 0.06985)
			(type default)
		)
		(layer "In2.Cu")
	)
	(gr_line
		(start 170.676062 -13.829538)
		(end 170.850306 -13.655294)
		(stroke
			(width 0.06985)
			(type default)
		)
		(layer "In2.Cu")
	)
	(gr_line
		(start 171.10964 -145.525236)
		(end 171.125134 -145.514314)
		(stroke
			(width 0.06985)
			(type default)
		)
		(layer "In2.Cu")
	)
	(gr_line
		(start 171.125134 -145.514314)
		(end 171.136056 -145.49882)
		(stroke
			(width 0.06985)
			(type default)
		)
		(layer "In2.Cu")
	)
	(gr_arc
		(start 171.293282 -13.655294)
		(mid 171.071794 -13.563625)
		(end 170.850306 -13.655294)
		(stroke
			(width 0.06985)
			(type default)
		)
		(layer "In2.Cu")
	)
	(gr_arc
		(start 171.29379 -222.294704)
		(mid 171.47236 -222.027354)
		(end 171.53509 -221.712028)
		(stroke
			(width 0.06985)
			(type default)
		)
		(layer "In2.Cu")
	)
	(gr_line
		(start 171.315634 -13.677646)
		(end 171.315888 -13.678154)
		(stroke
			(width 0.06985)
			(type default)
		)
		(layer "In2.Cu")
	)
	(gr_arc
		(start 171.339002 -17.593564)
		(mid 170.941649 -17.429104)
		(end 170.634406 -17.729962)
		(stroke
			(width 0.06985)
			(type default)
		)
		(layer "In2.Cu")
	)
	(gr_line
		(start 171.36491 -12.84859)
		(end 171.384468 -12.766548)
		(stroke
			(width 0.06985)
			(type default)
		)
		(layer "In2.Cu")
	)
	(gr_line
		(start 171.36491 -12.84859)
		(end 171.414694 -13.147294)
		(stroke
			(width 0.06985)
			(type default)
		)
		(layer "In2.Cu")
	)
	(gr_line
		(start 171.384468 -12.530074)
		(end 171.384468 -12.766548)
		(stroke
			(width 0.06985)
			(type default)
		)
		(layer "In2.Cu")
	)
	(gr_line
		(start 171.414694 -13.147294)
		(end 171.582842 -13.474446)
		(stroke
			(width 0.06985)
			(type default)
		)
		(layer "In2.Cu")
	)
	(gr_line
		(start 171.5008 -209.8802)
		(end 171.536868 -209.828638)
		(stroke
			(width 0.06985)
			(type default)
		)
		(layer "In2.Cu")
	)
	(gr_line
		(start 171.53509 -219.992194)
		(end 171.57192 -219.939616)
		(stroke
			(width 0.06985)
			(type default)
		)
		(layer "In2.Cu")
	)
	(gr_line
		(start 171.645326 -214.380572)
		(end 171.664884 -214.352632)
		(stroke
			(width 0.06985)
			(type default)
		)
		(layer "In2.Cu")
	)
	(gr_line
		(start 171.664884 -214.352632)
		(end 171.670726 -214.319612)
		(stroke
			(width 0.06985)
			(type default)
		)
		(layer "In2.Cu")
	)
	(gr_line
		(start 171.723304 -14.08557)
		(end 171.762674 -14.09827)
		(stroke
			(width 0.06985)
			(type default)
		)
		(layer "In2.Cu")
	)
	(gr_line
		(start 171.821348 -103.088186)
		(end 171.854368 -103.082344)
		(stroke
			(width 0.06985)
			(type default)
		)
		(layer "In2.Cu")
	)
	(gr_line
		(start 171.854368 -103.082344)
		(end 171.882308 -103.062786)
		(stroke
			(width 0.06985)
			(type default)
		)
		(layer "In2.Cu")
	)
	(gr_arc
		(start 171.86529 -221.712028)
		(mid 171.928011 -222.02735)
		(end 172.10659 -222.294704)
		(stroke
			(width 0.06985)
			(type default)
		)
		(layer "In2.Cu")
	)
	(gr_line
		(start 172.041058 -19.167602)
		(end 172.068744 -19.172936)
		(stroke
			(width 0.06985)
			(type default)
		)
		(layer "In2.Cu")
	)
	(gr_line
		(start 172.048678 -101.66985)
		(end 172.081698 -101.664008)
		(stroke
			(width 0.06985)
			(type default)
		)
		(layer "In2.Cu")
	)
	(gr_line
		(start 172.068744 -19.172936)
		(end 172.092366 -19.189446)
		(stroke
			(width 0.06985)
			(type default)
		)
		(layer "In2.Cu")
	)
	(gr_line
		(start 172.081698 -101.664008)
		(end 172.109638 -101.64445)
		(stroke
			(width 0.06985)
			(type default)
		)
		(layer "In2.Cu")
	)
	(gr_line
		(start 172.411136 -218.74099)
		(end 172.422058 -218.725496)
		(stroke
			(width 0.06985)
			(type default)
		)
		(layer "In2.Cu")
	)
	(gr_line
		(start 172.422058 -218.725496)
		(end 172.437552 -218.714574)
		(stroke
			(width 0.06985)
			(type default)
		)
		(layer "In2.Cu")
	)
	(gr_line
		(start 172.472858 -104.420924)
		(end 172.505878 -104.415082)
		(stroke
			(width 0.06985)
			(type default)
		)
		(layer "In2.Cu")
	)
	(gr_line
		(start 172.505878 -104.415082)
		(end 172.533818 -104.395524)
		(stroke
			(width 0.06985)
			(type default)
		)
		(layer "In2.Cu")
	)
	(gr_line
		(start 172.572426 -147.358354)
		(end 172.58792 -147.347432)
		(stroke
			(width 0.06985)
			(type default)
		)
		(layer "In2.Cu")
	)
	(gr_line
		(start 172.58792 -147.347432)
		(end 172.598842 -147.331938)
		(stroke
			(width 0.06985)
			(type default)
		)
		(layer "In2.Cu")
	)
	(gr_line
		(start 172.653452 -149.01545)
		(end 172.668946 -149.004528)
		(stroke
			(width 0.06985)
			(type default)
		)
		(layer "In2.Cu")
	)
	(gr_line
		(start 172.668946 -149.004528)
		(end 172.679868 -148.989034)
		(stroke
			(width 0.06985)
			(type default)
		)
		(layer "In2.Cu")
	)
	(gr_line
		(start 172.722794 -145.697956)
		(end 172.736764 -145.688304)
		(stroke
			(width 0.06985)
			(type default)
		)
		(layer "In2.Cu")
	)
	(gr_line
		(start 172.736764 -145.688304)
		(end 172.746924 -145.67408)
		(stroke
			(width 0.06985)
			(type default)
		)
		(layer "In2.Cu")
	)
	(gr_line
		(start 172.7454 -96.194372)
		(end 172.954696 -95.985076)
		(stroke
			(width 0.06985)
			(type default)
		)
		(layer "In2.Cu")
	)
	(gr_line
		(start 172.748702 -22.822916)
		(end 172.780452 -22.828504)
		(stroke
			(width 0.06985)
			(type default)
		)
		(layer "In2.Cu")
	)
	(gr_line
		(start 172.780452 -22.828504)
		(end 172.806868 -22.846792)
		(stroke
			(width 0.06985)
			(type default)
		)
		(layer "In2.Cu")
	)
	(gr_line
		(start 173.0248 -94.801182)
		(end 173.060868 -94.74962)
		(stroke
			(width 0.06985)
			(type default)
		)
		(layer "In2.Cu")
	)
	(gr_line
		(start 173.084744 -20.287742)
		(end 173.112176 -20.307046)
		(stroke
			(width 0.06985)
			(type default)
		)
		(layer "In2.Cu")
	)
	(gr_line
		(start 173.112176 -20.307046)
		(end 173.14418 -20.312634)
		(stroke
			(width 0.06985)
			(type default)
		)
		(layer "In2.Cu")
	)
	(gr_line
		(start 173.425104 -95.985076)
		(end 173.6344 -96.194372)
		(stroke
			(width 0.06985)
			(type default)
		)
		(layer "In2.Cu")
	)
	(gr_line
		(start 173.509686 -216.510362)
		(end 173.52518 -216.49944)
		(stroke
			(width 0.06985)
			(type default)
		)
		(layer "In2.Cu")
	)
	(gr_line
		(start 173.52518 -216.49944)
		(end 173.536102 -216.483946)
		(stroke
			(width 0.06985)
			(type default)
		)
		(layer "In2.Cu")
	)
	(gr_line
		(start 173.630844 -106.667808)
		(end 173.646338 -106.656886)
		(stroke
			(width 0.06985)
			(type default)
		)
		(layer "In2.Cu")
	)
	(gr_line
		(start 173.646338 -106.656886)
		(end 173.65726 -106.641392)
		(stroke
			(width 0.06985)
			(type default)
		)
		(layer "In2.Cu")
	)
	(gr_line
		(start 173.686978 -20.426426)
		(end 173.716442 -20.432776)
		(stroke
			(width 0.06985)
			(type default)
		)
		(layer "In2.Cu")
	)
	(gr_line
		(start 173.716442 -20.432776)
		(end 173.745906 -20.426426)
		(stroke
			(width 0.06985)
			(type default)
		)
		(layer "In2.Cu")
	)
	(gr_line
		(start 173.8884 -108.036106)
		(end 173.903894 -108.025184)
		(stroke
			(width 0.06985)
			(type default)
		)
		(layer "In2.Cu")
	)
	(gr_line
		(start 173.903894 -108.025184)
		(end 173.914816 -108.00969)
		(stroke
			(width 0.06985)
			(type default)
		)
		(layer "In2.Cu")
	)
	(gr_line
		(start 174.003462 -93.402912)
		(end 174.014384 -93.387418)
		(stroke
			(width 0.06985)
			(type default)
		)
		(layer "In2.Cu")
	)
	(gr_line
		(start 174.014384 -93.387418)
		(end 174.029878 -93.376496)
		(stroke
			(width 0.06985)
			(type default)
		)
		(layer "In2.Cu")
	)
	(gr_line
		(start 174.413418 -100.031296)
		(end 174.428912 -100.020374)
		(stroke
			(width 0.06985)
			(type default)
		)
		(layer "In2.Cu")
	)
	(gr_line
		(start 174.428912 -100.020374)
		(end 174.439834 -100.00488)
		(stroke
			(width 0.06985)
			(type default)
		)
		(layer "In2.Cu")
	)
	(gr_arc
		(start 174.493682 -222.294704)
		(mid 174.672253 -222.027354)
		(end 174.734982 -221.712028)
		(stroke
			(width 0.06985)
			(type default)
		)
		(layer "In2.Cu")
	)
	(gr_line
		(start 174.605442 -206.02194)
		(end 174.625 -205.994)
		(stroke
			(width 0.06985)
			(type default)
		)
		(layer "In2.Cu")
	)
	(gr_line
		(start 174.625 -205.994)
		(end 174.630842 -205.96098)
		(stroke
			(width 0.06985)
			(type default)
		)
		(layer "In2.Cu")
	)
	(gr_line
		(start 174.7266 -209.859118)
		(end 174.762668 -209.807556)
		(stroke
			(width 0.06985)
			(type default)
		)
		(layer "In2.Cu")
	)
	(gr_line
		(start 174.734982 -219.870528)
		(end 174.771812 -219.81795)
		(stroke
			(width 0.06985)
			(type default)
		)
		(layer "In2.Cu")
	)
	(gr_line
		(start 174.789592 -148.598636)
		(end 174.805086 -148.587714)
		(stroke
			(width 0.06985)
			(type default)
		)
		(layer "In2.Cu")
	)
	(gr_line
		(start 174.805086 -148.587714)
		(end 174.816008 -148.57222)
		(stroke
			(width 0.06985)
			(type default)
		)
		(layer "In2.Cu")
	)
	(gr_line
		(start 174.842932 -214.617554)
		(end 174.86249 -214.589614)
		(stroke
			(width 0.06985)
			(type default)
		)
		(layer "In2.Cu")
	)
	(gr_line
		(start 174.86249 -214.589614)
		(end 174.868332 -214.556594)
		(stroke
			(width 0.06985)
			(type default)
		)
		(layer "In2.Cu")
	)
	(gr_line
		(start 174.914052 -18.627344)
		(end 174.943516 -18.633694)
		(stroke
			(width 0.06985)
			(type default)
		)
		(layer "In2.Cu")
	)
	(gr_line
		(start 174.943516 -18.633694)
		(end 174.97298 -18.627344)
		(stroke
			(width 0.06985)
			(type default)
		)
		(layer "In2.Cu")
	)
	(gr_arc
		(start 175.065182 -221.712028)
		(mid 175.127903 -222.02735)
		(end 175.306482 -222.294704)
		(stroke
			(width 0.06985)
			(type default)
		)
		(layer "In2.Cu")
	)
	(gr_line
		(start 175.247046 -100.706936)
		(end 175.26254 -100.696014)
		(stroke
			(width 0.06985)
			(type default)
		)
		(layer "In2.Cu")
	)
	(gr_line
		(start 175.26254 -100.696014)
		(end 175.273462 -100.68052)
		(stroke
			(width 0.06985)
			(type default)
		)
		(layer "In2.Cu")
	)
	(gr_line
		(start 175.324008 -102.441502)
		(end 175.339502 -102.43058)
		(stroke
			(width 0.06985)
			(type default)
		)
		(layer "In2.Cu")
	)
	(gr_line
		(start 175.339502 -102.43058)
		(end 175.350424 -102.415086)
		(stroke
			(width 0.06985)
			(type default)
		)
		(layer "In2.Cu")
	)
	(gr_line
		(start 175.761904 -216.79027)
		(end 175.777398 -216.779348)
		(stroke
			(width 0.06985)
			(type default)
		)
		(layer "In2.Cu")
	)
	(gr_line
		(start 176.026318 -151.455374)
		(end 176.041812 -151.444452)
		(stroke
			(width 0.06985)
			(type default)
		)
		(layer "In2.Cu")
	)
	(gr_line
		(start 176.041812 -151.444452)
		(end 176.052734 -151.428958)
		(stroke
			(width 0.06985)
			(type default)
		)
		(layer "In2.Cu")
	)
	(gr_line
		(start 176.51984 -148.84908)
		(end 176.535334 -148.838158)
		(stroke
			(width 0.06985)
			(type default)
		)
		(layer "In2.Cu")
	)
	(gr_line
		(start 176.535334 -148.838158)
		(end 176.546256 -148.822664)
		(stroke
			(width 0.06985)
			(type default)
		)
		(layer "In2.Cu")
	)
	(gr_line
		(start 176.592992 -192.92951)
		(end 176.598834 -192.89649)
		(stroke
			(width 0.06985)
			(type default)
		)
		(layer "In2.Cu")
	)
	(gr_line
		(start 176.598834 -192.89649)
		(end 176.618392 -192.86855)
		(stroke
			(width 0.06985)
			(type default)
		)
		(layer "In2.Cu")
	)
	(gr_line
		(start 176.705768 -15.68069)
		(end 176.746408 -15.693644)
		(stroke
			(width 0.06985)
			(type default)
		)
		(layer "In2.Cu")
	)
	(gr_line
		(start 176.746408 -15.693644)
		(end 176.788318 -15.686278)
		(stroke
			(width 0.06985)
			(type default)
		)
		(layer "In2.Cu")
	)
	(gr_line
		(start 176.856136 -152.86863)
		(end 176.87163 -152.857708)
		(stroke
			(width 0.06985)
			(type default)
		)
		(layer "In2.Cu")
	)
	(gr_line
		(start 176.87163 -152.857708)
		(end 176.882552 -152.842214)
		(stroke
			(width 0.06985)
			(type default)
		)
		(layer "In2.Cu")
	)
	(gr_line
		(start 176.973738 -47.119286)
		(end 177.163476 -47.309024)
		(stroke
			(width 0.0635)
			(type default)
		)
		(layer "In2.Cu")
	)
	(gr_line
		(start 176.973738 -46.397164)
		(end 177.163476 -46.207426)
		(stroke
			(width 0.0635)
			(type default)
		)
		(layer "In2.Cu")
	)
	(gr_line
		(start 177.20691 -16.840708)
		(end 177.23739 -16.847058)
		(stroke
			(width 0.06985)
			(type default)
		)
		(layer "In2.Cu")
	)
	(gr_line
		(start 177.23739 -16.847058)
		(end 177.26787 -16.840708)
		(stroke
			(width 0.06985)
			(type default)
		)
		(layer "In2.Cu")
	)
	(gr_arc
		(start 177.5968 -220.6752)
		(mid 177.775906 -220.362847)
		(end 177.8381 -220.008196)
		(stroke
			(width 0.06985)
			(type default)
		)
		(layer "In2.Cu")
	)
	(gr_line
		(start 177.8381 -218.49969)
		(end 177.87493 -218.447112)
		(stroke
			(width 0.06985)
			(type default)
		)
		(layer "In2.Cu")
	)
	(gr_arc
		(start 178.1683 -220.092524)
		(mid 178.231021 -220.407846)
		(end 178.4096 -220.6752)
		(stroke
			(width 0.06985)
			(type default)
		)
		(layer "In2.Cu")
	)
	(gr_line
		(start 178.386486 -217.716354)
		(end 178.397408 -217.70086)
		(stroke
			(width 0.06985)
			(type default)
		)
		(layer "In2.Cu")
	)
	(gr_line
		(start 178.397408 -217.70086)
		(end 178.412902 -217.689938)
		(stroke
			(width 0.06985)
			(type default)
		)
		(layer "In2.Cu")
	)
	(gr_line
		(start 178.590448 -153.33091)
		(end 178.605942 -153.319988)
		(stroke
			(width 0.06985)
			(type default)
		)
		(layer "In2.Cu")
	)
	(gr_line
		(start 178.605942 -153.319988)
		(end 178.616864 -153.304494)
		(stroke
			(width 0.06985)
			(type default)
		)
		(layer "In2.Cu")
	)
	(gr_line
		(start 179.151026 -36.524184)
		(end 179.175664 -36.529264)
		(stroke
			(width 0.06985)
			(type default)
		)
		(layer "In2.Cu")
	)
	(gr_line
		(start 179.151026 -35.52698)
		(end 179.175664 -35.53206)
		(stroke
			(width 0.06985)
			(type default)
		)
		(layer "In2.Cu")
	)
	(gr_line
		(start 179.151026 -34.529522)
		(end 179.175664 -34.534602)
		(stroke
			(width 0.06985)
			(type default)
		)
		(layer "In2.Cu")
	)
	(gr_line
		(start 179.162202 -31.532322)
		(end 179.180998 -31.535624)
		(stroke
			(width 0.06985)
			(type default)
		)
		(layer "In2.Cu")
	)
	(gr_line
		(start 179.173886 -37.51707)
		(end 179.198524 -37.52215)
		(stroke
			(width 0.06985)
			(type default)
		)
		(layer "In2.Cu")
	)
	(gr_line
		(start 179.175664 -34.534602)
		(end 179.200302 -34.529522)
		(stroke
			(width 0.06985)
			(type default)
		)
		(layer "In2.Cu")
	)
	(gr_line
		(start 179.180998 -31.535624)
		(end 179.199794 -31.532322)
		(stroke
			(width 0.06985)
			(type default)
		)
		(layer "In2.Cu")
	)
	(gr_line
		(start 179.198524 -37.52215)
		(end 179.223162 -37.51707)
		(stroke
			(width 0.06985)
			(type default)
		)
		(layer "In2.Cu")
	)
	(gr_line
		(start 179.212748 -217.129868)
		(end 179.240688 -217.11031)
		(stroke
			(width 0.06985)
			(type default)
		)
		(layer "In2.Cu")
	)
	(gr_line
		(start 179.225956 -27.652726)
		(end 179.24653 -27.666696)
		(stroke
			(width 0.06985)
			(type default)
		)
		(layer "In2.Cu")
	)
	(gr_line
		(start 179.240688 -217.11031)
		(end 179.273708 -217.104468)
		(stroke
			(width 0.06985)
			(type default)
		)
		(layer "In2.Cu")
	)
	(gr_line
		(start 179.24653 -27.666696)
		(end 179.270152 -27.671522)
		(stroke
			(width 0.06985)
			(type default)
		)
		(layer "In2.Cu")
	)
	(gr_line
		(start 179.288948 -33.506156)
		(end 179.31003 -33.509966)
		(stroke
			(width 0.06985)
			(type default)
		)
		(layer "In2.Cu")
	)
	(gr_line
		(start 179.305204 -32.520636)
		(end 179.324 -32.523938)
		(stroke
			(width 0.06985)
			(type default)
		)
		(layer "In2.Cu")
	)
	(gr_line
		(start 179.31003 -33.509966)
		(end 179.330858 -33.505648)
		(stroke
			(width 0.06985)
			(type default)
		)
		(layer "In2.Cu")
	)
	(gr_line
		(start 179.324 -32.523938)
		(end 179.342796 -32.520636)
		(stroke
			(width 0.06985)
			(type default)
		)
		(layer "In2.Cu")
	)
	(gr_line
		(start 180.872638 -17.036542)
		(end 180.897022 -17.031462)
		(stroke
			(width 0.06985)
			(type default)
		)
		(layer "In2.Cu")
	)
	(gr_line
		(start 180.897022 -17.031462)
		(end 180.92166 -17.03578)
		(stroke
			(width 0.06985)
			(type default)
		)
		(layer "In2.Cu")
	)
	(gr_line
		(start 181.02453 -88.88222)
		(end 181.039516 -88.871806)
		(stroke
			(width 0.06985)
			(type default)
		)
		(layer "In2.Cu")
	)
	(gr_line
		(start 181.039516 -88.871806)
		(end 181.050438 -88.856312)
		(stroke
			(width 0.06985)
			(type default)
		)
		(layer "In2.Cu")
	)
	(gr_line
		(start 181.11851 -15.683738)
		(end 181.142894 -15.678658)
		(stroke
			(width 0.06985)
			(type default)
		)
		(layer "In2.Cu")
	)
	(gr_line
		(start 181.142894 -15.678658)
		(end 181.167532 -15.682976)
		(stroke
			(width 0.06985)
			(type default)
		)
		(layer "In2.Cu")
	)
	(gr_line
		(start 181.362604 -216.736168)
		(end 181.3814 -216.732866)
		(stroke
			(width 0.06985)
			(type default)
		)
		(layer "In2.Cu")
	)
	(gr_line
		(start 181.3814 -216.732866)
		(end 181.400196 -216.736168)
		(stroke
			(width 0.06985)
			(type default)
		)
		(layer "In2.Cu")
	)
	(gr_line
		(start 181.407308 -28.125928)
		(end 181.436772 -28.132278)
		(stroke
			(width 0.06985)
			(type default)
		)
		(layer "In2.Cu")
	)
	(gr_line
		(start 181.436772 -28.132278)
		(end 181.467252 -28.125928)
		(stroke
			(width 0.06985)
			(type default)
		)
		(layer "In2.Cu")
	)
	(gr_line
		(start 181.455568 -43.325034)
		(end 181.485032 -43.318684)
		(stroke
			(width 0.06985)
			(type default)
		)
		(layer "In2.Cu")
	)
	(gr_line
		(start 181.485032 -43.318684)
		(end 181.515512 -43.325034)
		(stroke
			(width 0.06985)
			(type default)
		)
		(layer "In2.Cu")
	)
	(gr_line
		(start 181.739032 -14.478508)
		(end 181.757828 -14.475206)
		(stroke
			(width 0.06985)
			(type default)
		)
		(layer "In2.Cu")
	)
	(gr_line
		(start 181.757828 -14.475206)
		(end 181.776624 -14.478508)
		(stroke
			(width 0.06985)
			(type default)
		)
		(layer "In2.Cu")
	)
	(gr_line
		(start 182.273194 -18.276316)
		(end 182.302658 -18.269966)
		(stroke
			(width 0.06985)
			(type default)
		)
		(layer "In2.Cu")
	)
	(gr_line
		(start 182.302658 -18.269966)
		(end 182.332122 -18.276316)
		(stroke
			(width 0.06985)
			(type default)
		)
		(layer "In2.Cu")
	)
	(gr_line
		(start 182.315358 -41.572434)
		(end 182.344314 -41.566338)
		(stroke
			(width 0.06985)
			(type default)
		)
		(layer "In2.Cu")
	)
	(gr_line
		(start 182.324248 -37.558726)
		(end 182.352188 -37.552884)
		(stroke
			(width 0.06985)
			(type default)
		)
		(layer "In2.Cu")
	)
	(gr_line
		(start 182.326026 -39.552118)
		(end 182.350664 -39.547038)
		(stroke
			(width 0.06985)
			(type default)
		)
		(layer "In2.Cu")
	)
	(gr_line
		(start 182.326026 -38.55466)
		(end 182.350664 -38.54958)
		(stroke
			(width 0.06985)
			(type default)
		)
		(layer "In2.Cu")
	)
	(gr_line
		(start 182.326026 -35.56254)
		(end 182.350664 -35.55746)
		(stroke
			(width 0.06985)
			(type default)
		)
		(layer "In2.Cu")
	)
	(gr_line
		(start 182.326026 -34.565336)
		(end 182.350664 -34.560256)
		(stroke
			(width 0.06985)
			(type default)
		)
		(layer "In2.Cu")
	)
	(gr_line
		(start 182.326534 -40.549322)
		(end 182.350664 -40.544496)
		(stroke
			(width 0.06985)
			(type default)
		)
		(layer "In2.Cu")
	)
	(gr_line
		(start 182.344314 -41.566338)
		(end 182.373016 -41.572434)
		(stroke
			(width 0.06985)
			(type default)
		)
		(layer "In2.Cu")
	)
	(gr_line
		(start 182.350664 -40.544496)
		(end 182.375048 -40.549322)
		(stroke
			(width 0.06985)
			(type default)
		)
		(layer "In2.Cu")
	)
	(gr_line
		(start 182.350664 -39.547038)
		(end 182.375302 -39.552118)
		(stroke
			(width 0.06985)
			(type default)
		)
		(layer "In2.Cu")
	)
	(gr_line
		(start 182.350664 -38.54958)
		(end 182.375302 -38.55466)
		(stroke
			(width 0.06985)
			(type default)
		)
		(layer "In2.Cu")
	)
	(gr_line
		(start 182.350664 -36.554918)
		(end 182.374794 -36.559744)
		(stroke
			(width 0.06985)
			(type default)
		)
		(layer "In2.Cu")
	)
	(gr_line
		(start 182.350664 -35.55746)
		(end 182.375302 -35.56254)
		(stroke
			(width 0.06985)
			(type default)
		)
		(layer "In2.Cu")
	)
	(gr_line
		(start 182.350664 -34.560256)
		(end 182.374794 -34.565082)
		(stroke
			(width 0.06985)
			(type default)
		)
		(layer "In2.Cu")
	)
	(gr_line
		(start 182.352188 -37.552884)
		(end 182.380128 -37.558472)
		(stroke
			(width 0.06985)
			(type default)
		)
		(layer "In2.Cu")
	)
	(gr_line
		(start 182.473346 -33.538414)
		(end 182.501286 -33.532826)
		(stroke
			(width 0.06985)
			(type default)
		)
		(layer "In2.Cu")
	)
	(gr_line
		(start 182.490872 -27.570176)
		(end 182.515256 -27.565096)
		(stroke
			(width 0.06985)
			(type default)
		)
		(layer "In2.Cu")
	)
	(gr_line
		(start 182.501286 -33.532826)
		(end 182.528972 -33.538668)
		(stroke
			(width 0.06985)
			(type default)
		)
		(layer "In2.Cu")
	)
	(gr_line
		(start 182.515256 -27.565096)
		(end 182.539894 -27.569414)
		(stroke
			(width 0.06985)
			(type default)
		)
		(layer "In2.Cu")
	)
	(gr_line
		(start 182.569104 -30.602428)
		(end 182.593742 -30.59811)
		(stroke
			(width 0.06985)
			(type default)
		)
		(layer "In2.Cu")
	)
	(gr_line
		(start 182.590694 -32.517334)
		(end 182.614824 -32.512508)
		(stroke
			(width 0.06985)
			(type default)
		)
		(layer "In2.Cu")
	)
	(gr_line
		(start 182.593742 -30.59811)
		(end 182.618126 -30.60319)
		(stroke
			(width 0.06985)
			(type default)
		)
		(layer "In2.Cu")
	)
	(gr_line
		(start 182.614824 -32.512508)
		(end 182.639208 -32.517588)
		(stroke
			(width 0.06985)
			(type default)
		)
		(layer "In2.Cu")
	)
	(gr_line
		(start 182.847996 -31.566866)
		(end 182.872634 -31.562548)
		(stroke
			(width 0.06985)
			(type default)
		)
		(layer "In2.Cu")
	)
	(gr_line
		(start 182.872634 -31.562548)
		(end 182.897018 -31.567628)
		(stroke
			(width 0.06985)
			(type default)
		)
		(layer "In2.Cu")
	)
	(gr_line
		(start 183.127396 -35.052508)
		(end 183.147716 -35.056572)
		(stroke
			(width 0.06985)
			(type default)
		)
		(layer "In2.Cu")
	)
	(gr_line
		(start 183.147716 -35.056572)
		(end 183.168798 -35.052762)
		(stroke
			(width 0.06985)
			(type default)
		)
		(layer "In2.Cu")
	)
	(gr_line
		(start 183.212994 -34.02203)
		(end 183.237378 -34.02711)
		(stroke
			(width 0.06985)
			(type default)
		)
		(layer "In2.Cu")
	)
	(gr_line
		(start 183.23052 -36.070032)
		(end 183.251348 -36.07435)
		(stroke
			(width 0.06985)
			(type default)
		)
		(layer "In2.Cu")
	)
	(gr_line
		(start 183.237378 -34.02711)
		(end 183.262016 -34.022792)
		(stroke
			(width 0.06985)
			(type default)
		)
		(layer "In2.Cu")
	)
	(gr_line
		(start 183.251348 -36.07435)
		(end 183.27243 -36.07054)
		(stroke
			(width 0.06985)
			(type default)
		)
		(layer "In2.Cu")
	)
	(gr_line
		(start 183.35117 -32.997902)
		(end 183.378856 -33.00349)
		(stroke
			(width 0.06985)
			(type default)
		)
		(layer "In2.Cu")
	)
	(gr_line
		(start 183.36133 -217.41765)
		(end 183.380126 -217.420952)
		(stroke
			(width 0.06985)
			(type default)
		)
		(layer "In2.Cu")
	)
	(gr_line
		(start 183.378856 -33.00349)
		(end 183.406542 -32.997648)
		(stroke
			(width 0.06985)
			(type default)
		)
		(layer "In2.Cu")
	)
	(gr_line
		(start 183.380126 -217.420952)
		(end 183.398922 -217.41765)
		(stroke
			(width 0.06985)
			(type default)
		)
		(layer "In2.Cu")
	)
	(gr_line
		(start 183.443626 -37.110416)
		(end 183.467756 -37.115242)
		(stroke
			(width 0.06985)
			(type default)
		)
		(layer "In2.Cu")
	)
	(gr_line
		(start 183.467756 -37.115242)
		(end 183.492394 -37.110162)
		(stroke
			(width 0.06985)
			(type default)
		)
		(layer "In2.Cu")
	)
	(gr_line
		(start 183.511952 -31.131002)
		(end 183.541416 -31.137352)
		(stroke
			(width 0.06985)
			(type default)
		)
		(layer "In2.Cu")
	)
	(gr_line
		(start 183.541416 -31.137352)
		(end 183.57088 -31.131002)
		(stroke
			(width 0.06985)
			(type default)
		)
		(layer "In2.Cu")
	)
	(gr_line
		(start 183.547512 -32.044132)
		(end 183.577992 -32.050482)
		(stroke
			(width 0.06985)
			(type default)
		)
		(layer "In2.Cu")
	)
	(gr_line
		(start 183.577992 -32.050482)
		(end 183.607456 -32.044132)
		(stroke
			(width 0.06985)
			(type default)
		)
		(layer "In2.Cu")
	)
	(gr_line
		(start 183.63057 -8.40613)
		(end 183.801766 -8.577326)
		(stroke
			(width 0.06985)
			(type default)
		)
		(layer "In2.Cu")
	)
	(gr_line
		(start 183.725566 -208.349088)
		(end 183.7436 -208.3308)
		(stroke
			(width 0.06985)
			(type default)
		)
		(layer "In2.Cu")
	)
	(gr_line
		(start 183.7309 -41.157144)
		(end 183.755538 -41.162224)
		(stroke
			(width 0.06985)
			(type default)
		)
		(layer "In2.Cu")
	)
	(gr_line
		(start 183.7436 -208.3308)
		(end 183.76773 -208.320386)
		(stroke
			(width 0.06985)
			(type default)
		)
		(layer "In2.Cu")
	)
	(gr_line
		(start 183.755538 -41.162224)
		(end 183.780176 -41.157144)
		(stroke
			(width 0.06985)
			(type default)
		)
		(layer "In2.Cu")
	)
	(gr_line
		(start 183.916574 -38.202362)
		(end 183.941212 -38.207442)
		(stroke
			(width 0.06985)
			(type default)
		)
		(layer "In2.Cu")
	)
	(gr_line
		(start 183.925464 -40.198802)
		(end 183.950102 -40.193722)
		(stroke
			(width 0.06985)
			(type default)
		)
		(layer "In2.Cu")
	)
	(gr_line
		(start 183.941212 -38.207442)
		(end 183.96585 -38.202362)
		(stroke
			(width 0.06985)
			(type default)
		)
		(layer "In2.Cu")
	)
	(gr_line
		(start 183.95569 -39.207186)
		(end 183.980328 -39.212266)
		(stroke
			(width 0.06985)
			(type default)
		)
		(layer "In2.Cu")
	)
	(gr_line
		(start 184.130442 -197.00494)
		(end 184.15 -196.977)
		(stroke
			(width 0.06985)
			(type default)
		)
		(layer "In2.Cu")
	)
	(gr_line
		(start 184.15 -196.977)
		(end 184.155842 -196.94398)
		(stroke
			(width 0.06985)
			(type default)
		)
		(layer "In2.Cu")
	)
	(gr_line
		(start 184.272174 -8.577326)
		(end 184.44337 -8.40613)
		(stroke
			(width 0.06985)
			(type default)
		)
		(layer "In2.Cu")
	)
	(gr_line
		(start 184.509918 -18.739358)
		(end 184.531 -18.743676)
		(stroke
			(width 0.06985)
			(type default)
		)
		(layer "In2.Cu")
	)
	(gr_line
		(start 184.531 -18.743676)
		(end 184.550304 -18.756122)
		(stroke
			(width 0.06985)
			(type default)
		)
		(layer "In2.Cu")
	)
	(gr_line
		(start 184.558686 -12.509754)
		(end 184.729882 -12.338558)
		(stroke
			(width 0.06985)
			(type default)
		)
		(layer "In2.Cu")
	)
	(gr_line
		(start 184.558686 -11.696954)
		(end 184.729882 -11.86815)
		(stroke
			(width 0.06985)
			(type default)
		)
		(layer "In2.Cu")
	)
	(gr_line
		(start 184.784746 -17.715992)
		(end 184.817766 -17.721834)
		(stroke
			(width 0.06985)
			(type default)
		)
		(layer "In2.Cu")
	)
	(gr_line
		(start 184.817766 -17.721834)
		(end 184.845706 -17.741392)
		(stroke
			(width 0.06985)
			(type default)
		)
		(layer "In2.Cu")
	)
	(gr_line
		(start 184.888886 -18.97634)
		(end 184.913524 -18.992342)
		(stroke
			(width 0.06985)
			(type default)
		)
		(layer "In2.Cu")
	)
	(gr_line
		(start 184.913524 -18.992342)
		(end 184.92978 -19.017234)
		(stroke
			(width 0.06985)
			(type default)
		)
		(layer "In2.Cu")
	)
	(gr_line
		(start 184.949084 -16.349472)
		(end 184.982104 -16.355314)
		(stroke
			(width 0.06985)
			(type default)
		)
		(layer "In2.Cu")
	)
	(gr_line
		(start 185.221626 -12.270994)
		(end 185.396886 -12.446254)
		(stroke
			(width 0.06985)
			(type default)
		)
		(layer "In2.Cu")
	)
	(gr_line
		(start 185.396886 -12.446254)
		(end 185.815986 -12.446254)
		(stroke
			(width 0.06985)
			(type default)
		)
		(layer "In2.Cu")
	)
	(gr_line
		(start 185.551826 -11.938254)
		(end 185.661046 -11.938254)
		(stroke
			(width 0.06985)
			(type default)
		)
		(layer "In2.Cu")
	)
	(gr_arc
		(start 185.693558 -222.294704)
		(mid 185.872185 -222.02737)
		(end 185.934858 -221.712028)
		(stroke
			(width 0.06985)
			(type default)
		)
		(layer "In2.Cu")
	)
	(gr_line
		(start 185.815986 -12.446254)
		(end 185.991246 -12.270994)
		(stroke
			(width 0.06985)
			(type default)
		)
		(layer "In2.Cu")
	)
	(gr_line
		(start 185.819288 -28.147772)
		(end 185.852308 -28.153614)
		(stroke
			(width 0.06985)
			(type default)
		)
		(layer "In2.Cu")
	)
	(gr_line
		(start 185.852308 -28.153614)
		(end 185.880248 -28.173172)
		(stroke
			(width 0.06985)
			(type default)
		)
		(layer "In2.Cu")
	)
	(gr_line
		(start 185.934858 -220.86189)
		(end 185.971688 -220.809312)
		(stroke
			(width 0.06985)
			(type default)
		)
		(layer "In2.Cu")
	)
	(gr_line
		(start 186.068208 -9.80694)
		(end 186.243468 -9.9822)
		(stroke
			(width 0.06985)
			(type default)
		)
		(layer "In2.Cu")
	)
	(gr_line
		(start 186.165236 -28.775914)
		(end 186.193176 -28.795472)
		(stroke
			(width 0.06985)
			(type default)
		)
		(layer "In2.Cu")
	)
	(gr_line
		(start 186.193176 -28.795472)
		(end 186.226196 -28.801314)
		(stroke
			(width 0.06985)
			(type default)
		)
		(layer "In2.Cu")
	)
	(gr_line
		(start 186.243468 -9.9822)
		(end 186.662568 -9.9822)
		(stroke
			(width 0.06985)
			(type default)
		)
		(layer "In2.Cu")
	)
	(gr_arc
		(start 186.265058 -221.712028)
		(mid 186.327743 -222.027368)
		(end 186.506358 -222.294704)
		(stroke
			(width 0.06985)
			(type default)
		)
		(layer "In2.Cu")
	)
	(gr_line
		(start 186.398408 -9.4742)
		(end 186.507628 -9.4742)
		(stroke
			(width 0.06985)
			(type default)
		)
		(layer "In2.Cu")
	)
	(gr_line
		(start 186.415426 -12.270994)
		(end 186.590686 -12.446254)
		(stroke
			(width 0.06985)
			(type default)
		)
		(layer "In2.Cu")
	)
	(gr_line
		(start 186.590686 -12.446254)
		(end 187.009786 -12.446254)
		(stroke
			(width 0.06985)
			(type default)
		)
		(layer "In2.Cu")
	)
	(gr_line
		(start 186.662568 -9.9822)
		(end 186.837828 -9.80694)
		(stroke
			(width 0.06985)
			(type default)
		)
		(layer "In2.Cu")
	)
	(gr_line
		(start 186.670696 -44.761404)
		(end 186.805824 -44.96943)
		(stroke
			(width 0.06985)
			(type default)
		)
		(layer "In2.Cu")
	)
	(gr_line
		(start 186.745626 -11.938254)
		(end 186.854846 -11.938254)
		(stroke
			(width 0.06985)
			(type default)
		)
		(layer "In2.Cu")
	)
	(gr_line
		(start 186.758326 -36.120578)
		(end 186.782964 -36.115498)
		(stroke
			(width 0.06985)
			(type default)
		)
		(layer "In2.Cu")
	)
	(gr_line
		(start 186.778646 -44.444412)
		(end 187.45454 -44.588176)
		(stroke
			(width 0.06985)
			(type default)
		)
		(layer "In2.Cu")
	)
	(gr_line
		(start 186.782964 -36.115498)
		(end 186.807602 -36.120578)
		(stroke
			(width 0.06985)
			(type default)
		)
		(layer "In2.Cu")
	)
	(gr_line
		(start 186.805824 -44.96943)
		(end 187.21578 -45.056552)
		(stroke
			(width 0.06985)
			(type default)
		)
		(layer "In2.Cu")
	)
	(gr_line
		(start 186.875674 -179.615592)
		(end 186.881516 -179.582572)
		(stroke
			(width 0.06985)
			(type default)
		)
		(layer "In2.Cu")
	)
	(gr_line
		(start 186.881516 -179.582572)
		(end 186.901074 -179.554632)
		(stroke
			(width 0.06985)
			(type default)
		)
		(layer "In2.Cu")
	)
	(gr_line
		(start 186.90463 -40.195754)
		(end 186.93257 -40.190166)
		(stroke
			(width 0.06985)
			(type default)
		)
		(layer "In2.Cu")
	)
	(gr_line
		(start 186.93257 -40.190166)
		(end 186.96051 -40.196008)
		(stroke
			(width 0.06985)
			(type default)
		)
		(layer "In2.Cu")
	)
	(gr_line
		(start 186.96051 -219.396818)
		(end 186.971432 -219.381324)
		(stroke
			(width 0.06985)
			(type default)
		)
		(layer "In2.Cu")
	)
	(gr_line
		(start 186.971432 -219.381324)
		(end 186.986926 -219.370402)
		(stroke
			(width 0.06985)
			(type default)
		)
		(layer "In2.Cu")
	)
	(gr_line
		(start 187.009786 -12.446254)
		(end 187.185046 -12.270994)
		(stroke
			(width 0.06985)
			(type default)
		)
		(layer "In2.Cu")
	)
	(gr_line
		(start 187.092082 -37.240972)
		(end 187.11672 -37.235892)
		(stroke
			(width 0.06985)
			(type default)
		)
		(layer "In2.Cu")
	)
	(gr_line
		(start 187.100464 -39.226998)
		(end 187.125102 -39.232078)
		(stroke
			(width 0.06985)
			(type default)
		)
		(layer "In2.Cu")
	)
	(gr_line
		(start 187.11672 -37.235892)
		(end 187.141358 -37.240972)
		(stroke
			(width 0.06985)
			(type default)
		)
		(layer "In2.Cu")
	)
	(gr_line
		(start 187.13069 -38.245542)
		(end 187.155328 -38.240462)
		(stroke
			(width 0.06985)
			(type default)
		)
		(layer "In2.Cu")
	)
	(gr_line
		(start 187.142374 -216.334848)
		(end 187.145168 -216.335864)
		(stroke
			(width 0.06985)
			(type default)
		)
		(layer "In2.Cu")
	)
	(gr_line
		(start 187.145168 -216.335864)
		(end 187.157614 -216.327228)
		(stroke
			(width 0.06985)
			(type default)
		)
		(layer "In2.Cu")
	)
	(gr_line
		(start 187.155328 -38.240462)
		(end 187.179966 -38.245542)
		(stroke
			(width 0.06985)
			(type default)
		)
		(layer "In2.Cu")
	)
	(gr_line
		(start 187.21578 -45.056552)
		(end 187.423806 -44.921424)
		(stroke
			(width 0.06985)
			(type default)
		)
		(layer "In2.Cu")
	)
	(gr_line
		(start 187.262008 -9.80694)
		(end 187.437268 -9.9822)
		(stroke
			(width 0.06985)
			(type default)
		)
		(layer "In2.Cu")
	)
	(gr_line
		(start 187.308744 -35.023806)
		(end 187.329826 -35.019996)
		(stroke
			(width 0.06985)
			(type default)
		)
		(layer "In2.Cu")
	)
	(gr_line
		(start 187.329826 -35.019996)
		(end 187.350654 -35.024314)
		(stroke
			(width 0.06985)
			(type default)
		)
		(layer "In2.Cu")
	)
	(gr_line
		(start 187.372244 -32.962342)
		(end 187.39104 -32.95904)
		(stroke
			(width 0.06985)
			(type default)
		)
		(layer "In2.Cu")
	)
	(gr_line
		(start 187.39104 -32.95904)
		(end 187.409836 -32.962342)
		(stroke
			(width 0.06985)
			(type default)
		)
		(layer "In2.Cu")
	)
	(gr_line
		(start 187.437268 -9.9822)
		(end 187.856368 -9.9822)
		(stroke
			(width 0.06985)
			(type default)
		)
		(layer "In2.Cu")
	)
	(gr_line
		(start 187.451746 -205.267052)
		(end 187.476384 -205.252066)
		(stroke
			(width 0.06985)
			(type default)
		)
		(layer "In2.Cu")
	)
	(gr_line
		(start 187.476384 -205.252066)
		(end 187.49264 -205.228698)
		(stroke
			(width 0.06985)
			(type default)
		)
		(layer "In2.Cu")
	)
	(gr_line
		(start 187.491116 -33.955482)
		(end 187.512198 -33.951672)
		(stroke
			(width 0.06985)
			(type default)
		)
		(layer "In2.Cu")
	)
	(gr_line
		(start 187.512198 -33.951672)
		(end 187.533026 -33.95599)
		(stroke
			(width 0.06985)
			(type default)
		)
		(layer "In2.Cu")
	)
	(gr_line
		(start 187.531756 -207.063086)
		(end 187.580524 -207.042004)
		(stroke
			(width 0.06985)
			(type default)
		)
		(layer "In2.Cu")
	)
	(gr_line
		(start 187.580524 -207.042004)
		(end 187.60059 -207.013302)
		(stroke
			(width 0.06985)
			(type default)
		)
		(layer "In2.Cu")
	)
	(gr_line
		(start 187.592208 -9.4742)
		(end 187.701428 -9.4742)
		(stroke
			(width 0.06985)
			(type default)
		)
		(layer "In2.Cu")
	)
	(gr_line
		(start 187.60059 -207.013302)
		(end 187.600844 -207.013048)
		(stroke
			(width 0.06985)
			(type default)
		)
		(layer "In2.Cu")
	)
	(gr_line
		(start 187.600844 -207.013048)
		(end 187.611766 -206.997554)
		(stroke
			(width 0.06985)
			(type default)
		)
		(layer "In2.Cu")
	)
	(gr_line
		(start 187.609226 -12.270994)
		(end 187.784486 -12.446254)
		(stroke
			(width 0.06985)
			(type default)
		)
		(layer "In2.Cu")
	)
	(gr_line
		(start 187.780422 -31.730442)
		(end 187.809886 -31.724092)
		(stroke
			(width 0.06985)
			(type default)
		)
		(layer "In2.Cu")
	)
	(gr_line
		(start 187.784486 -12.446254)
		(end 188.203586 -12.446254)
		(stroke
			(width 0.06985)
			(type default)
		)
		(layer "In2.Cu")
	)
	(gr_line
		(start 187.809886 -31.724092)
		(end 187.83935 -31.730442)
		(stroke
			(width 0.06985)
			(type default)
		)
		(layer "In2.Cu")
	)
	(gr_line
		(start 187.838334 -45.009562)
		(end 187.973462 -45.217588)
		(stroke
			(width 0.06985)
			(type default)
		)
		(layer "In2.Cu")
	)
	(gr_line
		(start 187.85332 -30.80385)
		(end 187.882784 -30.7975)
		(stroke
			(width 0.06985)
			(type default)
		)
		(layer "In2.Cu")
	)
	(gr_line
		(start 187.856368 -9.9822)
		(end 188.031628 -9.80694)
		(stroke
			(width 0.06985)
			(type default)
		)
		(layer "In2.Cu")
	)
	(gr_line
		(start 187.882784 -30.7975)
		(end 187.912248 -30.80385)
		(stroke
			(width 0.06985)
			(type default)
		)
		(layer "In2.Cu")
	)
	(gr_line
		(start 187.939426 -11.938254)
		(end 188.048646 -11.938254)
		(stroke
			(width 0.06985)
			(type default)
		)
		(layer "In2.Cu")
	)
	(gr_line
		(start 187.945522 -44.692316)
		(end 188.622686 -44.836334)
		(stroke
			(width 0.06985)
			(type default)
		)
		(layer "In2.Cu")
	)
	(gr_line
		(start 187.973462 -45.217588)
		(end 188.383418 -45.30471)
		(stroke
			(width 0.06985)
			(type default)
		)
		(layer "In2.Cu")
	)
	(gr_line
		(start 187.993782 -15.574772)
		(end 188.026802 -15.580614)
		(stroke
			(width 0.06985)
			(type default)
		)
		(layer "In2.Cu")
	)
	(gr_line
		(start 188.026802 -15.580614)
		(end 188.054742 -15.600172)
		(stroke
			(width 0.06985)
			(type default)
		)
		(layer "In2.Cu")
	)
	(gr_line
		(start 188.203586 -12.446254)
		(end 188.378846 -12.270994)
		(stroke
			(width 0.06985)
			(type default)
		)
		(layer "In2.Cu")
	)
	(gr_line
		(start 188.383418 -45.30471)
		(end 188.591444 -45.169582)
		(stroke
			(width 0.06985)
			(type default)
		)
		(layer "In2.Cu")
	)
	(gr_line
		(start 188.41593 -215.446102)
		(end 188.431424 -215.43518)
		(stroke
			(width 0.06985)
			(type default)
		)
		(layer "In2.Cu")
	)
	(gr_line
		(start 188.431424 -215.43518)
		(end 188.442346 -215.419686)
		(stroke
			(width 0.06985)
			(type default)
		)
		(layer "In2.Cu")
	)
	(gr_line
		(start 188.44387 -29.794708)
		(end 188.462666 -29.791406)
		(stroke
			(width 0.06985)
			(type default)
		)
		(layer "In2.Cu")
	)
	(gr_line
		(start 188.462666 -29.791406)
		(end 188.481462 -29.794708)
		(stroke
			(width 0.06985)
			(type default)
		)
		(layer "In2.Cu")
	)
	(gr_line
		(start 188.532516 -25.171908)
		(end 188.54547 -25.19172)
		(stroke
			(width 0.06985)
			(type default)
		)
		(layer "In2.Cu")
	)
	(gr_line
		(start 188.54547 -25.19172)
		(end 188.565028 -25.205436)
		(stroke
			(width 0.06985)
			(type default)
		)
		(layer "In2.Cu")
	)
	(gr_arc
		(start 188.893704 -222.294704)
		(mid 189.072271 -222.027353)
		(end 189.135004 -221.712028)
		(stroke
			(width 0.06985)
			(type default)
		)
		(layer "In2.Cu")
	)
	(gr_line
		(start 189.006226 -45.257974)
		(end 189.1411 -45.466)
		(stroke
			(width 0.06985)
			(type default)
		)
		(layer "In2.Cu")
	)
	(gr_line
		(start 189.0776 -209.463894)
		(end 189.145672 -209.395822)
		(stroke
			(width 0.06985)
			(type default)
		)
		(layer "In2.Cu")
	)
	(gr_line
		(start 189.11316 -44.940474)
		(end 189.792864 -45.085)
		(stroke
			(width 0.06985)
			(type default)
		)
		(layer "In2.Cu")
	)
	(gr_line
		(start 189.135004 -220.616018)
		(end 189.171072 -220.564456)
		(stroke
			(width 0.06985)
			(type default)
		)
		(layer "In2.Cu")
	)
	(gr_line
		(start 189.1411 -45.466)
		(end 189.551056 -45.553122)
		(stroke
			(width 0.06985)
			(type default)
		)
		(layer "In2.Cu")
	)
	(gr_line
		(start 189.227714 -214.297768)
		(end 189.247272 -214.269828)
		(stroke
			(width 0.06985)
			(type default)
		)
		(layer "In2.Cu")
	)
	(gr_line
		(start 189.247272 -214.269828)
		(end 189.253114 -214.236808)
		(stroke
			(width 0.06985)
			(type default)
		)
		(layer "In2.Cu")
	)
	(gr_arc
		(start 189.465204 -221.712028)
		(mid 189.527925 -222.02735)
		(end 189.706504 -222.294704)
		(stroke
			(width 0.06985)
			(type default)
		)
		(layer "In2.Cu")
	)
	(gr_line
		(start 189.551056 -45.553122)
		(end 189.759336 -45.417994)
		(stroke
			(width 0.06985)
			(type default)
		)
		(layer "In2.Cu")
	)
	(gr_line
		(start 189.934596 -219.47378)
		(end 189.945518 -219.458286)
		(stroke
			(width 0.06985)
			(type default)
		)
		(layer "In2.Cu")
	)
	(gr_line
		(start 189.945518 -219.458286)
		(end 189.961012 -219.447364)
		(stroke
			(width 0.06985)
			(type default)
		)
		(layer "In2.Cu")
	)
	(gr_line
		(start 190.173864 -45.506132)
		(end 190.308992 -45.714158)
		(stroke
			(width 0.06985)
			(type default)
		)
		(layer "In2.Cu")
	)
	(gr_line
		(start 190.279528 -45.188378)
		(end 190.959232 -45.332904)
		(stroke
			(width 0.06985)
			(type default)
		)
		(layer "In2.Cu")
	)
	(gr_line
		(start 190.308992 -45.714158)
		(end 190.718948 -45.80128)
		(stroke
			(width 0.06985)
			(type default)
		)
		(layer "In2.Cu")
	)
	(gr_line
		(start 190.397384 -75.507596)
		(end 190.416942 -75.479656)
		(stroke
			(width 0.06985)
			(type default)
		)
		(layer "In2.Cu")
	)
	(gr_line
		(start 190.416942 -75.479656)
		(end 190.422784 -75.446636)
		(stroke
			(width 0.06985)
			(type default)
		)
		(layer "In2.Cu")
	)
	(gr_line
		(start 190.483744 -217.325448)
		(end 190.499238 -217.314526)
		(stroke
			(width 0.06985)
			(type default)
		)
		(layer "In2.Cu")
	)
	(gr_line
		(start 190.499238 -217.314526)
		(end 190.51016 -217.299032)
		(stroke
			(width 0.06985)
			(type default)
		)
		(layer "In2.Cu")
	)
	(gr_line
		(start 190.718948 -45.80128)
		(end 190.926974 -45.666152)
		(stroke
			(width 0.06985)
			(type default)
		)
		(layer "In2.Cu")
	)
	(gr_line
		(start 190.950342 -43.689016)
		(end 191.086232 -43.89628)
		(stroke
			(width 0.06985)
			(type default)
		)
		(layer "In2.Cu")
	)
	(gr_line
		(start 191.056006 -43.371008)
		(end 191.733424 -43.51147)
		(stroke
			(width 0.06985)
			(type default)
		)
		(layer "In2.Cu")
	)
	(gr_line
		(start 191.086232 -43.89628)
		(end 191.496696 -43.981116)
		(stroke
			(width 0.06985)
			(type default)
		)
		(layer "In2.Cu")
	)
	(gr_line
		(start 191.24549 -27.08275)
		(end 191.27343 -27.102308)
		(stroke
			(width 0.06985)
			(type default)
		)
		(layer "In2.Cu")
	)
	(gr_line
		(start 191.27343 -27.102308)
		(end 191.30645 -27.10815)
		(stroke
			(width 0.06985)
			(type default)
		)
		(layer "In2.Cu")
	)
	(gr_line
		(start 191.35725 -199.709532)
		(end 191.376808 -199.681592)
		(stroke
			(width 0.06985)
			(type default)
		)
		(layer "In2.Cu")
	)
	(gr_line
		(start 191.376808 -199.681592)
		(end 191.38265 -199.648572)
		(stroke
			(width 0.06985)
			(type default)
		)
		(layer "In2.Cu")
	)
	(gr_line
		(start 191.484504 -75.661774)
		(end 191.504062 -75.633834)
		(stroke
			(width 0.06985)
			(type default)
		)
		(layer "In2.Cu")
	)
	(gr_line
		(start 191.496696 -43.981116)
		(end 191.70396 -43.844972)
		(stroke
			(width 0.06985)
			(type default)
		)
		(layer "In2.Cu")
	)
	(gr_line
		(start 191.504062 -75.633834)
		(end 191.509904 -75.600814)
		(stroke
			(width 0.06985)
			(type default)
		)
		(layer "In2.Cu")
	)
	(gr_line
		(start 191.715136 -55.667656)
		(end 191.720978 -55.634636)
		(stroke
			(width 0.06985)
			(type default)
		)
		(layer "In2.Cu")
	)
	(gr_line
		(start 191.720978 -55.634636)
		(end 191.740536 -55.606696)
		(stroke
			(width 0.06985)
			(type default)
		)
		(layer "In2.Cu")
	)
	(gr_line
		(start 191.86652 -60.695078)
		(end 191.869568 -60.71235)
		(stroke
			(width 0.06985)
			(type default)
		)
		(layer "In2.Cu")
	)
	(gr_line
		(start 191.86652 -60.695078)
		(end 191.869568 -60.678314)
		(stroke
			(width 0.06985)
			(type default)
		)
		(layer "In2.Cu")
	)
	(gr_line
		(start 192.048384 -66.226182)
		(end 192.048384 -66.226436)
		(stroke
			(width 0.06985)
			(type default)
		)
		(layer "In2.Cu")
	)
	(gr_line
		(start 192.048384 -66.226182)
		(end 192.051686 -66.207386)
		(stroke
			(width 0.06985)
			(type default)
		)
		(layer "In2.Cu")
	)
	(gr_line
		(start 192.048384 -66.18859)
		(end 192.051686 -66.207386)
		(stroke
			(width 0.06985)
			(type default)
		)
		(layer "In2.Cu")
	)
	(gr_arc
		(start 192.093596 -222.294704)
		(mid 192.272223 -222.02737)
		(end 192.334896 -221.712028)
		(stroke
			(width 0.06985)
			(type default)
		)
		(layer "In2.Cu")
	)
	(gr_line
		(start 192.118996 -43.931078)
		(end 192.255394 -44.138342)
		(stroke
			(width 0.06985)
			(type default)
		)
		(layer "In2.Cu")
	)
	(gr_line
		(start 192.22339 -43.612816)
		(end 192.902078 -43.753532)
		(stroke
			(width 0.06985)
			(type default)
		)
		(layer "In2.Cu")
	)
	(gr_line
		(start 192.255394 -44.138342)
		(end 192.665604 -44.223432)
		(stroke
			(width 0.06985)
			(type default)
		)
		(layer "In2.Cu")
	)
	(gr_line
		(start 192.280032 -32.07004)
		(end 192.304162 -32.07512)
		(stroke
			(width 0.06985)
			(type default)
		)
		(layer "In2.Cu")
	)
	(gr_line
		(start 192.304162 -32.07512)
		(end 192.328546 -32.070802)
		(stroke
			(width 0.06985)
			(type default)
		)
		(layer "In2.Cu")
	)
	(gr_line
		(start 192.334896 -221.487492)
		(end 192.371726 -221.434914)
		(stroke
			(width 0.06985)
			(type default)
		)
		(layer "In2.Cu")
	)
	(gr_line
		(start 192.385442 -200.17994)
		(end 192.405 -200.152)
		(stroke
			(width 0.06985)
			(type default)
		)
		(layer "In2.Cu")
	)
	(gr_line
		(start 192.39992 -209.634582)
		(end 192.435988 -209.58302)
		(stroke
			(width 0.06985)
			(type default)
		)
		(layer "In2.Cu")
	)
	(gr_line
		(start 192.405 -200.152)
		(end 192.410842 -200.11898)
		(stroke
			(width 0.06985)
			(type default)
		)
		(layer "In2.Cu")
	)
	(gr_line
		(start 192.466214 -76.10094)
		(end 192.485772 -76.073)
		(stroke
			(width 0.06985)
			(type default)
		)
		(layer "In2.Cu")
	)
	(gr_line
		(start 192.485772 -76.073)
		(end 192.491614 -76.03998)
		(stroke
			(width 0.06985)
			(type default)
		)
		(layer "In2.Cu")
	)
	(gr_line
		(start 192.529206 -29.912818)
		(end 192.548002 -29.91612)
		(stroke
			(width 0.06985)
			(type default)
		)
		(layer "In2.Cu")
	)
	(gr_line
		(start 192.548002 -29.91612)
		(end 192.566798 -29.912818)
		(stroke
			(width 0.06985)
			(type default)
		)
		(layer "In2.Cu")
	)
	(gr_line
		(start 192.589404 -214.329264)
		(end 192.608962 -214.301324)
		(stroke
			(width 0.06985)
			(type default)
		)
		(layer "In2.Cu")
	)
	(gr_line
		(start 192.608962 -214.301324)
		(end 192.614804 -214.268304)
		(stroke
			(width 0.06985)
			(type default)
		)
		(layer "In2.Cu")
	)
	(gr_line
		(start 192.612264 -30.858714)
		(end 192.63106 -30.862016)
		(stroke
			(width 0.06985)
			(type default)
		)
		(layer "In2.Cu")
	)
	(gr_line
		(start 192.63106 -30.862016)
		(end 192.649856 -30.858714)
		(stroke
			(width 0.06985)
			(type default)
		)
		(layer "In2.Cu")
	)
	(gr_arc
		(start 192.665096 -221.712028)
		(mid 192.727777 -222.027371)
		(end 192.906396 -222.294704)
		(stroke
			(width 0.06985)
			(type default)
		)
		(layer "In2.Cu")
	)
	(gr_line
		(start 192.665604 -44.223432)
		(end 192.872868 -44.087288)
		(stroke
			(width 0.06985)
			(type default)
		)
		(layer "In2.Cu")
	)
	(gr_line
		(start 192.666874 -56.14797)
		(end 192.672716 -56.11495)
		(stroke
			(width 0.06985)
			(type default)
		)
		(layer "In2.Cu")
	)
	(gr_line
		(start 192.672716 -56.11495)
		(end 192.692274 -56.08701)
		(stroke
			(width 0.06985)
			(type default)
		)
		(layer "In2.Cu")
	)
	(gr_line
		(start 192.900046 -60.643008)
		(end 192.903348 -60.662058)
		(stroke
			(width 0.06985)
			(type default)
		)
		(layer "In2.Cu")
	)
	(gr_line
		(start 192.900046 -60.643008)
		(end 192.903348 -60.623958)
		(stroke
			(width 0.06985)
			(type default)
		)
		(layer "In2.Cu")
	)
	(gr_line
		(start 192.903348 -60.661804)
		(end 192.903348 -60.662058)
		(stroke
			(width 0.06985)
			(type default)
		)
		(layer "In2.Cu")
	)
	(gr_line
		(start 193.156586 -66.260218)
		(end 193.159634 -66.2432)
		(stroke
			(width 0.06985)
			(type default)
		)
		(layer "In2.Cu")
	)
	(gr_line
		(start 193.15684 -66.226944)
		(end 193.159634 -66.2432)
		(stroke
			(width 0.06985)
			(type default)
		)
		(layer "In2.Cu")
	)
	(gr_line
		(start 193.287904 -44.17314)
		(end 193.424302 -44.380658)
		(stroke
			(width 0.06985)
			(type default)
		)
		(layer "In2.Cu")
	)
	(gr_line
		(start 193.393568 -43.855386)
		(end 194.071494 -43.995848)
		(stroke
			(width 0.06985)
			(type default)
		)
		(layer "In2.Cu")
	)
	(gr_line
		(start 193.424302 -44.380658)
		(end 193.834766 -44.465494)
		(stroke
			(width 0.06985)
			(type default)
		)
		(layer "In2.Cu")
	)
	(gr_line
		(start 193.425572 -219.929456)
		(end 193.436494 -219.913962)
		(stroke
			(width 0.06985)
			(type default)
		)
		(layer "In2.Cu")
	)
	(gr_line
		(start 193.436494 -219.913962)
		(end 193.451988 -219.90304)
		(stroke
			(width 0.06985)
			(type default)
		)
		(layer "In2.Cu")
	)
	(gr_line
		(start 193.450718 -76.582524)
		(end 193.470276 -76.554584)
		(stroke
			(width 0.06985)
			(type default)
		)
		(layer "In2.Cu")
	)
	(gr_line
		(start 193.470276 -76.554584)
		(end 193.476118 -76.521564)
		(stroke
			(width 0.06985)
			(type default)
		)
		(layer "In2.Cu")
	)
	(gr_line
		(start 193.592958 -56.707786)
		(end 193.5988 -56.674766)
		(stroke
			(width 0.06985)
			(type default)
		)
		(layer "In2.Cu")
	)
	(gr_line
		(start 193.5988 -56.674766)
		(end 193.618358 -56.646826)
		(stroke
			(width 0.06985)
			(type default)
		)
		(layer "In2.Cu")
	)
	(gr_line
		(start 193.629026 -33.299146)
		(end 193.65849 -33.305496)
		(stroke
			(width 0.06985)
			(type default)
		)
		(layer "In2.Cu")
	)
	(gr_line
		(start 193.65849 -33.305496)
		(end 193.687954 -33.299146)
		(stroke
			(width 0.06985)
			(type default)
		)
		(layer "In2.Cu")
	)
	(gr_line
		(start 193.793364 -205.215236)
		(end 193.839592 -205.169008)
		(stroke
			(width 0.06985)
			(type default)
		)
		(layer "In2.Cu")
	)
	(gr_line
		(start 193.819272 -34.427668)
		(end 193.838068 -34.43097)
		(stroke
			(width 0.06985)
			(type default)
		)
		(layer "In2.Cu")
	)
	(gr_line
		(start 193.834766 -44.465494)
		(end 194.04203 -44.32935)
		(stroke
			(width 0.06985)
			(type default)
		)
		(layer "In2.Cu")
	)
	(gr_line
		(start 193.838068 -34.43097)
		(end 193.856864 -34.427668)
		(stroke
			(width 0.06985)
			(type default)
		)
		(layer "In2.Cu")
	)
	(gr_line
		(start 193.839592 -205.169008)
		(end 193.851022 -205.104746)
		(stroke
			(width 0.06985)
			(type default)
		)
		(layer "In2.Cu")
	)
	(gr_line
		(start 193.94043 -60.715144)
		(end 193.943732 -60.734194)
		(stroke
			(width 0.06985)
			(type default)
		)
		(layer "In2.Cu")
	)
	(gr_line
		(start 193.94043 -60.715144)
		(end 193.943732 -60.696094)
		(stroke
			(width 0.06985)
			(type default)
		)
		(layer "In2.Cu")
	)
	(gr_line
		(start 194.217036 -66.252344)
		(end 194.217036 -66.252598)
		(stroke
			(width 0.06985)
			(type default)
		)
		(layer "In2.Cu")
	)
	(gr_line
		(start 194.217036 -66.252344)
		(end 194.220338 -66.233548)
		(stroke
			(width 0.06985)
			(type default)
		)
		(layer "In2.Cu")
	)
	(gr_line
		(start 194.217036 -66.214752)
		(end 194.220338 -66.233548)
		(stroke
			(width 0.06985)
			(type default)
		)
		(layer "In2.Cu")
	)
	(gr_line
		(start 194.430142 -76.974192)
		(end 194.4497 -76.946252)
		(stroke
			(width 0.06985)
			(type default)
		)
		(layer "In2.Cu")
	)
	(gr_line
		(start 194.4497 -76.946252)
		(end 194.455542 -76.913232)
		(stroke
			(width 0.06985)
			(type default)
		)
		(layer "In2.Cu")
	)
	(gr_line
		(start 194.457066 -44.415456)
		(end 194.59321 -44.62272)
		(stroke
			(width 0.06985)
			(type default)
		)
		(layer "In2.Cu")
	)
	(gr_line
		(start 194.555364 -57.223152)
		(end 194.561206 -57.190132)
		(stroke
			(width 0.06985)
			(type default)
		)
		(layer "In2.Cu")
	)
	(gr_line
		(start 194.561206 -57.190132)
		(end 194.580764 -57.162192)
		(stroke
			(width 0.06985)
			(type default)
		)
		(layer "In2.Cu")
	)
	(gr_line
		(start 194.56146 -44.097194)
		(end 195.241672 -44.238164)
		(stroke
			(width 0.06985)
			(type default)
		)
		(layer "In2.Cu")
	)
	(gr_line
		(start 194.59321 -44.62272)
		(end 195.003674 -44.70781)
		(stroke
			(width 0.06985)
			(type default)
		)
		(layer "In2.Cu")
	)
	(gr_line
		(start 194.683634 -216.544144)
		(end 194.699128 -216.533222)
		(stroke
			(width 0.06985)
			(type default)
		)
		(layer "In2.Cu")
	)
	(gr_line
		(start 194.699128 -216.533222)
		(end 194.71005 -216.517728)
		(stroke
			(width 0.06985)
			(type default)
		)
		(layer "In2.Cu")
	)
	(gr_line
		(start 194.825366 -206.746094)
		(end 194.844924 -206.718154)
		(stroke
			(width 0.06985)
			(type default)
		)
		(layer "In2.Cu")
	)
	(gr_line
		(start 194.844924 -206.718154)
		(end 194.850766 -206.685134)
		(stroke
			(width 0.06985)
			(type default)
		)
		(layer "In2.Cu")
	)
	(gr_line
		(start 194.983608 -60.682632)
		(end 194.98691 -60.701682)
		(stroke
			(width 0.06985)
			(type default)
		)
		(layer "In2.Cu")
	)
	(gr_line
		(start 194.983608 -60.682632)
		(end 194.98691 -60.663582)
		(stroke
			(width 0.06985)
			(type default)
		)
		(layer "In2.Cu")
	)
	(gr_line
		(start 195.003674 -44.70781)
		(end 195.210938 -44.571666)
		(stroke
			(width 0.06985)
			(type default)
		)
		(layer "In2.Cu")
	)
	(gr_line
		(start 195.265802 -66.367914)
		(end 195.269104 -66.349118)
		(stroke
			(width 0.06985)
			(type default)
		)
		(layer "In2.Cu")
	)
	(gr_line
		(start 195.265802 -66.330322)
		(end 195.269104 -66.349118)
		(stroke
			(width 0.06985)
			(type default)
		)
		(layer "In2.Cu")
	)
	(gr_arc
		(start 195.293742 -222.294704)
		(mid 195.472369 -222.02737)
		(end 195.535042 -221.712028)
		(stroke
			(width 0.06985)
			(type default)
		)
		(layer "In2.Cu")
	)
	(gr_line
		(start 195.36664 -24.032972)
		(end 195.388484 -24.048212)
		(stroke
			(width 0.06985)
			(type default)
		)
		(layer "In2.Cu")
	)
	(gr_line
		(start 195.388484 -24.048212)
		(end 195.414646 -24.0538)
		(stroke
			(width 0.06985)
			(type default)
		)
		(layer "In2.Cu")
	)
	(gr_line
		(start 195.416678 -208.391252)
		(end 195.41998 -208.410302)
		(stroke
			(width 0.06985)
			(type default)
		)
		(layer "In2.Cu")
	)
	(gr_line
		(start 195.416678 -208.391252)
		(end 195.41998 -208.372456)
		(stroke
			(width 0.06985)
			(type default)
		)
		(layer "In2.Cu")
	)
	(gr_line
		(start 195.43014 -77.291184)
		(end 195.449698 -77.263244)
		(stroke
			(width 0.06985)
			(type default)
		)
		(layer "In2.Cu")
	)
	(gr_line
		(start 195.449698 -77.263244)
		(end 195.45554 -77.230224)
		(stroke
			(width 0.06985)
			(type default)
		)
		(layer "In2.Cu")
	)
	(gr_line
		(start 195.526914 -57.596024)
		(end 195.532248 -57.566306)
		(stroke
			(width 0.06985)
			(type default)
		)
		(layer "In2.Cu")
	)
	(gr_line
		(start 195.532248 -57.566306)
		(end 195.548504 -57.54243)
		(stroke
			(width 0.06985)
			(type default)
		)
		(layer "In2.Cu")
	)
	(gr_line
		(start 195.535042 -221.244922)
		(end 195.57111 -221.19336)
		(stroke
			(width 0.06985)
			(type default)
		)
		(layer "In2.Cu")
	)
	(gr_line
		(start 195.582032 -215.27262)
		(end 195.60159 -215.24468)
		(stroke
			(width 0.06985)
			(type default)
		)
		(layer "In2.Cu")
	)
	(gr_line
		(start 195.596002 -44.648882)
		(end 195.624196 -44.654724)
		(stroke
			(width 0.06985)
			(type default)
		)
		(layer "In2.Cu")
	)
	(gr_line
		(start 195.60159 -215.24468)
		(end 195.607432 -215.21166)
		(stroke
			(width 0.06985)
			(type default)
		)
		(layer "In2.Cu")
	)
	(gr_line
		(start 195.624196 -44.654724)
		(end 195.653406 -44.648628)
		(stroke
			(width 0.06985)
			(type default)
		)
		(layer "In2.Cu")
	)
	(gr_line
		(start 195.688712 -49.967134)
		(end 195.699634 -49.95164)
		(stroke
			(width 0.06985)
			(type default)
		)
		(layer "In2.Cu")
	)
	(gr_line
		(start 195.699634 -49.95164)
		(end 195.715128 -49.940718)
		(stroke
			(width 0.06985)
			(type default)
		)
		(layer "In2.Cu")
	)
	(gr_line
		(start 195.84289 -55.361332)
		(end 195.852542 -55.347362)
		(stroke
			(width 0.06985)
			(type default)
		)
		(layer "In2.Cu")
	)
	(gr_line
		(start 195.852542 -55.347362)
		(end 195.866766 -55.337202)
		(stroke
			(width 0.06985)
			(type default)
		)
		(layer "In2.Cu")
	)
	(gr_arc
		(start 195.865242 -221.712028)
		(mid 195.927926 -222.027369)
		(end 196.106542 -222.294704)
		(stroke
			(width 0.06985)
			(type default)
		)
		(layer "In2.Cu")
	)
	(gr_line
		(start 195.93687 -38.283134)
		(end 195.961508 -38.288214)
		(stroke
			(width 0.06985)
			(type default)
		)
		(layer "In2.Cu")
	)
	(gr_line
		(start 195.961508 -38.288214)
		(end 195.986146 -38.283134)
		(stroke
			(width 0.06985)
			(type default)
		)
		(layer "In2.Cu")
	)
	(gr_line
		(start 196.012562 -60.691014)
		(end 196.01561 -60.708286)
		(stroke
			(width 0.06985)
			(type default)
		)
		(layer "In2.Cu")
	)
	(gr_line
		(start 196.012562 -60.689998)
		(end 196.012562 -60.691014)
		(stroke
			(width 0.06985)
			(type default)
		)
		(layer "In2.Cu")
	)
	(gr_line
		(start 196.012562 -60.689998)
		(end 196.01561 -60.673234)
		(stroke
			(width 0.06985)
			(type default)
		)
		(layer "In2.Cu")
	)
	(gr_line
		(start 196.048884 -39.35857)
		(end 196.073522 -39.36365)
		(stroke
			(width 0.06985)
			(type default)
		)
		(layer "In2.Cu")
	)
	(gr_line
		(start 196.073522 -39.36365)
		(end 196.09816 -39.35857)
		(stroke
			(width 0.06985)
			(type default)
		)
		(layer "In2.Cu")
	)
	(gr_line
		(start 196.130672 -37.113718)
		(end 196.1515 -37.118036)
		(stroke
			(width 0.06985)
			(type default)
		)
		(layer "In2.Cu")
	)
	(gr_line
		(start 196.1515 -37.118036)
		(end 196.172582 -37.114226)
		(stroke
			(width 0.06985)
			(type default)
		)
		(layer "In2.Cu")
	)
	(gr_line
		(start 196.289168 -220.1672)
		(end 196.30009 -220.151706)
		(stroke
			(width 0.06985)
			(type default)
		)
		(layer "In2.Cu")
	)
	(gr_line
		(start 196.30009 -220.151706)
		(end 196.315584 -220.140784)
		(stroke
			(width 0.06985)
			(type default)
		)
		(layer "In2.Cu")
	)
	(gr_line
		(start 196.302884 -26.168096)
		(end 196.324728 -26.183336)
		(stroke
			(width 0.06985)
			(type default)
		)
		(layer "In2.Cu")
	)
	(gr_line
		(start 196.314822 -66.366644)
		(end 196.314822 -66.366898)
		(stroke
			(width 0.06985)
			(type default)
		)
		(layer "In2.Cu")
	)
	(gr_line
		(start 196.314822 -66.366644)
		(end 196.318124 -66.347848)
		(stroke
			(width 0.06985)
			(type default)
		)
		(layer "In2.Cu")
	)
	(gr_line
		(start 196.314822 -66.329052)
		(end 196.318124 -66.347848)
		(stroke
			(width 0.06985)
			(type default)
		)
		(layer "In2.Cu")
	)
	(gr_line
		(start 196.324728 -26.183336)
		(end 196.35089 -26.188924)
		(stroke
			(width 0.06985)
			(type default)
		)
		(layer "In2.Cu")
	)
	(gr_line
		(start 196.335396 -50.883058)
		(end 196.346318 -50.867564)
		(stroke
			(width 0.06985)
			(type default)
		)
		(layer "In2.Cu")
	)
	(gr_line
		(start 196.346318 -50.867564)
		(end 196.361812 -50.856642)
		(stroke
			(width 0.06985)
			(type default)
		)
		(layer "In2.Cu")
	)
	(gr_line
		(start 196.36486 -36.058602)
		(end 196.385688 -36.06292)
		(stroke
			(width 0.06985)
			(type default)
		)
		(layer "In2.Cu")
	)
	(gr_line
		(start 196.385688 -36.06292)
		(end 196.40677 -36.05911)
		(stroke
			(width 0.06985)
			(type default)
		)
		(layer "In2.Cu")
	)
	(gr_line
		(start 196.449696 -58.162444)
		(end 196.454268 -58.136028)
		(stroke
			(width 0.06985)
			(type default)
		)
		(layer "In2.Cu")
	)
	(gr_line
		(start 196.454268 -58.136028)
		(end 196.469 -58.113168)
		(stroke
			(width 0.06985)
			(type default)
		)
		(layer "In2.Cu")
	)
	(gr_line
		(start 196.515736 -56.142382)
		(end 196.525388 -56.128412)
		(stroke
			(width 0.06985)
			(type default)
		)
		(layer "In2.Cu")
	)
	(gr_line
		(start 196.525388 -56.128412)
		(end 196.539612 -56.118252)
		(stroke
			(width 0.06985)
			(type default)
		)
		(layer "In2.Cu")
	)
	(gr_line
		(start 196.568568 -168.334436)
		(end 196.57441 -168.301416)
		(stroke
			(width 0.06985)
			(type default)
		)
		(layer "In2.Cu")
	)
	(gr_line
		(start 196.57441 -168.301416)
		(end 196.593968 -168.273476)
		(stroke
			(width 0.06985)
			(type default)
		)
		(layer "In2.Cu")
	)
	(gr_line
		(start 196.901562 -217.891106)
		(end 196.917056 -217.880184)
		(stroke
			(width 0.06985)
			(type default)
		)
		(layer "In2.Cu")
	)
	(gr_line
		(start 196.912738 -42.64914)
		(end 196.942202 -42.65549)
		(stroke
			(width 0.06985)
			(type default)
		)
		(layer "In2.Cu")
	)
	(gr_line
		(start 196.917056 -217.880184)
		(end 196.927978 -217.86469)
		(stroke
			(width 0.06985)
			(type default)
		)
		(layer "In2.Cu")
	)
	(gr_line
		(start 196.942202 -42.65549)
		(end 196.971666 -42.64914)
		(stroke
			(width 0.06985)
			(type default)
		)
		(layer "In2.Cu")
	)
	(gr_line
		(start 197.038722 -28.11907)
		(end 197.057518 -28.122372)
		(stroke
			(width 0.06985)
			(type default)
		)
		(layer "In2.Cu")
	)
	(gr_line
		(start 197.057518 -28.122372)
		(end 197.076314 -28.11907)
		(stroke
			(width 0.06985)
			(type default)
		)
		(layer "In2.Cu")
	)
	(gr_line
		(start 197.182994 -40.582596)
		(end 197.210934 -40.588184)
		(stroke
			(width 0.06985)
			(type default)
		)
		(layer "In2.Cu")
	)
	(gr_line
		(start 197.210934 -40.588184)
		(end 197.238874 -40.582342)
		(stroke
			(width 0.06985)
			(type default)
		)
		(layer "In2.Cu")
	)
	(gr_line
		(start 197.221348 -41.587928)
		(end 197.249288 -41.593516)
		(stroke
			(width 0.06985)
			(type default)
		)
		(layer "In2.Cu")
	)
	(gr_line
		(start 197.249288 -41.593516)
		(end 197.277228 -41.587674)
		(stroke
			(width 0.06985)
			(type default)
		)
		(layer "In2.Cu")
	)
	(gr_line
		(start 197.287134 -56.853836)
		(end 197.303136 -56.829198)
		(stroke
			(width 0.06985)
			(type default)
		)
		(layer "In2.Cu")
	)
	(gr_line
		(start 197.303136 -56.829198)
		(end 197.328028 -56.812942)
		(stroke
			(width 0.06985)
			(type default)
		)
		(layer "In2.Cu")
	)
	(gr_line
		(start 197.356984 -66.45275)
		(end 197.356984 -66.453004)
		(stroke
			(width 0.06985)
			(type default)
		)
		(layer "In2.Cu")
	)
	(gr_line
		(start 197.356984 -66.45275)
		(end 197.360286 -66.433954)
		(stroke
			(width 0.06985)
			(type default)
		)
		(layer "In2.Cu")
	)
	(gr_line
		(start 197.356984 -66.415158)
		(end 197.360286 -66.433954)
		(stroke
			(width 0.06985)
			(type default)
		)
		(layer "In2.Cu")
	)
	(gr_arc
		(start 197.423278 -45.98416)
		(mid 197.701666 -45.868853)
		(end 197.816978 -45.59046)
		(stroke
			(width 0.06985)
			(type default)
		)
		(layer "In2.Cu")
	)
	(gr_line
		(start 197.46976 -169.52468)
		(end 197.475602 -169.49166)
		(stroke
			(width 0.06985)
			(type default)
		)
		(layer "In2.Cu")
	)
	(gr_line
		(start 197.471284 -43.923966)
		(end 197.501764 -43.917616)
		(stroke
			(width 0.06985)
			(type default)
		)
		(layer "In2.Cu")
	)
	(gr_line
		(start 197.475602 -169.49166)
		(end 197.49516 -169.46372)
		(stroke
			(width 0.06985)
			(type default)
		)
		(layer "In2.Cu")
	)
	(gr_line
		(start 197.501764 -43.917616)
		(end 197.531228 -43.923966)
		(stroke
			(width 0.06985)
			(type default)
		)
		(layer "In2.Cu")
	)
	(gr_arc
		(start 197.816978 -46.70806)
		(mid 197.70165 -46.429706)
		(end 197.423278 -46.31436)
		(stroke
			(width 0.06985)
			(type default)
		)
		(layer "In2.Cu")
	)
	(gr_line
		(start 197.975728 -28.623514)
		(end 197.994524 -28.620212)
		(stroke
			(width 0.06985)
			(type default)
		)
		(layer "In2.Cu")
	)
	(gr_line
		(start 197.994524 -28.620212)
		(end 198.01332 -28.623514)
		(stroke
			(width 0.06985)
			(type default)
		)
		(layer "In2.Cu")
	)
	(gr_line
		(start 198.182992 -23.09622)
		(end 198.204836 -23.11146)
		(stroke
			(width 0.06985)
			(type default)
		)
		(layer "In2.Cu")
	)
	(gr_line
		(start 198.202804 -32.00146)
		(end 198.232268 -31.99511)
		(stroke
			(width 0.06985)
			(type default)
		)
		(layer "In2.Cu")
	)
	(gr_line
		(start 198.204836 -23.11146)
		(end 198.230998 -23.117048)
		(stroke
			(width 0.06985)
			(type default)
		)
		(layer "In2.Cu")
	)
	(gr_line
		(start 198.232268 -31.99511)
		(end 198.261732 -32.00146)
		(stroke
			(width 0.06985)
			(type default)
		)
		(layer "In2.Cu")
	)
	(gr_line
		(start 198.389494 -29.51099)
		(end 198.40829 -29.507688)
		(stroke
			(width 0.06985)
			(type default)
		)
		(layer "In2.Cu")
	)
	(gr_line
		(start 198.40829 -29.507688)
		(end 198.427086 -29.51099)
		(stroke
			(width 0.06985)
			(type default)
		)
		(layer "In2.Cu")
	)
	(gr_arc
		(start 198.493634 -222.294704)
		(mid 198.672261 -222.02737)
		(end 198.734934 -221.712028)
		(stroke
			(width 0.06985)
			(type default)
		)
		(layer "In2.Cu")
	)
	(gr_line
		(start 198.57085 -33.261554)
		(end 198.593964 -33.25749)
		(stroke
			(width 0.06985)
			(type default)
		)
		(layer "In2.Cu")
	)
	(gr_line
		(start 198.593964 -33.25749)
		(end 198.616062 -33.262062)
		(stroke
			(width 0.06985)
			(type default)
		)
		(layer "In2.Cu")
	)
	(gr_line
		(start 198.692262 -215.34501)
		(end 198.71182 -215.31707)
		(stroke
			(width 0.06985)
			(type default)
		)
		(layer "In2.Cu")
	)
	(gr_line
		(start 198.71182 -215.31707)
		(end 198.717662 -215.28405)
		(stroke
			(width 0.06985)
			(type default)
		)
		(layer "In2.Cu")
	)
	(gr_line
		(start 198.734934 -221.314518)
		(end 198.771002 -221.262956)
		(stroke
			(width 0.06985)
			(type default)
		)
		(layer "In2.Cu")
	)
	(gr_line
		(start 198.773542 -27.48407)
		(end 198.79818 -27.479752)
		(stroke
			(width 0.06985)
			(type default)
		)
		(layer "In2.Cu")
	)
	(gr_line
		(start 198.778622 -205.954376)
		(end 198.781924 -205.973426)
		(stroke
			(width 0.06985)
			(type default)
		)
		(layer "In2.Cu")
	)
	(gr_line
		(start 198.778622 -205.954376)
		(end 198.781924 -205.93558)
		(stroke
			(width 0.06985)
			(type default)
		)
		(layer "In2.Cu")
	)
	(gr_line
		(start 198.79818 -27.479752)
		(end 198.822564 -27.484832)
		(stroke
			(width 0.06985)
			(type default)
		)
		(layer "In2.Cu")
	)
	(gr_line
		(start 198.86168 -30.571694)
		(end 198.880476 -30.568392)
		(stroke
			(width 0.06985)
			(type default)
		)
		(layer "In2.Cu")
	)
	(gr_line
		(start 198.880476 -30.568392)
		(end 198.899272 -30.571694)
		(stroke
			(width 0.06985)
			(type default)
		)
		(layer "In2.Cu")
	)
	(gr_line
		(start 198.924418 -44.22013)
		(end 198.94423 -44.224194)
		(stroke
			(width 0.06985)
			(type default)
		)
		(layer "In2.Cu")
	)
	(gr_line
		(start 198.94423 -44.224194)
		(end 198.96201 -44.235624)
		(stroke
			(width 0.06985)
			(type default)
		)
		(layer "In2.Cu")
	)
	(gr_line
		(start 199.055482 -23.292054)
		(end 199.084946 -23.298404)
		(stroke
			(width 0.06985)
			(type default)
		)
		(layer "In2.Cu")
	)
	(gr_arc
		(start 199.065134 -221.712028)
		(mid 199.127818 -222.027369)
		(end 199.306434 -222.294704)
		(stroke
			(width 0.06985)
			(type default)
		)
		(layer "In2.Cu")
	)
	(gr_line
		(start 199.084946 -23.298404)
		(end 199.11441 -23.292054)
		(stroke
			(width 0.06985)
			(type default)
		)
		(layer "In2.Cu")
	)
	(gr_line
		(start 199.238108 -47.474378)
		(end 199.259952 -47.459138)
		(stroke
			(width 0.06985)
			(type default)
		)
		(layer "In2.Cu")
	)
	(gr_line
		(start 199.259952 -47.459138)
		(end 199.286114 -47.45355)
		(stroke
			(width 0.06985)
			(type default)
		)
		(layer "In2.Cu")
	)
	(gr_line
		(start 199.271382 -24.87295)
		(end 199.300846 -24.8793)
		(stroke
			(width 0.06985)
			(type default)
		)
		(layer "In2.Cu")
	)
	(gr_line
		(start 199.300846 -24.8793)
		(end 199.33031 -24.87295)
		(stroke
			(width 0.06985)
			(type default)
		)
		(layer "In2.Cu")
	)
	(gr_line
		(start 199.3265 -220.469206)
		(end 199.337422 -220.453712)
		(stroke
			(width 0.06985)
			(type default)
		)
		(layer "In2.Cu")
	)
	(gr_line
		(start 199.337422 -220.453712)
		(end 199.352916 -220.44279)
		(stroke
			(width 0.06985)
			(type default)
		)
		(layer "In2.Cu")
	)
	(gr_line
		(start 199.386698 -207.536796)
		(end 199.386698 -207.53705)
		(stroke
			(width 0.06985)
			(type default)
		)
		(layer "In2.Cu")
	)
	(gr_line
		(start 199.386698 -207.536796)
		(end 199.39 -207.518)
		(stroke
			(width 0.06985)
			(type default)
		)
		(layer "In2.Cu")
	)
	(gr_line
		(start 199.386698 -207.499204)
		(end 199.39 -207.518)
		(stroke
			(width 0.06985)
			(type default)
		)
		(layer "In2.Cu")
	)
	(gr_line
		(start 199.61733 -218.232482)
		(end 199.632824 -218.22156)
		(stroke
			(width 0.06985)
			(type default)
		)
		(layer "In2.Cu")
	)
	(gr_line
		(start 199.632824 -218.22156)
		(end 199.643746 -218.206066)
		(stroke
			(width 0.06985)
			(type default)
		)
		(layer "In2.Cu")
	)
	(gr_line
		(start 199.793352 -48.453802)
		(end 199.815196 -48.438562)
		(stroke
			(width 0.06985)
			(type default)
		)
		(layer "In2.Cu")
	)
	(gr_line
		(start 199.815196 -48.438562)
		(end 199.841358 -48.432974)
		(stroke
			(width 0.06985)
			(type default)
		)
		(layer "In2.Cu")
	)
	(gr_line
		(start 200.07326 -55.030116)
		(end 200.09104 -55.018686)
		(stroke
			(width 0.06985)
			(type default)
		)
		(layer "In2.Cu")
	)
	(gr_line
		(start 200.09104 -55.018686)
		(end 200.110852 -55.014622)
		(stroke
			(width 0.06985)
			(type default)
		)
		(layer "In2.Cu")
	)
	(gr_line
		(start 200.094088 -167.793924)
		(end 200.09993 -167.760904)
		(stroke
			(width 0.06985)
			(type default)
		)
		(layer "In2.Cu")
	)
	(gr_line
		(start 200.09993 -167.760904)
		(end 200.119488 -167.732964)
		(stroke
			(width 0.06985)
			(type default)
		)
		(layer "In2.Cu")
	)
	(gr_line
		(start 200.161144 -45.407834)
		(end 200.208896 -45.438822)
		(stroke
			(width 0.06985)
			(type default)
		)
		(layer "In2.Cu")
	)
	(gr_arc
		(start 200.4568 -50.2412)
		(mid 200.333769 -49.923469)
		(end 200.0504 -49.734216)
		(stroke
			(width 0.06985)
			(type default)
		)
		(layer "In2.Cu")
	)
	(gr_line
		(start 200.56602 -203.209652)
		(end 200.566274 -203.209906)
		(stroke
			(width 0.06985)
			(type default)
		)
		(layer "In2.Cu")
	)
	(gr_line
		(start 200.56602 -203.209398)
		(end 200.566528 -203.207366)
		(stroke
			(width 0.06985)
			(type default)
		)
		(layer "In2.Cu")
	)
	(gr_line
		(start 200.691496 -53.210968)
		(end 200.719436 -53.19141)
		(stroke
			(width 0.06985)
			(type default)
		)
		(layer "In2.Cu")
	)
	(gr_line
		(start 200.719436 -53.19141)
		(end 200.752456 -53.185568)
		(stroke
			(width 0.06985)
			(type default)
		)
		(layer "In2.Cu")
	)
	(gr_arc
		(start 200.96226 -49.86401)
		(mid 200.833543 -50.005152)
		(end 200.787 -50.1904)
		(stroke
			(width 0.06985)
			(type default)
		)
		(layer "In2.Cu")
	)
	(gr_line
		(start 200.96226 -49.86401)
		(end 201.168 -49.727612)
		(stroke
			(width 0.06985)
			(type default)
		)
		(layer "In2.Cu")
	)
	(gr_arc
		(start 200.96734 -45.108622)
		(mid 201.24571 -44.993297)
		(end 201.36104 -44.714922)
		(stroke
			(width 0.06985)
			(type default)
		)
		(layer "In2.Cu")
	)
	(gr_line
		(start 201.114152 -51.663092)
		(end 201.165714 -51.627024)
		(stroke
			(width 0.06985)
			(type default)
		)
		(layer "In2.Cu")
	)
	(gr_arc
		(start 201.36104 -45.832522)
		(mid 201.245738 -45.554106)
		(end 200.96734 -45.438822)
		(stroke
			(width 0.06985)
			(type default)
		)
		(layer "In2.Cu")
	)
	(gr_line
		(start 201.363072 -167.845486)
		(end 201.368914 -167.812466)
		(stroke
			(width 0.06985)
			(type default)
		)
		(layer "In2.Cu")
	)
	(gr_line
		(start 201.368914 -167.812466)
		(end 201.388472 -167.784526)
		(stroke
			(width 0.06985)
			(type default)
		)
		(layer "In2.Cu")
	)
	(gr_line
		(start 201.455528 -34.177478)
		(end 201.478388 -34.18205)
		(stroke
			(width 0.06985)
			(type default)
		)
		(layer "In2.Cu")
	)
	(gr_line
		(start 201.478388 -34.18205)
		(end 201.501502 -34.177986)
		(stroke
			(width 0.06985)
			(type default)
		)
		(layer "In2.Cu")
	)
	(gr_line
		(start 201.488802 -208.605628)
		(end 201.494644 -208.638648)
		(stroke
			(width 0.06985)
			(type default)
		)
		(layer "In2.Cu")
	)
	(gr_line
		(start 201.494644 -208.638648)
		(end 201.514202 -208.666588)
		(stroke
			(width 0.06985)
			(type default)
		)
		(layer "In2.Cu")
	)
	(gr_arc
		(start 201.69378 -222.294704)
		(mid 201.872407 -222.02737)
		(end 201.93508 -221.712028)
		(stroke
			(width 0.06985)
			(type default)
		)
		(layer "In2.Cu")
	)
	(gr_line
		(start 201.725022 -24.026368)
		(end 201.754486 -24.020018)
		(stroke
			(width 0.06985)
			(type default)
		)
		(layer "In2.Cu")
	)
	(gr_line
		(start 201.754486 -24.020018)
		(end 201.78395 -24.026368)
		(stroke
			(width 0.06985)
			(type default)
		)
		(layer "In2.Cu")
	)
	(gr_line
		(start 201.786998 -33.08858)
		(end 201.811382 -33.09366)
		(stroke
			(width 0.06985)
			(type default)
		)
		(layer "In2.Cu")
	)
	(gr_line
		(start 201.811382 -33.09366)
		(end 201.83602 -33.089342)
		(stroke
			(width 0.06985)
			(type default)
		)
		(layer "In2.Cu")
	)
	(gr_line
		(start 201.93508 -220.955616)
		(end 201.971148 -220.904054)
		(stroke
			(width 0.06985)
			(type default)
		)
		(layer "In2.Cu")
	)
	(gr_line
		(start 201.945494 -22.352762)
		(end 201.974958 -22.346412)
		(stroke
			(width 0.06985)
			(type default)
		)
		(layer "In2.Cu")
	)
	(gr_line
		(start 201.974958 -22.346412)
		(end 202.004422 -22.352762)
		(stroke
			(width 0.06985)
			(type default)
		)
		(layer "In2.Cu")
	)
	(gr_line
		(start 202.046332 -214.774526)
		(end 202.06589 -214.746586)
		(stroke
			(width 0.06985)
			(type default)
		)
		(layer "In2.Cu")
	)
	(gr_line
		(start 202.06589 -214.746586)
		(end 202.071732 -214.713566)
		(stroke
			(width 0.06985)
			(type default)
		)
		(layer "In2.Cu")
	)
	(gr_line
		(start 202.23861 -209.125058)
		(end 202.274678 -209.17662)
		(stroke
			(width 0.06985)
			(type default)
		)
		(layer "In2.Cu")
	)
	(gr_arc
		(start 202.26528 -221.712028)
		(mid 202.32796 -222.027372)
		(end 202.50658 -222.294704)
		(stroke
			(width 0.06985)
			(type default)
		)
		(layer "In2.Cu")
	)
	(gr_line
		(start 202.427586 -168.62933)
		(end 202.433428 -168.59631)
		(stroke
			(width 0.06985)
			(type default)
		)
		(layer "In2.Cu")
	)
	(gr_line
		(start 202.433428 -168.59631)
		(end 202.452986 -168.56837)
		(stroke
			(width 0.06985)
			(type default)
		)
		(layer "In2.Cu")
	)
	(gr_line
		(start 202.769216 -219.764102)
		(end 202.780138 -219.748608)
		(stroke
			(width 0.06985)
			(type default)
		)
		(layer "In2.Cu")
	)
	(gr_line
		(start 202.780138 -219.748608)
		(end 202.795632 -219.737686)
		(stroke
			(width 0.06985)
			(type default)
		)
		(layer "In2.Cu")
	)
	(gr_line
		(start 202.905106 -54.758336)
		(end 202.931268 -54.752748)
		(stroke
			(width 0.06985)
			(type default)
		)
		(layer "In2.Cu")
	)
	(gr_line
		(start 202.931268 -54.752748)
		(end 202.953112 -54.737508)
		(stroke
			(width 0.06985)
			(type default)
		)
		(layer "In2.Cu")
	)
	(gr_line
		(start 202.980798 -47.005748)
		(end 203.00061 -47.001684)
		(stroke
			(width 0.06985)
			(type default)
		)
		(layer "In2.Cu")
	)
	(gr_line
		(start 203.00061 -47.001684)
		(end 203.01839 -46.990254)
		(stroke
			(width 0.06985)
			(type default)
		)
		(layer "In2.Cu")
	)
	(gr_line
		(start 203.014072 -197.070218)
		(end 203.017374 -197.089268)
		(stroke
			(width 0.06985)
			(type default)
		)
		(layer "In2.Cu")
	)
	(gr_line
		(start 203.014072 -197.070218)
		(end 203.017374 -197.051422)
		(stroke
			(width 0.06985)
			(type default)
		)
		(layer "In2.Cu")
	)
	(gr_arc
		(start 203.1746 -50.335942)
		(mid 203.11519 -50.037241)
		(end 202.946 -49.784)
		(stroke
			(width 0.06985)
			(type default)
		)
		(layer "In2.Cu")
	)
	(gr_line
		(start 203.198476 -27.644852)
		(end 203.22794 -27.651202)
		(stroke
			(width 0.06985)
			(type default)
		)
		(layer "In2.Cu")
	)
	(gr_line
		(start 203.22794 -27.651202)
		(end 203.257404 -27.644852)
		(stroke
			(width 0.06985)
			(type default)
		)
		(layer "In2.Cu")
	)
	(gr_line
		(start 203.602082 -53.01869)
		(end 203.635102 -53.012848)
		(stroke
			(width 0.06985)
			(type default)
		)
		(layer "In2.Cu")
	)
	(gr_line
		(start 203.635102 -53.012848)
		(end 203.663042 -52.99329)
		(stroke
			(width 0.06985)
			(type default)
		)
		(layer "In2.Cu")
	)
	(gr_arc
		(start 203.641198 -49.901348)
		(mid 203.540186 -50.052621)
		(end 203.5048 -50.23104)
		(stroke
			(width 0.06985)
			(type default)
		)
		(layer "In2.Cu")
	)
	(gr_line
		(start 203.641198 -49.901348)
		(end 203.7588 -49.784)
		(stroke
			(width 0.06985)
			(type default)
		)
		(layer "In2.Cu")
	)
	(gr_line
		(start 204.006958 -31.808166)
		(end 204.025754 -31.811468)
		(stroke
			(width 0.06985)
			(type default)
		)
		(layer "In2.Cu")
	)
	(gr_line
		(start 204.025754 -31.811468)
		(end 204.04455 -31.808166)
		(stroke
			(width 0.06985)
			(type default)
		)
		(layer "In2.Cu")
	)
	(gr_line
		(start 204.141832 -217.493088)
		(end 204.157326 -217.482166)
		(stroke
			(width 0.06985)
			(type default)
		)
		(layer "In2.Cu")
	)
	(gr_line
		(start 204.157326 -217.482166)
		(end 204.168248 -217.466672)
		(stroke
			(width 0.06985)
			(type default)
		)
		(layer "In2.Cu")
	)
	(gr_line
		(start 204.362304 -65.12687)
		(end 204.365606 -65.14592)
		(stroke
			(width 0.06985)
			(type default)
		)
		(layer "In2.Cu")
	)
	(gr_line
		(start 204.362304 -65.12687)
		(end 204.365606 -65.108074)
		(stroke
			(width 0.06985)
			(type default)
		)
		(layer "In2.Cu")
	)
	(gr_line
		(start 204.365606 -65.145666)
		(end 204.365606 -65.14592)
		(stroke
			(width 0.06985)
			(type default)
		)
		(layer "In2.Cu")
	)
	(gr_line
		(start 204.379576 -76.584556)
		(end 204.399134 -76.556616)
		(stroke
			(width 0.06985)
			(type default)
		)
		(layer "In2.Cu")
	)
	(gr_line
		(start 204.399134 -76.556616)
		(end 204.404976 -76.523596)
		(stroke
			(width 0.06985)
			(type default)
		)
		(layer "In2.Cu")
	)
	(gr_line
		(start 204.488796 -30.916118)
		(end 204.507592 -30.91942)
		(stroke
			(width 0.06985)
			(type default)
		)
		(layer "In2.Cu")
	)
	(gr_line
		(start 204.507592 -30.91942)
		(end 204.526388 -30.916118)
		(stroke
			(width 0.06985)
			(type default)
		)
		(layer "In2.Cu")
	)
	(gr_line
		(start 204.568806 -30.114748)
		(end 204.587602 -30.11805)
		(stroke
			(width 0.06985)
			(type default)
		)
		(layer "In2.Cu")
	)
	(gr_line
		(start 204.587602 -30.11805)
		(end 204.606398 -30.114748)
		(stroke
			(width 0.06985)
			(type default)
		)
		(layer "In2.Cu")
	)
	(gr_line
		(start 204.759306 -29.084778)
		(end 204.78369 -29.089858)
		(stroke
			(width 0.06985)
			(type default)
		)
		(layer "In2.Cu")
	)
	(gr_line
		(start 204.78369 -29.089858)
		(end 204.808328 -29.08554)
		(stroke
			(width 0.06985)
			(type default)
		)
		(layer "In2.Cu")
	)
	(gr_arc
		(start 204.893672 -222.294704)
		(mid 205.072245 -222.027355)
		(end 205.134972 -221.712028)
		(stroke
			(width 0.06985)
			(type default)
		)
		(layer "In2.Cu")
	)
	(gr_line
		(start 205.001876 -216.276174)
		(end 205.021434 -216.248234)
		(stroke
			(width 0.06985)
			(type default)
		)
		(layer "In2.Cu")
	)
	(gr_line
		(start 205.021434 -216.248234)
		(end 205.027276 -216.215214)
		(stroke
			(width 0.06985)
			(type default)
		)
		(layer "In2.Cu")
	)
	(gr_line
		(start 205.038706 -52.030122)
		(end 205.0542 -52.0192)
		(stroke
			(width 0.06985)
			(type default)
		)
		(layer "In2.Cu")
	)
	(gr_line
		(start 205.0542 -52.0192)
		(end 205.065122 -52.003706)
		(stroke
			(width 0.06985)
			(type default)
		)
		(layer "In2.Cu")
	)
	(gr_line
		(start 205.379574 -78.193392)
		(end 205.399132 -78.165452)
		(stroke
			(width 0.06985)
			(type default)
		)
		(layer "In2.Cu")
	)
	(gr_line
		(start 205.399132 -78.165452)
		(end 205.404974 -78.132432)
		(stroke
			(width 0.06985)
			(type default)
		)
		(layer "In2.Cu")
	)
	(gr_arc
		(start 205.465172 -221.712028)
		(mid 205.527893 -222.02735)
		(end 205.706472 -222.294704)
		(stroke
			(width 0.06985)
			(type default)
		)
		(layer "In2.Cu")
	)
	(gr_line
		(start 205.552548 -70.013322)
		(end 205.552548 -70.013576)
		(stroke
			(width 0.06985)
			(type default)
		)
		(layer "In2.Cu")
	)
	(gr_line
		(start 205.552548 -70.013322)
		(end 205.55585 -69.994526)
		(stroke
			(width 0.06985)
			(type default)
		)
		(layer "In2.Cu")
	)
	(gr_line
		(start 205.552548 -69.97573)
		(end 205.55585 -69.994526)
		(stroke
			(width 0.06985)
			(type default)
		)
		(layer "In2.Cu")
	)
	(gr_line
		(start 205.64983 -26.798524)
		(end 205.674214 -26.793444)
		(stroke
			(width 0.06985)
			(type default)
		)
		(layer "In2.Cu")
	)
	(gr_line
		(start 205.672944 -57.693306)
		(end 205.678786 -57.660286)
		(stroke
			(width 0.06985)
			(type default)
		)
		(layer "In2.Cu")
	)
	(gr_line
		(start 205.674214 -26.793444)
		(end 205.698852 -26.797762)
		(stroke
			(width 0.06985)
			(type default)
		)
		(layer "In2.Cu")
	)
	(gr_line
		(start 205.678786 -57.660286)
		(end 205.698344 -57.632346)
		(stroke
			(width 0.06985)
			(type default)
		)
		(layer "In2.Cu")
	)
	(gr_line
		(start 205.792832 -66.537586)
		(end 205.796134 -66.556636)
		(stroke
			(width 0.06985)
			(type default)
		)
		(layer "In2.Cu")
	)
	(gr_line
		(start 205.792832 -66.537586)
		(end 205.796134 -66.51879)
		(stroke
			(width 0.06985)
			(type default)
		)
		(layer "In2.Cu")
	)
	(gr_line
		(start 205.798928 -24.879808)
		(end 205.893162 -24.899874)
		(stroke
			(width 0.06985)
			(type default)
		)
		(layer "In2.Cu")
	)
	(gr_line
		(start 205.893162 -24.899874)
		(end 205.945486 -24.980392)
		(stroke
			(width 0.06985)
			(type default)
		)
		(layer "In2.Cu")
	)
	(gr_line
		(start 205.9051 -165.538658)
		(end 205.910942 -165.505638)
		(stroke
			(width 0.06985)
			(type default)
		)
		(layer "In2.Cu")
	)
	(gr_line
		(start 205.910942 -165.505638)
		(end 205.9305 -165.477698)
		(stroke
			(width 0.06985)
			(type default)
		)
		(layer "In2.Cu")
	)
	(gr_line
		(start 206.000858 -52.603654)
		(end 206.015844 -52.59324)
		(stroke
			(width 0.06985)
			(type default)
		)
		(layer "In2.Cu")
	)
	(gr_line
		(start 206.015844 -52.59324)
		(end 206.026766 -52.577746)
		(stroke
			(width 0.06985)
			(type default)
		)
		(layer "In2.Cu")
	)
	(gr_line
		(start 206.039466 -187.96)
		(end 206.042768 -187.97905)
		(stroke
			(width 0.06985)
			(type default)
		)
		(layer "In2.Cu")
	)
	(gr_line
		(start 206.039466 -187.96)
		(end 206.042768 -187.941204)
		(stroke
			(width 0.06985)
			(type default)
		)
		(layer "In2.Cu")
	)
	(gr_line
		(start 206.349346 -47.38751)
		(end 206.369158 -47.383446)
		(stroke
			(width 0.06985)
			(type default)
		)
		(layer "In2.Cu")
	)
	(gr_line
		(start 206.369158 -47.383446)
		(end 206.386938 -47.372016)
		(stroke
			(width 0.06985)
			(type default)
		)
		(layer "In2.Cu")
	)
	(gr_line
		(start 206.422498 -26.32202)
		(end 206.474822 -26.402538)
		(stroke
			(width 0.06985)
			(type default)
		)
		(layer "In2.Cu")
	)
	(gr_line
		(start 206.474822 -26.402538)
		(end 206.569056 -26.422604)
		(stroke
			(width 0.06985)
			(type default)
		)
		(layer "In2.Cu")
	)
	(gr_line
		(start 206.484474 -217.558112)
		(end 206.499968 -217.54719)
		(stroke
			(width 0.06985)
			(type default)
		)
		(layer "In2.Cu")
	)
	(gr_line
		(start 206.499968 -217.54719)
		(end 206.51089 -217.531696)
		(stroke
			(width 0.06985)
			(type default)
		)
		(layer "In2.Cu")
	)
	(gr_line
		(start 206.627984 -23.673308)
		(end 206.657448 -23.679658)
		(stroke
			(width 0.06985)
			(type default)
		)
		(layer "In2.Cu")
	)
	(gr_line
		(start 206.657448 -23.679658)
		(end 206.686912 -23.673308)
		(stroke
			(width 0.06985)
			(type default)
		)
		(layer "In2.Cu")
	)
	(gr_line
		(start 206.785718 -70.303898)
		(end 206.785718 -70.304152)
		(stroke
			(width 0.06985)
			(type default)
		)
		(layer "In2.Cu")
	)
	(gr_line
		(start 206.785718 -70.303898)
		(end 206.78902 -70.285102)
		(stroke
			(width 0.06985)
			(type default)
		)
		(layer "In2.Cu")
	)
	(gr_line
		(start 206.785718 -70.266306)
		(end 206.78902 -70.285102)
		(stroke
			(width 0.06985)
			(type default)
		)
		(layer "In2.Cu")
	)
	(gr_line
		(start 207.06334 -188.058552)
		(end 207.066642 -188.077602)
		(stroke
			(width 0.06985)
			(type default)
		)
		(layer "In2.Cu")
	)
	(gr_line
		(start 207.06334 -188.058552)
		(end 207.066642 -188.039756)
		(stroke
			(width 0.06985)
			(type default)
		)
		(layer "In2.Cu")
	)
	(gr_line
		(start 207.06461 -23.255224)
		(end 207.094582 -23.248874)
		(stroke
			(width 0.06985)
			(type default)
		)
		(layer "In2.Cu")
	)
	(gr_line
		(start 207.094582 -23.248874)
		(end 207.124046 -23.255224)
		(stroke
			(width 0.06985)
			(type default)
		)
		(layer "In2.Cu")
	)
	(gr_line
		(start 207.20431 -165.562026)
		(end 207.210152 -165.529006)
		(stroke
			(width 0.06985)
			(type default)
		)
		(layer "In2.Cu")
	)
	(gr_line
		(start 207.210152 -165.529006)
		(end 207.22971 -165.501066)
		(stroke
			(width 0.06985)
			(type default)
		)
		(layer "In2.Cu")
	)
	(gr_line
		(start 207.320388 -57.877964)
		(end 207.32623 -57.844944)
		(stroke
			(width 0.06985)
			(type default)
		)
		(layer "In2.Cu")
	)
	(gr_line
		(start 207.32623 -57.844944)
		(end 207.345788 -57.817004)
		(stroke
			(width 0.06985)
			(type default)
		)
		(layer "In2.Cu")
	)
	(gr_line
		(start 207.44815 -48.024288)
		(end 207.458564 -48.009302)
		(stroke
			(width 0.06985)
			(type default)
		)
		(layer "In2.Cu")
	)
	(gr_line
		(start 207.458564 -48.009302)
		(end 207.474058 -47.99838)
		(stroke
			(width 0.06985)
			(type default)
		)
		(layer "In2.Cu")
	)
	(gr_line
		(start 207.610456 -26.644346)
		(end 207.640936 -26.650696)
		(stroke
			(width 0.06985)
			(type default)
		)
		(layer "In2.Cu")
	)
	(gr_line
		(start 207.640936 -26.650696)
		(end 207.6704 -26.644346)
		(stroke
			(width 0.06985)
			(type default)
		)
		(layer "In2.Cu")
	)
	(gr_line
		(start 207.949546 -215.47709)
		(end 207.969104 -215.44915)
		(stroke
			(width 0.06985)
			(type default)
		)
		(layer "In2.Cu")
	)
	(gr_line
		(start 207.969104 -215.44915)
		(end 207.974946 -215.41613)
		(stroke
			(width 0.06985)
			(type default)
		)
		(layer "In2.Cu")
	)
	(gr_line
		(start 208.013808 -27.540458)
		(end 208.032858 -27.54376)
		(stroke
			(width 0.06985)
			(type default)
		)
		(layer "In2.Cu")
	)
	(gr_line
		(start 208.032858 -27.54376)
		(end 208.051654 -27.540458)
		(stroke
			(width 0.06985)
			(type default)
		)
		(layer "In2.Cu")
	)
	(gr_line
		(start 208.350358 -166.8018)
		(end 208.3562 -166.76878)
		(stroke
			(width 0.06985)
			(type default)
		)
		(layer "In2.Cu")
	)
	(gr_line
		(start 208.3562 -166.76878)
		(end 208.375758 -166.74084)
		(stroke
			(width 0.06985)
			(type default)
		)
		(layer "In2.Cu")
	)
	(gr_line
		(start 208.40446 -48.623474)
		(end 208.415382 -48.60798)
		(stroke
			(width 0.06985)
			(type default)
		)
		(layer "In2.Cu")
	)
	(gr_line
		(start 208.415382 -48.60798)
		(end 208.430368 -48.597566)
		(stroke
			(width 0.06985)
			(type default)
		)
		(layer "In2.Cu")
	)
	(gr_line
		(start 208.420208 -187.846716)
		(end 208.42351 -187.865766)
		(stroke
			(width 0.06985)
			(type default)
		)
		(layer "In2.Cu")
	)
	(gr_line
		(start 208.420208 -187.846716)
		(end 208.42351 -187.82792)
		(stroke
			(width 0.06985)
			(type default)
		)
		(layer "In2.Cu")
	)
	(gr_line
		(start 208.534762 -43.01363)
		(end 208.552542 -43.0022)
		(stroke
			(width 0.06985)
			(type default)
		)
		(layer "In2.Cu")
	)
	(gr_line
		(start 208.552542 -43.0022)
		(end 208.572354 -42.998136)
		(stroke
			(width 0.06985)
			(type default)
		)
		(layer "In2.Cu")
	)
	(gr_line
		(start 208.593182 -26.448258)
		(end 208.612994 -26.444194)
		(stroke
			(width 0.06985)
			(type default)
		)
		(layer "In2.Cu")
	)
	(gr_line
		(start 208.612994 -26.444194)
		(end 208.630774 -26.432764)
		(stroke
			(width 0.06985)
			(type default)
		)
		(layer "In2.Cu")
	)
	(gr_line
		(start 208.826608 -216.063576)
		(end 208.846166 -216.035636)
		(stroke
			(width 0.06985)
			(type default)
		)
		(layer "In2.Cu")
	)
	(gr_line
		(start 208.846166 -216.035636)
		(end 208.852008 -216.002616)
		(stroke
			(width 0.06985)
			(type default)
		)
		(layer "In2.Cu")
	)
	(gr_line
		(start 209.044032 -27.365198)
		(end 209.077052 -27.359356)
		(stroke
			(width 0.06985)
			(type default)
		)
		(layer "In2.Cu")
	)
	(gr_line
		(start 209.077052 -27.359356)
		(end 209.104992 -27.339798)
		(stroke
			(width 0.06985)
			(type default)
		)
		(layer "In2.Cu")
	)
	(gr_line
		(start 209.265012 -28.300172)
		(end 209.298032 -28.29433)
		(stroke
			(width 0.06985)
			(type default)
		)
		(layer "In2.Cu")
	)
	(gr_line
		(start 209.298032 -28.29433)
		(end 209.325972 -28.274772)
		(stroke
			(width 0.06985)
			(type default)
		)
		(layer "In2.Cu")
	)
	(gr_line
		(start 209.313526 -62.277498)
		(end 209.316828 -62.296548)
		(stroke
			(width 0.06985)
			(type default)
		)
		(layer "In2.Cu")
	)
	(gr_line
		(start 209.313526 -62.277498)
		(end 209.316828 -62.258702)
		(stroke
			(width 0.06985)
			(type default)
		)
		(layer "In2.Cu")
	)
	(gr_line
		(start 209.354928 -42.831512)
		(end 210.03895 -42.68597)
		(stroke
			(width 0.06985)
			(type default)
		)
		(layer "In2.Cu")
	)
	(gr_line
		(start 209.389472 -43.164506)
		(end 209.597498 -43.299634)
		(stroke
			(width 0.06985)
			(type default)
		)
		(layer "In2.Cu")
	)
	(gr_line
		(start 209.451702 -24.087582)
		(end 209.481166 -24.093932)
		(stroke
			(width 0.06985)
			(type default)
		)
		(layer "In2.Cu")
	)
	(gr_line
		(start 209.481166 -24.093932)
		(end 209.511392 -24.087582)
		(stroke
			(width 0.06985)
			(type default)
		)
		(layer "In2.Cu")
	)
	(gr_line
		(start 209.566764 -167.955722)
		(end 209.572606 -167.922702)
		(stroke
			(width 0.06985)
			(type default)
		)
		(layer "In2.Cu")
	)
	(gr_line
		(start 209.572606 -167.922702)
		(end 209.592164 -167.894762)
		(stroke
			(width 0.06985)
			(type default)
		)
		(layer "In2.Cu")
	)
	(gr_line
		(start 209.592164 -206.243682)
		(end 209.592164 -206.243936)
		(stroke
			(width 0.06985)
			(type default)
		)
		(layer "In2.Cu")
	)
	(gr_line
		(start 209.592164 -206.243682)
		(end 209.595466 -206.224886)
		(stroke
			(width 0.06985)
			(type default)
		)
		(layer "In2.Cu")
	)
	(gr_line
		(start 209.592164 -206.20609)
		(end 209.595466 -206.224886)
		(stroke
			(width 0.06985)
			(type default)
		)
		(layer "In2.Cu")
	)
	(gr_line
		(start 209.597498 -43.299634)
		(end 210.007454 -43.212512)
		(stroke
			(width 0.06985)
			(type default)
		)
		(layer "In2.Cu")
	)
	(gr_line
		(start 209.764884 -76.275692)
		(end 209.784442 -76.247752)
		(stroke
			(width 0.06985)
			(type default)
		)
		(layer "In2.Cu")
	)
	(gr_line
		(start 209.784442 -76.247752)
		(end 209.790284 -76.214732)
		(stroke
			(width 0.06985)
			(type default)
		)
		(layer "In2.Cu")
	)
	(gr_line
		(start 209.86623 -187.193682)
		(end 209.869532 -187.212732)
		(stroke
			(width 0.06985)
			(type default)
		)
		(layer "In2.Cu")
	)
	(gr_line
		(start 209.86623 -187.193682)
		(end 209.869532 -187.174886)
		(stroke
			(width 0.06985)
			(type default)
		)
		(layer "In2.Cu")
	)
	(gr_line
		(start 209.873596 -29.186378)
		(end 209.906616 -29.180536)
		(stroke
			(width 0.06985)
			(type default)
		)
		(layer "In2.Cu")
	)
	(gr_line
		(start 209.906616 -29.180536)
		(end 209.934556 -29.160978)
		(stroke
			(width 0.06985)
			(type default)
		)
		(layer "In2.Cu")
	)
	(gr_line
		(start 210.007454 -43.212512)
		(end 210.142582 -43.004486)
		(stroke
			(width 0.06985)
			(type default)
		)
		(layer "In2.Cu")
	)
	(gr_line
		(start 210.317334 -23.915624)
		(end 210.332574 -23.912322)
		(stroke
			(width 0.06985)
			(type default)
		)
		(layer "In2.Cu")
	)
	(gr_line
		(start 210.332574 -23.912322)
		(end 210.345782 -23.904448)
		(stroke
			(width 0.06985)
			(type default)
		)
		(layer "In2.Cu")
	)
	(gr_line
		(start 210.406996 -169.096436)
		(end 210.412838 -169.063416)
		(stroke
			(width 0.06985)
			(type default)
		)
		(layer "In2.Cu")
	)
	(gr_line
		(start 210.412838 -169.063416)
		(end 210.432396 -169.035476)
		(stroke
			(width 0.06985)
			(type default)
		)
		(layer "In2.Cu")
	)
	(gr_line
		(start 210.483196 -55.64378)
		(end 210.489038 -55.61076)
		(stroke
			(width 0.06985)
			(type default)
		)
		(layer "In2.Cu")
	)
	(gr_line
		(start 210.489038 -55.61076)
		(end 210.508596 -55.58282)
		(stroke
			(width 0.06985)
			(type default)
		)
		(layer "In2.Cu")
	)
	(gr_line
		(start 210.522058 -42.583354)
		(end 211.204302 -42.43832)
		(stroke
			(width 0.06985)
			(type default)
		)
		(layer "In2.Cu")
	)
	(gr_line
		(start 210.523074 -29.85897)
		(end 210.556094 -29.853128)
		(stroke
			(width 0.06985)
			(type default)
		)
		(layer "In2.Cu")
	)
	(gr_line
		(start 210.538314 -62.000638)
		(end 210.541616 -62.019688)
		(stroke
			(width 0.06985)
			(type default)
		)
		(layer "In2.Cu")
	)
	(gr_line
		(start 210.538314 -62.000638)
		(end 210.541616 -61.981842)
		(stroke
			(width 0.06985)
			(type default)
		)
		(layer "In2.Cu")
	)
	(gr_line
		(start 210.556094 -29.853128)
		(end 210.584034 -29.83357)
		(stroke
			(width 0.06985)
			(type default)
		)
		(layer "In2.Cu")
	)
	(gr_line
		(start 210.55711 -42.916348)
		(end 210.765136 -43.051476)
		(stroke
			(width 0.06985)
			(type default)
		)
		(layer "In2.Cu")
	)
	(gr_line
		(start 210.585812 -206.17053)
		(end 210.585812 -206.170784)
		(stroke
			(width 0.06985)
			(type default)
		)
		(layer "In2.Cu")
	)
	(gr_line
		(start 210.585812 -206.17053)
		(end 210.589114 -206.151734)
		(stroke
			(width 0.06985)
			(type default)
		)
		(layer "In2.Cu")
	)
	(gr_line
		(start 210.585812 -206.132938)
		(end 210.589114 -206.151734)
		(stroke
			(width 0.06985)
			(type default)
		)
		(layer "In2.Cu")
	)
	(gr_line
		(start 210.765136 -43.051476)
		(end 211.175092 -42.964354)
		(stroke
			(width 0.06985)
			(type default)
		)
		(layer "In2.Cu")
	)
	(gr_line
		(start 210.78698 -44.120054)
		(end 210.810602 -44.104814)
		(stroke
			(width 0.06985)
			(type default)
		)
		(layer "In2.Cu")
	)
	(gr_line
		(start 210.810602 -44.104814)
		(end 210.83778 -44.099988)
		(stroke
			(width 0.06985)
			(type default)
		)
		(layer "In2.Cu")
	)
	(gr_line
		(start 210.945984 -69.670422)
		(end 210.945984 -69.670676)
		(stroke
			(width 0.06985)
			(type default)
		)
		(layer "In2.Cu")
	)
	(gr_line
		(start 210.945984 -69.670422)
		(end 210.949286 -69.651626)
		(stroke
			(width 0.06985)
			(type default)
		)
		(layer "In2.Cu")
	)
	(gr_line
		(start 210.945984 -69.63283)
		(end 210.949286 -69.651626)
		(stroke
			(width 0.06985)
			(type default)
		)
		(layer "In2.Cu")
	)
	(gr_line
		(start 210.96351 -211.241894)
		(end 210.963764 -211.242148)
		(stroke
			(width 0.06985)
			(type default)
		)
		(layer "In2.Cu")
	)
	(gr_line
		(start 210.96351 -211.24164)
		(end 210.964018 -211.239608)
		(stroke
			(width 0.06985)
			(type default)
		)
		(layer "In2.Cu")
	)
	(gr_line
		(start 211.106512 -49.908968)
		(end 211.117434 -49.893474)
		(stroke
			(width 0.06985)
			(type default)
		)
		(layer "In2.Cu")
	)
	(gr_line
		(start 211.110576 -71.29653)
		(end 211.113878 -71.31558)
		(stroke
			(width 0.06985)
			(type default)
		)
		(layer "In2.Cu")
	)
	(gr_line
		(start 211.110576 -71.29653)
		(end 211.113878 -71.277734)
		(stroke
			(width 0.06985)
			(type default)
		)
		(layer "In2.Cu")
	)
	(gr_line
		(start 211.117434 -49.893474)
		(end 211.132928 -49.882552)
		(stroke
			(width 0.06985)
			(type default)
		)
		(layer "In2.Cu")
	)
	(gr_line
		(start 211.175092 -42.964354)
		(end 211.309966 -42.756328)
		(stroke
			(width 0.06985)
			(type default)
		)
		(layer "In2.Cu")
	)
	(gr_line
		(start 211.197444 -30.546802)
		(end 211.230464 -30.54096)
		(stroke
			(width 0.06985)
			(type default)
		)
		(layer "In2.Cu")
	)
	(gr_line
		(start 211.230464 -30.54096)
		(end 211.258404 -30.521402)
		(stroke
			(width 0.06985)
			(type default)
		)
		(layer "In2.Cu")
	)
	(gr_line
		(start 211.235036 -42.432224)
		(end 211.24926 -42.428922)
		(stroke
			(width 0.06985)
			(type default)
		)
		(layer "In2.Cu")
	)
	(gr_arc
		(start 211.29371 -222.294704)
		(mid 211.472337 -222.02737)
		(end 211.53501 -221.712028)
		(stroke
			(width 0.06985)
			(type default)
		)
		(layer "In2.Cu")
	)
	(gr_line
		(start 211.311998 -42.75328)
		(end 211.31784 -42.75201)
		(stroke
			(width 0.06985)
			(type default)
		)
		(layer "In2.Cu")
	)
	(gr_line
		(start 211.413852 -31.400496)
		(end 211.446872 -31.394654)
		(stroke
			(width 0.06985)
			(type default)
		)
		(layer "In2.Cu")
	)
	(gr_line
		(start 211.446872 -31.394654)
		(end 211.474812 -31.375096)
		(stroke
			(width 0.06985)
			(type default)
		)
		(layer "In2.Cu")
	)
	(gr_line
		(start 211.579968 -56.093868)
		(end 211.58581 -56.060848)
		(stroke
			(width 0.06985)
			(type default)
		)
		(layer "In2.Cu")
	)
	(gr_line
		(start 211.58581 -56.060848)
		(end 211.605368 -56.032908)
		(stroke
			(width 0.06985)
			(type default)
		)
		(layer "In2.Cu")
	)
	(gr_line
		(start 211.632038 -169.632122)
		(end 211.63788 -169.599102)
		(stroke
			(width 0.06985)
			(type default)
		)
		(layer "In2.Cu")
	)
	(gr_line
		(start 211.63788 -169.599102)
		(end 211.657438 -169.571162)
		(stroke
			(width 0.06985)
			(type default)
		)
		(layer "In2.Cu")
	)
	(gr_line
		(start 211.692998 -42.334688)
		(end 212.371686 -42.190416)
		(stroke
			(width 0.06985)
			(type default)
		)
		(layer "In2.Cu")
	)
	(gr_line
		(start 211.714842 -76.15174)
		(end 211.7344 -76.1238)
		(stroke
			(width 0.06985)
			(type default)
		)
		(layer "In2.Cu")
	)
	(gr_line
		(start 211.724748 -45.022008)
		(end 211.752688 -45.00245)
		(stroke
			(width 0.06985)
			(type default)
		)
		(layer "In2.Cu")
	)
	(gr_line
		(start 211.725002 -42.66819)
		(end 211.933028 -42.803318)
		(stroke
			(width 0.06985)
			(type default)
		)
		(layer "In2.Cu")
	)
	(gr_line
		(start 211.7344 -76.1238)
		(end 211.740242 -76.09078)
		(stroke
			(width 0.06985)
			(type default)
		)
		(layer "In2.Cu")
	)
	(gr_line
		(start 211.752688 -45.00245)
		(end 211.785708 -44.996608)
		(stroke
			(width 0.06985)
			(type default)
		)
		(layer "In2.Cu")
	)
	(gr_arc
		(start 211.86521 -221.712028)
		(mid 211.927892 -222.02737)
		(end 212.10651 -222.294704)
		(stroke
			(width 0.06985)
			(type default)
		)
		(layer "In2.Cu")
	)
	(gr_line
		(start 211.933028 -42.803318)
		(end 212.342984 -42.715942)
		(stroke
			(width 0.06985)
			(type default)
		)
		(layer "In2.Cu")
	)
	(gr_line
		(start 211.976462 -68.290694)
		(end 211.976462 -68.290948)
		(stroke
			(width 0.06985)
			(type default)
		)
		(layer "In2.Cu")
	)
	(gr_line
		(start 211.976462 -68.290694)
		(end 211.979764 -68.271898)
		(stroke
			(width 0.06985)
			(type default)
		)
		(layer "In2.Cu")
	)
	(gr_line
		(start 211.976462 -68.253102)
		(end 211.979764 -68.271898)
		(stroke
			(width 0.06985)
			(type default)
		)
		(layer "In2.Cu")
	)
	(gr_line
		(start 212.01253 -74.546206)
		(end 212.01253 -74.54646)
		(stroke
			(width 0.06985)
			(type default)
		)
		(layer "In2.Cu")
	)
	(gr_line
		(start 212.01253 -74.546206)
		(end 212.015832 -74.52741)
		(stroke
			(width 0.06985)
			(type default)
		)
		(layer "In2.Cu")
	)
	(gr_line
		(start 212.01253 -74.508614)
		(end 212.015832 -74.52741)
		(stroke
			(width 0.06985)
			(type default)
		)
		(layer "In2.Cu")
	)
	(gr_line
		(start 212.022944 -61.763656)
		(end 212.026246 -61.782706)
		(stroke
			(width 0.06985)
			(type default)
		)
		(layer "In2.Cu")
	)
	(gr_line
		(start 212.022944 -61.763656)
		(end 212.026246 -61.74486)
		(stroke
			(width 0.06985)
			(type default)
		)
		(layer "In2.Cu")
	)
	(gr_line
		(start 212.086698 -206.774796)
		(end 212.086698 -206.77505)
		(stroke
			(width 0.06985)
			(type default)
		)
		(layer "In2.Cu")
	)
	(gr_line
		(start 212.086698 -206.774796)
		(end 212.09 -206.756)
		(stroke
			(width 0.06985)
			(type default)
		)
		(layer "In2.Cu")
	)
	(gr_line
		(start 212.086698 -206.737204)
		(end 212.09 -206.756)
		(stroke
			(width 0.06985)
			(type default)
		)
		(layer "In2.Cu")
	)
	(gr_line
		(start 212.174582 -45.975778)
		(end 212.202522 -45.95622)
		(stroke
			(width 0.06985)
			(type default)
		)
		(layer "In2.Cu")
	)
	(gr_line
		(start 212.202522 -45.95622)
		(end 212.235542 -45.950378)
		(stroke
			(width 0.06985)
			(type default)
		)
		(layer "In2.Cu")
	)
	(gr_line
		(start 212.289136 -22.738588)
		(end 212.29066 -22.737572)
		(stroke
			(width 0.06985)
			(type default)
		)
		(layer "In2.Cu")
	)
	(gr_line
		(start 212.303106 -217.146378)
		(end 212.303106 -217.146632)
		(stroke
			(width 0.06985)
			(type default)
		)
		(layer "In2.Cu")
	)
	(gr_line
		(start 212.303106 -217.146378)
		(end 212.306408 -217.127582)
		(stroke
			(width 0.06985)
			(type default)
		)
		(layer "In2.Cu")
	)
	(gr_line
		(start 212.303106 -217.108532)
		(end 212.306408 -217.127582)
		(stroke
			(width 0.06985)
			(type default)
		)
		(layer "In2.Cu")
	)
	(gr_line
		(start 212.342984 -42.715942)
		(end 212.477858 -42.50817)
		(stroke
			(width 0.06985)
			(type default)
		)
		(layer "In2.Cu")
	)
	(gr_line
		(start 212.34781 -50.672492)
		(end 212.358732 -50.656998)
		(stroke
			(width 0.06985)
			(type default)
		)
		(layer "In2.Cu")
	)
	(gr_line
		(start 212.358732 -50.656998)
		(end 212.374226 -50.646076)
		(stroke
			(width 0.06985)
			(type default)
		)
		(layer "In2.Cu")
	)
	(gr_line
		(start 212.60054 -52.595272)
		(end 212.611462 -52.579778)
		(stroke
			(width 0.06985)
			(type default)
		)
		(layer "In2.Cu")
	)
	(gr_line
		(start 212.611462 -52.579778)
		(end 212.626956 -52.568856)
		(stroke
			(width 0.06985)
			(type default)
		)
		(layer "In2.Cu")
	)
	(gr_line
		(start 212.638386 -38.981634)
		(end 212.662516 -38.976554)
		(stroke
			(width 0.06985)
			(type default)
		)
		(layer "In2.Cu")
	)
	(gr_line
		(start 212.662516 -38.976554)
		(end 212.687154 -38.980872)
		(stroke
			(width 0.06985)
			(type default)
		)
		(layer "In2.Cu")
	)
	(gr_line
		(start 212.664294 -34.808414)
		(end 212.68309 -34.805112)
		(stroke
			(width 0.06985)
			(type default)
		)
		(layer "In2.Cu")
	)
	(gr_line
		(start 212.68309 -34.805112)
		(end 212.701886 -34.808414)
		(stroke
			(width 0.06985)
			(type default)
		)
		(layer "In2.Cu")
	)
	(gr_line
		(start 212.708744 -78.499462)
		(end 212.728302 -78.471522)
		(stroke
			(width 0.06985)
			(type default)
		)
		(layer "In2.Cu")
	)
	(gr_line
		(start 212.728302 -78.471522)
		(end 212.734144 -78.438502)
		(stroke
			(width 0.06985)
			(type default)
		)
		(layer "In2.Cu")
	)
	(gr_line
		(start 212.771736 -37.955982)
		(end 212.795866 -37.950902)
		(stroke
			(width 0.06985)
			(type default)
		)
		(layer "In2.Cu")
	)
	(gr_line
		(start 212.795866 -37.950902)
		(end 212.820504 -37.95522)
		(stroke
			(width 0.06985)
			(type default)
		)
		(layer "In2.Cu")
	)
	(gr_line
		(start 212.804756 -35.87496)
		(end 212.823552 -35.871658)
		(stroke
			(width 0.06985)
			(type default)
		)
		(layer "In2.Cu")
	)
	(gr_line
		(start 212.818472 -57.253632)
		(end 212.824314 -57.220612)
		(stroke
			(width 0.06985)
			(type default)
		)
		(layer "In2.Cu")
	)
	(gr_line
		(start 212.81898 -170.447208)
		(end 212.824822 -170.414188)
		(stroke
			(width 0.06985)
			(type default)
		)
		(layer "In2.Cu")
	)
	(gr_line
		(start 212.823552 -35.871658)
		(end 212.842348 -35.87496)
		(stroke
			(width 0.06985)
			(type default)
		)
		(layer "In2.Cu")
	)
	(gr_line
		(start 212.824314 -57.220612)
		(end 212.843872 -57.192672)
		(stroke
			(width 0.06985)
			(type default)
		)
		(layer "In2.Cu")
	)
	(gr_line
		(start 212.824822 -170.414188)
		(end 212.84438 -170.386248)
		(stroke
			(width 0.06985)
			(type default)
		)
		(layer "In2.Cu")
	)
	(gr_line
		(start 212.860382 -42.08653)
		(end 213.539324 -41.942258)
		(stroke
			(width 0.06985)
			(type default)
		)
		(layer "In2.Cu")
	)
	(gr_line
		(start 212.892894 -42.419778)
		(end 213.100666 -42.554906)
		(stroke
			(width 0.06985)
			(type default)
		)
		(layer "In2.Cu")
	)
	(gr_line
		(start 212.95868 -33.818322)
		(end 212.977476 -33.81502)
		(stroke
			(width 0.06985)
			(type default)
		)
		(layer "In2.Cu")
	)
	(gr_line
		(start 212.977476 -33.81502)
		(end 212.996272 -33.818322)
		(stroke
			(width 0.06985)
			(type default)
		)
		(layer "In2.Cu")
	)
	(gr_line
		(start 213.039706 -32.790638)
		(end 213.058502 -32.787336)
		(stroke
			(width 0.06985)
			(type default)
		)
		(layer "In2.Cu")
	)
	(gr_line
		(start 213.058502 -32.787336)
		(end 213.077298 -32.790638)
		(stroke
			(width 0.06985)
			(type default)
		)
		(layer "In2.Cu")
	)
	(gr_line
		(start 213.100666 -42.554906)
		(end 213.510622 -42.467784)
		(stroke
			(width 0.06985)
			(type default)
		)
		(layer "In2.Cu")
	)
	(gr_line
		(start 213.147402 -205.803246)
		(end 213.153244 -205.836266)
		(stroke
			(width 0.06985)
			(type default)
		)
		(layer "In2.Cu")
	)
	(gr_line
		(start 213.153244 -205.836266)
		(end 213.172802 -205.864206)
		(stroke
			(width 0.06985)
			(type default)
		)
		(layer "In2.Cu")
	)
	(gr_line
		(start 213.2076 -31.77794)
		(end 213.226396 -31.774638)
		(stroke
			(width 0.06985)
			(type default)
		)
		(layer "In2.Cu")
	)
	(gr_line
		(start 213.226396 -31.774638)
		(end 213.245192 -31.77794)
		(stroke
			(width 0.06985)
			(type default)
		)
		(layer "In2.Cu")
	)
	(gr_line
		(start 213.280752 -36.83508)
		(end 213.310216 -36.82873)
		(stroke
			(width 0.06985)
			(type default)
		)
		(layer "In2.Cu")
	)
	(gr_line
		(start 213.310216 -36.82873)
		(end 213.33968 -36.83508)
		(stroke
			(width 0.06985)
			(type default)
		)
		(layer "In2.Cu")
	)
	(gr_line
		(start 213.32571 -53.575966)
		(end 213.336632 -53.560472)
		(stroke
			(width 0.06985)
			(type default)
		)
		(layer "In2.Cu")
	)
	(gr_line
		(start 213.336632 -53.560472)
		(end 213.352126 -53.54955)
		(stroke
			(width 0.06985)
			(type default)
		)
		(layer "In2.Cu")
	)
	(gr_line
		(start 213.418166 -67.810888)
		(end 213.418166 -67.811142)
		(stroke
			(width 0.06985)
			(type default)
		)
		(layer "In2.Cu")
	)
	(gr_line
		(start 213.418166 -67.810888)
		(end 213.421468 -67.792092)
		(stroke
			(width 0.06985)
			(type default)
		)
		(layer "In2.Cu")
	)
	(gr_line
		(start 213.418166 -67.773296)
		(end 213.421468 -67.792092)
		(stroke
			(width 0.06985)
			(type default)
		)
		(layer "In2.Cu")
	)
	(gr_line
		(start 213.510622 -42.467784)
		(end 213.64575 -42.260012)
		(stroke
			(width 0.06985)
			(type default)
		)
		(layer "In2.Cu")
	)
	(gr_line
		(start 213.524846 -63.73241)
		(end 213.528148 -63.75146)
		(stroke
			(width 0.06985)
			(type default)
		)
		(layer "In2.Cu")
	)
	(gr_line
		(start 213.524846 -63.73241)
		(end 213.528148 -63.713614)
		(stroke
			(width 0.06985)
			(type default)
		)
		(layer "In2.Cu")
	)
	(gr_line
		(start 213.615778 -79.02956)
		(end 213.635336 -79.00162)
		(stroke
			(width 0.06985)
			(type default)
		)
		(layer "In2.Cu")
	)
	(gr_line
		(start 213.635336 -79.00162)
		(end 213.641178 -78.9686)
		(stroke
			(width 0.06985)
			(type default)
		)
		(layer "In2.Cu")
	)
	(gr_line
		(start 213.659466 -70.739)
		(end 213.662768 -70.75805)
		(stroke
			(width 0.06985)
			(type default)
		)
		(layer "In2.Cu")
	)
	(gr_line
		(start 213.659466 -70.739)
		(end 213.662768 -70.720204)
		(stroke
			(width 0.06985)
			(type default)
		)
		(layer "In2.Cu")
	)
	(gr_line
		(start 213.805008 -23.645876)
		(end 213.832948 -23.626318)
		(stroke
			(width 0.06985)
			(type default)
		)
		(layer "In2.Cu")
	)
	(gr_line
		(start 213.832948 -23.626318)
		(end 213.865968 -23.620476)
		(stroke
			(width 0.06985)
			(type default)
		)
		(layer "In2.Cu")
	)
	(gr_line
		(start 213.991952 -41.843706)
		(end 213.996016 -41.839642)
		(stroke
			(width 0.06985)
			(type default)
		)
		(layer "In2.Cu")
	)
	(gr_line
		(start 214.000588 -24.59863)
		(end 214.028528 -24.579072)
		(stroke
			(width 0.06985)
			(type default)
		)
		(layer "In2.Cu")
	)
	(gr_line
		(start 214.028528 -24.579072)
		(end 214.061548 -24.57323)
		(stroke
			(width 0.06985)
			(type default)
		)
		(layer "In2.Cu")
	)
	(gr_line
		(start 214.067644 -22.50821)
		(end 214.091266 -22.49297)
		(stroke
			(width 0.06985)
			(type default)
		)
		(layer "In2.Cu")
	)
	(gr_line
		(start 214.091266 -22.49297)
		(end 214.118444 -22.488144)
		(stroke
			(width 0.06985)
			(type default)
		)
		(layer "In2.Cu")
	)
	(gr_line
		(start 214.098886 -82.00644)
		(end 214.118444 -81.9785)
		(stroke
			(width 0.06985)
			(type default)
		)
		(layer "In2.Cu")
	)
	(gr_line
		(start 214.118444 -81.9785)
		(end 214.124286 -81.94548)
		(stroke
			(width 0.06985)
			(type default)
		)
		(layer "In2.Cu")
	)
	(gr_line
		(start 214.36203 -28.950158)
		(end 214.387938 -28.932124)
		(stroke
			(width 0.06985)
			(type default)
		)
		(layer "In2.Cu")
	)
	(gr_line
		(start 214.387938 -28.932124)
		(end 214.418672 -28.926536)
		(stroke
			(width 0.06985)
			(type default)
		)
		(layer "In2.Cu")
	)
	(gr_line
		(start 214.447628 -218.645994)
		(end 214.45093 -218.665044)
		(stroke
			(width 0.06985)
			(type default)
		)
		(layer "In2.Cu")
	)
	(gr_line
		(start 214.447628 -218.645994)
		(end 214.45093 -218.627198)
		(stroke
			(width 0.06985)
			(type default)
		)
		(layer "In2.Cu")
	)
	(gr_line
		(start 214.466932 -25.584658)
		(end 214.494872 -25.5651)
		(stroke
			(width 0.06985)
			(type default)
		)
		(layer "In2.Cu")
	)
	(gr_line
		(start 214.478108 -20.286218)
		(end 214.500206 -20.27174)
		(stroke
			(width 0.06985)
			(type default)
		)
		(layer "In2.Cu")
	)
	(gr_arc
		(start 214.493602 -222.294704)
		(mid 214.672169 -222.027353)
		(end 214.734902 -221.712028)
		(stroke
			(width 0.06985)
			(type default)
		)
		(layer "In2.Cu")
	)
	(gr_line
		(start 214.494872 -25.5651)
		(end 214.527892 -25.559258)
		(stroke
			(width 0.06985)
			(type default)
		)
		(layer "In2.Cu")
	)
	(gr_line
		(start 214.500206 -20.27174)
		(end 214.52713 -20.266914)
		(stroke
			(width 0.06985)
			(type default)
		)
		(layer "In2.Cu")
	)
	(gr_line
		(start 214.520272 -26.672794)
		(end 214.548212 -26.653236)
		(stroke
			(width 0.06985)
			(type default)
		)
		(layer "In2.Cu")
	)
	(gr_line
		(start 214.540338 -73.86955)
		(end 214.540338 -73.869804)
		(stroke
			(width 0.06985)
			(type default)
		)
		(layer "In2.Cu")
	)
	(gr_line
		(start 214.540338 -73.86955)
		(end 214.54364 -73.850754)
		(stroke
			(width 0.06985)
			(type default)
		)
		(layer "In2.Cu")
	)
	(gr_line
		(start 214.540338 -73.831958)
		(end 214.54364 -73.850754)
		(stroke
			(width 0.06985)
			(type default)
		)
		(layer "In2.Cu")
	)
	(gr_line
		(start 214.542116 -67.63639)
		(end 214.542116 -67.636644)
		(stroke
			(width 0.06985)
			(type default)
		)
		(layer "In2.Cu")
	)
	(gr_line
		(start 214.542116 -67.63639)
		(end 214.545418 -67.617594)
		(stroke
			(width 0.06985)
			(type default)
		)
		(layer "In2.Cu")
	)
	(gr_line
		(start 214.542116 -67.598798)
		(end 214.545418 -67.617594)
		(stroke
			(width 0.06985)
			(type default)
		)
		(layer "In2.Cu")
	)
	(gr_line
		(start 214.548212 -26.653236)
		(end 214.581232 -26.647394)
		(stroke
			(width 0.06985)
			(type default)
		)
		(layer "In2.Cu")
	)
	(gr_line
		(start 214.59317 -27.783028)
		(end 214.620348 -27.763978)
		(stroke
			(width 0.06985)
			(type default)
		)
		(layer "In2.Cu")
	)
	(gr_line
		(start 214.620348 -27.763978)
		(end 214.65286 -27.758136)
		(stroke
			(width 0.06985)
			(type default)
		)
		(layer "In2.Cu")
	)
	(gr_line
		(start 214.66556 -207.419956)
		(end 214.685118 -207.447896)
		(stroke
			(width 0.06985)
			(type default)
		)
		(layer "In2.Cu")
	)
	(gr_line
		(start 214.685118 -207.447896)
		(end 214.69096 -207.480916)
		(stroke
			(width 0.06985)
			(type default)
		)
		(layer "In2.Cu")
	)
	(gr_line
		(start 214.8078 -63.412624)
		(end 214.811102 -63.431674)
		(stroke
			(width 0.06985)
			(type default)
		)
		(layer "In2.Cu")
	)
	(gr_line
		(start 214.8078 -63.412624)
		(end 214.811102 -63.393828)
		(stroke
			(width 0.06985)
			(type default)
		)
		(layer "In2.Cu")
	)
	(gr_line
		(start 214.826088 -56.352186)
		(end 214.83193 -56.319166)
		(stroke
			(width 0.06985)
			(type default)
		)
		(layer "In2.Cu")
	)
	(gr_line
		(start 214.83193 -56.319166)
		(end 214.851488 -56.291226)
		(stroke
			(width 0.06985)
			(type default)
		)
		(layer "In2.Cu")
	)
	(gr_line
		(start 214.931498 -70.993254)
		(end 214.9348 -71.012304)
		(stroke
			(width 0.06985)
			(type default)
		)
		(layer "In2.Cu")
	)
	(gr_line
		(start 214.931498 -70.993254)
		(end 214.9348 -70.974458)
		(stroke
			(width 0.06985)
			(type default)
		)
		(layer "In2.Cu")
	)
	(gr_arc
		(start 215.065102 -221.712028)
		(mid 215.127784 -222.027371)
		(end 215.306402 -222.294704)
		(stroke
			(width 0.06985)
			(type default)
		)
		(layer "In2.Cu")
	)
	(gr_line
		(start 215.185244 -53.848762)
		(end 215.196166 -53.833268)
		(stroke
			(width 0.06985)
			(type default)
		)
		(layer "In2.Cu")
	)
	(gr_line
		(start 215.196166 -53.833268)
		(end 215.21166 -53.822346)
		(stroke
			(width 0.06985)
			(type default)
		)
		(layer "In2.Cu")
	)
	(gr_line
		(start 215.321642 -82.3976)
		(end 215.3412 -82.36966)
		(stroke
			(width 0.06985)
			(type default)
		)
		(layer "In2.Cu")
	)
	(gr_line
		(start 215.3412 -82.36966)
		(end 215.347042 -82.33664)
		(stroke
			(width 0.06985)
			(type default)
		)
		(layer "In2.Cu")
	)
	(gr_line
		(start 215.341962 -215.477344)
		(end 215.341962 -215.477598)
		(stroke
			(width 0.06985)
			(type default)
		)
		(layer "In2.Cu")
	)
	(gr_line
		(start 215.341962 -215.477344)
		(end 215.345264 -215.458548)
		(stroke
			(width 0.06985)
			(type default)
		)
		(layer "In2.Cu")
	)
	(gr_line
		(start 215.341962 -215.439752)
		(end 215.345264 -215.458548)
		(stroke
			(width 0.06985)
			(type default)
		)
		(layer "In2.Cu")
	)
	(gr_line
		(start 215.658192 -73.24979)
		(end 215.658192 -73.250044)
		(stroke
			(width 0.06985)
			(type default)
		)
		(layer "In2.Cu")
	)
	(gr_line
		(start 215.658192 -73.24979)
		(end 215.661494 -73.230994)
		(stroke
			(width 0.06985)
			(type default)
		)
		(layer "In2.Cu")
	)
	(gr_line
		(start 215.658192 -73.212198)
		(end 215.661494 -73.230994)
		(stroke
			(width 0.06985)
			(type default)
		)
		(layer "In2.Cu")
	)
	(gr_line
		(start 215.870282 -67.572382)
		(end 215.870282 -67.572636)
		(stroke
			(width 0.06985)
			(type default)
		)
		(layer "In2.Cu")
	)
	(gr_line
		(start 215.870282 -67.572382)
		(end 215.873584 -67.553586)
		(stroke
			(width 0.06985)
			(type default)
		)
		(layer "In2.Cu")
	)
	(gr_line
		(start 215.870282 -67.53479)
		(end 215.873584 -67.553586)
		(stroke
			(width 0.06985)
			(type default)
		)
		(layer "In2.Cu")
	)
	(gr_line
		(start 215.897206 -62.249304)
		(end 215.900508 -62.268354)
		(stroke
			(width 0.06985)
			(type default)
		)
		(layer "In2.Cu")
	)
	(gr_line
		(start 215.897206 -62.249304)
		(end 215.900508 -62.230508)
		(stroke
			(width 0.06985)
			(type default)
		)
		(layer "In2.Cu")
	)
	(gr_line
		(start 215.934798 -57.02173)
		(end 215.94064 -56.98871)
		(stroke
			(width 0.06985)
			(type default)
		)
		(layer "In2.Cu")
	)
	(gr_line
		(start 215.94064 -56.98871)
		(end 215.960198 -56.96077)
		(stroke
			(width 0.06985)
			(type default)
		)
		(layer "In2.Cu")
	)
	(gr_line
		(start 215.96858 -54.695852)
		(end 215.979502 -54.680358)
		(stroke
			(width 0.06985)
			(type default)
		)
		(layer "In2.Cu")
	)
	(gr_line
		(start 215.979502 -54.680358)
		(end 215.994996 -54.669436)
		(stroke
			(width 0.06985)
			(type default)
		)
		(layer "In2.Cu")
	)
	(gr_line
		(start 216.050876 -72.009254)
		(end 216.054178 -72.028304)
		(stroke
			(width 0.06985)
			(type default)
		)
		(layer "In2.Cu")
	)
	(gr_line
		(start 216.050876 -72.009254)
		(end 216.054178 -71.990458)
		(stroke
			(width 0.06985)
			(type default)
		)
		(layer "In2.Cu")
	)
	(gr_line
		(start 216.213436 -46.325282)
		(end 216.241376 -46.305724)
		(stroke
			(width 0.06985)
			(type default)
		)
		(layer "In2.Cu")
	)
	(gr_line
		(start 216.238582 -47.940214)
		(end 216.266522 -47.920656)
		(stroke
			(width 0.06985)
			(type default)
		)
		(layer "In2.Cu")
	)
	(gr_line
		(start 216.241376 -46.305724)
		(end 216.274396 -46.299882)
		(stroke
			(width 0.06985)
			(type default)
		)
		(layer "In2.Cu")
	)
	(gr_line
		(start 216.266522 -47.920656)
		(end 216.299542 -47.914814)
		(stroke
			(width 0.06985)
			(type default)
		)
		(layer "In2.Cu")
	)
	(gr_line
		(start 216.441782 -23.501858)
		(end 216.474802 -23.496016)
		(stroke
			(width 0.06985)
			(type default)
		)
		(layer "In2.Cu")
	)
	(gr_line
		(start 216.474802 -23.496016)
		(end 216.502742 -23.476458)
		(stroke
			(width 0.06985)
			(type default)
		)
		(layer "In2.Cu")
	)
	(gr_line
		(start 216.52484 -83.157568)
		(end 216.544398 -83.129628)
		(stroke
			(width 0.06985)
			(type default)
		)
		(layer "In2.Cu")
	)
	(gr_line
		(start 216.544398 -83.129628)
		(end 216.55024 -83.096608)
		(stroke
			(width 0.06985)
			(type default)
		)
		(layer "In2.Cu")
	)
	(gr_line
		(start 216.594944 -58.294016)
		(end 216.600786 -58.260996)
		(stroke
			(width 0.06985)
			(type default)
		)
		(layer "In2.Cu")
	)
	(gr_line
		(start 216.59596 -22.386798)
		(end 216.62898 -22.380956)
		(stroke
			(width 0.06985)
			(type default)
		)
		(layer "In2.Cu")
	)
	(gr_line
		(start 216.600786 -58.260996)
		(end 216.620344 -58.233056)
		(stroke
			(width 0.06985)
			(type default)
		)
		(layer "In2.Cu")
	)
	(gr_line
		(start 216.62898 -22.380956)
		(end 216.65692 -22.361398)
		(stroke
			(width 0.06985)
			(type default)
		)
		(layer "In2.Cu")
	)
	(gr_line
		(start 216.774268 -74.246232)
		(end 216.774268 -74.246486)
		(stroke
			(width 0.06985)
			(type default)
		)
		(layer "In2.Cu")
	)
	(gr_line
		(start 216.774268 -74.246232)
		(end 216.77757 -74.227436)
		(stroke
			(width 0.06985)
			(type default)
		)
		(layer "In2.Cu")
	)
	(gr_line
		(start 216.774268 -74.20864)
		(end 216.77757 -74.227436)
		(stroke
			(width 0.06985)
			(type default)
		)
		(layer "In2.Cu")
	)
	(gr_line
		(start 216.984072 -62.067948)
		(end 216.987374 -62.086998)
		(stroke
			(width 0.06985)
			(type default)
		)
		(layer "In2.Cu")
	)
	(gr_line
		(start 216.984072 -62.067948)
		(end 216.987374 -62.049152)
		(stroke
			(width 0.06985)
			(type default)
		)
		(layer "In2.Cu")
	)
	(gr_line
		(start 217.12555 -55.296308)
		(end 217.136472 -55.280814)
		(stroke
			(width 0.06985)
			(type default)
		)
		(layer "In2.Cu")
	)
	(gr_line
		(start 217.136472 -55.280814)
		(end 217.151966 -55.269892)
		(stroke
			(width 0.06985)
			(type default)
		)
		(layer "In2.Cu")
	)
	(gr_line
		(start 217.166698 -67.582796)
		(end 217.166698 -67.58305)
		(stroke
			(width 0.06985)
			(type default)
		)
		(layer "In2.Cu")
	)
	(gr_line
		(start 217.166698 -67.582796)
		(end 217.17 -67.564)
		(stroke
			(width 0.06985)
			(type default)
		)
		(layer "In2.Cu")
	)
	(gr_line
		(start 217.166698 -67.545204)
		(end 217.17 -67.564)
		(stroke
			(width 0.06985)
			(type default)
		)
		(layer "In2.Cu")
	)
	(gr_line
		(start 217.442796 -70.482206)
		(end 217.445844 -70.499478)
		(stroke
			(width 0.06985)
			(type default)
		)
		(layer "In2.Cu")
	)
	(gr_line
		(start 217.442796 -70.482206)
		(end 217.445844 -70.465188)
		(stroke
			(width 0.06985)
			(type default)
		)
		(layer "In2.Cu")
	)
	(gr_line
		(start 217.520012 -49.14265)
		(end 217.547952 -49.123092)
		(stroke
			(width 0.06985)
			(type default)
		)
		(layer "In2.Cu")
	)
	(gr_line
		(start 217.547952 -49.123092)
		(end 217.580972 -49.11725)
		(stroke
			(width 0.06985)
			(type default)
		)
		(layer "In2.Cu")
	)
	(gr_line
		(start 217.581226 -52.163218)
		(end 217.609166 -52.14366)
		(stroke
			(width 0.06985)
			(type default)
		)
		(layer "In2.Cu")
	)
	(gr_line
		(start 217.581734 -58.679334)
		(end 217.587576 -58.646314)
		(stroke
			(width 0.06985)
			(type default)
		)
		(layer "In2.Cu")
	)
	(gr_line
		(start 217.587576 -58.646314)
		(end 217.607134 -58.618374)
		(stroke
			(width 0.06985)
			(type default)
		)
		(layer "In2.Cu")
	)
	(gr_line
		(start 217.592148 -20.062444)
		(end 217.625168 -20.056602)
		(stroke
			(width 0.06985)
			(type default)
		)
		(layer "In2.Cu")
	)
	(gr_line
		(start 217.609166 -52.14366)
		(end 217.642186 -52.137818)
		(stroke
			(width 0.06985)
			(type default)
		)
		(layer "In2.Cu")
	)
	(gr_line
		(start 217.625168 -20.056602)
		(end 217.653108 -20.037044)
		(stroke
			(width 0.06985)
			(type default)
		)
		(layer "In2.Cu")
	)
	(gr_line
		(start 217.974672 -42.839132)
		(end 217.976704 -42.8371)
		(stroke
			(width 0.06985)
			(type default)
		)
		(layer "In2.Cu")
	)
	(gr_line
		(start 218.07297 -82.387186)
		(end 218.092528 -82.359246)
		(stroke
			(width 0.06985)
			(type default)
		)
		(layer "In2.Cu")
	)
	(gr_line
		(start 218.092528 -82.359246)
		(end 218.09837 -82.326226)
		(stroke
			(width 0.06985)
			(type default)
		)
		(layer "In2.Cu")
	)
	(gr_line
		(start 218.166188 -53.149246)
		(end 218.194128 -53.129688)
		(stroke
			(width 0.06985)
			(type default)
		)
		(layer "In2.Cu")
	)
	(gr_line
		(start 218.194128 -53.129688)
		(end 218.227148 -53.123846)
		(stroke
			(width 0.06985)
			(type default)
		)
		(layer "In2.Cu")
	)
	(gr_line
		(start 218.221306 -50.140362)
		(end 218.249246 -50.120804)
		(stroke
			(width 0.06985)
			(type default)
		)
		(layer "In2.Cu")
	)
	(gr_line
		(start 218.249246 -50.120804)
		(end 218.282266 -50.114962)
		(stroke
			(width 0.06985)
			(type default)
		)
		(layer "In2.Cu")
	)
	(gr_line
		(start 218.267534 -73.363582)
		(end 218.270582 -73.346564)
		(stroke
			(width 0.06985)
			(type default)
		)
		(layer "In2.Cu")
	)
	(gr_line
		(start 218.267788 -73.330308)
		(end 218.270582 -73.346564)
		(stroke
			(width 0.06985)
			(type default)
		)
		(layer "In2.Cu")
	)
	(gr_line
		(start 218.269312 -55.877968)
		(end 218.280234 -55.862474)
		(stroke
			(width 0.06985)
			(type default)
		)
		(layer "In2.Cu")
	)
	(gr_line
		(start 218.280234 -55.862474)
		(end 218.295728 -55.851552)
		(stroke
			(width 0.06985)
			(type default)
		)
		(layer "In2.Cu")
	)
	(gr_line
		(start 218.287346 -67.593972)
		(end 218.287346 -67.594226)
		(stroke
			(width 0.06985)
			(type default)
		)
		(layer "In2.Cu")
	)
	(gr_line
		(start 218.287346 -67.593972)
		(end 218.290648 -67.575176)
		(stroke
			(width 0.06985)
			(type default)
		)
		(layer "In2.Cu")
	)
	(gr_line
		(start 218.287346 -67.55638)
		(end 218.290648 -67.575176)
		(stroke
			(width 0.06985)
			(type default)
		)
		(layer "In2.Cu")
	)
	(gr_line
		(start 218.615768 -61.700156)
		(end 218.61907 -61.719206)
		(stroke
			(width 0.06985)
			(type default)
		)
		(layer "In2.Cu")
	)
	(gr_line
		(start 218.615768 -61.700156)
		(end 218.61907 -61.68136)
		(stroke
			(width 0.06985)
			(type default)
		)
		(layer "In2.Cu")
	)
	(gr_line
		(start 218.716352 -35.164522)
		(end 218.718384 -35.166554)
		(stroke
			(width 0.06985)
			(type default)
		)
		(layer "In2.Cu")
	)
	(gr_line
		(start 218.770454 -56.95696)
		(end 218.781376 -56.941466)
		(stroke
			(width 0.06985)
			(type default)
		)
		(layer "In2.Cu")
	)
	(gr_line
		(start 218.773502 -54.134512)
		(end 218.801442 -54.114954)
		(stroke
			(width 0.06985)
			(type default)
		)
		(layer "In2.Cu")
	)
	(gr_line
		(start 218.781376 -56.941466)
		(end 218.79687 -56.930544)
		(stroke
			(width 0.06985)
			(type default)
		)
		(layer "In2.Cu")
	)
	(gr_line
		(start 218.801442 -54.114954)
		(end 218.834462 -54.109112)
		(stroke
			(width 0.06985)
			(type default)
		)
		(layer "In2.Cu")
	)
	(gr_line
		(start 218.91117 -71.032116)
		(end 218.914472 -71.051166)
		(stroke
			(width 0.06985)
			(type default)
		)
		(layer "In2.Cu")
	)
	(gr_line
		(start 218.91117 -71.032116)
		(end 218.914472 -71.01332)
		(stroke
			(width 0.06985)
			(type default)
		)
		(layer "In2.Cu")
	)
	(gr_line
		(start 218.914472 -71.050912)
		(end 218.914472 -71.051166)
		(stroke
			(width 0.06985)
			(type default)
		)
		(layer "In2.Cu")
	)
	(gr_line
		(start 219.03944 -59.295792)
		(end 219.05087 -59.23153)
		(stroke
			(width 0.06985)
			(type default)
		)
		(layer "In2.Cu")
	)
	(gr_line
		(start 219.208858 -33.167828)
		(end 219.21089 -33.16986)
		(stroke
			(width 0.06985)
			(type default)
		)
		(layer "In2.Cu")
	)
	(gr_line
		(start 219.24264 -82.491326)
		(end 219.262198 -82.463386)
		(stroke
			(width 0.06985)
			(type default)
		)
		(layer "In2.Cu")
	)
	(gr_line
		(start 219.262198 -82.463386)
		(end 219.26804 -82.430366)
		(stroke
			(width 0.06985)
			(type default)
		)
		(layer "In2.Cu")
	)
	(gr_line
		(start 219.285566 -18.490946)
		(end 219.313506 -18.471388)
		(stroke
			(width 0.06985)
			(type default)
		)
		(layer "In2.Cu")
	)
	(gr_line
		(start 219.313506 -18.471388)
		(end 219.346526 -18.465546)
		(stroke
			(width 0.06985)
			(type default)
		)
		(layer "In2.Cu")
	)
	(gr_line
		(start 219.416122 -55.066946)
		(end 219.444062 -55.047388)
		(stroke
			(width 0.06985)
			(type default)
		)
		(layer "In2.Cu")
	)
	(gr_line
		(start 219.444062 -55.047388)
		(end 219.477082 -55.041546)
		(stroke
			(width 0.06985)
			(type default)
		)
		(layer "In2.Cu")
	)
	(gr_line
		(start 219.664788 -73.442068)
		(end 219.664788 -73.442322)
		(stroke
			(width 0.06985)
			(type default)
		)
		(layer "In2.Cu")
	)
	(gr_line
		(start 219.664788 -73.442068)
		(end 219.66809 -73.423272)
		(stroke
			(width 0.06985)
			(type default)
		)
		(layer "In2.Cu")
	)
	(gr_line
		(start 219.664788 -73.404476)
		(end 219.66809 -73.423272)
		(stroke
			(width 0.06985)
			(type default)
		)
		(layer "In2.Cu")
	)
	(gr_line
		(start 219.898722 -70.044056)
		(end 219.902024 -70.06463)
		(stroke
			(width 0.06985)
			(type default)
		)
		(layer "In2.Cu")
	)
	(gr_line
		(start 219.898722 -70.044056)
		(end 219.902786 -70.024244)
		(stroke
			(width 0.06985)
			(type default)
		)
		(layer "In2.Cu")
	)
	(gr_line
		(start 219.91828 -67.223386)
		(end 219.91828 -67.22364)
		(stroke
			(width 0.06985)
			(type default)
		)
		(layer "In2.Cu")
	)
	(gr_line
		(start 219.91828 -67.223386)
		(end 219.921582 -67.20459)
		(stroke
			(width 0.06985)
			(type default)
		)
		(layer "In2.Cu")
	)
	(gr_line
		(start 219.91828 -67.185794)
		(end 219.921582 -67.20459)
		(stroke
			(width 0.06985)
			(type default)
		)
		(layer "In2.Cu")
	)
	(gr_line
		(start 220.066108 -56.041798)
		(end 220.094048 -56.02224)
		(stroke
			(width 0.06985)
			(type default)
		)
		(layer "In2.Cu")
	)
	(gr_line
		(start 220.094048 -56.02224)
		(end 220.127068 -56.016398)
		(stroke
			(width 0.06985)
			(type default)
		)
		(layer "In2.Cu")
	)
	(gr_line
		(start 220.150436 -19.511518)
		(end 220.175328 -19.494246)
		(stroke
			(width 0.06985)
			(type default)
		)
		(layer "In2.Cu")
	)
	(gr_line
		(start 220.170502 -20.504912)
		(end 220.195394 -20.48764)
		(stroke
			(width 0.06985)
			(type default)
		)
		(layer "In2.Cu")
	)
	(gr_line
		(start 220.175328 -19.494246)
		(end 220.204538 -19.488404)
		(stroke
			(width 0.06985)
			(type default)
		)
		(layer "In2.Cu")
	)
	(gr_line
		(start 220.195394 -20.48764)
		(end 220.224604 -20.481798)
		(stroke
			(width 0.06985)
			(type default)
		)
		(layer "In2.Cu")
	)
	(gr_line
		(start 220.211396 -59.368182)
		(end 220.222826 -59.30392)
		(stroke
			(width 0.06985)
			(type default)
		)
		(layer "In2.Cu")
	)
	(gr_line
		(start 220.23959 -83.700366)
		(end 220.259148 -83.672426)
		(stroke
			(width 0.06985)
			(type default)
		)
		(layer "In2.Cu")
	)
	(gr_line
		(start 220.259148 -83.672426)
		(end 220.26499 -83.639406)
		(stroke
			(width 0.06985)
			(type default)
		)
		(layer "In2.Cu")
	)
	(gr_line
		(start 220.464634 -38.16223)
		(end 220.490034 -38.16223)
		(stroke
			(width 0.0508)
			(type default)
		)
		(layer "In2.Cu")
	)
	(gr_line
		(start 220.464634 -37.83203)
		(end 220.490034 -37.83203)
		(stroke
			(width 0.0508)
			(type default)
		)
		(layer "In2.Cu")
	)
	(gr_line
		(start 220.47581 -39.166546)
		(end 220.550486 -39.166546)
		(stroke
			(width 0.0508)
			(type default)
		)
		(layer "In2.Cu")
	)
	(gr_line
		(start 220.490034 -38.16223)
		(end 220.509592 -38.142672)
		(stroke
			(width 0.0508)
			(type default)
		)
		(layer "In2.Cu")
	)
	(gr_line
		(start 220.490034 -37.83203)
		(end 220.509592 -37.851588)
		(stroke
			(width 0.0508)
			(type default)
		)
		(layer "In2.Cu")
	)
	(gr_line
		(start 220.51137 -38.140894)
		(end 220.553534 -38.09873)
		(stroke
			(width 0.0508)
			(type default)
		)
		(layer "In2.Cu")
	)
	(gr_line
		(start 220.51137 -37.853366)
		(end 220.553534 -37.89553)
		(stroke
			(width 0.0508)
			(type default)
		)
		(layer "In2.Cu")
	)
	(gr_line
		(start 220.525086 -38.836346)
		(end 220.550486 -38.836346)
		(stroke
			(width 0.0508)
			(type default)
		)
		(layer "In2.Cu")
	)
	(gr_line
		(start 220.550486 -39.166546)
		(end 220.570044 -39.146988)
		(stroke
			(width 0.0508)
			(type default)
		)
		(layer "In2.Cu")
	)
	(gr_line
		(start 220.550486 -38.836346)
		(end 220.570044 -38.855904)
		(stroke
			(width 0.0508)
			(type default)
		)
		(layer "In2.Cu")
	)
	(gr_line
		(start 220.571822 -39.14521)
		(end 220.613986 -39.103046)
		(stroke
			(width 0.0508)
			(type default)
		)
		(layer "In2.Cu")
	)
	(gr_line
		(start 220.571822 -38.857682)
		(end 220.613986 -38.899846)
		(stroke
			(width 0.0508)
			(type default)
		)
		(layer "In2.Cu")
	)
	(gr_line
		(start 220.642942 -40.161718)
		(end 220.717618 -40.161718)
		(stroke
			(width 0.0508)
			(type default)
		)
		(layer "In2.Cu")
	)
	(gr_line
		(start 220.692218 -39.831518)
		(end 220.717618 -39.831518)
		(stroke
			(width 0.0508)
			(type default)
		)
		(layer "In2.Cu")
	)
	(gr_line
		(start 220.717618 -40.161718)
		(end 220.737176 -40.14216)
		(stroke
			(width 0.0508)
			(type default)
		)
		(layer "In2.Cu")
	)
	(gr_line
		(start 220.717618 -39.831518)
		(end 220.737176 -39.851076)
		(stroke
			(width 0.0508)
			(type default)
		)
		(layer "In2.Cu")
	)
	(gr_line
		(start 220.738954 -40.140382)
		(end 220.781118 -40.098218)
		(stroke
			(width 0.0508)
			(type default)
		)
		(layer "In2.Cu")
	)
	(gr_line
		(start 220.738954 -39.852854)
		(end 220.781118 -39.895018)
		(stroke
			(width 0.0508)
			(type default)
		)
		(layer "In2.Cu")
	)
	(gr_line
		(start 220.8149 -67.146932)
		(end 220.81998 -67.121786)
		(stroke
			(width 0.06985)
			(type default)
		)
		(layer "In2.Cu")
	)
	(gr_line
		(start 220.8149 -67.097148)
		(end 220.81998 -67.121786)
		(stroke
			(width 0.06985)
			(type default)
		)
		(layer "In2.Cu")
	)
	(gr_line
		(start 220.824044 -73.603866)
		(end 220.827092 -73.58634)
		(stroke
			(width 0.06985)
			(type default)
		)
		(layer "In2.Cu")
	)
	(gr_line
		(start 220.824298 -73.568814)
		(end 220.827092 -73.58634)
		(stroke
			(width 0.06985)
			(type default)
		)
		(layer "In2.Cu")
	)
	(gr_line
		(start 221.009464 -68.766944)
		(end 221.013274 -68.78828)
		(stroke
			(width 0.06985)
			(type default)
		)
		(layer "In2.Cu")
	)
	(gr_line
		(start 221.009464 -68.766944)
		(end 221.013782 -68.746116)
		(stroke
			(width 0.06985)
			(type default)
		)
		(layer "In2.Cu")
	)
	(gr_line
		(start 221.056454 -33.850326)
		(end 221.245938 -33.850326)
		(stroke
			(width 0.06985)
			(type default)
		)
		(layer "In2.Cu")
	)
	(gr_line
		(start 221.09684 -85.196426)
		(end 221.116398 -85.168486)
		(stroke
			(width 0.06985)
			(type default)
		)
		(layer "In2.Cu")
	)
	(gr_line
		(start 221.09811 -60.096146)
		(end 221.109286 -60.033154)
		(stroke
			(width 0.06985)
			(type default)
		)
		(layer "In2.Cu")
	)
	(gr_line
		(start 221.109286 -60.033154)
		(end 221.15526 -59.98718)
		(stroke
			(width 0.06985)
			(type default)
		)
		(layer "In2.Cu")
	)
	(gr_line
		(start 221.116398 -85.168486)
		(end 221.12224 -85.133942)
		(stroke
			(width 0.06985)
			(type default)
		)
		(layer "In2.Cu")
	)
	(gr_line
		(start 221.116906 -37.169852)
		(end 221.142306 -37.169852)
		(stroke
			(width 0.0508)
			(type default)
		)
		(layer "In2.Cu")
	)
	(gr_line
		(start 221.116906 -36.839652)
		(end 221.142306 -36.839652)
		(stroke
			(width 0.0508)
			(type default)
		)
		(layer "In2.Cu")
	)
	(gr_line
		(start 221.142306 -37.169852)
		(end 221.161864 -37.150294)
		(stroke
			(width 0.0508)
			(type default)
		)
		(layer "In2.Cu")
	)
	(gr_line
		(start 221.142306 -36.839652)
		(end 221.161864 -36.85921)
		(stroke
			(width 0.0508)
			(type default)
		)
		(layer "In2.Cu")
	)
	(gr_line
		(start 221.163642 -37.148516)
		(end 221.205806 -37.106352)
		(stroke
			(width 0.0508)
			(type default)
		)
		(layer "In2.Cu")
	)
	(gr_line
		(start 221.163642 -36.860988)
		(end 221.205806 -36.903152)
		(stroke
			(width 0.0508)
			(type default)
		)
		(layer "In2.Cu")
	)
	(gr_line
		(start 221.245938 -33.850326)
		(end 221.26702 -33.871408)
		(stroke
			(width 0.0508)
			(type default)
		)
		(layer "In2.Cu")
	)
	(gr_line
		(start 221.248986 -34.180526)
		(end 221.26702 -34.162492)
		(stroke
			(width 0.0508)
			(type default)
		)
		(layer "In2.Cu")
	)
	(gr_line
		(start 221.268798 -34.160714)
		(end 221.323154 -34.106358)
		(stroke
			(width 0.0508)
			(type default)
		)
		(layer "In2.Cu")
	)
	(gr_line
		(start 221.268798 -33.873186)
		(end 221.29877 -33.903158)
		(stroke
			(width 0.0508)
			(type default)
		)
		(layer "In2.Cu")
	)
	(gr_line
		(start 221.273624 -48.8696)
		(end 221.346776 -48.8696)
		(stroke
			(width 0.06985)
			(type default)
		)
		(layer "In2.Cu")
	)
	(gr_line
		(start 221.284038 -45.124878)
		(end 221.314772 -45.124878)
		(stroke
			(width 0.06985)
			(type default)
		)
		(layer "In2.Cu")
	)
	(gr_line
		(start 221.303596 -36.161726)
		(end 221.328996 -36.161726)
		(stroke
			(width 0.0508)
			(type default)
		)
		(layer "In2.Cu")
	)
	(gr_line
		(start 221.303596 -35.831526)
		(end 221.328996 -35.831526)
		(stroke
			(width 0.0508)
			(type default)
		)
		(layer "In2.Cu")
	)
	(gr_line
		(start 221.314772 -45.124878)
		(end 221.342712 -45.096938)
		(stroke
			(width 0.0508)
			(type default)
		)
		(layer "In2.Cu")
	)
	(gr_line
		(start 221.319852 -33.16986)
		(end 221.345252 -33.16986)
		(stroke
			(width 0.0508)
			(type default)
		)
		(layer "In2.Cu")
	)
	(gr_line
		(start 221.319852 -32.83966)
		(end 221.345252 -32.83966)
		(stroke
			(width 0.0508)
			(type default)
		)
		(layer "In2.Cu")
	)
	(gr_line
		(start 221.323154 -34.106358)
		(end 221.512638 -34.106358)
		(stroke
			(width 0.0508)
			(type default)
		)
		(layer "In2.Cu")
	)
	(gr_line
		(start 221.328996 -36.161726)
		(end 221.348554 -36.142168)
		(stroke
			(width 0.0508)
			(type default)
		)
		(layer "In2.Cu")
	)
	(gr_line
		(start 221.328996 -35.831526)
		(end 221.348554 -35.851084)
		(stroke
			(width 0.0508)
			(type default)
		)
		(layer "In2.Cu")
	)
	(gr_line
		(start 221.342712 -45.096938)
		(end 221.344998 -45.096938)
		(stroke
			(width 0.0508)
			(type default)
		)
		(layer "In2.Cu")
	)
	(gr_line
		(start 221.345252 -33.16986)
		(end 221.36481 -33.150302)
		(stroke
			(width 0.0508)
			(type default)
		)
		(layer "In2.Cu")
	)
	(gr_line
		(start 221.345252 -32.83966)
		(end 221.36481 -32.859218)
		(stroke
			(width 0.0508)
			(type default)
		)
		(layer "In2.Cu")
	)
	(gr_line
		(start 221.346776 -48.8696)
		(end 221.370652 -48.893476)
		(stroke
			(width 0.0508)
			(type default)
		)
		(layer "In2.Cu")
	)
	(gr_line
		(start 221.350332 -36.14039)
		(end 221.392496 -36.098226)
		(stroke
			(width 0.0508)
			(type default)
		)
		(layer "In2.Cu")
	)
	(gr_line
		(start 221.350332 -35.852862)
		(end 221.392496 -35.895026)
		(stroke
			(width 0.0508)
			(type default)
		)
		(layer "In2.Cu")
	)
	(gr_line
		(start 221.35592 -35.166554)
		(end 221.38132 -35.166554)
		(stroke
			(width 0.0508)
			(type default)
		)
		(layer "In2.Cu")
	)
	(gr_line
		(start 221.35592 -34.836354)
		(end 221.38132 -34.836354)
		(stroke
			(width 0.0508)
			(type default)
		)
		(layer "In2.Cu")
	)
	(gr_line
		(start 221.366588 -33.148524)
		(end 221.408752 -33.10636)
		(stroke
			(width 0.0508)
			(type default)
		)
		(layer "In2.Cu")
	)
	(gr_line
		(start 221.366588 -32.860996)
		(end 221.408752 -32.90316)
		(stroke
			(width 0.0508)
			(type default)
		)
		(layer "In2.Cu")
	)
	(gr_line
		(start 221.38132 -35.166554)
		(end 221.400878 -35.146996)
		(stroke
			(width 0.0508)
			(type default)
		)
		(layer "In2.Cu")
	)
	(gr_line
		(start 221.38132 -34.836354)
		(end 221.400878 -34.855912)
		(stroke
			(width 0.0508)
			(type default)
		)
		(layer "In2.Cu")
	)
	(gr_arc
		(start 221.3864 -55.8292)
		(mid 221.562739 -55.877271)
		(end 221.744794 -55.893462)
		(stroke
			(width 0.0508)
			(type default)
		)
		(layer "In2.Cu")
	)
	(gr_line
		(start 221.400116 -45.8978)
		(end 221.452694 -45.8978)
		(stroke
			(width 0.06985)
			(type default)
		)
		(layer "In2.Cu")
	)
	(gr_line
		(start 221.402656 -35.145218)
		(end 221.44482 -35.103054)
		(stroke
			(width 0.0508)
			(type default)
		)
		(layer "In2.Cu")
	)
	(gr_line
		(start 221.402656 -34.85769)
		(end 221.44482 -34.899854)
		(stroke
			(width 0.0508)
			(type default)
		)
		(layer "In2.Cu")
	)
	(gr_line
		(start 221.427548 -51.8414)
		(end 221.5134 -51.8414)
		(stroke
			(width 0.06985)
			(type default)
		)
		(layer "In2.Cu")
	)
	(gr_line
		(start 221.4372 -49.1998)
		(end 221.537784 -49.099216)
		(stroke
			(width 0.0508)
			(type default)
		)
		(layer "In2.Cu")
	)
	(gr_line
		(start 221.451678 -44.794678)
		(end 221.548198 -44.891198)
		(stroke
			(width 0.0508)
			(type default)
		)
		(layer "In2.Cu")
	)
	(gr_line
		(start 221.478094 -56.1594)
		(end 221.5896 -56.1594)
		(stroke
			(width 0.06985)
			(type default)
		)
		(layer "In2.Cu")
	)
	(gr_line
		(start 221.49435 -53.848)
		(end 221.5642 -53.848)
		(stroke
			(width 0.06985)
			(type default)
		)
		(layer "In2.Cu")
	)
	(gr_arc
		(start 221.5134 -51.8414)
		(mid 221.571091 -51.87992)
		(end 221.63913 -51.89347)
		(stroke
			(width 0.0508)
			(type default)
		)
		(layer "In2.Cu")
	)
	(gr_line
		(start 221.540324 -49.096676)
		(end 221.613476 -49.096676)
		(stroke
			(width 0.0508)
			(type default)
		)
		(layer "In2.Cu")
	)
	(gr_line
		(start 221.547944 -25.41905)
		(end 221.56674 -25.415748)
		(stroke
			(width 0.06985)
			(type default)
		)
		(layer "In2.Cu")
	)
	(gr_line
		(start 221.550738 -44.893738)
		(end 221.581472 -44.893738)
		(stroke
			(width 0.0508)
			(type default)
		)
		(layer "In2.Cu")
	)
	(gr_arc
		(start 221.5642 -53.848)
		(mid 221.614544 -53.881639)
		(end 221.673928 -53.893466)
		(stroke
			(width 0.0508)
			(type default)
		)
		(layer "In2.Cu")
	)
	(gr_line
		(start 221.56674 -25.415748)
		(end 221.585536 -25.41905)
		(stroke
			(width 0.06985)
			(type default)
		)
		(layer "In2.Cu")
	)
	(gr_line
		(start 221.604078 -42.169842)
		(end 221.629478 -42.169842)
		(stroke
			(width 0.0508)
			(type default)
		)
		(layer "In2.Cu")
	)
	(gr_line
		(start 221.604078 -41.839642)
		(end 221.629478 -41.839642)
		(stroke
			(width 0.0508)
			(type default)
		)
		(layer "In2.Cu")
	)
	(gr_line
		(start 221.614746 -49.8348)
		(end 221.641924 -49.8348)
		(stroke
			(width 0.06985)
			(type default)
		)
		(layer "In2.Cu")
	)
	(gr_line
		(start 221.629478 -42.169842)
		(end 221.649036 -42.150284)
		(stroke
			(width 0.0508)
			(type default)
		)
		(layer "In2.Cu")
	)
	(gr_line
		(start 221.629478 -41.839642)
		(end 221.649036 -41.8592)
		(stroke
			(width 0.0508)
			(type default)
		)
		(layer "In2.Cu")
	)
	(gr_line
		(start 221.633542 -52.832)
		(end 221.742 -52.832)
		(stroke
			(width 0.06985)
			(type default)
		)
		(layer "In2.Cu")
	)
	(gr_arc
		(start 221.641924 -49.8348)
		(mid 221.706964 -49.878208)
		(end 221.783656 -49.893474)
		(stroke
			(width 0.0508)
			(type default)
		)
		(layer "In2.Cu")
	)
	(gr_line
		(start 221.650814 -42.148506)
		(end 221.692978 -42.106342)
		(stroke
			(width 0.0508)
			(type default)
		)
		(layer "In2.Cu")
	)
	(gr_line
		(start 221.650814 -41.860978)
		(end 221.692978 -41.903142)
		(stroke
			(width 0.0508)
			(type default)
		)
		(layer "In2.Cu")
	)
	(gr_line
		(start 221.669864 -67.146932)
		(end 221.674944 -67.121786)
		(stroke
			(width 0.06985)
			(type default)
		)
		(layer "In2.Cu")
	)
	(gr_line
		(start 221.669864 -67.097148)
		(end 221.674944 -67.121786)
		(stroke
			(width 0.06985)
			(type default)
		)
		(layer "In2.Cu")
	)
	(gr_arc
		(start 221.694248 -52.09667)
		(mid 221.596366 -52.11614)
		(end 221.5134 -52.1716)
		(stroke
			(width 0.0508)
			(type default)
		)
		(layer "In2.Cu")
	)
	(gr_line
		(start 221.694248 -52.09667)
		(end 221.7801 -52.09667)
		(stroke
			(width 0.0508)
			(type default)
		)
		(layer "In2.Cu")
	)
	(gr_line
		(start 221.730316 -46.087284)
		(end 221.782894 -46.087284)
		(stroke
			(width 0.06985)
			(type default)
		)
		(layer "In2.Cu")
	)
	(gr_arc
		(start 221.740984 -56.096662)
		(mid 221.659055 -56.112986)
		(end 221.5896 -56.1594)
		(stroke
			(width 0.0508)
			(type default)
		)
		(layer "In2.Cu")
	)
	(gr_arc
		(start 221.742 -52.832)
		(mid 221.810057 -52.877474)
		(end 221.890336 -52.893468)
		(stroke
			(width 0.0508)
			(type default)
		)
		(layer "In2.Cu")
	)
	(gr_line
		(start 221.744794 -55.893462)
		(end 221.8563 -55.893462)
		(stroke
			(width 0.0508)
			(type default)
		)
		(layer "In2.Cu")
	)
	(gr_line
		(start 221.745302 -55.1434)
		(end 221.8182 -55.1434)
		(stroke
			(width 0.06985)
			(type default)
		)
		(layer "In2.Cu")
	)
	(gr_arc
		(start 221.76105 -54.096666)
		(mid 221.654509 -54.117843)
		(end 221.5642 -54.1782)
		(stroke
			(width 0.0508)
			(type default)
		)
		(layer "In2.Cu")
	)
	(gr_line
		(start 221.76105 -54.096666)
		(end 221.8309 -54.096666)
		(stroke
			(width 0.0508)
			(type default)
		)
		(layer "In2.Cu")
	)
	(gr_line
		(start 221.801436 -56.8706)
		(end 221.8182 -56.8706)
		(stroke
			(width 0.06985)
			(type default)
		)
		(layer "In2.Cu")
	)
	(gr_line
		(start 221.8182 -57.2008)
		(end 221.819216 -57.199784)
		(stroke
			(width 0.0508)
			(type default)
		)
		(layer "In2.Cu")
	)
	(gr_line
		(start 221.8182 -56.8706)
		(end 221.84106 -56.89346)
		(stroke
			(width 0.0508)
			(type default)
		)
		(layer "In2.Cu")
	)
	(gr_arc
		(start 221.8182 -54.8132)
		(mid 221.907117 -54.872613)
		(end 222.012002 -54.893464)
		(stroke
			(width 0.0508)
			(type default)
		)
		(layer "In2.Cu")
	)
	(gr_line
		(start 221.84106 -56.89346)
		(end 221.862396 -56.89346)
		(stroke
			(width 0.0508)
			(type default)
		)
		(layer "In2.Cu")
	)
	(gr_line
		(start 221.858586 -26.47442)
		(end 221.877382 -26.471118)
		(stroke
			(width 0.06985)
			(type default)
		)
		(layer "In2.Cu")
	)
	(gr_line
		(start 221.877382 -26.471118)
		(end 221.896178 -26.47442)
		(stroke
			(width 0.06985)
			(type default)
		)
		(layer "In2.Cu")
	)
	(gr_arc
		(start 221.881446 -50.096674)
		(mid 221.792233 -50.114458)
		(end 221.7166 -50.165)
		(stroke
			(width 0.0508)
			(type default)
		)
		(layer "In2.Cu")
	)
	(gr_line
		(start 221.881446 -50.096674)
		(end 221.908624 -50.096674)
		(stroke
			(width 0.0508)
			(type default)
		)
		(layer "In2.Cu")
	)
	(gr_arc
		(start 221.894146 -57.893458)
		(mid 221.653159 -57.941348)
		(end 221.448884 -58.077862)
		(stroke
			(width 0.0508)
			(type default)
		)
		(layer "In2.Cu")
	)
	(gr_arc
		(start 221.900242 -53.096668)
		(mid 221.814601 -53.113691)
		(end 221.742 -53.1622)
		(stroke
			(width 0.0508)
			(type default)
		)
		(layer "In2.Cu")
	)
	(gr_line
		(start 221.900242 -53.096668)
		(end 222.0087 -53.096668)
		(stroke
			(width 0.0508)
			(type default)
		)
		(layer "In2.Cu")
	)
	(gr_arc
		(start 221.930976 -55.096664)
		(mid 221.869953 -55.108839)
		(end 221.8182 -55.1434)
		(stroke
			(width 0.0508)
			(type default)
		)
		(layer "In2.Cu")
	)
	(gr_line
		(start 222.012002 -54.893464)
		(end 222.0849 -54.893464)
		(stroke
			(width 0.0508)
			(type default)
		)
		(layer "In2.Cu")
	)
	(gr_arc
		(start 222.014796 -58.096658)
		(mid 221.906347 -58.118286)
		(end 221.81439 -58.179716)
		(stroke
			(width 0.0508)
			(type default)
		)
		(layer "In2.Cu")
	)
	(gr_arc
		(start 222.068136 -57.09666)
		(mid 221.933415 -57.123458)
		(end 221.819216 -57.199784)
		(stroke
			(width 0.0508)
			(type default)
		)
		(layer "In2.Cu")
	)
	(gr_line
		(start 222.068136 -57.09666)
		(end 222.0849 -57.09666)
		(stroke
			(width 0.0508)
			(type default)
		)
		(layer "In2.Cu")
	)
	(gr_line
		(start 222.112332 -73.15962)
		(end 222.112332 -73.159874)
		(stroke
			(width 0.06985)
			(type default)
		)
		(layer "In2.Cu")
	)
	(gr_line
		(start 222.112332 -73.15962)
		(end 222.115634 -73.140824)
		(stroke
			(width 0.06985)
			(type default)
		)
		(layer "In2.Cu")
	)
	(gr_line
		(start 222.112332 -73.122028)
		(end 222.115634 -73.140824)
		(stroke
			(width 0.06985)
			(type default)
		)
		(layer "In2.Cu")
	)
	(gr_line
		(start 222.171006 -27.515566)
		(end 222.189548 -27.512264)
		(stroke
			(width 0.06985)
			(type default)
		)
		(layer "In2.Cu")
	)
	(gr_line
		(start 222.189548 -27.512264)
		(end 222.207836 -27.515566)
		(stroke
			(width 0.06985)
			(type default)
		)
		(layer "In2.Cu")
	)
	(gr_arc
		(start 222.327216 -58.893456)
		(mid 222.25519 -58.907783)
		(end 222.19412 -58.948574)
		(stroke
			(width 0.0508)
			(type default)
		)
		(layer "In2.Cu")
	)
	(gr_line
		(start 222.327216 -58.893456)
		(end 222.42526 -58.893456)
		(stroke
			(width 0.0508)
			(type default)
		)
		(layer "In2.Cu")
	)
	(gr_line
		(start 222.3897 -66.775076)
		(end 222.4913 -66.673476)
		(stroke
			(width 0.0508)
			(type default)
		)
		(layer "In2.Cu")
	)
	(gr_line
		(start 222.4278 -59.182)
		(end 222.429832 -59.179968)
		(stroke
			(width 0.0508)
			(type default)
		)
		(layer "In2.Cu")
	)
	(gr_line
		(start 222.48622 -85.11667)
		(end 222.505778 -85.08873)
		(stroke
			(width 0.06985)
			(type default)
		)
		(layer "In2.Cu")
	)
	(gr_line
		(start 222.49384 -66.583052)
		(end 222.49384 -66.670936)
		(stroke
			(width 0.0508)
			(type default)
		)
		(layer "In2.Cu")
	)
	(gr_line
		(start 222.505778 -85.08873)
		(end 222.51162 -85.05571)
		(stroke
			(width 0.06985)
			(type default)
		)
		(layer "In2.Cu")
	)
	(gr_arc
		(start 222.631 -59.096656)
		(mid 222.522115 -59.11828)
		(end 222.429832 -59.179968)
		(stroke
			(width 0.0508)
			(type default)
		)
		(layer "In2.Cu")
	)
	(gr_line
		(start 222.674942 -62.92977)
		(end 222.75419 -62.866524)
		(stroke
			(width 0.0508)
			(type default)
		)
		(layer "In2.Cu")
	)
	(gr_arc
		(start 222.69704 -66.78803)
		(mid 222.698683 -66.802099)
		(end 222.70339 -66.815462)
		(stroke
			(width 0.0508)
			(type default)
		)
		(layer "In2.Cu")
	)
	(gr_line
		(start 222.70339 -66.815462)
		(end 222.7199 -66.849752)
		(stroke
			(width 0.0508)
			(type default)
		)
		(layer "In2.Cu")
	)
	(gr_line
		(start 222.7199 -66.849752)
		(end 222.7199 -66.937636)
		(stroke
			(width 0.06985)
			(type default)
		)
		(layer "In2.Cu")
	)
	(gr_line
		(start 222.75419 -62.866524)
		(end 222.754698 -62.866016)
		(stroke
			(width 0.0508)
			(type default)
		)
		(layer "In2.Cu")
	)
	(gr_line
		(start 222.754698 -62.866016)
		(end 222.797878 -62.831726)
		(stroke
			(width 0.0508)
			(type default)
		)
		(layer "In2.Cu")
	)
	(gr_line
		(start 222.797878 -62.831726)
		(end 222.818452 -62.815724)
		(stroke
			(width 0.0508)
			(type default)
		)
		(layer "In2.Cu")
	)
	(gr_line
		(start 222.818452 -62.815724)
		(end 222.824294 -62.811152)
		(stroke
			(width 0.0508)
			(type default)
		)
		(layer "In2.Cu")
	)
	(gr_line
		(start 222.824294 -62.811152)
		(end 222.829374 -62.807342)
		(stroke
			(width 0.0508)
			(type default)
		)
		(layer "In2.Cu")
	)
	(gr_line
		(start 222.829374 -62.807342)
		(end 222.851218 -62.79007)
		(stroke
			(width 0.0508)
			(type default)
		)
		(layer "In2.Cu")
	)
	(gr_line
		(start 222.851218 -62.79007)
		(end 222.851472 -62.79007)
		(stroke
			(width 0.0508)
			(type default)
		)
		(layer "In2.Cu")
	)
	(gr_line
		(start 222.851472 -62.79007)
		(end 222.858076 -62.784736)
		(stroke
			(width 0.0508)
			(type default)
		)
		(layer "In2.Cu")
	)
	(gr_line
		(start 222.858076 -62.784736)
		(end 222.895922 -62.755272)
		(stroke
			(width 0.0508)
			(type default)
		)
		(layer "In2.Cu")
	)
	(gr_line
		(start 222.895922 -62.755272)
		(end 222.902018 -62.7507)
		(stroke
			(width 0.0508)
			(type default)
		)
		(layer "In2.Cu")
	)
	(gr_line
		(start 222.902018 -62.7507)
		(end 222.904558 -62.748414)
		(stroke
			(width 0.0508)
			(type default)
		)
		(layer "In2.Cu")
	)
	(gr_line
		(start 222.904558 -62.748414)
		(end 223.026224 -62.652402)
		(stroke
			(width 0.0508)
			(type default)
		)
		(layer "In2.Cu")
	)
	(gr_line
		(start 222.911924 -43.1673)
		(end 222.924624 -43.1673)
		(stroke
			(width 0.0508)
			(type default)
		)
		(layer "In2.Cu")
	)
	(gr_line
		(start 222.924624 -43.1673)
		(end 222.97517 -43.116754)
		(stroke
			(width 0.0508)
			(type default)
		)
		(layer "In2.Cu")
	)
	(gr_line
		(start 222.958406 -63.03518)
		(end 222.996252 -63.03518)
		(stroke
			(width 0.0508)
			(type default)
		)
		(layer "In2.Cu")
	)
	(gr_line
		(start 222.9612 -42.8371)
		(end 222.9866 -42.8371)
		(stroke
			(width 0.0508)
			(type default)
		)
		(layer "In2.Cu")
	)
	(gr_line
		(start 222.962216 -44.1452)
		(end 223.0882 -44.1452)
		(stroke
			(width 0.06985)
			(type default)
		)
		(layer "In2.Cu")
	)
	(gr_line
		(start 222.976948 -43.114976)
		(end 222.988124 -43.1038)
		(stroke
			(width 0.0508)
			(type default)
		)
		(layer "In2.Cu")
	)
	(gr_line
		(start 222.9866 -42.8371)
		(end 223.0501 -42.9006)
		(stroke
			(width 0.0508)
			(type default)
		)
		(layer "In2.Cu")
	)
	(gr_arc
		(start 223.026224 -62.652402)
		(mid 223.080696 -62.584554)
		(end 223.100138 -62.499748)
		(stroke
			(width 0.0508)
			(type default)
		)
		(layer "In2.Cu")
	)
	(gr_line
		(start 223.0882 -44.1452)
		(end 223.125792 -44.1452)
		(stroke
			(width 0.0508)
			(type default)
		)
		(layer "In2.Cu")
	)
	(gr_line
		(start 223.0882 -43.815)
		(end 223.139254 -43.866054)
		(stroke
			(width 0.0508)
			(type default)
		)
		(layer "In2.Cu")
	)
	(gr_line
		(start 223.100138 -63.499746)
		(end 223.204532 -63.395352)
		(stroke
			(width 0.0508)
			(type default)
		)
		(layer "In2.Cu")
	)
	(gr_line
		(start 223.105472 -73.161652)
		(end 223.109028 -73.140824)
		(stroke
			(width 0.06985)
			(type default)
		)
		(layer "In2.Cu")
	)
	(gr_line
		(start 223.105726 -73.122028)
		(end 223.109028 -73.140824)
		(stroke
			(width 0.06985)
			(type default)
		)
		(layer "In2.Cu")
	)
	(gr_line
		(start 223.125792 -44.108878)
		(end 223.125792 -44.1452)
		(stroke
			(width 0.0508)
			(type default)
		)
		(layer "In2.Cu")
	)
	(gr_arc
		(start 223.13138 -63.091314)
		(mid 223.069398 -63.049806)
		(end 222.996252 -63.03518)
		(stroke
			(width 0.0508)
			(type default)
		)
		(layer "In2.Cu")
	)
	(gr_line
		(start 223.13138 -63.091314)
		(end 223.204532 -63.162434)
		(stroke
			(width 0.0508)
			(type default)
		)
		(layer "In2.Cu")
	)
	(gr_arc
		(start 223.139254 -43.866054)
		(mid 223.180397 -43.893516)
		(end 223.228916 -43.903138)
		(stroke
			(width 0.0508)
			(type default)
		)
		(layer "In2.Cu")
	)
	(gr_arc
		(start 223.204532 -63.395352)
		(mid 223.252718 -63.27893)
		(end 223.204532 -63.162434)
		(stroke
			(width 0.0508)
			(type default)
		)
		(layer "In2.Cu")
	)
	(gr_line
		(start 223.228916 -43.903138)
		(end 223.3549 -43.903138)
		(stroke
			(width 0.0508)
			(type default)
		)
		(layer "In2.Cu")
	)
	(gr_line
		(start 223.389698 -86.421976)
		(end 223.409256 -86.394036)
		(stroke
			(width 0.06985)
			(type default)
		)
		(layer "In2.Cu")
	)
	(gr_line
		(start 223.389952 -17.752568)
		(end 223.408748 -17.749266)
		(stroke
			(width 0.06985)
			(type default)
		)
		(layer "In2.Cu")
	)
	(gr_line
		(start 223.398334 -19.847306)
		(end 223.419162 -19.842988)
		(stroke
			(width 0.06985)
			(type default)
		)
		(layer "In2.Cu")
	)
	(gr_line
		(start 223.408748 -17.749266)
		(end 223.427544 -17.752568)
		(stroke
			(width 0.06985)
			(type default)
		)
		(layer "In2.Cu")
	)
	(gr_line
		(start 223.409256 -86.394036)
		(end 223.415098 -86.361016)
		(stroke
			(width 0.06985)
			(type default)
		)
		(layer "In2.Cu")
	)
	(gr_line
		(start 223.419162 -19.842988)
		(end 223.440244 -19.846798)
		(stroke
			(width 0.06985)
			(type default)
		)
		(layer "In2.Cu")
	)
	(gr_line
		(start 223.442784 -66.891662)
		(end 223.4438 -66.7766)
		(stroke
			(width 0.06985)
			(type default)
		)
		(layer "In2.Cu")
	)
	(gr_line
		(start 223.4438 -66.7766)
		(end 223.491298 -66.729102)
		(stroke
			(width 0.0508)
			(type default)
		)
		(layer "In2.Cu")
	)
	(gr_line
		(start 223.628712 -18.803366)
		(end 223.656652 -18.797778)
		(stroke
			(width 0.06985)
			(type default)
		)
		(layer "In2.Cu")
	)
	(gr_line
		(start 223.656652 -18.797778)
		(end 223.684338 -18.80362)
		(stroke
			(width 0.06985)
			(type default)
		)
		(layer "In2.Cu")
	)
	(gr_line
		(start 223.67494 -61.929772)
		(end 224.025714 -61.65342)
		(stroke
			(width 0.0508)
			(type default)
		)
		(layer "In2.Cu")
	)
	(gr_line
		(start 223.697038 -66.81089)
		(end 223.710246 -66.813684)
		(stroke
			(width 0.0508)
			(type default)
		)
		(layer "In2.Cu")
	)
	(gr_line
		(start 223.697038 -66.693034)
		(end 223.697038 -66.81089)
		(stroke
			(width 0.0508)
			(type default)
		)
		(layer "In2.Cu")
	)
	(gr_line
		(start 223.712786 -66.814192)
		(end 223.773746 -66.826638)
		(stroke
			(width 0.0508)
			(type default)
		)
		(layer "In2.Cu")
	)
	(gr_line
		(start 223.773492 -66.852038)
		(end 223.773746 -66.826638)
		(stroke
			(width 0.0508)
			(type default)
		)
		(layer "In2.Cu")
	)
	(gr_line
		(start 223.958404 -62.035182)
		(end 224.009204 -62.035182)
		(stroke
			(width 0.0508)
			(type default)
		)
		(layer "In2.Cu")
	)
	(gr_arc
		(start 224.025714 -61.65342)
		(mid 224.080628 -61.585145)
		(end 224.100136 -61.49975)
		(stroke
			(width 0.0508)
			(type default)
		)
		(layer "In2.Cu")
	)
	(gr_arc
		(start 224.100136 -62.499748)
		(mid 224.139428 -62.440887)
		(end 224.153222 -62.371478)
		(stroke
			(width 0.0508)
			(type default)
		)
		(layer "In2.Cu")
	)
	(gr_arc
		(start 224.153222 -62.1792)
		(mid 224.11104 -62.077362)
		(end 224.009204 -62.035182)
		(stroke
			(width 0.0508)
			(type default)
		)
		(layer "In2.Cu")
	)
	(gr_line
		(start 224.153222 -62.1792)
		(end 224.153222 -62.371478)
		(stroke
			(width 0.0508)
			(type default)
		)
		(layer "In2.Cu")
	)
	(gr_line
		(start 224.37852 -87.946992)
		(end 224.398078 -87.919052)
		(stroke
			(width 0.06985)
			(type default)
		)
		(layer "In2.Cu")
	)
	(gr_line
		(start 224.398078 -87.919052)
		(end 224.40392 -87.886032)
		(stroke
			(width 0.06985)
			(type default)
		)
		(layer "In2.Cu")
	)
	(gr_line
		(start 224.400872 -74.334116)
		(end 224.40265 -74.323956)
		(stroke
			(width 0.06985)
			(type default)
		)
		(layer "In2.Cu")
	)
	(gr_line
		(start 224.40138 -74.313796)
		(end 224.40265 -74.323956)
		(stroke
			(width 0.06985)
			(type default)
		)
		(layer "In2.Cu")
	)
	(gr_line
		(start 224.493836 -66.940176)
		(end 224.493836 -67.060064)
		(stroke
			(width 0.0508)
			(type default)
		)
		(layer "In2.Cu")
	)
	(gr_arc
		(start 224.5106 -45.757084)
		(mid 224.661985 -45.858222)
		(end 224.840546 -45.893736)
		(stroke
			(width 0.0508)
			(type default)
		)
		(layer "In2.Cu")
	)
	(gr_line
		(start 224.536 -46.087284)
		(end 224.545652 -46.096936)
		(stroke
			(width 0.0508)
			(type default)
		)
		(layer "In2.Cu")
	)
	(gr_line
		(start 224.545652 -46.096936)
		(end 224.634806 -46.096936)
		(stroke
			(width 0.0508)
			(type default)
		)
		(layer "In2.Cu")
	)
	(gr_line
		(start 224.674938 -62.92977)
		(end 225.025712 -62.653418)
		(stroke
			(width 0.0508)
			(type default)
		)
		(layer "In2.Cu")
	)
	(gr_line
		(start 224.698814 -67.14617)
		(end 224.73412 -67.181476)
		(stroke
			(width 0.0508)
			(type default)
		)
		(layer "In2.Cu")
	)
	(gr_line
		(start 224.73412 -67.181476)
		(end 224.7392 -67.181476)
		(stroke
			(width 0.0508)
			(type default)
		)
		(layer "In2.Cu")
	)
	(gr_line
		(start 224.7392 -67.181476)
		(end 224.7519 -67.194176)
		(stroke
			(width 0.0508)
			(type default)
		)
		(layer "In2.Cu")
	)
	(gr_line
		(start 224.7519 -67.206876)
		(end 224.7519 -67.326764)
		(stroke
			(width 0.06985)
			(type default)
		)
		(layer "In2.Cu")
	)
	(gr_line
		(start 224.7519 -67.194176)
		(end 224.7519 -67.206876)
		(stroke
			(width 0.0508)
			(type default)
		)
		(layer "In2.Cu")
	)
	(gr_line
		(start 224.958402 -63.03518)
		(end 225.009202 -63.03518)
		(stroke
			(width 0.0508)
			(type default)
		)
		(layer "In2.Cu")
	)
	(gr_arc
		(start 225.025712 -62.653418)
		(mid 225.080626 -62.585143)
		(end 225.100134 -62.499748)
		(stroke
			(width 0.0508)
			(type default)
		)
		(layer "In2.Cu")
	)
	(gr_arc
		(start 225.099118 -63.072264)
		(mid 225.057857 -63.044758)
		(end 225.009202 -63.03518)
		(stroke
			(width 0.0508)
			(type default)
		)
		(layer "In2.Cu")
	)
	(gr_line
		(start 225.099118 -63.072264)
		(end 225.171 -63.144654)
		(stroke
			(width 0.0508)
			(type default)
		)
		(layer "In2.Cu")
	)
	(gr_line
		(start 225.100134 -63.499746)
		(end 225.171 -63.42888)
		(stroke
			(width 0.0508)
			(type default)
		)
		(layer "In2.Cu")
	)
	(gr_arc
		(start 225.100134 -58.499756)
		(mid 225.155917 -58.634476)
		(end 225.290634 -58.690256)
		(stroke
			(width 0.0508)
			(type default)
		)
		(layer "In2.Cu")
	)
	(gr_arc
		(start 225.100134 -56.49976)
		(mid 225.155918 -56.634478)
		(end 225.290634 -56.69026)
		(stroke
			(width 0.0508)
			(type default)
		)
		(layer "In2.Cu")
	)
	(gr_arc
		(start 225.100134 -54.499764)
		(mid 225.155919 -54.634479)
		(end 225.290634 -54.690264)
		(stroke
			(width 0.0508)
			(type default)
		)
		(layer "In2.Cu")
	)
	(gr_arc
		(start 225.100134 -52.499768)
		(mid 225.15593 -52.634472)
		(end 225.290634 -52.690268)
		(stroke
			(width 0.0508)
			(type default)
		)
		(layer "In2.Cu")
	)
	(gr_arc
		(start 225.100134 -49.499774)
		(mid 225.15593 -49.634478)
		(end 225.290634 -49.690274)
		(stroke
			(width 0.0508)
			(type default)
		)
		(layer "In2.Cu")
	)
	(gr_line
		(start 225.100134 -46.512734)
		(end 225.305366 -46.717966)
		(stroke
			(width 0.0508)
			(type default)
		)
		(layer "In2.Cu")
	)
	(gr_line
		(start 225.100134 -46.500034)
		(end 225.100134 -46.512734)
		(stroke
			(width 0.0508)
			(type default)
		)
		(layer "In2.Cu")
	)
	(gr_line
		(start 225.100134 -39.500048)
		(end 225.396806 -39.500048)
		(stroke
			(width 0.0508)
			(type default)
		)
		(layer "In2.Cu")
	)
	(gr_line
		(start 225.100134 -37.500052)
		(end 225.149918 -37.551868)
		(stroke
			(width 0.0508)
			(type default)
		)
		(layer "In2.Cu")
	)
	(gr_line
		(start 225.100134 -35.500056)
		(end 225.396806 -35.500056)
		(stroke
			(width 0.0508)
			(type default)
		)
		(layer "In2.Cu")
	)
	(gr_line
		(start 225.100134 -33.50006)
		(end 225.309684 -33.583372)
		(stroke
			(width 0.0508)
			(type default)
		)
		(layer "In2.Cu")
	)
	(gr_arc
		(start 225.149918 -37.551868)
		(mid 225.475355 -37.558157)
		(end 225.481388 -37.232844)
		(stroke
			(width 0.0508)
			(type default)
		)
		(layer "In2.Cu")
	)
	(gr_arc
		(start 225.171 -63.42888)
		(mid 225.229963 -63.286777)
		(end 225.171 -63.144654)
		(stroke
			(width 0.0508)
			(type default)
		)
		(layer "In2.Cu")
	)
	(gr_line
		(start 225.290634 -58.690256)
		(end 225.48088 -58.690256)
		(stroke
			(width 0.0508)
			(type default)
		)
		(layer "In2.Cu")
	)
	(gr_line
		(start 225.290634 -56.69026)
		(end 225.48088 -56.69026)
		(stroke
			(width 0.0508)
			(type default)
		)
		(layer "In2.Cu")
	)
	(gr_line
		(start 225.290634 -54.690264)
		(end 225.48088 -54.690264)
		(stroke
			(width 0.0508)
			(type default)
		)
		(layer "In2.Cu")
	)
	(gr_line
		(start 225.290634 -52.690268)
		(end 225.48088 -52.690268)
		(stroke
			(width 0.0508)
			(type default)
		)
		(layer "In2.Cu")
	)
	(gr_line
		(start 225.290634 -49.690274)
		(end 225.48088 -49.690274)
		(stroke
			(width 0.0508)
			(type default)
		)
		(layer "In2.Cu")
	)
	(gr_arc
		(start 225.305366 -46.717966)
		(mid 225.383562 -46.770215)
		(end 225.4758 -46.788578)
		(stroke
			(width 0.0508)
			(type default)
		)
		(layer "In2.Cu")
	)
	(gr_arc
		(start 225.309684 -33.583372)
		(mid 225.586635 -33.464157)
		(end 225.467164 -33.187386)
		(stroke
			(width 0.0508)
			(type default)
		)
		(layer "In2.Cu")
	)
	(gr_line
		(start 225.408236 -33.163764)
		(end 225.467164 -33.187386)
		(stroke
			(width 0.0508)
			(type default)
		)
		(layer "In2.Cu")
	)
	(gr_line
		(start 225.4377 -67.351148)
		(end 225.4377 -67.472306)
		(stroke
			(width 0.06985)
			(type default)
		)
		(layer "In2.Cu")
	)
	(gr_line
		(start 225.4377 -67.351148)
		(end 225.493834 -67.339718)
		(stroke
			(width 0.0508)
			(type default)
		)
		(layer "In2.Cu")
	)
	(gr_arc
		(start 225.4758 -46.788578)
		(mid 225.544522 -46.774908)
		(end 225.6028 -46.736)
		(stroke
			(width 0.0508)
			(type default)
		)
		(layer "In2.Cu")
	)
	(gr_arc
		(start 225.48088 -58.690256)
		(mid 225.562528 -58.674015)
		(end 225.631756 -58.627772)
		(stroke
			(width 0.0508)
			(type default)
		)
		(layer "In2.Cu")
	)
	(gr_arc
		(start 225.48088 -56.69026)
		(mid 225.562528 -56.67402)
		(end 225.631756 -56.627776)
		(stroke
			(width 0.0508)
			(type default)
		)
		(layer "In2.Cu")
	)
	(gr_arc
		(start 225.48088 -54.690264)
		(mid 225.562528 -54.674024)
		(end 225.631756 -54.62778)
		(stroke
			(width 0.0508)
			(type default)
		)
		(layer "In2.Cu")
	)
	(gr_arc
		(start 225.48088 -52.690268)
		(mid 225.562529 -52.674027)
		(end 225.631756 -52.627784)
		(stroke
			(width 0.0508)
			(type default)
		)
		(layer "In2.Cu")
	)
	(gr_arc
		(start 225.48088 -49.690274)
		(mid 225.562529 -49.674033)
		(end 225.631756 -49.62779)
		(stroke
			(width 0.0508)
			(type default)
		)
		(layer "In2.Cu")
	)
	(gr_arc
		(start 225.498406 -39.601648)
		(mid 225.468665 -39.529773)
		(end 225.396806 -39.500048)
		(stroke
			(width 0.0508)
			(type default)
		)
		(layer "In2.Cu")
	)
	(gr_arc
		(start 225.498406 -35.601656)
		(mid 225.468633 -35.52984)
		(end 225.396806 -35.500056)
		(stroke
			(width 0.0508)
			(type default)
		)
		(layer "In2.Cu")
	)
	(gr_line
		(start 225.541586 -28.438602)
		(end 225.560382 -28.441904)
		(stroke
			(width 0.06985)
			(type default)
		)
		(layer "In2.Cu")
	)
	(gr_line
		(start 225.560382 -28.441904)
		(end 225.579178 -28.438602)
		(stroke
			(width 0.06985)
			(type default)
		)
		(layer "In2.Cu")
	)
	(gr_line
		(start 225.568764 -26.456894)
		(end 225.58756 -26.460196)
		(stroke
			(width 0.06985)
			(type default)
		)
		(layer "In2.Cu")
	)
	(gr_arc
		(start 225.574606 -56.17718)
		(mid 225.485466 -56.117573)
		(end 225.380296 -56.096662)
		(stroke
			(width 0.0508)
			(type default)
		)
		(layer "In2.Cu")
	)
	(gr_line
		(start 225.580702 -74.084434)
		(end 225.58375 -74.067416)
		(stroke
			(width 0.06985)
			(type default)
		)
		(layer "In2.Cu")
	)
	(gr_line
		(start 225.580956 -74.05116)
		(end 225.58375 -74.067416)
		(stroke
			(width 0.06985)
			(type default)
		)
		(layer "In2.Cu")
	)
	(gr_line
		(start 225.58756 -26.460196)
		(end 225.606356 -26.456894)
		(stroke
			(width 0.06985)
			(type default)
		)
		(layer "In2.Cu")
	)
	(gr_line
		(start 225.6028 -46.736)
		(end 225.6282 -46.7106)
		(stroke
			(width 0.0508)
			(type default)
		)
		(layer "In2.Cu")
	)
	(gr_arc
		(start 225.6282 -46.7106)
		(mid 225.686133 -46.623897)
		(end 225.706432 -46.521624)
		(stroke
			(width 0.0508)
			(type default)
		)
		(layer "In2.Cu")
	)
	(gr_line
		(start 225.631756 -58.627772)
		(end 225.636328 -58.623454)
		(stroke
			(width 0.0508)
			(type default)
		)
		(layer "In2.Cu")
	)
	(gr_line
		(start 225.631756 -56.627776)
		(end 225.636328 -56.623458)
		(stroke
			(width 0.0508)
			(type default)
		)
		(layer "In2.Cu")
	)
	(gr_line
		(start 225.631756 -54.62778)
		(end 225.636328 -54.623462)
		(stroke
			(width 0.0508)
			(type default)
		)
		(layer "In2.Cu")
	)
	(gr_line
		(start 225.631756 -52.627784)
		(end 225.636328 -52.623466)
		(stroke
			(width 0.0508)
			(type default)
		)
		(layer "In2.Cu")
	)
	(gr_line
		(start 225.631756 -49.62779)
		(end 225.636328 -49.623472)
		(stroke
			(width 0.0508)
			(type default)
		)
		(layer "In2.Cu")
	)
	(gr_arc
		(start 225.633788 -57.962546)
		(mid 225.521686 -57.911077)
		(end 225.3996 -57.893458)
		(stroke
			(width 0.0508)
			(type default)
		)
		(layer "In2.Cu")
	)
	(gr_arc
		(start 225.633788 -55.96255)
		(mid 225.521686 -55.91108)
		(end 225.3996 -55.893462)
		(stroke
			(width 0.0508)
			(type default)
		)
		(layer "In2.Cu")
	)
	(gr_arc
		(start 225.633788 -53.962554)
		(mid 225.521686 -53.911084)
		(end 225.3996 -53.893466)
		(stroke
			(width 0.0508)
			(type default)
		)
		(layer "In2.Cu")
	)
	(gr_arc
		(start 225.636328 -58.623454)
		(mid 225.688281 -58.545597)
		(end 225.706432 -58.453782)
		(stroke
			(width 0.0508)
			(type default)
		)
		(layer "In2.Cu")
	)
	(gr_arc
		(start 225.636328 -56.623458)
		(mid 225.688283 -56.545602)
		(end 225.706432 -56.453786)
		(stroke
			(width 0.0508)
			(type default)
		)
		(layer "In2.Cu")
	)
	(gr_arc
		(start 225.636328 -54.623462)
		(mid 225.688284 -54.545606)
		(end 225.706432 -54.45379)
		(stroke
			(width 0.0508)
			(type default)
		)
		(layer "In2.Cu")
	)
	(gr_arc
		(start 225.636328 -52.623466)
		(mid 225.68826 -52.545605)
		(end 225.706432 -52.453794)
		(stroke
			(width 0.0508)
			(type default)
		)
		(layer "In2.Cu")
	)
	(gr_arc
		(start 225.636328 -49.623472)
		(mid 225.68826 -49.545611)
		(end 225.706432 -49.4538)
		(stroke
			(width 0.0508)
			(type default)
		)
		(layer "In2.Cu")
	)
	(gr_line
		(start 225.674936 -61.929772)
		(end 226.02571 -61.65342)
		(stroke
			(width 0.0508)
			(type default)
		)
		(layer "In2.Cu")
	)
	(gr_line
		(start 225.697034 -67.084448)
		(end 225.697034 -67.205606)
		(stroke
			(width 0.0508)
			(type default)
		)
		(layer "In2.Cu")
	)
	(gr_line
		(start 225.699574 -67.208146)
		(end 225.7679 -67.276472)
		(stroke
			(width 0.0508)
			(type default)
		)
		(layer "In2.Cu")
	)
	(gr_arc
		(start 225.700844 -52.354988)
		(mid 225.677629 -52.293362)
		(end 225.638106 -52.240688)
		(stroke
			(width 0.0508)
			(type default)
		)
		(layer "In2.Cu")
	)
	(gr_arc
		(start 225.700844 -49.354994)
		(mid 225.677629 -49.293368)
		(end 225.638106 -49.240694)
		(stroke
			(width 0.0508)
			(type default)
		)
		(layer "In2.Cu")
	)
	(gr_arc
		(start 225.704908 -56.019954)
		(mid 225.670876 -55.989358)
		(end 225.633788 -55.96255)
		(stroke
			(width 0.0508)
			(type default)
		)
		(layer "In2.Cu")
	)
	(gr_arc
		(start 225.706432 -58.405522)
		(mid 225.68864 -58.316314)
		(end 225.638106 -58.240676)
		(stroke
			(width 0.0508)
			(type default)
		)
		(layer "In2.Cu")
	)
	(gr_line
		(start 225.706432 -58.405522)
		(end 225.706432 -58.453782)
		(stroke
			(width 0.0508)
			(type default)
		)
		(layer "In2.Cu")
	)
	(gr_arc
		(start 225.706432 -56.405526)
		(mid 225.688641 -56.316317)
		(end 225.638106 -56.24068)
		(stroke
			(width 0.0508)
			(type default)
		)
		(layer "In2.Cu")
	)
	(gr_line
		(start 225.706432 -56.405526)
		(end 225.706432 -56.453786)
		(stroke
			(width 0.0508)
			(type default)
		)
		(layer "In2.Cu")
	)
	(gr_arc
		(start 225.706432 -54.40553)
		(mid 225.688643 -54.31632)
		(end 225.638106 -54.240684)
		(stroke
			(width 0.0508)
			(type default)
		)
		(layer "In2.Cu")
	)
	(gr_line
		(start 225.706432 -54.40553)
		(end 225.706432 -54.45379)
		(stroke
			(width 0.0508)
			(type default)
		)
		(layer "In2.Cu")
	)
	(gr_arc
		(start 225.706432 -52.405534)
		(mid 225.705014 -52.380109)
		(end 225.700844 -52.354988)
		(stroke
			(width 0.0508)
			(type default)
		)
		(layer "In2.Cu")
	)
	(gr_line
		(start 225.706432 -52.405534)
		(end 225.706432 -52.453794)
		(stroke
			(width 0.0508)
			(type default)
		)
		(layer "In2.Cu")
	)
	(gr_arc
		(start 225.706432 -49.40554)
		(mid 225.705014 -49.380115)
		(end 225.700844 -49.354994)
		(stroke
			(width 0.0508)
			(type default)
		)
		(layer "In2.Cu")
	)
	(gr_line
		(start 225.706432 -49.40554)
		(end 225.706432 -49.4538)
		(stroke
			(width 0.0508)
			(type default)
		)
		(layer "In2.Cu")
	)
	(gr_arc
		(start 225.706432 -46.404784)
		(mid 225.688934 -46.316817)
		(end 225.639122 -46.242224)
		(stroke
			(width 0.0508)
			(type default)
		)
		(layer "In2.Cu")
	)
	(gr_line
		(start 225.706432 -46.404784)
		(end 225.706432 -46.521624)
		(stroke
			(width 0.0508)
			(type default)
		)
		(layer "In2.Cu")
	)
	(gr_line
		(start 225.739706 -27.487626)
		(end 225.758502 -27.490928)
		(stroke
			(width 0.06985)
			(type default)
		)
		(layer "In2.Cu")
	)
	(gr_line
		(start 225.758502 -27.490928)
		(end 225.777298 -27.487626)
		(stroke
			(width 0.06985)
			(type default)
		)
		(layer "In2.Cu")
	)
	(gr_arc
		(start 225.803206 -39.500048)
		(mid 225.731364 -39.529806)
		(end 225.701606 -39.601648)
		(stroke
			(width 0.0508)
			(type default)
		)
		(layer "In2.Cu")
	)
	(gr_line
		(start 225.803206 -39.500048)
		(end 226.100132 -39.500048)
		(stroke
			(width 0.0508)
			(type default)
		)
		(layer "In2.Cu")
	)
	(gr_arc
		(start 225.803206 -35.500056)
		(mid 225.731345 -35.529809)
		(end 225.701606 -35.601656)
		(stroke
			(width 0.0508)
			(type default)
		)
		(layer "In2.Cu")
	)
	(gr_line
		(start 225.803206 -35.500056)
		(end 226.100132 -35.500056)
		(stroke
			(width 0.0508)
			(type default)
		)
		(layer "In2.Cu")
	)
	(gr_line
		(start 225.803968 -58.11901)
		(end 226.040442 -58.35523)
		(stroke
			(width 0.0508)
			(type default)
		)
		(layer "In2.Cu")
	)
	(gr_line
		(start 225.803968 -56.119014)
		(end 226.040442 -56.355234)
		(stroke
			(width 0.0508)
			(type default)
		)
		(layer "In2.Cu")
	)
	(gr_line
		(start 225.803968 -54.119018)
		(end 226.040442 -54.355238)
		(stroke
			(width 0.0508)
			(type default)
		)
		(layer "In2.Cu")
	)
	(gr_line
		(start 225.804476 -46.119796)
		(end 225.898202 -46.213522)
		(stroke
			(width 0.0508)
			(type default)
		)
		(layer "In2.Cu")
	)
	(gr_line
		(start 225.834448 -22.366732)
		(end 225.859086 -22.361652)
		(stroke
			(width 0.06985)
			(type default)
		)
		(layer "In2.Cu")
	)
	(gr_line
		(start 225.85807 -52.173124)
		(end 226.040442 -52.355242)
		(stroke
			(width 0.0508)
			(type default)
		)
		(layer "In2.Cu")
	)
	(gr_line
		(start 225.85807 -49.17313)
		(end 226.040442 -49.355248)
		(stroke
			(width 0.0508)
			(type default)
		)
		(layer "In2.Cu")
	)
	(gr_line
		(start 225.859086 -22.361652)
		(end 225.883724 -22.366732)
		(stroke
			(width 0.06985)
			(type default)
		)
		(layer "In2.Cu")
	)
	(gr_line
		(start 225.898202 -46.213522)
		(end 226.040442 -46.355508)
		(stroke
			(width 0.0508)
			(type default)
		)
		(layer "In2.Cu")
	)
	(gr_line
		(start 225.919538 -23.467568)
		(end 225.944176 -23.462488)
		(stroke
			(width 0.06985)
			(type default)
		)
		(layer "In2.Cu")
	)
	(gr_line
		(start 225.944176 -23.462488)
		(end 225.968814 -23.467568)
		(stroke
			(width 0.06985)
			(type default)
		)
		(layer "In2.Cu")
	)
	(gr_line
		(start 225.9584 -62.035182)
		(end 226.0092 -62.035182)
		(stroke
			(width 0.0508)
			(type default)
		)
		(layer "In2.Cu")
	)
	(gr_arc
		(start 226.02571 -61.65342)
		(mid 226.080624 -61.585145)
		(end 226.100132 -61.49975)
		(stroke
			(width 0.0508)
			(type default)
		)
		(layer "In2.Cu")
	)
	(gr_line
		(start 226.100132 -62.499748)
		(end 226.182428 -62.417452)
		(stroke
			(width 0.0508)
			(type default)
		)
		(layer "In2.Cu")
	)
	(gr_arc
		(start 226.100132 -59.499754)
		(mid 226.155914 -59.634476)
		(end 226.290632 -59.690254)
		(stroke
			(width 0.0508)
			(type default)
		)
		(layer "In2.Cu")
	)
	(gr_arc
		(start 226.100132 -58.499756)
		(mid 226.084672 -58.421551)
		(end 226.040442 -58.35523)
		(stroke
			(width 0.0508)
			(type default)
		)
		(layer "In2.Cu")
	)
	(gr_arc
		(start 226.100132 -57.499758)
		(mid 226.155928 -57.634462)
		(end 226.290632 -57.690258)
		(stroke
			(width 0.0508)
			(type default)
		)
		(layer "In2.Cu")
	)
	(gr_arc
		(start 226.100132 -56.49976)
		(mid 226.084673 -56.421554)
		(end 226.040442 -56.355234)
		(stroke
			(width 0.0508)
			(type default)
		)
		(layer "In2.Cu")
	)
	(gr_arc
		(start 226.100132 -55.499762)
		(mid 226.155917 -55.634479)
		(end 226.290632 -55.690262)
		(stroke
			(width 0.0508)
			(type default)
		)
		(layer "In2.Cu")
	)
	(gr_arc
		(start 226.100132 -54.499764)
		(mid 226.084674 -54.421557)
		(end 226.040442 -54.355238)
		(stroke
			(width 0.0508)
			(type default)
		)
		(layer "In2.Cu")
	)
	(gr_arc
		(start 226.100132 -53.499766)
		(mid 226.155918 -53.634481)
		(end 226.290632 -53.690266)
		(stroke
			(width 0.0508)
			(type default)
		)
		(layer "In2.Cu")
	)
	(gr_arc
		(start 226.100132 -52.499768)
		(mid 226.08467 -52.421564)
		(end 226.040442 -52.355242)
		(stroke
			(width 0.0508)
			(type default)
		)
		(layer "In2.Cu")
	)
	(gr_arc
		(start 226.100132 -50.499772)
		(mid 226.15592 -50.634483)
		(end 226.290632 -50.690272)
		(stroke
			(width 0.0508)
			(type default)
		)
		(layer "In2.Cu")
	)
	(gr_arc
		(start 226.100132 -49.499774)
		(mid 226.08467 -49.42157)
		(end 226.040442 -49.355248)
		(stroke
			(width 0.0508)
			(type default)
		)
		(layer "In2.Cu")
	)
	(gr_arc
		(start 226.100132 -48.622966)
		(mid 226.372166 -48.895)
		(end 226.6442 -48.622966)
		(stroke
			(width 0.06985)
			(type default)
		)
		(layer "In2.Cu")
	)
	(gr_line
		(start 226.100132 -48.499776)
		(end 226.100132 -48.622966)
		(stroke
			(width 0.06985)
			(type default)
		)
		(layer "In2.Cu")
	)
	(gr_arc
		(start 226.100132 -46.500034)
		(mid 226.08467 -46.42183)
		(end 226.040442 -46.355508)
		(stroke
			(width 0.0508)
			(type default)
		)
		(layer "In2.Cu")
	)
	(gr_line
		(start 226.100132 -40.500046)
		(end 226.396804 -40.500046)
		(stroke
			(width 0.0508)
			(type default)
		)
		(layer "In2.Cu")
	)
	(gr_line
		(start 226.100132 -38.50005)
		(end 226.397058 -38.50005)
		(stroke
			(width 0.0508)
			(type default)
		)
		(layer "In2.Cu")
	)
	(gr_arc
		(start 226.100132 -37.500052)
		(mid 225.822879 -37.223155)
		(end 225.505518 -36.993322)
		(stroke
			(width 0.0508)
			(type default)
		)
		(layer "In2.Cu")
	)
	(gr_line
		(start 226.100132 -36.500054)
		(end 226.396804 -36.500054)
		(stroke
			(width 0.0508)
			(type default)
		)
		(layer "In2.Cu")
	)
	(gr_line
		(start 226.100132 -34.500058)
		(end 226.283012 -34.500058)
		(stroke
			(width 0.0508)
			(type default)
		)
		(layer "In2.Cu")
	)
	(gr_arc
		(start 226.110292 -62.077092)
		(mid 226.063927 -62.046041)
		(end 226.0092 -62.035182)
		(stroke
			(width 0.0508)
			(type default)
		)
		(layer "In2.Cu")
	)
	(gr_line
		(start 226.110292 -62.077092)
		(end 226.182428 -62.149228)
		(stroke
			(width 0.0508)
			(type default)
		)
		(layer "In2.Cu")
	)
	(gr_arc
		(start 226.182428 -62.417452)
		(mid 226.238003 -62.283328)
		(end 226.182428 -62.149228)
		(stroke
			(width 0.0508)
			(type default)
		)
		(layer "In2.Cu")
	)
	(gr_line
		(start 226.290632 -59.690254)
		(end 226.480878 -59.690254)
		(stroke
			(width 0.0508)
			(type default)
		)
		(layer "In2.Cu")
	)
	(gr_line
		(start 226.290632 -57.690258)
		(end 226.480878 -57.690258)
		(stroke
			(width 0.0508)
			(type default)
		)
		(layer "In2.Cu")
	)
	(gr_line
		(start 226.290632 -55.690262)
		(end 226.480878 -55.690262)
		(stroke
			(width 0.0508)
			(type default)
		)
		(layer "In2.Cu")
	)
	(gr_line
		(start 226.290632 -53.690266)
		(end 226.480878 -53.690266)
		(stroke
			(width 0.0508)
			(type default)
		)
		(layer "In2.Cu")
	)
	(gr_line
		(start 226.290632 -50.690272)
		(end 226.480878 -50.690272)
		(stroke
			(width 0.0508)
			(type default)
		)
		(layer "In2.Cu")
	)
	(gr_arc
		(start 226.396804 -40.500046)
		(mid 226.46866 -40.470289)
		(end 226.498404 -40.398446)
		(stroke
			(width 0.0508)
			(type default)
		)
		(layer "In2.Cu")
	)
	(gr_arc
		(start 226.396804 -36.500054)
		(mid 226.468627 -36.470292)
		(end 226.498404 -36.398454)
		(stroke
			(width 0.0508)
			(type default)
		)
		(layer "In2.Cu")
	)
	(gr_line
		(start 226.4283 -67.1195)
		(end 226.447858 -67.099942)
		(stroke
			(width 0.0508)
			(type default)
		)
		(layer "In2.Cu")
	)
	(gr_arc
		(start 226.435158 -34.56305)
		(mid 226.365353 -34.516408)
		(end 226.283012 -34.500058)
		(stroke
			(width 0.0508)
			(type default)
		)
		(layer "In2.Cu")
	)
	(gr_line
		(start 226.449636 -67.098164)
		(end 226.493832 -67.053968)
		(stroke
			(width 0.0508)
			(type default)
		)
		(layer "In2.Cu")
	)
	(gr_arc
		(start 226.480878 -59.690254)
		(mid 226.562526 -59.674014)
		(end 226.631754 -59.62777)
		(stroke
			(width 0.0508)
			(type default)
		)
		(layer "In2.Cu")
	)
	(gr_arc
		(start 226.480878 -57.690258)
		(mid 226.562527 -57.674017)
		(end 226.631754 -57.627774)
		(stroke
			(width 0.0508)
			(type default)
		)
		(layer "In2.Cu")
	)
	(gr_arc
		(start 226.480878 -55.690262)
		(mid 226.562526 -55.674022)
		(end 226.631754 -55.627778)
		(stroke
			(width 0.0508)
			(type default)
		)
		(layer "In2.Cu")
	)
	(gr_arc
		(start 226.480878 -53.690266)
		(mid 226.562527 -53.674027)
		(end 226.631754 -53.627782)
		(stroke
			(width 0.0508)
			(type default)
		)
		(layer "In2.Cu")
	)
	(gr_arc
		(start 226.480878 -50.690272)
		(mid 226.562527 -50.674033)
		(end 226.631754 -50.627788)
		(stroke
			(width 0.0508)
			(type default)
		)
		(layer "In2.Cu")
	)
	(gr_line
		(start 226.488244 -87.32647)
		(end 226.5172 -87.285068)
		(stroke
			(width 0.06985)
			(type default)
		)
		(layer "In2.Cu")
	)
	(gr_line
		(start 226.493832 -66.8528)
		(end 226.493832 -67.053968)
		(stroke
			(width 0.0508)
			(type default)
		)
		(layer "In2.Cu")
	)
	(gr_arc
		(start 226.496626 -34.67735)
		(mid 226.474279 -34.615692)
		(end 226.435158 -34.56305)
		(stroke
			(width 0.0508)
			(type default)
		)
		(layer "In2.Cu")
	)
	(gr_arc
		(start 226.498658 -38.60165)
		(mid 226.46888 -38.529855)
		(end 226.397058 -38.50005)
		(stroke
			(width 0.0508)
			(type default)
		)
		(layer "In2.Cu")
	)
	(gr_line
		(start 226.5172 -87.285068)
		(end 226.52101 -87.234268)
		(stroke
			(width 0.06985)
			(type default)
		)
		(layer "In2.Cu")
	)
	(gr_arc
		(start 226.574604 -59.177174)
		(mid 226.485464 -59.117569)
		(end 226.380294 -59.096656)
		(stroke
			(width 0.0508)
			(type default)
		)
		(layer "In2.Cu")
	)
	(gr_arc
		(start 226.574604 -55.177182)
		(mid 226.485464 -55.117575)
		(end 226.380294 -55.096664)
		(stroke
			(width 0.0508)
			(type default)
		)
		(layer "In2.Cu")
	)
	(gr_arc
		(start 226.574604 -53.177186)
		(mid 226.485464 -53.117578)
		(end 226.380294 -53.096668)
		(stroke
			(width 0.0508)
			(type default)
		)
		(layer "In2.Cu")
	)
	(gr_arc
		(start 226.574604 -50.177192)
		(mid 226.485465 -50.117583)
		(end 226.380294 -50.096674)
		(stroke
			(width 0.0508)
			(type default)
		)
		(layer "In2.Cu")
	)
	(gr_line
		(start 226.631754 -59.62777)
		(end 226.636326 -59.623452)
		(stroke
			(width 0.0508)
			(type default)
		)
		(layer "In2.Cu")
	)
	(gr_line
		(start 226.631754 -57.627774)
		(end 226.636326 -57.623456)
		(stroke
			(width 0.0508)
			(type default)
		)
		(layer "In2.Cu")
	)
	(gr_line
		(start 226.631754 -55.627778)
		(end 226.636326 -55.62346)
		(stroke
			(width 0.0508)
			(type default)
		)
		(layer "In2.Cu")
	)
	(gr_line
		(start 226.631754 -53.627782)
		(end 226.636326 -53.623464)
		(stroke
			(width 0.0508)
			(type default)
		)
		(layer "In2.Cu")
	)
	(gr_line
		(start 226.631754 -50.627788)
		(end 226.636326 -50.62347)
		(stroke
			(width 0.0508)
			(type default)
		)
		(layer "In2.Cu")
	)
	(gr_arc
		(start 226.633786 -54.962552)
		(mid 226.521684 -54.911082)
		(end 226.399598 -54.893464)
		(stroke
			(width 0.0508)
			(type default)
		)
		(layer "In2.Cu")
	)
	(gr_arc
		(start 226.633786 -52.962556)
		(mid 226.521684 -52.911086)
		(end 226.399598 -52.893468)
		(stroke
			(width 0.0508)
			(type default)
		)
		(layer "In2.Cu")
	)
	(gr_arc
		(start 226.636326 -59.623452)
		(mid 226.688279 -59.545595)
		(end 226.70643 -59.45378)
		(stroke
			(width 0.0508)
			(type default)
		)
		(layer "In2.Cu")
	)
	(gr_arc
		(start 226.636326 -57.623456)
		(mid 226.688258 -57.545595)
		(end 226.70643 -57.453784)
		(stroke
			(width 0.0508)
			(type default)
		)
		(layer "In2.Cu")
	)
	(gr_arc
		(start 226.636326 -55.62346)
		(mid 226.688282 -55.545604)
		(end 226.70643 -55.453788)
		(stroke
			(width 0.0508)
			(type default)
		)
		(layer "In2.Cu")
	)
	(gr_arc
		(start 226.636326 -53.623464)
		(mid 226.688283 -53.545608)
		(end 226.70643 -53.453792)
		(stroke
			(width 0.0508)
			(type default)
		)
		(layer "In2.Cu")
	)
	(gr_arc
		(start 226.636326 -50.62347)
		(mid 226.688252 -50.545609)
		(end 226.70643 -50.453798)
		(stroke
			(width 0.0508)
			(type default)
		)
		(layer "In2.Cu")
	)
	(gr_line
		(start 226.640644 -48.122586)
		(end 226.640898 -48.12284)
		(stroke
			(width 0.06985)
			(type default)
		)
		(layer "In2.Cu")
	)
	(gr_line
		(start 226.6442 -48.515524)
		(end 226.6442 -48.622966)
		(stroke
			(width 0.06985)
			(type default)
		)
		(layer "In2.Cu")
	)
	(gr_line
		(start 226.6442 -48.176942)
		(end 226.6442 -48.512984)
		(stroke
			(width 0.06985)
			(type default)
		)
		(layer "In2.Cu")
	)
	(gr_line
		(start 226.674934 -62.92977)
		(end 227.025708 -62.653418)
		(stroke
			(width 0.0508)
			(type default)
		)
		(layer "In2.Cu")
	)
	(gr_line
		(start 226.692968 -22.865334)
		(end 226.7458 -22.876002)
		(stroke
			(width 0.06985)
			(type default)
		)
		(layer "In2.Cu")
	)
	(gr_line
		(start 226.697032 -67.058032)
		(end 226.737164 -67.098164)
		(stroke
			(width 0.0508)
			(type default)
		)
		(layer "In2.Cu")
	)
	(gr_arc
		(start 226.700842 -53.354986)
		(mid 226.677639 -53.293351)
		(end 226.638104 -53.240686)
		(stroke
			(width 0.0508)
			(type default)
		)
		(layer "In2.Cu")
	)
	(gr_arc
		(start 226.701604 -40.398446)
		(mid 226.731362 -40.470288)
		(end 226.803204 -40.500046)
		(stroke
			(width 0.0508)
			(type default)
		)
		(layer "In2.Cu")
	)
	(gr_arc
		(start 226.701604 -36.398454)
		(mid 226.731362 -36.470296)
		(end 226.803204 -36.500054)
		(stroke
			(width 0.0508)
			(type default)
		)
		(layer "In2.Cu")
	)
	(gr_arc
		(start 226.704906 -55.019956)
		(mid 226.670874 -54.98936)
		(end 226.633786 -54.962552)
		(stroke
			(width 0.0508)
			(type default)
		)
		(layer "In2.Cu")
	)
	(gr_arc
		(start 226.704906 -53.01996)
		(mid 226.670875 -52.989364)
		(end 226.633786 -52.962556)
		(stroke
			(width 0.0508)
			(type default)
		)
		(layer "In2.Cu")
	)
	(gr_arc
		(start 226.70643 -59.40552)
		(mid 226.688637 -59.316313)
		(end 226.638104 -59.240674)
		(stroke
			(width 0.0508)
			(type default)
		)
		(layer "In2.Cu")
	)
	(gr_line
		(start 226.70643 -59.40552)
		(end 226.70643 -59.45378)
		(stroke
			(width 0.0508)
			(type default)
		)
		(layer "In2.Cu")
	)
	(gr_arc
		(start 226.70643 -57.405524)
		(mid 226.688681 -57.316293)
		(end 226.638104 -57.240678)
		(stroke
			(width 0.0508)
			(type default)
		)
		(layer "In2.Cu")
	)
	(gr_line
		(start 226.70643 -57.405524)
		(end 226.70643 -57.453784)
		(stroke
			(width 0.0508)
			(type default)
		)
		(layer "In2.Cu")
	)
	(gr_arc
		(start 226.70643 -55.405528)
		(mid 226.68864 -55.316319)
		(end 226.638104 -55.240682)
		(stroke
			(width 0.0508)
			(type default)
		)
		(layer "In2.Cu")
	)
	(gr_line
		(start 226.70643 -55.405528)
		(end 226.70643 -55.453788)
		(stroke
			(width 0.0508)
			(type default)
		)
		(layer "In2.Cu")
	)
	(gr_arc
		(start 226.70643 -53.405532)
		(mid 226.705026 -53.380105)
		(end 226.700842 -53.354986)
		(stroke
			(width 0.0508)
			(type default)
		)
		(layer "In2.Cu")
	)
	(gr_line
		(start 226.70643 -53.405532)
		(end 226.70643 -53.453792)
		(stroke
			(width 0.0508)
			(type default)
		)
		(layer "In2.Cu")
	)
	(gr_arc
		(start 226.70643 -50.405538)
		(mid 226.688643 -50.316327)
		(end 226.638104 -50.240692)
		(stroke
			(width 0.0508)
			(type default)
		)
		(layer "In2.Cu")
	)
	(gr_line
		(start 226.70643 -50.405538)
		(end 226.70643 -50.453798)
		(stroke
			(width 0.0508)
			(type default)
		)
		(layer "In2.Cu")
	)
	(gr_line
		(start 226.706684 -74.824844)
		(end 226.706684 -74.825098)
		(stroke
			(width 0.06985)
			(type default)
		)
		(layer "In2.Cu")
	)
	(gr_line
		(start 226.706684 -74.824844)
		(end 226.709986 -74.806048)
		(stroke
			(width 0.06985)
			(type default)
		)
		(layer "In2.Cu")
	)
	(gr_line
		(start 226.706684 -74.787252)
		(end 226.709986 -74.806048)
		(stroke
			(width 0.06985)
			(type default)
		)
		(layer "In2.Cu")
	)
	(gr_arc
		(start 226.729798 -34.58464)
		(mid 226.707605 -34.617716)
		(end 226.699826 -34.656776)
		(stroke
			(width 0.0508)
			(type default)
		)
		(layer "In2.Cu")
	)
	(gr_line
		(start 226.729798 -34.58464)
		(end 226.730306 -34.584132)
		(stroke
			(width 0.0508)
			(type default)
		)
		(layer "In2.Cu")
	)
	(gr_line
		(start 226.738942 -67.099942)
		(end 226.7585 -67.1195)
		(stroke
			(width 0.0508)
			(type default)
		)
		(layer "In2.Cu")
	)
	(gr_line
		(start 226.745546 -47.624746)
		(end 226.7458 -47.625)
		(stroke
			(width 0.06985)
			(type default)
		)
		(layer "In2.Cu")
	)
	(gr_line
		(start 226.7458 -47.625)
		(end 226.746054 -47.625)
		(stroke
			(width 0.06985)
			(type default)
		)
		(layer "In2.Cu")
	)
	(gr_line
		(start 226.7458 -22.876002)
		(end 226.795838 -22.857206)
		(stroke
			(width 0.06985)
			(type default)
		)
		(layer "In2.Cu")
	)
	(gr_line
		(start 226.7585 -67.1195)
		(end 226.7585 -67.320668)
		(stroke
			(width 0.06985)
			(type default)
		)
		(layer "In2.Cu")
	)
	(gr_line
		(start 226.803204 -40.500046)
		(end 227.10013 -40.500046)
		(stroke
			(width 0.0508)
			(type default)
		)
		(layer "In2.Cu")
	)
	(gr_line
		(start 226.803204 -36.500054)
		(end 227.10013 -36.500054)
		(stroke
			(width 0.0508)
			(type default)
		)
		(layer "In2.Cu")
	)
	(gr_arc
		(start 226.803458 -38.50005)
		(mid 226.731616 -38.529808)
		(end 226.701858 -38.60165)
		(stroke
			(width 0.0508)
			(type default)
		)
		(layer "In2.Cu")
	)
	(gr_line
		(start 226.803458 -38.50005)
		(end 227.10013 -38.50005)
		(stroke
			(width 0.0508)
			(type default)
		)
		(layer "In2.Cu")
	)
	(gr_line
		(start 226.803966 -59.119008)
		(end 227.04044 -59.355228)
		(stroke
			(width 0.0508)
			(type default)
		)
		(layer "In2.Cu")
	)
	(gr_line
		(start 226.803966 -57.119012)
		(end 227.04044 -57.355232)
		(stroke
			(width 0.0508)
			(type default)
		)
		(layer "In2.Cu")
	)
	(gr_line
		(start 226.803966 -55.119016)
		(end 227.04044 -55.355236)
		(stroke
			(width 0.0508)
			(type default)
		)
		(layer "In2.Cu")
	)
	(gr_line
		(start 226.803966 -50.119026)
		(end 227.04044 -50.355246)
		(stroke
			(width 0.0508)
			(type default)
		)
		(layer "In2.Cu")
	)
	(gr_line
		(start 226.858068 -53.173122)
		(end 227.04044 -53.35524)
		(stroke
			(width 0.0508)
			(type default)
		)
		(layer "In2.Cu")
	)
	(gr_line
		(start 226.891596 -25.894792)
		(end 226.910392 -25.89149)
		(stroke
			(width 0.06985)
			(type default)
		)
		(layer "In2.Cu")
	)
	(gr_line
		(start 226.910392 -25.89149)
		(end 226.929188 -25.894792)
		(stroke
			(width 0.06985)
			(type default)
		)
		(layer "In2.Cu")
	)
	(gr_arc
		(start 226.934522 -34.500058)
		(mid 226.824096 -34.521893)
		(end 226.730306 -34.584132)
		(stroke
			(width 0.0508)
			(type default)
		)
		(layer "In2.Cu")
	)
	(gr_line
		(start 226.934522 -34.500058)
		(end 227.10013 -34.500058)
		(stroke
			(width 0.0508)
			(type default)
		)
		(layer "In2.Cu")
	)
	(gr_line
		(start 226.958398 -63.03518)
		(end 227.04298 -63.03518)
		(stroke
			(width 0.0508)
			(type default)
		)
		(layer "In2.Cu")
	)
	(gr_arc
		(start 226.968812 -48.182784)
		(mid 227.00296 -48.354331)
		(end 227.10013 -48.499776)
		(stroke
			(width 0.06985)
			(type default)
		)
		(layer "In2.Cu")
	)
	(gr_line
		(start 226.968812 -48.082962)
		(end 226.968812 -48.182784)
		(stroke
			(width 0.06985)
			(type default)
		)
		(layer "In2.Cu")
	)
	(gr_arc
		(start 227.025708 -62.653418)
		(mid 227.080622 -62.585143)
		(end 227.10013 -62.499748)
		(stroke
			(width 0.0508)
			(type default)
		)
		(layer "In2.Cu")
	)
	(gr_line
		(start 227.046282 -24.019764)
		(end 227.100892 -24.030686)
		(stroke
			(width 0.06985)
			(type default)
		)
		(layer "In2.Cu")
	)
	(gr_line
		(start 227.082096 -26.921968)
		(end 227.1014 -26.918666)
		(stroke
			(width 0.06985)
			(type default)
		)
		(layer "In2.Cu")
	)
	(gr_arc
		(start 227.10013 -63.499746)
		(mid 227.176284 -63.385774)
		(end 227.203 -63.251334)
		(stroke
			(width 0.0508)
			(type default)
		)
		(layer "In2.Cu")
	)
	(gr_arc
		(start 227.10013 -59.499754)
		(mid 227.084668 -59.42155)
		(end 227.04044 -59.355228)
		(stroke
			(width 0.0508)
			(type default)
		)
		(layer "In2.Cu")
	)
	(gr_arc
		(start 227.10013 -57.499758)
		(mid 227.084668 -57.421554)
		(end 227.04044 -57.355232)
		(stroke
			(width 0.0508)
			(type default)
		)
		(layer "In2.Cu")
	)
	(gr_arc
		(start 227.10013 -55.499762)
		(mid 227.084671 -55.421556)
		(end 227.04044 -55.355236)
		(stroke
			(width 0.0508)
			(type default)
		)
		(layer "In2.Cu")
	)
	(gr_arc
		(start 227.10013 -53.499766)
		(mid 227.084673 -53.421559)
		(end 227.04044 -53.35524)
		(stroke
			(width 0.0508)
			(type default)
		)
		(layer "In2.Cu")
	)
	(gr_arc
		(start 227.10013 -50.499772)
		(mid 227.084668 -50.421568)
		(end 227.04044 -50.355246)
		(stroke
			(width 0.0508)
			(type default)
		)
		(layer "In2.Cu")
	)
	(gr_line
		(start 227.100892 -24.030686)
		(end 227.153216 -24.010874)
		(stroke
			(width 0.06985)
			(type default)
		)
		(layer "In2.Cu")
	)
	(gr_line
		(start 227.1014 -26.918666)
		(end 227.120196 -26.921968)
		(stroke
			(width 0.06985)
			(type default)
		)
		(layer "In2.Cu")
	)
	(gr_arc
		(start 227.203 -63.1952)
		(mid 227.156131 -63.082049)
		(end 227.04298 -63.03518)
		(stroke
			(width 0.0508)
			(type default)
		)
		(layer "In2.Cu")
	)
	(gr_line
		(start 227.203 -63.1952)
		(end 227.203 -63.251334)
		(stroke
			(width 0.0508)
			(type default)
		)
		(layer "In2.Cu")
	)
	(gr_line
		(start 227.229162 -15.16634)
		(end 227.404422 -15.3416)
		(stroke
			(width 0.06985)
			(type default)
		)
		(layer "In2.Cu")
	)
	(gr_line
		(start 227.234496 -27.811222)
		(end 227.253292 -27.80792)
		(stroke
			(width 0.06985)
			(type default)
		)
		(layer "In2.Cu")
	)
	(gr_line
		(start 227.253292 -27.80792)
		(end 227.272088 -27.811222)
		(stroke
			(width 0.06985)
			(type default)
		)
		(layer "In2.Cu")
	)
	(gr_line
		(start 227.277676 -88.86317)
		(end 227.297234 -88.83523)
		(stroke
			(width 0.06985)
			(type default)
		)
		(layer "In2.Cu")
	)
	(gr_line
		(start 227.297234 -88.83523)
		(end 227.303076 -88.80221)
		(stroke
			(width 0.06985)
			(type default)
		)
		(layer "In2.Cu")
	)
	(gr_line
		(start 227.404422 -15.3416)
		(end 227.823522 -15.3416)
		(stroke
			(width 0.06985)
			(type default)
		)
		(layer "In2.Cu")
	)
	(gr_line
		(start 227.45065 -67.1322)
		(end 227.45065 -67.31508)
		(stroke
			(width 0.06985)
			(type default)
		)
		(layer "In2.Cu")
	)
	(gr_line
		(start 227.45065 -67.1322)
		(end 227.470208 -67.112642)
		(stroke
			(width 0.0508)
			(type default)
		)
		(layer "In2.Cu")
	)
	(gr_line
		(start 227.471986 -67.110864)
		(end 227.49383 -67.08902)
		(stroke
			(width 0.0508)
			(type default)
		)
		(layer "In2.Cu")
	)
	(gr_line
		(start 227.500942 -16.48714)
		(end 227.676202 -16.6624)
		(stroke
			(width 0.06985)
			(type default)
		)
		(layer "In2.Cu")
	)
	(gr_line
		(start 227.526596 -22.23008)
		(end 227.59797 -22.20341)
		(stroke
			(width 0.06985)
			(type default)
		)
		(layer "In2.Cu")
	)
	(gr_line
		(start 227.559362 -14.8336)
		(end 227.668582 -14.8336)
		(stroke
			(width 0.06985)
			(type default)
		)
		(layer "In2.Cu")
	)
	(gr_line
		(start 227.572062 -23.498556)
		(end 227.63988 -23.472902)
		(stroke
			(width 0.06985)
			(type default)
		)
		(layer "In2.Cu")
	)
	(gr_line
		(start 227.59797 -22.20341)
		(end 227.670614 -22.227032)
		(stroke
			(width 0.06985)
			(type default)
		)
		(layer "In2.Cu")
	)
	(gr_line
		(start 227.63988 -23.472902)
		(end 227.709222 -23.494238)
		(stroke
			(width 0.06985)
			(type default)
		)
		(layer "In2.Cu")
	)
	(gr_line
		(start 227.674932 -61.929772)
		(end 228.025706 -61.65342)
		(stroke
			(width 0.0508)
			(type default)
		)
		(layer "In2.Cu")
	)
	(gr_line
		(start 227.676202 -16.6624)
		(end 228.095302 -16.6624)
		(stroke
			(width 0.06985)
			(type default)
		)
		(layer "In2.Cu")
	)
	(gr_line
		(start 227.69703 -67.04838)
		(end 227.759514 -67.110864)
		(stroke
			(width 0.0508)
			(type default)
		)
		(layer "In2.Cu")
	)
	(gr_line
		(start 227.69703 -66.8655)
		(end 227.69703 -67.04838)
		(stroke
			(width 0.0508)
			(type default)
		)
		(layer "In2.Cu")
	)
	(gr_line
		(start 227.761292 -67.112642)
		(end 227.78085 -67.1322)
		(stroke
			(width 0.0508)
			(type default)
		)
		(layer "In2.Cu")
	)
	(gr_line
		(start 227.823522 -15.3416)
		(end 227.998782 -15.16634)
		(stroke
			(width 0.06985)
			(type default)
		)
		(layer "In2.Cu")
	)
	(gr_line
		(start 227.82784 -75.338432)
		(end 227.82784 -75.338686)
		(stroke
			(width 0.06985)
			(type default)
		)
		(layer "In2.Cu")
	)
	(gr_line
		(start 227.82784 -75.338432)
		(end 227.831142 -75.319636)
		(stroke
			(width 0.06985)
			(type default)
		)
		(layer "In2.Cu")
	)
	(gr_line
		(start 227.82784 -75.30084)
		(end 227.831142 -75.319636)
		(stroke
			(width 0.06985)
			(type default)
		)
		(layer "In2.Cu")
	)
	(gr_line
		(start 227.831142 -16.1544)
		(end 227.940362 -16.1544)
		(stroke
			(width 0.06985)
			(type default)
		)
		(layer "In2.Cu")
	)
	(gr_line
		(start 227.858574 -79.172054)
		(end 227.861876 -79.191104)
		(stroke
			(width 0.06985)
			(type default)
		)
		(layer "In2.Cu")
	)
	(gr_line
		(start 227.858574 -79.172054)
		(end 227.861876 -79.153258)
		(stroke
			(width 0.06985)
			(type default)
		)
		(layer "In2.Cu")
	)
	(gr_line
		(start 227.958396 -62.035182)
		(end 228.009196 -62.035182)
		(stroke
			(width 0.0508)
			(type default)
		)
		(layer "In2.Cu")
	)
	(gr_arc
		(start 228.025706 -61.65342)
		(mid 228.08062 -61.585145)
		(end 228.100128 -61.49975)
		(stroke
			(width 0.0508)
			(type default)
		)
		(layer "In2.Cu")
	)
	(gr_line
		(start 228.095302 -16.6624)
		(end 228.270562 -16.48714)
		(stroke
			(width 0.06985)
			(type default)
		)
		(layer "In2.Cu")
	)
	(gr_arc
		(start 228.100128 -62.499748)
		(mid 228.139422 -62.440887)
		(end 228.153214 -62.371478)
		(stroke
			(width 0.0508)
			(type default)
		)
		(layer "In2.Cu")
	)
	(gr_arc
		(start 228.153214 -62.1792)
		(mid 228.111032 -62.077365)
		(end 228.009196 -62.035182)
		(stroke
			(width 0.0508)
			(type default)
		)
		(layer "In2.Cu")
	)
	(gr_line
		(start 228.153214 -62.1792)
		(end 228.153214 -62.371478)
		(stroke
			(width 0.0508)
			(type default)
		)
		(layer "In2.Cu")
	)
	(gr_line
		(start 228.338126 -23.688802)
		(end 228.34854 -23.69185)
		(stroke
			(width 0.06985)
			(type default)
		)
		(layer "In2.Cu")
	)
	(gr_line
		(start 228.34854 -23.69185)
		(end 228.357684 -23.6982)
		(stroke
			(width 0.06985)
			(type default)
		)
		(layer "In2.Cu")
	)
	(gr_line
		(start 228.365304 -89.68359)
		(end 228.384862 -89.65565)
		(stroke
			(width 0.06985)
			(type default)
		)
		(layer "In2.Cu")
	)
	(gr_line
		(start 228.384862 -89.65565)
		(end 228.390704 -89.62263)
		(stroke
			(width 0.06985)
			(type default)
		)
		(layer "In2.Cu")
	)
	(gr_line
		(start 228.422962 -15.16634)
		(end 228.598222 -15.3416)
		(stroke
			(width 0.06985)
			(type default)
		)
		(layer "In2.Cu")
	)
	(gr_line
		(start 228.4476 -67.1576)
		(end 228.4476 -67.343528)
		(stroke
			(width 0.06985)
			(type default)
		)
		(layer "In2.Cu")
	)
	(gr_line
		(start 228.4476 -67.1576)
		(end 228.467158 -67.138042)
		(stroke
			(width 0.0508)
			(type default)
		)
		(layer "In2.Cu")
	)
	(gr_line
		(start 228.468936 -67.136264)
		(end 228.493828 -67.111372)
		(stroke
			(width 0.0508)
			(type default)
		)
		(layer "In2.Cu")
	)
	(gr_line
		(start 228.594412 -81.479136)
		(end 228.594412 -81.47939)
		(stroke
			(width 0.06985)
			(type default)
		)
		(layer "In2.Cu")
	)
	(gr_line
		(start 228.594412 -81.479136)
		(end 228.597714 -81.46034)
		(stroke
			(width 0.06985)
			(type default)
		)
		(layer "In2.Cu")
	)
	(gr_line
		(start 228.594412 -81.441544)
		(end 228.597714 -81.46034)
		(stroke
			(width 0.06985)
			(type default)
		)
		(layer "In2.Cu")
	)
	(gr_line
		(start 228.598222 -15.3416)
		(end 229.017322 -15.3416)
		(stroke
			(width 0.06985)
			(type default)
		)
		(layer "In2.Cu")
	)
	(gr_line
		(start 228.67493 -62.92977)
		(end 229.025704 -62.653418)
		(stroke
			(width 0.0508)
			(type default)
		)
		(layer "In2.Cu")
	)
	(gr_line
		(start 228.694742 -16.48714)
		(end 228.870002 -16.6624)
		(stroke
			(width 0.06985)
			(type default)
		)
		(layer "In2.Cu")
	)
	(gr_line
		(start 228.697028 -67.076828)
		(end 228.756464 -67.136264)
		(stroke
			(width 0.0508)
			(type default)
		)
		(layer "In2.Cu")
	)
	(gr_line
		(start 228.697028 -66.8909)
		(end 228.697028 -67.076828)
		(stroke
			(width 0.0508)
			(type default)
		)
		(layer "In2.Cu")
	)
	(gr_line
		(start 228.753162 -14.8336)
		(end 228.862382 -14.8336)
		(stroke
			(width 0.06985)
			(type default)
		)
		(layer "In2.Cu")
	)
	(gr_line
		(start 228.758242 -67.138042)
		(end 228.7778 -67.1576)
		(stroke
			(width 0.0508)
			(type default)
		)
		(layer "In2.Cu")
	)
	(gr_line
		(start 228.86035 -75.395328)
		(end 228.86035 -75.395582)
		(stroke
			(width 0.06985)
			(type default)
		)
		(layer "In2.Cu")
	)
	(gr_line
		(start 228.86035 -75.395328)
		(end 228.863652 -75.376532)
		(stroke
			(width 0.06985)
			(type default)
		)
		(layer "In2.Cu")
	)
	(gr_line
		(start 228.86035 -75.357736)
		(end 228.863652 -75.376532)
		(stroke
			(width 0.06985)
			(type default)
		)
		(layer "In2.Cu")
	)
	(gr_line
		(start 228.870002 -16.6624)
		(end 229.289102 -16.6624)
		(stroke
			(width 0.06985)
			(type default)
		)
		(layer "In2.Cu")
	)
	(gr_line
		(start 228.90861 -79.21244)
		(end 228.911912 -79.23149)
		(stroke
			(width 0.06985)
			(type default)
		)
		(layer "In2.Cu")
	)
	(gr_line
		(start 228.90861 -79.21244)
		(end 228.911912 -79.193644)
		(stroke
			(width 0.06985)
			(type default)
		)
		(layer "In2.Cu")
	)
	(gr_line
		(start 228.958394 -63.03518)
		(end 229.009194 -63.03518)
		(stroke
			(width 0.0508)
			(type default)
		)
		(layer "In2.Cu")
	)
	(gr_line
		(start 229.017322 -15.3416)
		(end 229.192582 -15.16634)
		(stroke
			(width 0.06985)
			(type default)
		)
		(layer "In2.Cu")
	)
	(gr_line
		(start 229.024942 -16.1544)
		(end 229.134162 -16.1544)
		(stroke
			(width 0.06985)
			(type default)
		)
		(layer "In2.Cu")
	)
	(gr_arc
		(start 229.025704 -62.653418)
		(mid 229.080618 -62.585143)
		(end 229.100126 -62.499748)
		(stroke
			(width 0.0508)
			(type default)
		)
		(layer "In2.Cu")
	)
	(gr_line
		(start 229.07244 -20.839176)
		(end 229.10546 -20.845018)
		(stroke
			(width 0.06985)
			(type default)
		)
		(layer "In2.Cu")
	)
	(gr_arc
		(start 229.100126 -63.499746)
		(mid 229.13942 -63.440885)
		(end 229.153212 -63.371476)
		(stroke
			(width 0.0508)
			(type default)
		)
		(layer "In2.Cu")
	)
	(gr_line
		(start 229.10546 -20.845018)
		(end 229.1334 -20.864576)
		(stroke
			(width 0.06985)
			(type default)
		)
		(layer "In2.Cu")
	)
	(gr_arc
		(start 229.153212 -63.179198)
		(mid 229.111029 -63.077365)
		(end 229.009194 -63.03518)
		(stroke
			(width 0.0508)
			(type default)
		)
		(layer "In2.Cu")
	)
	(gr_line
		(start 229.153212 -63.179198)
		(end 229.153212 -63.371476)
		(stroke
			(width 0.0508)
			(type default)
		)
		(layer "In2.Cu")
	)
	(gr_line
		(start 229.289102 -16.6624)
		(end 229.464362 -16.48714)
		(stroke
			(width 0.06985)
			(type default)
		)
		(layer "In2.Cu")
	)
	(gr_line
		(start 229.4382 -67.1576)
		(end 229.4382 -67.352926)
		(stroke
			(width 0.06985)
			(type default)
		)
		(layer "In2.Cu")
	)
	(gr_line
		(start 229.4382 -67.1576)
		(end 229.457758 -67.138042)
		(stroke
			(width 0.0508)
			(type default)
		)
		(layer "In2.Cu")
	)
	(gr_line
		(start 229.459536 -67.136264)
		(end 229.493826 -67.101974)
		(stroke
			(width 0.0508)
			(type default)
		)
		(layer "In2.Cu")
	)
	(gr_line
		(start 229.465886 -22.812502)
		(end 229.475792 -22.81555)
		(stroke
			(width 0.06985)
			(type default)
		)
		(layer "In2.Cu")
	)
	(gr_line
		(start 229.475792 -22.81555)
		(end 229.484936 -22.8219)
		(stroke
			(width 0.06985)
			(type default)
		)
		(layer "In2.Cu")
	)
	(gr_line
		(start 229.616762 -15.16634)
		(end 229.792022 -15.3416)
		(stroke
			(width 0.06985)
			(type default)
		)
		(layer "In2.Cu")
	)
	(gr_line
		(start 229.674928 -61.929772)
		(end 229.798118 -61.832236)
		(stroke
			(width 0.0508)
			(type default)
		)
		(layer "In2.Cu")
	)
	(gr_line
		(start 229.697026 -67.086226)
		(end 229.747064 -67.136264)
		(stroke
			(width 0.0508)
			(type default)
		)
		(layer "In2.Cu")
	)
	(gr_line
		(start 229.697026 -66.8909)
		(end 229.697026 -67.086226)
		(stroke
			(width 0.0508)
			(type default)
		)
		(layer "In2.Cu")
	)
	(gr_line
		(start 229.731824 -82.016854)
		(end 229.731824 -82.017362)
		(stroke
			(width 0.06985)
			(type default)
		)
		(layer "In2.Cu")
	)
	(gr_line
		(start 229.731824 -82.016854)
		(end 229.735126 -81.997804)
		(stroke
			(width 0.06985)
			(type default)
		)
		(layer "In2.Cu")
	)
	(gr_line
		(start 229.731824 -81.978754)
		(end 229.735126 -81.99755)
		(stroke
			(width 0.06985)
			(type default)
		)
		(layer "In2.Cu")
	)
	(gr_line
		(start 229.735126 -81.99755)
		(end 229.735126 -81.997804)
		(stroke
			(width 0.06985)
			(type default)
		)
		(layer "In2.Cu")
	)
	(gr_line
		(start 229.748842 -67.138042)
		(end 229.7684 -67.1576)
		(stroke
			(width 0.0508)
			(type default)
		)
		(layer "In2.Cu")
	)
	(gr_line
		(start 229.792022 -15.3416)
		(end 230.211122 -15.3416)
		(stroke
			(width 0.06985)
			(type default)
		)
		(layer "In2.Cu")
	)
	(gr_line
		(start 229.798118 -61.832236)
		(end 229.79888 -61.831474)
		(stroke
			(width 0.0508)
			(type default)
		)
		(layer "In2.Cu")
	)
	(gr_line
		(start 229.79888 -61.831474)
		(end 229.829614 -61.807598)
		(stroke
			(width 0.0508)
			(type default)
		)
		(layer "In2.Cu")
	)
	(gr_line
		(start 229.829614 -61.807598)
		(end 229.87127 -61.774832)
		(stroke
			(width 0.0508)
			(type default)
		)
		(layer "In2.Cu")
	)
	(gr_line
		(start 229.87127 -61.774832)
		(end 229.871524 -61.774324)
		(stroke
			(width 0.0508)
			(type default)
		)
		(layer "In2.Cu")
	)
	(gr_line
		(start 229.871524 -61.774324)
		(end 230.025702 -61.65342)
		(stroke
			(width 0.0508)
			(type default)
		)
		(layer "In2.Cu")
	)
	(gr_line
		(start 229.887272 -75.565254)
		(end 229.887272 -75.565508)
		(stroke
			(width 0.06985)
			(type default)
		)
		(layer "In2.Cu")
	)
	(gr_line
		(start 229.887272 -75.565254)
		(end 229.890574 -75.546458)
		(stroke
			(width 0.06985)
			(type default)
		)
		(layer "In2.Cu")
	)
	(gr_line
		(start 229.887272 -75.527662)
		(end 229.890574 -75.546458)
		(stroke
			(width 0.06985)
			(type default)
		)
		(layer "In2.Cu")
	)
	(gr_line
		(start 229.888542 -16.48714)
		(end 230.063802 -16.6624)
		(stroke
			(width 0.06985)
			(type default)
		)
		(layer "In2.Cu")
	)
	(gr_line
		(start 229.946962 -14.8336)
		(end 230.056182 -14.8336)
		(stroke
			(width 0.06985)
			(type default)
		)
		(layer "In2.Cu")
	)
	(gr_line
		(start 229.958392 -62.035182)
		(end 230.030782 -62.035182)
		(stroke
			(width 0.0508)
			(type default)
		)
		(layer "In2.Cu")
	)
	(gr_arc
		(start 230.025702 -61.65342)
		(mid 230.080616 -61.585145)
		(end 230.100124 -61.49975)
		(stroke
			(width 0.0508)
			(type default)
		)
		(layer "In2.Cu")
	)
	(gr_line
		(start 230.063802 -16.6624)
		(end 230.482902 -16.6624)
		(stroke
			(width 0.06985)
			(type default)
		)
		(layer "In2.Cu")
	)
	(gr_arc
		(start 230.100124 -62.499748)
		(mid 230.176245 -62.385766)
		(end 230.202994 -62.251336)
		(stroke
			(width 0.0508)
			(type default)
		)
		(layer "In2.Cu")
	)
	(gr_line
		(start 230.142542 -28.31719)
		(end 230.152448 -28.318968)
		(stroke
			(width 0.06985)
			(type default)
		)
		(layer "In2.Cu")
	)
	(gr_line
		(start 230.152448 -28.318968)
		(end 230.161846 -28.323794)
		(stroke
			(width 0.06985)
			(type default)
		)
		(layer "In2.Cu")
	)
	(gr_arc
		(start 230.163878 -62.0903)
		(mid 230.102806 -62.049526)
		(end 230.030782 -62.035182)
		(stroke
			(width 0.0508)
			(type default)
		)
		(layer "In2.Cu")
	)
	(gr_line
		(start 230.169466 -77.597)
		(end 230.172768 -77.61605)
		(stroke
			(width 0.06985)
			(type default)
		)
		(layer "In2.Cu")
	)
	(gr_line
		(start 230.169466 -77.597)
		(end 230.172768 -77.578204)
		(stroke
			(width 0.06985)
			(type default)
		)
		(layer "In2.Cu")
	)
	(gr_arc
		(start 230.202994 -62.195202)
		(mid 230.192876 -62.139233)
		(end 230.163878 -62.0903)
		(stroke
			(width 0.0508)
			(type default)
		)
		(layer "In2.Cu")
	)
	(gr_line
		(start 230.202994 -62.195202)
		(end 230.202994 -62.251336)
		(stroke
			(width 0.0508)
			(type default)
		)
		(layer "In2.Cu")
	)
	(gr_line
		(start 230.211122 -15.3416)
		(end 230.386382 -15.16634)
		(stroke
			(width 0.06985)
			(type default)
		)
		(layer "In2.Cu")
	)
	(gr_line
		(start 230.218742 -16.1544)
		(end 230.327962 -16.1544)
		(stroke
			(width 0.06985)
			(type default)
		)
		(layer "In2.Cu")
	)
	(gr_line
		(start 230.269034 -28.752038)
		(end 230.29164 -28.763976)
		(stroke
			(width 0.0508)
			(type default)
		)
		(layer "In2.Cu")
	)
	(gr_line
		(start 230.29164 -28.763976)
		(end 230.381556 -28.735274)
		(stroke
			(width 0.0508)
			(type default)
		)
		(layer "In2.Cu")
	)
	(gr_line
		(start 230.421688 -28.459176)
		(end 230.44404 -28.47086)
		(stroke
			(width 0.0508)
			(type default)
		)
		(layer "In2.Cu")
	)
	(gr_line
		(start 230.44404 -28.47086)
		(end 230.467662 -28.546044)
		(stroke
			(width 0.0508)
			(type default)
		)
		(layer "In2.Cu")
	)
	(gr_line
		(start 230.482902 -16.6624)
		(end 230.658162 -16.48714)
		(stroke
			(width 0.06985)
			(type default)
		)
		(layer "In2.Cu")
	)
	(gr_line
		(start 230.55199 -27.527504)
		(end 230.579168 -27.532076)
		(stroke
			(width 0.06985)
			(type default)
		)
		(layer "In2.Cu")
	)
	(gr_line
		(start 230.579168 -27.532076)
		(end 230.603044 -27.547824)
		(stroke
			(width 0.06985)
			(type default)
		)
		(layer "In2.Cu")
	)
	(gr_line
		(start 230.638858 -26.54935)
		(end 230.66883 -26.55443)
		(stroke
			(width 0.06985)
			(type default)
		)
		(layer "In2.Cu")
	)
	(gr_line
		(start 230.66883 -26.55443)
		(end 230.694738 -26.571956)
		(stroke
			(width 0.06985)
			(type default)
		)
		(layer "In2.Cu")
	)
	(gr_line
		(start 230.700326 -28.669742)
		(end 230.70058 -28.669742)
		(stroke
			(width 0.0508)
			(type default)
		)
		(layer "In2.Cu")
	)
	(gr_line
		(start 230.70058 -28.669742)
		(end 230.701088 -28.67025)
		(stroke
			(width 0.0508)
			(type default)
		)
		(layer "In2.Cu")
	)
	(gr_line
		(start 230.810562 -15.16634)
		(end 230.985822 -15.3416)
		(stroke
			(width 0.06985)
			(type default)
		)
		(layer "In2.Cu")
	)
	(gr_line
		(start 230.816912 -96.662748)
		(end 230.83647 -96.634808)
		(stroke
			(width 0.06985)
			(type default)
		)
		(layer "In2.Cu")
	)
	(gr_line
		(start 230.83647 -96.634808)
		(end 230.842312 -96.601788)
		(stroke
			(width 0.06985)
			(type default)
		)
		(layer "In2.Cu")
	)
	(gr_line
		(start 230.870506 -75.523852)
		(end 230.870506 -75.524106)
		(stroke
			(width 0.06985)
			(type default)
		)
		(layer "In2.Cu")
	)
	(gr_line
		(start 230.870506 -75.523852)
		(end 230.873808 -75.505056)
		(stroke
			(width 0.06985)
			(type default)
		)
		(layer "In2.Cu")
	)
	(gr_line
		(start 230.870506 -75.48626)
		(end 230.873808 -75.505056)
		(stroke
			(width 0.06985)
			(type default)
		)
		(layer "In2.Cu")
	)
	(gr_line
		(start 230.874824 -30.898846)
		(end 230.909876 -30.891988)
		(stroke
			(width 0.0508)
			(type default)
		)
		(layer "In2.Cu")
	)
	(gr_arc
		(start 230.909876 -30.891988)
		(mid 231.046423 -30.81114)
		(end 231.100122 -30.661864)
		(stroke
			(width 0.0508)
			(type default)
		)
		(layer "In2.Cu")
	)
	(gr_arc
		(start 230.911654 -31.101538)
		(mid 230.896981 -31.102229)
		(end 230.882444 -31.104332)
		(stroke
			(width 0.0508)
			(type default)
		)
		(layer "In2.Cu")
	)
	(gr_line
		(start 230.911654 -31.101538)
		(end 230.998522 -31.101538)
		(stroke
			(width 0.0508)
			(type default)
		)
		(layer "In2.Cu")
	)
	(gr_line
		(start 230.920544 -22.99716)
		(end 230.957374 -23.049992)
		(stroke
			(width 0.06985)
			(type default)
		)
		(layer "In2.Cu")
	)
	(gr_line
		(start 230.957374 -23.049992)
		(end 231.012492 -23.0886)
		(stroke
			(width 0.06985)
			(type default)
		)
		(layer "In2.Cu")
	)
	(gr_line
		(start 230.985822 -15.3416)
		(end 231.404922 -15.3416)
		(stroke
			(width 0.06985)
			(type default)
		)
		(layer "In2.Cu")
	)
	(gr_line
		(start 231.082342 -16.48714)
		(end 231.257602 -16.6624)
		(stroke
			(width 0.06985)
			(type default)
		)
		(layer "In2.Cu")
	)
	(gr_arc
		(start 231.100122 -31.203138)
		(mid 231.070379 -31.131264)
		(end 230.998522 -31.101538)
		(stroke
			(width 0.0508)
			(type default)
		)
		(layer "In2.Cu")
	)
	(gr_line
		(start 231.100122 -31.203138)
		(end 231.100122 -31.500064)
		(stroke
			(width 0.0508)
			(type default)
		)
		(layer "In2.Cu")
	)
	(gr_line
		(start 231.100122 -30.500066)
		(end 231.100122 -30.661864)
		(stroke
			(width 0.0508)
			(type default)
		)
		(layer "In2.Cu")
	)
	(gr_line
		(start 231.140762 -14.8336)
		(end 231.249982 -14.8336)
		(stroke
			(width 0.06985)
			(type default)
		)
		(layer "In2.Cu")
	)
	(gr_line
		(start 231.18572 -20.40128)
		(end 231.205532 -20.405344)
		(stroke
			(width 0.06985)
			(type default)
		)
		(layer "In2.Cu")
	)
	(gr_line
		(start 231.202738 -24.025606)
		(end 231.21747 -24.03602)
		(stroke
			(width 0.06985)
			(type default)
		)
		(layer "In2.Cu")
	)
	(gr_line
		(start 231.205532 -20.405344)
		(end 231.223312 -20.416774)
		(stroke
			(width 0.06985)
			(type default)
		)
		(layer "In2.Cu")
	)
	(gr_line
		(start 231.21747 -24.03602)
		(end 231.218486 -24.037544)
		(stroke
			(width 0.06985)
			(type default)
		)
		(layer "In2.Cu")
	)
	(gr_line
		(start 231.218486 -24.037544)
		(end 231.227122 -24.04999)
		(stroke
			(width 0.06985)
			(type default)
		)
		(layer "In2.Cu")
	)
	(gr_line
		(start 231.257602 -16.6624)
		(end 231.676702 -16.6624)
		(stroke
			(width 0.06985)
			(type default)
		)
		(layer "In2.Cu")
	)
	(gr_line
		(start 231.290622 -69.935852)
		(end 231.293924 -69.954902)
		(stroke
			(width 0.06985)
			(type default)
		)
		(layer "In2.Cu")
	)
	(gr_line
		(start 231.290622 -69.935852)
		(end 231.293924 -69.917056)
		(stroke
			(width 0.06985)
			(type default)
		)
		(layer "In2.Cu")
	)
	(gr_line
		(start 231.404922 -15.3416)
		(end 231.580182 -15.16634)
		(stroke
			(width 0.06985)
			(type default)
		)
		(layer "In2.Cu")
	)
	(gr_line
		(start 231.412542 -16.1544)
		(end 231.521762 -16.1544)
		(stroke
			(width 0.06985)
			(type default)
		)
		(layer "In2.Cu")
	)
	(gr_line
		(start 231.4194 -67.2846)
		(end 231.4194 -67.359276)
		(stroke
			(width 0.0508)
			(type default)
		)
		(layer "In2.Cu")
	)
	(gr_line
		(start 231.4194 -67.2846)
		(end 231.438958 -67.265042)
		(stroke
			(width 0.0508)
			(type default)
		)
		(layer "In2.Cu")
	)
	(gr_line
		(start 231.440736 -67.263264)
		(end 231.493822 -67.210178)
		(stroke
			(width 0.0508)
			(type default)
		)
		(layer "In2.Cu")
	)
	(gr_line
		(start 231.481122 -77.7875)
		(end 231.484424 -77.80655)
		(stroke
			(width 0.06985)
			(type default)
		)
		(layer "In2.Cu")
	)
	(gr_line
		(start 231.481122 -77.7875)
		(end 231.484424 -77.768704)
		(stroke
			(width 0.06985)
			(type default)
		)
		(layer "In2.Cu")
	)
	(gr_line
		(start 231.493822 -67.0179)
		(end 231.493822 -67.210178)
		(stroke
			(width 0.0508)
			(type default)
		)
		(layer "In2.Cu")
	)
	(gr_line
		(start 231.556052 -98.150172)
		(end 231.57561 -98.122232)
		(stroke
			(width 0.06985)
			(type default)
		)
		(layer "In2.Cu")
	)
	(gr_line
		(start 231.566974 -109.912404)
		(end 231.586532 -109.884464)
		(stroke
			(width 0.06985)
			(type default)
		)
		(layer "In2.Cu")
	)
	(gr_line
		(start 231.57561 -98.122232)
		(end 231.581452 -98.089212)
		(stroke
			(width 0.06985)
			(type default)
		)
		(layer "In2.Cu")
	)
	(gr_line
		(start 231.586532 -109.884464)
		(end 231.592374 -109.851444)
		(stroke
			(width 0.06985)
			(type default)
		)
		(layer "In2.Cu")
	)
	(gr_line
		(start 231.622346 -25.188418)
		(end 231.632506 -25.202896)
		(stroke
			(width 0.06985)
			(type default)
		)
		(layer "In2.Cu")
	)
	(gr_line
		(start 231.632252 -25.20315)
		(end 231.632506 -25.202896)
		(stroke
			(width 0.06985)
			(type default)
		)
		(layer "In2.Cu")
	)
	(gr_line
		(start 231.632252 -25.20315)
		(end 231.648762 -25.214834)
		(stroke
			(width 0.06985)
			(type default)
		)
		(layer "In2.Cu")
	)
	(gr_line
		(start 231.674924 -62.92977)
		(end 231.754172 -62.866524)
		(stroke
			(width 0.0508)
			(type default)
		)
		(layer "In2.Cu")
	)
	(gr_line
		(start 231.676702 -16.6624)
		(end 231.851962 -16.48714)
		(stroke
			(width 0.06985)
			(type default)
		)
		(layer "In2.Cu")
	)
	(gr_line
		(start 231.697022 -67.232022)
		(end 231.728264 -67.263264)
		(stroke
			(width 0.0508)
			(type default)
		)
		(layer "In2.Cu")
	)
	(gr_line
		(start 231.730042 -67.265042)
		(end 231.7496 -67.2846)
		(stroke
			(width 0.0508)
			(type default)
		)
		(layer "In2.Cu")
	)
	(gr_line
		(start 231.7496 -67.2846)
		(end 231.7496 -67.476878)
		(stroke
			(width 0.06985)
			(type default)
		)
		(layer "In2.Cu")
	)
	(gr_line
		(start 231.754172 -62.866524)
		(end 231.75468 -62.866016)
		(stroke
			(width 0.0508)
			(type default)
		)
		(layer "In2.Cu")
	)
	(gr_line
		(start 231.75468 -62.866016)
		(end 231.79786 -62.831726)
		(stroke
			(width 0.0508)
			(type default)
		)
		(layer "In2.Cu")
	)
	(gr_line
		(start 231.79786 -62.831726)
		(end 231.818434 -62.815724)
		(stroke
			(width 0.0508)
			(type default)
		)
		(layer "In2.Cu")
	)
	(gr_line
		(start 231.818434 -62.815724)
		(end 231.824276 -62.811152)
		(stroke
			(width 0.0508)
			(type default)
		)
		(layer "In2.Cu")
	)
	(gr_line
		(start 231.824276 -62.811152)
		(end 231.829356 -62.807342)
		(stroke
			(width 0.0508)
			(type default)
		)
		(layer "In2.Cu")
	)
	(gr_line
		(start 231.829356 -62.807342)
		(end 231.8512 -62.79007)
		(stroke
			(width 0.0508)
			(type default)
		)
		(layer "In2.Cu")
	)
	(gr_line
		(start 231.839008 -28.765246)
		(end 231.860344 -28.778708)
		(stroke
			(width 0.0508)
			(type default)
		)
		(layer "In2.Cu")
	)
	(gr_line
		(start 231.8512 -62.79007)
		(end 231.851454 -62.79007)
		(stroke
			(width 0.0508)
			(type default)
		)
		(layer "In2.Cu")
	)
	(gr_line
		(start 231.851454 -62.79007)
		(end 231.858058 -62.784736)
		(stroke
			(width 0.0508)
			(type default)
		)
		(layer "In2.Cu")
	)
	(gr_line
		(start 231.858058 -62.784736)
		(end 231.895904 -62.755272)
		(stroke
			(width 0.0508)
			(type default)
		)
		(layer "In2.Cu")
	)
	(gr_line
		(start 231.860344 -28.778708)
		(end 231.948736 -28.758896)
		(stroke
			(width 0.0508)
			(type default)
		)
		(layer "In2.Cu")
	)
	(gr_line
		(start 231.895904 -62.755272)
		(end 231.902 -62.7507)
		(stroke
			(width 0.0508)
			(type default)
		)
		(layer "In2.Cu")
	)
	(gr_line
		(start 231.902 -62.7507)
		(end 231.90454 -62.748414)
		(stroke
			(width 0.0508)
			(type default)
		)
		(layer "In2.Cu")
	)
	(gr_line
		(start 231.90454 -62.748414)
		(end 232.026206 -62.652402)
		(stroke
			(width 0.0508)
			(type default)
		)
		(layer "In2.Cu")
	)
	(gr_line
		(start 231.958388 -63.03518)
		(end 231.996234 -63.03518)
		(stroke
			(width 0.0508)
			(type default)
		)
		(layer "In2.Cu")
	)
	(gr_arc
		(start 231.99852 -29.89834)
		(mid 232.070362 -29.868582)
		(end 232.10012 -29.79674)
		(stroke
			(width 0.0508)
			(type default)
		)
		(layer "In2.Cu")
	)
	(gr_line
		(start 232.017062 -28.486862)
		(end 232.038398 -28.500324)
		(stroke
			(width 0.0508)
			(type default)
		)
		(layer "In2.Cu")
	)
	(gr_arc
		(start 232.026206 -62.652402)
		(mid 232.080678 -62.584554)
		(end 232.10012 -62.499748)
		(stroke
			(width 0.0508)
			(type default)
		)
		(layer "In2.Cu")
	)
	(gr_line
		(start 232.038398 -28.500324)
		(end 232.055924 -28.580588)
		(stroke
			(width 0.0508)
			(type default)
		)
		(layer "In2.Cu")
	)
	(gr_arc
		(start 232.10012 -63.499746)
		(mid 232.176241 -63.385764)
		(end 232.20299 -63.251334)
		(stroke
			(width 0.0508)
			(type default)
		)
		(layer "In2.Cu")
	)
	(gr_arc
		(start 232.10012 -30.20314)
		(mid 232.070377 -30.131265)
		(end 231.99852 -30.10154)
		(stroke
			(width 0.0508)
			(type default)
		)
		(layer "In2.Cu")
	)
	(gr_line
		(start 232.10012 -30.20314)
		(end 232.10012 -30.500066)
		(stroke
			(width 0.0508)
			(type default)
		)
		(layer "In2.Cu")
	)
	(gr_line
		(start 232.10012 -29.500068)
		(end 232.10012 -29.79674)
		(stroke
			(width 0.0508)
			(type default)
		)
		(layer "In2.Cu")
	)
	(gr_arc
		(start 232.131362 -63.091314)
		(mid 232.06937 -63.049846)
		(end 231.996234 -63.03518)
		(stroke
			(width 0.0508)
			(type default)
		)
		(layer "In2.Cu")
	)
	(gr_line
		(start 232.131362 -63.091314)
		(end 232.140252 -63.09995)
		(stroke
			(width 0.0508)
			(type default)
		)
		(layer "In2.Cu")
	)
	(gr_line
		(start 232.157524 -19.29257)
		(end 232.190544 -19.298412)
		(stroke
			(width 0.06985)
			(type default)
		)
		(layer "In2.Cu")
	)
	(gr_line
		(start 232.190544 -19.298412)
		(end 232.218484 -19.31797)
		(stroke
			(width 0.06985)
			(type default)
		)
		(layer "In2.Cu")
	)
	(gr_arc
		(start 232.20299 -63.251334)
		(mid 232.186647 -63.169419)
		(end 232.140252 -63.09995)
		(stroke
			(width 0.0508)
			(type default)
		)
		(layer "In2.Cu")
	)
	(gr_line
		(start 232.249218 -70.261734)
		(end 232.25252 -70.280784)
		(stroke
			(width 0.06985)
			(type default)
		)
		(layer "In2.Cu")
	)
	(gr_line
		(start 232.249218 -70.261734)
		(end 232.25252 -70.242938)
		(stroke
			(width 0.06985)
			(type default)
		)
		(layer "In2.Cu")
	)
	(gr_line
		(start 232.323386 -28.111196)
		(end 232.339896 -28.130246)
		(stroke
			(width 0.0508)
			(type default)
		)
		(layer "In2.Cu")
	)
	(gr_line
		(start 232.339896 -28.130246)
		(end 232.426256 -28.135834)
		(stroke
			(width 0.0508)
			(type default)
		)
		(layer "In2.Cu")
	)
	(gr_line
		(start 232.346246 -88.073738)
		(end 232.346246 -88.073992)
		(stroke
			(width 0.06985)
			(type default)
		)
		(layer "In2.Cu")
	)
	(gr_line
		(start 232.346246 -88.073738)
		(end 232.349548 -88.054942)
		(stroke
			(width 0.06985)
			(type default)
		)
		(layer "In2.Cu")
	)
	(gr_line
		(start 232.346246 -88.036146)
		(end 232.349548 -88.054942)
		(stroke
			(width 0.06985)
			(type default)
		)
		(layer "In2.Cu")
	)
	(gr_line
		(start 232.3465 -111.963708)
		(end 232.366058 -111.935768)
		(stroke
			(width 0.06985)
			(type default)
		)
		(layer "In2.Cu")
	)
	(gr_line
		(start 232.366058 -111.935768)
		(end 232.3719 -111.902748)
		(stroke
			(width 0.06985)
			(type default)
		)
		(layer "In2.Cu")
	)
	(gr_line
		(start 232.408222 -28.808172)
		(end 232.420414 -28.816046)
		(stroke
			(width 0.0508)
			(type default)
		)
		(layer "In2.Cu")
	)
	(gr_line
		(start 232.410254 -74.420476)
		(end 232.410254 -74.42073)
		(stroke
			(width 0.06985)
			(type default)
		)
		(layer "In2.Cu")
	)
	(gr_line
		(start 232.410254 -74.420476)
		(end 232.413556 -74.40168)
		(stroke
			(width 0.06985)
			(type default)
		)
		(layer "In2.Cu")
	)
	(gr_line
		(start 232.410254 -74.382884)
		(end 232.413556 -74.40168)
		(stroke
			(width 0.06985)
			(type default)
		)
		(layer "In2.Cu")
	)
	(gr_line
		(start 232.420414 -28.816046)
		(end 232.428288 -28.828238)
		(stroke
			(width 0.0508)
			(type default)
		)
		(layer "In2.Cu")
	)
	(gr_line
		(start 232.4354 -67.308476)
		(end 232.4354 -67.43192)
		(stroke
			(width 0.06985)
			(type default)
		)
		(layer "In2.Cu")
	)
	(gr_line
		(start 232.4354 -67.2338)
		(end 232.4354 -67.308476)
		(stroke
			(width 0.0508)
			(type default)
		)
		(layer "In2.Cu")
	)
	(gr_line
		(start 232.4354 -67.2338)
		(end 232.454958 -67.214242)
		(stroke
			(width 0.0508)
			(type default)
		)
		(layer "In2.Cu")
	)
	(gr_line
		(start 232.43921 -99.07397)
		(end 232.458768 -99.04603)
		(stroke
			(width 0.06985)
			(type default)
		)
		(layer "In2.Cu")
	)
	(gr_line
		(start 232.456736 -67.212464)
		(end 232.49382 -67.17538)
		(stroke
			(width 0.0508)
			(type default)
		)
		(layer "In2.Cu")
	)
	(gr_line
		(start 232.458768 -99.04603)
		(end 232.46461 -99.01301)
		(stroke
			(width 0.06985)
			(type default)
		)
		(layer "In2.Cu")
	)
	(gr_line
		(start 232.461054 -27.767788)
		(end 232.461816 -27.768296)
		(stroke
			(width 0.06985)
			(type default)
		)
		(layer "In2.Cu")
	)
	(gr_line
		(start 232.461816 -27.768296)
		(end 232.462832 -27.769312)
		(stroke
			(width 0.06985)
			(type default)
		)
		(layer "In2.Cu")
	)
	(gr_line
		(start 232.51795 -77.675232)
		(end 232.521252 -77.694282)
		(stroke
			(width 0.06985)
			(type default)
		)
		(layer "In2.Cu")
	)
	(gr_line
		(start 232.51795 -77.675232)
		(end 232.521252 -77.656436)
		(stroke
			(width 0.06985)
			(type default)
		)
		(layer "In2.Cu")
	)
	(gr_line
		(start 232.530904 -25.427686)
		(end 232.550208 -25.44064)
		(stroke
			(width 0.06985)
			(type default)
		)
		(layer "In2.Cu")
	)
	(gr_line
		(start 232.550208 -25.44064)
		(end 232.563162 -25.459182)
		(stroke
			(width 0.06985)
			(type default)
		)
		(layer "In2.Cu")
	)
	(gr_line
		(start 232.572052 -27.893518)
		(end 232.588562 -27.912568)
		(stroke
			(width 0.0508)
			(type default)
		)
		(layer "In2.Cu")
	)
	(gr_line
		(start 232.58272 -27.998674)
		(end 232.588562 -27.912568)
		(stroke
			(width 0.0508)
			(type default)
		)
		(layer "In2.Cu")
	)
	(gr_line
		(start 232.674922 -61.929772)
		(end 232.75417 -61.866526)
		(stroke
			(width 0.0508)
			(type default)
		)
		(layer "In2.Cu")
	)
	(gr_line
		(start 232.687622 -29.23159)
		(end 232.702608 -29.254958)
		(stroke
			(width 0.0508)
			(type default)
		)
		(layer "In2.Cu")
	)
	(gr_line
		(start 232.69702 -67.16522)
		(end 232.744264 -67.212464)
		(stroke
			(width 0.0508)
			(type default)
		)
		(layer "In2.Cu")
	)
	(gr_line
		(start 232.69702 -67.041776)
		(end 232.69702 -67.16522)
		(stroke
			(width 0.0508)
			(type default)
		)
		(layer "In2.Cu")
	)
	(gr_line
		(start 232.71607 -21.386038)
		(end 232.740962 -21.402294)
		(stroke
			(width 0.06985)
			(type default)
		)
		(layer "In2.Cu")
	)
	(gr_line
		(start 232.72242 -22.2631)
		(end 232.726992 -22.284436)
		(stroke
			(width 0.06985)
			(type default)
		)
		(layer "In2.Cu")
	)
	(gr_line
		(start 232.726992 -22.284436)
		(end 232.73893 -22.302978)
		(stroke
			(width 0.06985)
			(type default)
		)
		(layer "In2.Cu")
	)
	(gr_line
		(start 232.740962 -21.402294)
		(end 232.756964 -21.426932)
		(stroke
			(width 0.06985)
			(type default)
		)
		(layer "In2.Cu")
	)
	(gr_line
		(start 232.746042 -67.214242)
		(end 232.7656 -67.2338)
		(stroke
			(width 0.0508)
			(type default)
		)
		(layer "In2.Cu")
	)
	(gr_line
		(start 232.75417 -61.866526)
		(end 232.754678 -61.866018)
		(stroke
			(width 0.0508)
			(type default)
		)
		(layer "In2.Cu")
	)
	(gr_line
		(start 232.754678 -61.866018)
		(end 232.797858 -61.831728)
		(stroke
			(width 0.0508)
			(type default)
		)
		(layer "In2.Cu")
	)
	(gr_line
		(start 232.797858 -61.831728)
		(end 232.818432 -61.815726)
		(stroke
			(width 0.0508)
			(type default)
		)
		(layer "In2.Cu")
	)
	(gr_line
		(start 232.818432 -61.815726)
		(end 232.824274 -61.811154)
		(stroke
			(width 0.0508)
			(type default)
		)
		(layer "In2.Cu")
	)
	(gr_line
		(start 232.824274 -61.811154)
		(end 232.829354 -61.807344)
		(stroke
			(width 0.0508)
			(type default)
		)
		(layer "In2.Cu")
	)
	(gr_line
		(start 232.829354 -61.807344)
		(end 232.851198 -61.790072)
		(stroke
			(width 0.0508)
			(type default)
		)
		(layer "In2.Cu")
	)
	(gr_line
		(start 232.851198 -61.790072)
		(end 232.851452 -61.790072)
		(stroke
			(width 0.0508)
			(type default)
		)
		(layer "In2.Cu")
	)
	(gr_line
		(start 232.851452 -61.790072)
		(end 232.858056 -61.784738)
		(stroke
			(width 0.0508)
			(type default)
		)
		(layer "In2.Cu")
	)
	(gr_line
		(start 232.858056 -61.784738)
		(end 232.895902 -61.755274)
		(stroke
			(width 0.0508)
			(type default)
		)
		(layer "In2.Cu")
	)
	(gr_line
		(start 232.895902 -61.755274)
		(end 232.901998 -61.750702)
		(stroke
			(width 0.0508)
			(type default)
		)
		(layer "In2.Cu")
	)
	(gr_line
		(start 232.901998 -61.750702)
		(end 232.904538 -61.748416)
		(stroke
			(width 0.0508)
			(type default)
		)
		(layer "In2.Cu")
	)
	(gr_line
		(start 232.904538 -61.748416)
		(end 233.026204 -61.652404)
		(stroke
			(width 0.0508)
			(type default)
		)
		(layer "In2.Cu")
	)
	(gr_arc
		(start 232.921556 -30.898338)
		(mid 232.989889 -30.884746)
		(end 233.047794 -30.846014)
		(stroke
			(width 0.0508)
			(type default)
		)
		(layer "In2.Cu")
	)
	(gr_line
		(start 232.931208 -21.695156)
		(end 232.943146 -21.713698)
		(stroke
			(width 0.06985)
			(type default)
		)
		(layer "In2.Cu")
	)
	(gr_line
		(start 232.943146 -21.713698)
		(end 232.947718 -21.735034)
		(stroke
			(width 0.06985)
			(type default)
		)
		(layer "In2.Cu")
	)
	(gr_line
		(start 232.958386 -62.035182)
		(end 232.996232 -62.035182)
		(stroke
			(width 0.0508)
			(type default)
		)
		(layer "In2.Cu")
	)
	(gr_arc
		(start 233.026204 -61.652404)
		(mid 233.080676 -61.584556)
		(end 233.100118 -61.49975)
		(stroke
			(width 0.0508)
			(type default)
		)
		(layer "In2.Cu")
	)
	(gr_arc
		(start 233.047032 -31.154624)
		(mid 232.988173 -31.115336)
		(end 232.918762 -31.101538)
		(stroke
			(width 0.0508)
			(type default)
		)
		(layer "In2.Cu")
	)
	(gr_line
		(start 233.047032 -31.154624)
		(end 233.0704 -31.177992)
		(stroke
			(width 0.0508)
			(type default)
		)
		(layer "In2.Cu")
	)
	(gr_line
		(start 233.047794 -30.846014)
		(end 233.0704 -30.823408)
		(stroke
			(width 0.0508)
			(type default)
		)
		(layer "In2.Cu")
	)
	(gr_line
		(start 233.05516 -28.54071)
		(end 233.058208 -28.544266)
		(stroke
			(width 0.0508)
			(type default)
		)
		(layer "In2.Cu")
	)
	(gr_line
		(start 233.058208 -28.544266)
		(end 233.059986 -28.548584)
		(stroke
			(width 0.0508)
			(type default)
		)
		(layer "In2.Cu")
	)
	(gr_arc
		(start 233.0704 -30.823408)
		(mid 233.092383 -30.790414)
		(end 233.100118 -30.751526)
		(stroke
			(width 0.0508)
			(type default)
		)
		(layer "In2.Cu")
	)
	(gr_arc
		(start 233.100118 -62.499748)
		(mid 233.17624 -62.385766)
		(end 233.202988 -62.251336)
		(stroke
			(width 0.0508)
			(type default)
		)
		(layer "In2.Cu")
	)
	(gr_arc
		(start 233.100118 -31.249874)
		(mid 233.092394 -31.210981)
		(end 233.0704 -31.177992)
		(stroke
			(width 0.0508)
			(type default)
		)
		(layer "In2.Cu")
	)
	(gr_line
		(start 233.100118 -31.249874)
		(end 233.100118 -31.500064)
		(stroke
			(width 0.0508)
			(type default)
		)
		(layer "In2.Cu")
	)
	(gr_line
		(start 233.100118 -30.500066)
		(end 233.100118 -30.751526)
		(stroke
			(width 0.0508)
			(type default)
		)
		(layer "In2.Cu")
	)
	(gr_arc
		(start 233.13136 -62.091316)
		(mid 233.069368 -62.049848)
		(end 232.996232 -62.035182)
		(stroke
			(width 0.0508)
			(type default)
		)
		(layer "In2.Cu")
	)
	(gr_line
		(start 233.13136 -62.091316)
		(end 233.14025 -62.099952)
		(stroke
			(width 0.0508)
			(type default)
		)
		(layer "In2.Cu")
	)
	(gr_line
		(start 233.185462 -70.427088)
		(end 233.188764 -70.446138)
		(stroke
			(width 0.06985)
			(type default)
		)
		(layer "In2.Cu")
	)
	(gr_line
		(start 233.185462 -70.427088)
		(end 233.188764 -70.408292)
		(stroke
			(width 0.06985)
			(type default)
		)
		(layer "In2.Cu")
	)
	(gr_arc
		(start 233.202988 -62.251336)
		(mid 233.186645 -62.16942)
		(end 233.14025 -62.099952)
		(stroke
			(width 0.0508)
			(type default)
		)
		(layer "In2.Cu")
	)
	(gr_line
		(start 233.279188 -29.09697)
		(end 233.281728 -29.10332)
		(stroke
			(width 0.0508)
			(type default)
		)
		(layer "In2.Cu")
	)
	(gr_line
		(start 233.369358 -74.748898)
		(end 233.369358 -74.749152)
		(stroke
			(width 0.06985)
			(type default)
		)
		(layer "In2.Cu")
	)
	(gr_line
		(start 233.369358 -74.748898)
		(end 233.37266 -74.730102)
		(stroke
			(width 0.06985)
			(type default)
		)
		(layer "In2.Cu")
	)
	(gr_line
		(start 233.369358 -74.711306)
		(end 233.37266 -74.730102)
		(stroke
			(width 0.06985)
			(type default)
		)
		(layer "In2.Cu")
	)
	(gr_line
		(start 233.4006 -67.2338)
		(end 233.420158 -67.214242)
		(stroke
			(width 0.0508)
			(type default)
		)
		(layer "In2.Cu")
	)
	(gr_line
		(start 233.421936 -67.212464)
		(end 233.493818 -67.140582)
		(stroke
			(width 0.0508)
			(type default)
		)
		(layer "In2.Cu")
	)
	(gr_line
		(start 233.450384 -24.39289)
		(end 233.465878 -24.403812)
		(stroke
			(width 0.06985)
			(type default)
		)
		(layer "In2.Cu")
	)
	(gr_line
		(start 233.465878 -24.403812)
		(end 233.4768 -24.419306)
		(stroke
			(width 0.06985)
			(type default)
		)
		(layer "In2.Cu")
	)
	(gr_line
		(start 233.485436 -87.29091)
		(end 233.485436 -87.291164)
		(stroke
			(width 0.06985)
			(type default)
		)
		(layer "In2.Cu")
	)
	(gr_line
		(start 233.485436 -87.29091)
		(end 233.488738 -87.272114)
		(stroke
			(width 0.06985)
			(type default)
		)
		(layer "In2.Cu")
	)
	(gr_line
		(start 233.485436 -87.253318)
		(end 233.488738 -87.272114)
		(stroke
			(width 0.06985)
			(type default)
		)
		(layer "In2.Cu")
	)
	(gr_line
		(start 233.493818 -66.9671)
		(end 233.493818 -67.140582)
		(stroke
			(width 0.0508)
			(type default)
		)
		(layer "In2.Cu")
	)
	(gr_line
		(start 233.493818 -34.127694)
		(end 233.530394 -34.091372)
		(stroke
			(width 0.0508)
			(type default)
		)
		(layer "In2.Cu")
	)
	(gr_line
		(start 233.504232 -77.625194)
		(end 233.507534 -77.644244)
		(stroke
			(width 0.06985)
			(type default)
		)
		(layer "In2.Cu")
	)
	(gr_line
		(start 233.504232 -77.625194)
		(end 233.507534 -77.606398)
		(stroke
			(width 0.06985)
			(type default)
		)
		(layer "In2.Cu")
	)
	(gr_line
		(start 233.50728 -112.199166)
		(end 233.526838 -112.171226)
		(stroke
			(width 0.06985)
			(type default)
		)
		(layer "In2.Cu")
	)
	(gr_line
		(start 233.526838 -112.171226)
		(end 233.53268 -112.138206)
		(stroke
			(width 0.06985)
			(type default)
		)
		(layer "In2.Cu")
	)
	(gr_line
		(start 233.640884 -28.41879)
		(end 233.658664 -28.43657)
		(stroke
			(width 0.0508)
			(type default)
		)
		(layer "In2.Cu")
	)
	(gr_line
		(start 233.658664 -28.43657)
		(end 233.74477 -28.436316)
		(stroke
			(width 0.0508)
			(type default)
		)
		(layer "In2.Cu")
	)
	(gr_line
		(start 233.67492 -62.92977)
		(end 233.754168 -62.866524)
		(stroke
			(width 0.0508)
			(type default)
		)
		(layer "In2.Cu")
	)
	(gr_line
		(start 233.686858 -33.934908)
		(end 233.723688 -33.898332)
		(stroke
			(width 0.0508)
			(type default)
		)
		(layer "In2.Cu")
	)
	(gr_line
		(start 233.697018 -67.200018)
		(end 233.709464 -67.212464)
		(stroke
			(width 0.0508)
			(type default)
		)
		(layer "In2.Cu")
	)
	(gr_line
		(start 233.711242 -67.214242)
		(end 233.7308 -67.2338)
		(stroke
			(width 0.0508)
			(type default)
		)
		(layer "In2.Cu")
	)
	(gr_line
		(start 233.7308 -67.2338)
		(end 233.7308 -67.407282)
		(stroke
			(width 0.06985)
			(type default)
		)
		(layer "In2.Cu")
	)
	(gr_line
		(start 233.746294 -20.387818)
		(end 233.761788 -20.39874)
		(stroke
			(width 0.06985)
			(type default)
		)
		(layer "In2.Cu")
	)
	(gr_line
		(start 233.754168 -62.866524)
		(end 233.754676 -62.866016)
		(stroke
			(width 0.0508)
			(type default)
		)
		(layer "In2.Cu")
	)
	(gr_line
		(start 233.754676 -62.866016)
		(end 233.797856 -62.831726)
		(stroke
			(width 0.0508)
			(type default)
		)
		(layer "In2.Cu")
	)
	(gr_line
		(start 233.761788 -20.39874)
		(end 233.77271 -20.414234)
		(stroke
			(width 0.06985)
			(type default)
		)
		(layer "In2.Cu")
	)
	(gr_line
		(start 233.797856 -62.831726)
		(end 233.81843 -62.815724)
		(stroke
			(width 0.0508)
			(type default)
		)
		(layer "In2.Cu")
	)
	(gr_line
		(start 233.81843 -62.815724)
		(end 233.824272 -62.811152)
		(stroke
			(width 0.0508)
			(type default)
		)
		(layer "In2.Cu")
	)
	(gr_line
		(start 233.824272 -62.811152)
		(end 233.829352 -62.807342)
		(stroke
			(width 0.0508)
			(type default)
		)
		(layer "In2.Cu")
	)
	(gr_line
		(start 233.829352 -62.807342)
		(end 233.851196 -62.79007)
		(stroke
			(width 0.0508)
			(type default)
		)
		(layer "In2.Cu")
	)
	(gr_line
		(start 233.851196 -62.79007)
		(end 233.85145 -62.79007)
		(stroke
			(width 0.0508)
			(type default)
		)
		(layer "In2.Cu")
	)
	(gr_line
		(start 233.85145 -62.79007)
		(end 233.858054 -62.784736)
		(stroke
			(width 0.0508)
			(type default)
		)
		(layer "In2.Cu")
	)
	(gr_line
		(start 233.858054 -62.784736)
		(end 233.8959 -62.755272)
		(stroke
			(width 0.0508)
			(type default)
		)
		(layer "In2.Cu")
	)
	(gr_line
		(start 233.874564 -28.185364)
		(end 233.892344 -28.203144)
		(stroke
			(width 0.0508)
			(type default)
		)
		(layer "In2.Cu")
	)
	(gr_line
		(start 233.892344 -28.203144)
		(end 233.892344 -28.289758)
		(stroke
			(width 0.0508)
			(type default)
		)
		(layer "In2.Cu")
	)
	(gr_line
		(start 233.8959 -62.755272)
		(end 233.901996 -62.7507)
		(stroke
			(width 0.0508)
			(type default)
		)
		(layer "In2.Cu")
	)
	(gr_line
		(start 233.901996 -62.7507)
		(end 233.904536 -62.748414)
		(stroke
			(width 0.0508)
			(type default)
		)
		(layer "In2.Cu")
	)
	(gr_line
		(start 233.904536 -62.748414)
		(end 234.026202 -62.652402)
		(stroke
			(width 0.0508)
			(type default)
		)
		(layer "In2.Cu")
	)
	(gr_line
		(start 233.958384 -63.03518)
		(end 233.99623 -63.03518)
		(stroke
			(width 0.0508)
			(type default)
		)
		(layer "In2.Cu")
	)
	(gr_arc
		(start 234.026202 -62.652402)
		(mid 234.080674 -62.584554)
		(end 234.100116 -62.499748)
		(stroke
			(width 0.0508)
			(type default)
		)
		(layer "In2.Cu")
	)
	(gr_arc
		(start 234.100116 -63.499746)
		(mid 234.176238 -63.385764)
		(end 234.202986 -63.251334)
		(stroke
			(width 0.0508)
			(type default)
		)
		(layer "In2.Cu")
	)
	(gr_arc
		(start 234.100116 -30.20314)
		(mid 234.070358 -30.131298)
		(end 233.998516 -30.10154)
		(stroke
			(width 0.0508)
			(type default)
		)
		(layer "In2.Cu")
	)
	(gr_line
		(start 234.100116 -30.20314)
		(end 234.100116 -30.500066)
		(stroke
			(width 0.0508)
			(type default)
		)
		(layer "In2.Cu")
	)
	(gr_line
		(start 234.100116 -29.500068)
		(end 234.100116 -29.79674)
		(stroke
			(width 0.0508)
			(type default)
		)
		(layer "In2.Cu")
	)
	(gr_arc
		(start 234.131358 -63.091314)
		(mid 234.069365 -63.049847)
		(end 233.99623 -63.03518)
		(stroke
			(width 0.0508)
			(type default)
		)
		(layer "In2.Cu")
	)
	(gr_line
		(start 234.131358 -63.091314)
		(end 234.140248 -63.09995)
		(stroke
			(width 0.0508)
			(type default)
		)
		(layer "In2.Cu")
	)
	(gr_line
		(start 234.187492 -70.648576)
		(end 234.190794 -70.667626)
		(stroke
			(width 0.06985)
			(type default)
		)
		(layer "In2.Cu")
	)
	(gr_line
		(start 234.187492 -70.648576)
		(end 234.190794 -70.62978)
		(stroke
			(width 0.06985)
			(type default)
		)
		(layer "In2.Cu")
	)
	(gr_arc
		(start 234.202986 -63.251334)
		(mid 234.186642 -63.169419)
		(end 234.140248 -63.09995)
		(stroke
			(width 0.0508)
			(type default)
		)
		(layer "In2.Cu")
	)
	(gr_line
		(start 234.311698 -74.948796)
		(end 234.311698 -74.94905)
		(stroke
			(width 0.06985)
			(type default)
		)
		(layer "In2.Cu")
	)
	(gr_line
		(start 234.311698 -74.948796)
		(end 234.315 -74.93)
		(stroke
			(width 0.06985)
			(type default)
		)
		(layer "In2.Cu")
	)
	(gr_line
		(start 234.311698 -74.911204)
		(end 234.315 -74.93)
		(stroke
			(width 0.06985)
			(type default)
		)
		(layer "In2.Cu")
	)
	(gr_line
		(start 234.442 -67.308476)
		(end 234.442 -67.425316)
		(stroke
			(width 0.06985)
			(type default)
		)
		(layer "In2.Cu")
	)
	(gr_line
		(start 234.442 -67.2338)
		(end 234.442 -67.308476)
		(stroke
			(width 0.0508)
			(type default)
		)
		(layer "In2.Cu")
	)
	(gr_line
		(start 234.442 -67.2338)
		(end 234.461558 -67.214242)
		(stroke
			(width 0.0508)
			(type default)
		)
		(layer "In2.Cu")
	)
	(gr_line
		(start 234.463336 -67.212464)
		(end 234.493816 -67.181984)
		(stroke
			(width 0.0508)
			(type default)
		)
		(layer "In2.Cu")
	)
	(gr_line
		(start 234.46359 -27.95651)
		(end 234.481624 -27.974544)
		(stroke
			(width 0.0508)
			(type default)
		)
		(layer "In2.Cu")
	)
	(gr_line
		(start 234.481624 -27.974544)
		(end 234.50931 -27.974544)
		(stroke
			(width 0.0508)
			(type default)
		)
		(layer "In2.Cu")
	)
	(gr_line
		(start 234.498896 -112.153954)
		(end 234.518454 -112.126014)
		(stroke
			(width 0.06985)
			(type default)
		)
		(layer "In2.Cu")
	)
	(gr_line
		(start 234.51185 -27.974544)
		(end 234.571286 -27.974544)
		(stroke
			(width 0.0508)
			(type default)
		)
		(layer "In2.Cu")
	)
	(gr_line
		(start 234.518454 -112.126014)
		(end 234.524296 -112.092994)
		(stroke
			(width 0.06985)
			(type default)
		)
		(layer "In2.Cu")
	)
	(gr_line
		(start 234.536996 -87.26043)
		(end 234.536996 -87.260684)
		(stroke
			(width 0.06985)
			(type default)
		)
		(layer "In2.Cu")
	)
	(gr_line
		(start 234.536996 -87.26043)
		(end 234.540298 -87.241634)
		(stroke
			(width 0.06985)
			(type default)
		)
		(layer "In2.Cu")
	)
	(gr_line
		(start 234.536996 -87.222838)
		(end 234.540298 -87.241634)
		(stroke
			(width 0.06985)
			(type default)
		)
		(layer "In2.Cu")
	)
	(gr_line
		(start 234.588558 -25.15108)
		(end 234.604814 -25.175972)
		(stroke
			(width 0.06985)
			(type default)
		)
		(layer "In2.Cu")
	)
	(gr_line
		(start 234.602782 -77.94752)
		(end 234.606084 -77.96657)
		(stroke
			(width 0.06985)
			(type default)
		)
		(layer "In2.Cu")
	)
	(gr_line
		(start 234.602782 -77.94752)
		(end 234.606084 -77.928724)
		(stroke
			(width 0.06985)
			(type default)
		)
		(layer "In2.Cu")
	)
	(gr_line
		(start 234.604814 -25.175972)
		(end 234.629452 -25.191974)
		(stroke
			(width 0.06985)
			(type default)
		)
		(layer "In2.Cu")
	)
	(gr_line
		(start 234.674918 -61.929772)
		(end 234.754166 -61.866526)
		(stroke
			(width 0.0508)
			(type default)
		)
		(layer "In2.Cu")
	)
	(gr_line
		(start 234.697016 -67.158616)
		(end 234.750864 -67.212464)
		(stroke
			(width 0.0508)
			(type default)
		)
		(layer "In2.Cu")
	)
	(gr_line
		(start 234.697016 -67.041776)
		(end 234.697016 -67.158616)
		(stroke
			(width 0.0508)
			(type default)
		)
		(layer "In2.Cu")
	)
	(gr_line
		(start 234.69727 -27.723084)
		(end 234.71505 -27.740864)
		(stroke
			(width 0.0508)
			(type default)
		)
		(layer "In2.Cu")
	)
	(gr_line
		(start 234.71505 -27.771344)
		(end 234.71505 -27.83078)
		(stroke
			(width 0.0508)
			(type default)
		)
		(layer "In2.Cu")
	)
	(gr_line
		(start 234.71505 -27.740864)
		(end 234.71505 -27.768804)
		(stroke
			(width 0.0508)
			(type default)
		)
		(layer "In2.Cu")
	)
	(gr_line
		(start 234.752642 -67.214242)
		(end 234.7722 -67.2338)
		(stroke
			(width 0.0508)
			(type default)
		)
		(layer "In2.Cu")
	)
	(gr_line
		(start 234.754166 -61.866526)
		(end 234.754674 -61.866018)
		(stroke
			(width 0.0508)
			(type default)
		)
		(layer "In2.Cu")
	)
	(gr_line
		(start 234.754674 -61.866018)
		(end 234.797854 -61.831728)
		(stroke
			(width 0.0508)
			(type default)
		)
		(layer "In2.Cu")
	)
	(gr_arc
		(start 234.781598 -33.814512)
		(mid 234.797867 -33.800859)
		(end 234.813348 -33.786318)
		(stroke
			(width 0.0508)
			(type default)
		)
		(layer "In2.Cu")
	)
	(gr_line
		(start 234.797854 -61.831728)
		(end 234.818428 -61.815726)
		(stroke
			(width 0.0508)
			(type default)
		)
		(layer "In2.Cu")
	)
	(gr_line
		(start 234.813348 -33.786318)
		(end 234.813602 -33.786318)
		(stroke
			(width 0.0508)
			(type default)
		)
		(layer "In2.Cu")
	)
	(gr_line
		(start 234.813602 -33.786064)
		(end 234.813602 -33.786318)
		(stroke
			(width 0.0508)
			(type default)
		)
		(layer "In2.Cu")
	)
	(gr_line
		(start 234.813602 -33.786064)
		(end 235.100114 -33.50006)
		(stroke
			(width 0.0508)
			(type default)
		)
		(layer "In2.Cu")
	)
	(gr_line
		(start 234.818428 -61.815726)
		(end 234.82427 -61.811154)
		(stroke
			(width 0.0508)
			(type default)
		)
		(layer "In2.Cu")
	)
	(gr_line
		(start 234.82427 -61.811154)
		(end 234.82935 -61.807344)
		(stroke
			(width 0.0508)
			(type default)
		)
		(layer "In2.Cu")
	)
	(gr_line
		(start 234.82935 -61.807344)
		(end 234.851194 -61.790072)
		(stroke
			(width 0.0508)
			(type default)
		)
		(layer "In2.Cu")
	)
	(gr_line
		(start 234.851194 -61.790072)
		(end 234.851448 -61.790072)
		(stroke
			(width 0.0508)
			(type default)
		)
		(layer "In2.Cu")
	)
	(gr_line
		(start 234.851448 -61.790072)
		(end 234.858052 -61.784738)
		(stroke
			(width 0.0508)
			(type default)
		)
		(layer "In2.Cu")
	)
	(gr_line
		(start 234.858052 -61.784738)
		(end 234.895898 -61.755274)
		(stroke
			(width 0.0508)
			(type default)
		)
		(layer "In2.Cu")
	)
	(gr_arc
		(start 234.860846 -30.901386)
		(mid 235.035763 -30.733684)
		(end 235.100114 -30.500066)
		(stroke
			(width 0.0508)
			(type default)
		)
		(layer "In2.Cu")
	)
	(gr_line
		(start 234.895898 -61.755274)
		(end 234.901994 -61.750702)
		(stroke
			(width 0.0508)
			(type default)
		)
		(layer "In2.Cu")
	)
	(gr_line
		(start 234.901994 -61.750702)
		(end 234.904534 -61.748416)
		(stroke
			(width 0.0508)
			(type default)
		)
		(layer "In2.Cu")
	)
	(gr_line
		(start 234.904534 -61.748416)
		(end 235.0262 -61.652404)
		(stroke
			(width 0.0508)
			(type default)
		)
		(layer "In2.Cu")
	)
	(gr_arc
		(start 234.911646 -31.101538)
		(mid 234.896973 -31.10223)
		(end 234.882436 -31.104332)
		(stroke
			(width 0.0508)
			(type default)
		)
		(layer "In2.Cu")
	)
	(gr_line
		(start 234.911646 -31.101538)
		(end 234.998514 -31.101538)
		(stroke
			(width 0.0508)
			(type default)
		)
		(layer "In2.Cu")
	)
	(gr_line
		(start 234.958382 -62.035182)
		(end 234.996228 -62.035182)
		(stroke
			(width 0.0508)
			(type default)
		)
		(layer "In2.Cu")
	)
	(gr_arc
		(start 235.0262 -61.652404)
		(mid 235.080672 -61.584556)
		(end 235.100114 -61.49975)
		(stroke
			(width 0.0508)
			(type default)
		)
		(layer "In2.Cu")
	)
	(gr_arc
		(start 235.100114 -62.499748)
		(mid 235.176237 -62.385766)
		(end 235.202984 -62.251336)
		(stroke
			(width 0.0508)
			(type default)
		)
		(layer "In2.Cu")
	)
	(gr_line
		(start 235.100114 -34.500058)
		(end 235.218732 -34.38144)
		(stroke
			(width 0.0508)
			(type default)
		)
		(layer "In2.Cu")
	)
	(gr_arc
		(start 235.100114 -31.203138)
		(mid 235.07037 -31.131266)
		(end 234.998514 -31.101538)
		(stroke
			(width 0.0508)
			(type default)
		)
		(layer "In2.Cu")
	)
	(gr_line
		(start 235.100114 -31.203138)
		(end 235.100114 -31.500064)
		(stroke
			(width 0.0508)
			(type default)
		)
		(layer "In2.Cu")
	)
	(gr_arc
		(start 235.131356 -62.091316)
		(mid 235.069363 -62.049849)
		(end 234.996228 -62.035182)
		(stroke
			(width 0.0508)
			(type default)
		)
		(layer "In2.Cu")
	)
	(gr_line
		(start 235.131356 -62.091316)
		(end 235.140246 -62.099952)
		(stroke
			(width 0.0508)
			(type default)
		)
		(layer "In2.Cu")
	)
	(gr_arc
		(start 235.202984 -62.251336)
		(mid 235.186641 -62.169421)
		(end 235.140246 -62.099952)
		(stroke
			(width 0.0508)
			(type default)
		)
		(layer "In2.Cu")
	)
	(gr_arc
		(start 235.212382 -34.086292)
		(mid 235.04278 -33.997901)
		(end 234.851702 -34.005774)
		(stroke
			(width 0.0508)
			(type default)
		)
		(layer "In2.Cu")
	)
	(gr_arc
		(start 235.218732 -34.38144)
		(mid 235.278646 -34.232508)
		(end 235.212382 -34.086292)
		(stroke
			(width 0.0508)
			(type default)
		)
		(layer "In2.Cu")
	)
	(gr_line
		(start 235.36021 -113.484914)
		(end 235.379768 -113.456974)
		(stroke
			(width 0.06985)
			(type default)
		)
		(layer "In2.Cu")
	)
	(gr_line
		(start 235.370878 -75.49388)
		(end 235.370878 -75.494134)
		(stroke
			(width 0.06985)
			(type default)
		)
		(layer "In2.Cu")
	)
	(gr_line
		(start 235.370878 -75.49388)
		(end 235.37418 -75.475084)
		(stroke
			(width 0.06985)
			(type default)
		)
		(layer "In2.Cu")
	)
	(gr_line
		(start 235.370878 -75.456288)
		(end 235.37418 -75.475084)
		(stroke
			(width 0.06985)
			(type default)
		)
		(layer "In2.Cu")
	)
	(gr_line
		(start 235.379768 -113.456974)
		(end 235.38561 -113.423954)
		(stroke
			(width 0.06985)
			(type default)
		)
		(layer "In2.Cu")
	)
	(gr_line
		(start 235.4326 -67.34048)
		(end 235.4326 -67.466718)
		(stroke
			(width 0.06985)
			(type default)
		)
		(layer "In2.Cu")
	)
	(gr_line
		(start 235.4326 -67.31508)
		(end 235.4326 -67.34048)
		(stroke
			(width 0.0508)
			(type default)
		)
		(layer "In2.Cu")
	)
	(gr_line
		(start 235.4326 -67.31508)
		(end 235.476796 -67.270884)
		(stroke
			(width 0.0508)
			(type default)
		)
		(layer "In2.Cu")
	)
	(gr_line
		(start 235.478574 -67.269106)
		(end 235.493814 -67.253866)
		(stroke
			(width 0.0508)
			(type default)
		)
		(layer "In2.Cu")
	)
	(gr_line
		(start 235.54182 -27.94762)
		(end 235.54182 -27.950668)
		(stroke
			(width 0.06985)
			(type default)
		)
		(layer "In2.Cu")
	)
	(gr_line
		(start 235.554012 -87.384636)
		(end 235.554012 -87.38489)
		(stroke
			(width 0.06985)
			(type default)
		)
		(layer "In2.Cu")
	)
	(gr_line
		(start 235.554012 -87.384636)
		(end 235.557314 -87.36584)
		(stroke
			(width 0.06985)
			(type default)
		)
		(layer "In2.Cu")
	)
	(gr_line
		(start 235.554012 -87.347044)
		(end 235.557314 -87.36584)
		(stroke
			(width 0.06985)
			(type default)
		)
		(layer "In2.Cu")
	)
	(gr_line
		(start 235.674916 -62.92977)
		(end 235.754164 -62.866524)
		(stroke
			(width 0.0508)
			(type default)
		)
		(layer "In2.Cu")
	)
	(gr_line
		(start 235.697014 -67.200018)
		(end 235.7628 -67.265804)
		(stroke
			(width 0.0508)
			(type default)
		)
		(layer "In2.Cu")
	)
	(gr_line
		(start 235.697014 -67.07378)
		(end 235.697014 -67.200018)
		(stroke
			(width 0.0508)
			(type default)
		)
		(layer "In2.Cu")
	)
	(gr_line
		(start 235.754164 -62.866524)
		(end 235.754672 -62.866016)
		(stroke
			(width 0.0508)
			(type default)
		)
		(layer "In2.Cu")
	)
	(gr_line
		(start 235.754672 -62.866016)
		(end 235.797852 -62.831726)
		(stroke
			(width 0.0508)
			(type default)
		)
		(layer "In2.Cu")
	)
	(gr_line
		(start 235.797852 -62.831726)
		(end 235.818426 -62.815724)
		(stroke
			(width 0.0508)
			(type default)
		)
		(layer "In2.Cu")
	)
	(gr_line
		(start 235.818426 -62.815724)
		(end 235.824268 -62.811152)
		(stroke
			(width 0.0508)
			(type default)
		)
		(layer "In2.Cu")
	)
	(gr_line
		(start 235.824268 -62.811152)
		(end 235.829348 -62.807342)
		(stroke
			(width 0.0508)
			(type default)
		)
		(layer "In2.Cu")
	)
	(gr_line
		(start 235.829348 -62.807342)
		(end 235.851192 -62.79007)
		(stroke
			(width 0.0508)
			(type default)
		)
		(layer "In2.Cu")
	)
	(gr_line
		(start 235.851192 -62.79007)
		(end 235.851446 -62.79007)
		(stroke
			(width 0.0508)
			(type default)
		)
		(layer "In2.Cu")
	)
	(gr_line
		(start 235.851446 -62.79007)
		(end 235.85805 -62.784736)
		(stroke
			(width 0.0508)
			(type default)
		)
		(layer "In2.Cu")
	)
	(gr_line
		(start 235.85805 -62.784736)
		(end 235.895896 -62.755272)
		(stroke
			(width 0.0508)
			(type default)
		)
		(layer "In2.Cu")
	)
	(gr_line
		(start 235.884466 -79.248)
		(end 235.887768 -79.26705)
		(stroke
			(width 0.06985)
			(type default)
		)
		(layer "In2.Cu")
	)
	(gr_line
		(start 235.884466 -79.248)
		(end 235.887768 -79.229204)
		(stroke
			(width 0.06985)
			(type default)
		)
		(layer "In2.Cu")
	)
	(gr_line
		(start 235.895896 -62.755272)
		(end 235.901992 -62.7507)
		(stroke
			(width 0.0508)
			(type default)
		)
		(layer "In2.Cu")
	)
	(gr_line
		(start 235.901992 -62.7507)
		(end 235.904532 -62.748414)
		(stroke
			(width 0.0508)
			(type default)
		)
		(layer "In2.Cu")
	)
	(gr_line
		(start 235.904532 -62.748414)
		(end 236.026198 -62.652402)
		(stroke
			(width 0.0508)
			(type default)
		)
		(layer "In2.Cu")
	)
	(gr_line
		(start 235.95838 -63.03518)
		(end 235.996226 -63.03518)
		(stroke
			(width 0.0508)
			(type default)
		)
		(layer "In2.Cu")
	)
	(gr_arc
		(start 235.961682 -33.93694)
		(mid 236.062614 -33.863117)
		(end 236.101128 -33.744154)
		(stroke
			(width 0.0508)
			(type default)
		)
		(layer "In2.Cu")
	)
	(gr_arc
		(start 235.982002 -29.91485)
		(mid 236.065518 -29.880256)
		(end 236.100112 -29.79674)
		(stroke
			(width 0.0508)
			(type default)
		)
		(layer "In2.Cu")
	)
	(gr_arc
		(start 236.026198 -62.652402)
		(mid 236.080674 -62.584553)
		(end 236.100112 -62.499748)
		(stroke
			(width 0.0508)
			(type default)
		)
		(layer "In2.Cu")
	)
	(gr_arc
		(start 236.100112 -63.499746)
		(mid 236.176266 -63.385774)
		(end 236.202982 -63.251334)
		(stroke
			(width 0.0508)
			(type default)
		)
		(layer "In2.Cu")
	)
	(gr_line
		(start 236.100112 -37.412168)
		(end 236.100112 -37.500052)
		(stroke
			(width 0.0508)
			(type default)
		)
		(layer "In2.Cu")
	)
	(gr_arc
		(start 236.100112 -36.796726)
		(mid 236.12988 -36.868547)
		(end 236.201712 -36.898326)
		(stroke
			(width 0.0508)
			(type default)
		)
		(layer "In2.Cu")
	)
	(gr_line
		(start 236.100112 -36.500054)
		(end 236.100112 -36.796726)
		(stroke
			(width 0.0508)
			(type default)
		)
		(layer "In2.Cu")
	)
	(gr_line
		(start 236.100112 -34.500058)
		(end 236.101128 -34.499042)
		(stroke
			(width 0.0508)
			(type default)
		)
		(layer "In2.Cu")
	)
	(gr_line
		(start 236.100112 -33.50006)
		(end 236.101128 -33.501076)
		(stroke
			(width 0.0508)
			(type default)
		)
		(layer "In2.Cu")
	)
	(gr_arc
		(start 236.100112 -30.253686)
		(mid 236.060379 -30.157794)
		(end 235.964476 -30.11805)
		(stroke
			(width 0.0508)
			(type default)
		)
		(layer "In2.Cu")
	)
	(gr_line
		(start 236.100112 -30.253686)
		(end 236.100112 -30.500066)
		(stroke
			(width 0.0508)
			(type default)
		)
		(layer "In2.Cu")
	)
	(gr_line
		(start 236.100112 -29.500068)
		(end 236.100112 -29.79674)
		(stroke
			(width 0.0508)
			(type default)
		)
		(layer "In2.Cu")
	)
	(gr_arc
		(start 236.101128 -34.250122)
		(mid 236.068926 -34.172323)
		(end 235.991146 -34.14014)
		(stroke
			(width 0.0508)
			(type default)
		)
		(layer "In2.Cu")
	)
	(gr_line
		(start 236.101128 -34.250122)
		(end 236.101128 -34.499042)
		(stroke
			(width 0.0508)
			(type default)
		)
		(layer "In2.Cu")
	)
	(gr_line
		(start 236.101128 -33.501076)
		(end 236.101128 -33.744154)
		(stroke
			(width 0.0508)
			(type default)
		)
		(layer "In2.Cu")
	)
	(gr_line
		(start 236.101636 -28.510484)
		(end 236.119416 -28.528264)
		(stroke
			(width 0.0508)
			(type default)
		)
		(layer "In2.Cu")
	)
	(gr_line
		(start 236.119416 -28.528264)
		(end 236.147356 -28.528264)
		(stroke
			(width 0.0508)
			(type default)
		)
		(layer "In2.Cu")
	)
	(gr_arc
		(start 236.131354 -63.091314)
		(mid 236.069372 -63.049806)
		(end 235.996226 -63.03518)
		(stroke
			(width 0.0508)
			(type default)
		)
		(layer "In2.Cu")
	)
	(gr_line
		(start 236.131354 -63.091314)
		(end 236.140244 -63.09995)
		(stroke
			(width 0.0508)
			(type default)
		)
		(layer "In2.Cu")
	)
	(gr_line
		(start 236.149896 -28.528264)
		(end 236.209332 -28.528264)
		(stroke
			(width 0.0508)
			(type default)
		)
		(layer "In2.Cu")
	)
	(gr_line
		(start 236.201712 -36.898326)
		(end 236.357414 -36.898326)
		(stroke
			(width 0.0508)
			(type default)
		)
		(layer "In2.Cu")
	)
	(gr_arc
		(start 236.202982 -63.251334)
		(mid 236.186683 -63.169393)
		(end 236.140244 -63.09995)
		(stroke
			(width 0.0508)
			(type default)
		)
		(layer "In2.Cu")
	)
	(gr_arc
		(start 236.212126 -37.141658)
		(mid 236.129198 -37.265769)
		(end 236.100112 -37.412168)
		(stroke
			(width 0.0508)
			(type default)
		)
		(layer "In2.Cu")
	)
	(gr_line
		(start 236.222794 -114.731292)
		(end 236.242352 -114.703352)
		(stroke
			(width 0.06985)
			(type default)
		)
		(layer "In2.Cu")
	)
	(gr_arc
		(start 236.232954 -35.903154)
		(mid 236.271849 -35.895435)
		(end 236.304836 -35.873436)
		(stroke
			(width 0.0508)
			(type default)
		)
		(layer "In2.Cu")
	)
	(gr_line
		(start 236.242352 -114.703352)
		(end 236.248194 -114.670332)
		(stroke
			(width 0.06985)
			(type default)
		)
		(layer "In2.Cu")
	)
	(gr_arc
		(start 236.300264 -35.096958)
		(mid 236.348782 -35.087325)
		(end 236.389926 -35.059874)
		(stroke
			(width 0.0508)
			(type default)
		)
		(layer "In2.Cu")
	)
	(gr_arc
		(start 236.306868 -36.106354)
		(mid 236.355386 -36.096721)
		(end 236.39653 -36.06927)
		(stroke
			(width 0.0508)
			(type default)
		)
		(layer "In2.Cu")
	)
	(gr_line
		(start 236.335316 -28.276804)
		(end 236.353096 -28.294584)
		(stroke
			(width 0.0508)
			(type default)
		)
		(layer "In2.Cu")
	)
	(gr_line
		(start 236.353096 -28.325064)
		(end 236.353096 -28.3845)
		(stroke
			(width 0.0508)
			(type default)
		)
		(layer "In2.Cu")
	)
	(gr_line
		(start 236.353096 -28.294584)
		(end 236.353096 -28.322524)
		(stroke
			(width 0.0508)
			(type default)
		)
		(layer "In2.Cu")
	)
	(gr_arc
		(start 236.357414 -37.101526)
		(mid 236.282056 -37.111755)
		(end 236.212126 -37.141658)
		(stroke
			(width 0.0508)
			(type default)
		)
		(layer "In2.Cu")
	)
	(gr_line
		(start 236.4232 -67.2846)
		(end 236.4232 -67.359276)
		(stroke
			(width 0.0508)
			(type default)
		)
		(layer "In2.Cu")
	)
	(gr_line
		(start 236.4232 -67.2846)
		(end 236.442758 -67.265042)
		(stroke
			(width 0.0508)
			(type default)
		)
		(layer "In2.Cu")
	)
	(gr_line
		(start 236.444536 -67.263264)
		(end 236.493812 -67.213988)
		(stroke
			(width 0.0508)
			(type default)
		)
		(layer "In2.Cu")
	)
	(gr_arc
		(start 236.464094 -35.714178)
		(mid 236.486077 -35.681184)
		(end 236.493812 -35.642296)
		(stroke
			(width 0.0508)
			(type default)
		)
		(layer "In2.Cu")
	)
	(gr_line
		(start 236.475016 -34.687256)
		(end 236.493812 -34.66846)
		(stroke
			(width 0.0508)
			(type default)
		)
		(layer "In2.Cu")
	)
	(gr_line
		(start 236.493812 -67.0179)
		(end 236.493812 -67.213988)
		(stroke
			(width 0.0508)
			(type default)
		)
		(layer "In2.Cu")
	)
	(gr_line
		(start 236.587792 -33.998916)
		(end 236.589062 -33.997646)
		(stroke
			(width 0.0508)
			(type default)
		)
		(layer "In2.Cu")
	)
	(gr_line
		(start 236.589062 -33.997646)
		(end 236.589316 -33.997646)
		(stroke
			(width 0.0508)
			(type default)
		)
		(layer "In2.Cu")
	)
	(gr_line
		(start 236.64545 -87.667084)
		(end 236.64545 -87.667338)
		(stroke
			(width 0.06985)
			(type default)
		)
		(layer "In2.Cu")
	)
	(gr_line
		(start 236.64545 -87.667084)
		(end 236.648752 -87.648288)
		(stroke
			(width 0.06985)
			(type default)
		)
		(layer "In2.Cu")
	)
	(gr_line
		(start 236.64545 -87.629492)
		(end 236.648752 -87.648288)
		(stroke
			(width 0.06985)
			(type default)
		)
		(layer "In2.Cu")
	)
	(gr_arc
		(start 236.659928 -35.805872)
		(mid 236.687361 -35.764721)
		(end 236.697012 -35.71621)
		(stroke
			(width 0.0508)
			(type default)
		)
		(layer "In2.Cu")
	)
	(gr_arc
		(start 236.659928 -34.789872)
		(mid 236.687361 -34.748721)
		(end 236.697012 -34.70021)
		(stroke
			(width 0.0508)
			(type default)
		)
		(layer "In2.Cu")
	)
	(gr_line
		(start 236.674914 -61.929772)
		(end 236.754162 -61.866526)
		(stroke
			(width 0.0508)
			(type default)
		)
		(layer "In2.Cu")
	)
	(gr_line
		(start 236.697012 -67.228212)
		(end 236.732064 -67.263264)
		(stroke
			(width 0.0508)
			(type default)
		)
		(layer "In2.Cu")
	)
	(gr_line
		(start 236.697012 -34.621978)
		(end 236.697266 -34.621724)
		(stroke
			(width 0.0508)
			(type default)
		)
		(layer "In2.Cu")
	)
	(gr_line
		(start 236.733842 -67.265042)
		(end 236.7534 -67.2846)
		(stroke
			(width 0.0508)
			(type default)
		)
		(layer "In2.Cu")
	)
	(gr_line
		(start 236.7534 -67.2846)
		(end 236.7534 -67.480688)
		(stroke
			(width 0.06985)
			(type default)
		)
		(layer "In2.Cu")
	)
	(gr_line
		(start 236.754162 -61.866526)
		(end 236.75467 -61.866018)
		(stroke
			(width 0.0508)
			(type default)
		)
		(layer "In2.Cu")
	)
	(gr_line
		(start 236.75467 -61.866018)
		(end 236.79785 -61.831728)
		(stroke
			(width 0.0508)
			(type default)
		)
		(layer "In2.Cu")
	)
	(gr_line
		(start 236.78388 -79.167736)
		(end 236.787182 -79.186786)
		(stroke
			(width 0.06985)
			(type default)
		)
		(layer "In2.Cu")
	)
	(gr_line
		(start 236.78388 -79.167736)
		(end 236.787182 -79.14894)
		(stroke
			(width 0.06985)
			(type default)
		)
		(layer "In2.Cu")
	)
	(gr_line
		(start 236.785658 -34.969958)
		(end 236.815376 -34.94024)
		(stroke
			(width 0.0508)
			(type default)
		)
		(layer "In2.Cu")
	)
	(gr_line
		(start 236.79785 -61.831728)
		(end 236.818424 -61.815726)
		(stroke
			(width 0.0508)
			(type default)
		)
		(layer "In2.Cu")
	)
	(gr_line
		(start 236.818424 -61.815726)
		(end 236.824266 -61.811154)
		(stroke
			(width 0.0508)
			(type default)
		)
		(layer "In2.Cu")
	)
	(gr_line
		(start 236.824266 -61.811154)
		(end 236.829346 -61.807344)
		(stroke
			(width 0.0508)
			(type default)
		)
		(layer "In2.Cu")
	)
	(gr_line
		(start 236.829346 -61.807344)
		(end 236.85119 -61.790072)
		(stroke
			(width 0.0508)
			(type default)
		)
		(layer "In2.Cu")
	)
	(gr_line
		(start 236.85119 -61.790072)
		(end 236.851444 -61.790072)
		(stroke
			(width 0.0508)
			(type default)
		)
		(layer "In2.Cu")
	)
	(gr_line
		(start 236.851444 -61.790072)
		(end 236.858048 -61.784738)
		(stroke
			(width 0.0508)
			(type default)
		)
		(layer "In2.Cu")
	)
	(gr_line
		(start 236.858048 -61.784738)
		(end 236.895894 -61.755274)
		(stroke
			(width 0.0508)
			(type default)
		)
		(layer "In2.Cu")
	)
	(gr_line
		(start 236.870748 -75.557634)
		(end 236.870748 -75.557888)
		(stroke
			(width 0.06985)
			(type default)
		)
		(layer "In2.Cu")
	)
	(gr_line
		(start 236.870748 -75.557634)
		(end 236.87405 -75.538838)
		(stroke
			(width 0.06985)
			(type default)
		)
		(layer "In2.Cu")
	)
	(gr_line
		(start 236.870748 -75.520042)
		(end 236.87405 -75.538838)
		(stroke
			(width 0.06985)
			(type default)
		)
		(layer "In2.Cu")
	)
	(gr_line
		(start 236.87913 -26.25979)
		(end 236.903768 -26.275792)
		(stroke
			(width 0.06985)
			(type default)
		)
		(layer "In2.Cu")
	)
	(gr_line
		(start 236.895894 -61.755274)
		(end 236.90199 -61.750702)
		(stroke
			(width 0.0508)
			(type default)
		)
		(layer "In2.Cu")
	)
	(gr_arc
		(start 236.899196 -33.903666)
		(mid 236.918082 -33.902647)
		(end 236.936788 -33.899856)
		(stroke
			(width 0.0508)
			(type default)
		)
		(layer "In2.Cu")
	)
	(gr_line
		(start 236.90199 -61.750702)
		(end 236.90453 -61.748416)
		(stroke
			(width 0.0508)
			(type default)
		)
		(layer "In2.Cu")
	)
	(gr_line
		(start 236.903768 -26.275792)
		(end 236.91977 -26.30043)
		(stroke
			(width 0.06985)
			(type default)
		)
		(layer "In2.Cu")
	)
	(gr_line
		(start 236.90453 -61.748416)
		(end 237.026196 -61.652404)
		(stroke
			(width 0.0508)
			(type default)
		)
		(layer "In2.Cu")
	)
	(gr_arc
		(start 236.905038 -34.903156)
		(mid 236.856525 -34.912801)
		(end 236.815376 -34.94024)
		(stroke
			(width 0.0508)
			(type default)
		)
		(layer "In2.Cu")
	)
	(gr_arc
		(start 236.921548 -30.898338)
		(mid 236.989881 -30.884746)
		(end 237.047786 -30.846014)
		(stroke
			(width 0.0508)
			(type default)
		)
		(layer "In2.Cu")
	)
	(gr_arc
		(start 236.936788 -33.899856)
		(mid 236.993 -33.880283)
		(end 237.040928 -33.844992)
		(stroke
			(width 0.0508)
			(type default)
		)
		(layer "In2.Cu")
	)
	(gr_line
		(start 236.958378 -62.035182)
		(end 236.996224 -62.035182)
		(stroke
			(width 0.0508)
			(type default)
		)
		(layer "In2.Cu")
	)
	(gr_arc
		(start 236.978952 -35.106356)
		(mid 236.940062 -35.114085)
		(end 236.90707 -35.136074)
		(stroke
			(width 0.0508)
			(type default)
		)
		(layer "In2.Cu")
	)
	(gr_line
		(start 237.01502 -28.47467)
		(end 237.034578 -28.494228)
		(stroke
			(width 0.0508)
			(type default)
		)
		(layer "In2.Cu")
	)
	(gr_line
		(start 237.01502 -28.44927)
		(end 237.01502 -28.47467)
		(stroke
			(width 0.0508)
			(type default)
		)
		(layer "In2.Cu")
	)
	(gr_arc
		(start 237.026196 -61.652404)
		(mid 237.080673 -61.584556)
		(end 237.10011 -61.49975)
		(stroke
			(width 0.0508)
			(type default)
		)
		(layer "In2.Cu")
	)
	(gr_line
		(start 237.036356 -28.496006)
		(end 237.07852 -28.53817)
		(stroke
			(width 0.0508)
			(type default)
		)
		(layer "In2.Cu")
	)
	(gr_line
		(start 237.040928 -33.844992)
		(end 237.041182 -33.844738)
		(stroke
			(width 0.0508)
			(type default)
		)
		(layer "In2.Cu")
	)
	(gr_arc
		(start 237.041182 -33.844738)
		(mid 237.084799 -33.779481)
		(end 237.10011 -33.702498)
		(stroke
			(width 0.0508)
			(type default)
		)
		(layer "In2.Cu")
	)
	(gr_arc
		(start 237.047024 -31.154624)
		(mid 236.988165 -31.115339)
		(end 236.918754 -31.101538)
		(stroke
			(width 0.0508)
			(type default)
		)
		(layer "In2.Cu")
	)
	(gr_line
		(start 237.047024 -31.154624)
		(end 237.070392 -31.177992)
		(stroke
			(width 0.0508)
			(type default)
		)
		(layer "In2.Cu")
	)
	(gr_line
		(start 237.047786 -30.846014)
		(end 237.070392 -30.823408)
		(stroke
			(width 0.0508)
			(type default)
		)
		(layer "In2.Cu")
	)
	(gr_arc
		(start 237.070392 -30.823408)
		(mid 237.092375 -30.790414)
		(end 237.10011 -30.751526)
		(stroke
			(width 0.0508)
			(type default)
		)
		(layer "In2.Cu")
	)
	(gr_arc
		(start 237.10011 -62.499748)
		(mid 237.176264 -62.385776)
		(end 237.20298 -62.251336)
		(stroke
			(width 0.0508)
			(type default)
		)
		(layer "In2.Cu")
	)
	(gr_line
		(start 237.10011 -37.304726)
		(end 237.10011 -37.500052)
		(stroke
			(width 0.0508)
			(type default)
		)
		(layer "In2.Cu")
	)
	(gr_arc
		(start 237.10011 -36.78174)
		(mid 237.136576 -36.869731)
		(end 237.22457 -36.9062)
		(stroke
			(width 0.0508)
			(type default)
		)
		(layer "In2.Cu")
	)
	(gr_line
		(start 237.10011 -36.500054)
		(end 237.10011 -36.78174)
		(stroke
			(width 0.0508)
			(type default)
		)
		(layer "In2.Cu")
	)
	(gr_arc
		(start 237.10011 -34.500058)
		(mid 237.125511 -34.46207)
		(end 237.1344 -34.417254)
		(stroke
			(width 0.0508)
			(type default)
		)
		(layer "In2.Cu")
	)
	(gr_line
		(start 237.10011 -33.50006)
		(end 237.10011 -33.702498)
		(stroke
			(width 0.0508)
			(type default)
		)
		(layer "In2.Cu")
	)
	(gr_arc
		(start 237.10011 -31.249874)
		(mid 237.092386 -31.210982)
		(end 237.070392 -31.177992)
		(stroke
			(width 0.0508)
			(type default)
		)
		(layer "In2.Cu")
	)
	(gr_line
		(start 237.10011 -31.249874)
		(end 237.10011 -31.500064)
		(stroke
			(width 0.0508)
			(type default)
		)
		(layer "In2.Cu")
	)
	(gr_line
		(start 237.10011 -30.500066)
		(end 237.10011 -30.751526)
		(stroke
			(width 0.0508)
			(type default)
		)
		(layer "In2.Cu")
	)
	(gr_arc
		(start 237.131352 -62.091316)
		(mid 237.06937 -62.049808)
		(end 236.996224 -62.035182)
		(stroke
			(width 0.0508)
			(type default)
		)
		(layer "In2.Cu")
	)
	(gr_line
		(start 237.131352 -62.091316)
		(end 237.140242 -62.099952)
		(stroke
			(width 0.0508)
			(type default)
		)
		(layer "In2.Cu")
	)
	(gr_arc
		(start 237.1344 -34.2392)
		(mid 237.095638 -34.145638)
		(end 237.002066 -34.106866)
		(stroke
			(width 0.0508)
			(type default)
		)
		(layer "In2.Cu")
	)
	(gr_line
		(start 237.1344 -34.2392)
		(end 237.1344 -34.417254)
		(stroke
			(width 0.0508)
			(type default)
		)
		(layer "In2.Cu")
	)
	(gr_arc
		(start 237.20298 -62.251336)
		(mid 237.186681 -62.169395)
		(end 237.140242 -62.099952)
		(stroke
			(width 0.0508)
			(type default)
		)
		(layer "In2.Cu")
	)
	(gr_arc
		(start 237.260892 -37.112448)
		(mid 237.145582 -37.179395)
		(end 237.10011 -37.304726)
		(stroke
			(width 0.0508)
			(type default)
		)
		(layer "In2.Cu")
	)
	(gr_line
		(start 237.260892 -37.112448)
		(end 237.263686 -37.11194)
		(stroke
			(width 0.0508)
			(type default)
		)
		(layer "In2.Cu")
	)
	(gr_line
		(start 237.28172 -28.53817)
		(end 237.323884 -28.496006)
		(stroke
			(width 0.0508)
			(type default)
		)
		(layer "In2.Cu")
	)
	(gr_line
		(start 237.314232 -26.907998)
		(end 237.34522 -26.955496)
		(stroke
			(width 0.06985)
			(type default)
		)
		(layer "In2.Cu")
	)
	(gr_line
		(start 237.325662 -28.494228)
		(end 237.34522 -28.47467)
		(stroke
			(width 0.0508)
			(type default)
		)
		(layer "In2.Cu")
	)
	(gr_line
		(start 237.34522 -28.44927)
		(end 237.34522 -28.47467)
		(stroke
			(width 0.0508)
			(type default)
		)
		(layer "In2.Cu")
	)
	(gr_line
		(start 237.364778 -115.117626)
		(end 237.384336 -115.089686)
		(stroke
			(width 0.06985)
			(type default)
		)
		(layer "In2.Cu")
	)
	(gr_line
		(start 237.384336 -115.089686)
		(end 237.390178 -115.056666)
		(stroke
			(width 0.06985)
			(type default)
		)
		(layer "In2.Cu")
	)
	(gr_line
		(start 237.4138 -67.31)
		(end 237.433358 -67.290442)
		(stroke
			(width 0.0508)
			(type default)
		)
		(layer "In2.Cu")
	)
	(gr_line
		(start 237.435136 -67.288664)
		(end 237.49381 -67.22999)
		(stroke
			(width 0.0508)
			(type default)
		)
		(layer "In2.Cu")
	)
	(gr_line
		(start 237.49381 -67.0433)
		(end 237.49381 -67.22999)
		(stroke
			(width 0.0508)
			(type default)
		)
		(layer "In2.Cu")
	)
	(gr_line
		(start 237.58779 -33.998916)
		(end 237.58906 -33.997646)
		(stroke
			(width 0.0508)
			(type default)
		)
		(layer "In2.Cu")
	)
	(gr_line
		(start 237.58906 -33.997646)
		(end 237.589314 -33.997646)
		(stroke
			(width 0.0508)
			(type default)
		)
		(layer "In2.Cu")
	)
	(gr_line
		(start 237.674912 -62.92977)
		(end 237.75416 -62.866524)
		(stroke
			(width 0.0508)
			(type default)
		)
		(layer "In2.Cu")
	)
	(gr_line
		(start 237.69701 -67.26301)
		(end 237.722664 -67.288664)
		(stroke
			(width 0.0508)
			(type default)
		)
		(layer "In2.Cu")
	)
	(gr_line
		(start 237.724442 -67.290442)
		(end 237.744 -67.31)
		(stroke
			(width 0.0508)
			(type default)
		)
		(layer "In2.Cu")
	)
	(gr_line
		(start 237.73257 -28.304998)
		(end 237.752128 -28.324556)
		(stroke
			(width 0.0508)
			(type default)
		)
		(layer "In2.Cu")
	)
	(gr_line
		(start 237.73257 -28.279598)
		(end 237.73257 -28.304998)
		(stroke
			(width 0.0508)
			(type default)
		)
		(layer "In2.Cu")
	)
	(gr_line
		(start 237.744 -67.31)
		(end 237.744 -67.49669)
		(stroke
			(width 0.06985)
			(type default)
		)
		(layer "In2.Cu")
	)
	(gr_line
		(start 237.748572 -79.270606)
		(end 237.751874 -79.289656)
		(stroke
			(width 0.06985)
			(type default)
		)
		(layer "In2.Cu")
	)
	(gr_line
		(start 237.748572 -79.270606)
		(end 237.751874 -79.25181)
		(stroke
			(width 0.06985)
			(type default)
		)
		(layer "In2.Cu")
	)
	(gr_line
		(start 237.753906 -28.326334)
		(end 237.79607 -28.368498)
		(stroke
			(width 0.0508)
			(type default)
		)
		(layer "In2.Cu")
	)
	(gr_line
		(start 237.75416 -62.866524)
		(end 237.754668 -62.866016)
		(stroke
			(width 0.0508)
			(type default)
		)
		(layer "In2.Cu")
	)
	(gr_line
		(start 237.754668 -62.866016)
		(end 237.797848 -62.831726)
		(stroke
			(width 0.0508)
			(type default)
		)
		(layer "In2.Cu")
	)
	(gr_line
		(start 237.772702 -88.090756)
		(end 237.776004 -88.07196)
		(stroke
			(width 0.06985)
			(type default)
		)
		(layer "In2.Cu")
	)
	(gr_line
		(start 237.772702 -88.05291)
		(end 237.776004 -88.07196)
		(stroke
			(width 0.06985)
			(type default)
		)
		(layer "In2.Cu")
	)
	(gr_line
		(start 237.797848 -62.831726)
		(end 237.818422 -62.815724)
		(stroke
			(width 0.0508)
			(type default)
		)
		(layer "In2.Cu")
	)
	(gr_line
		(start 237.80877 -75.257914)
		(end 237.80877 -75.258168)
		(stroke
			(width 0.06985)
			(type default)
		)
		(layer "In2.Cu")
	)
	(gr_line
		(start 237.80877 -75.257914)
		(end 237.812072 -75.239118)
		(stroke
			(width 0.06985)
			(type default)
		)
		(layer "In2.Cu")
	)
	(gr_line
		(start 237.80877 -75.220322)
		(end 237.812072 -75.239118)
		(stroke
			(width 0.06985)
			(type default)
		)
		(layer "In2.Cu")
	)
	(gr_line
		(start 237.818422 -62.815724)
		(end 237.824264 -62.811152)
		(stroke
			(width 0.0508)
			(type default)
		)
		(layer "In2.Cu")
	)
	(gr_line
		(start 237.824264 -62.811152)
		(end 237.829344 -62.807342)
		(stroke
			(width 0.0508)
			(type default)
		)
		(layer "In2.Cu")
	)
	(gr_line
		(start 237.829344 -62.807342)
		(end 237.851188 -62.79007)
		(stroke
			(width 0.0508)
			(type default)
		)
		(layer "In2.Cu")
	)
	(gr_line
		(start 237.851188 -62.79007)
		(end 237.851442 -62.79007)
		(stroke
			(width 0.0508)
			(type default)
		)
		(layer "In2.Cu")
	)
	(gr_line
		(start 237.851442 -62.79007)
		(end 237.858046 -62.784736)
		(stroke
			(width 0.0508)
			(type default)
		)
		(layer "In2.Cu")
	)
	(gr_line
		(start 237.858046 -62.784736)
		(end 237.895892 -62.755272)
		(stroke
			(width 0.0508)
			(type default)
		)
		(layer "In2.Cu")
	)
	(gr_line
		(start 237.895892 -62.755272)
		(end 237.901988 -62.7507)
		(stroke
			(width 0.0508)
			(type default)
		)
		(layer "In2.Cu")
	)
	(gr_arc
		(start 237.899194 -33.903666)
		(mid 237.914356 -33.902976)
		(end 237.92942 -33.901126)
		(stroke
			(width 0.0508)
			(type default)
		)
		(layer "In2.Cu")
	)
	(gr_line
		(start 237.901988 -62.7507)
		(end 237.904528 -62.748414)
		(stroke
			(width 0.0508)
			(type default)
		)
		(layer "In2.Cu")
	)
	(gr_line
		(start 237.904528 -62.748414)
		(end 238.026194 -62.652402)
		(stroke
			(width 0.0508)
			(type default)
		)
		(layer "In2.Cu")
	)
	(gr_arc
		(start 237.92942 -33.901126)
		(mid 237.929674 -33.901126)
		(end 237.929928 -33.901126)
		(stroke
			(width 0.0508)
			(type default)
		)
		(layer "In2.Cu")
	)
	(gr_arc
		(start 237.929928 -33.901126)
		(mid 237.989895 -33.881891)
		(end 238.040926 -33.844992)
		(stroke
			(width 0.0508)
			(type default)
		)
		(layer "In2.Cu")
	)
	(gr_line
		(start 237.958376 -63.03518)
		(end 237.996222 -63.03518)
		(stroke
			(width 0.0508)
			(type default)
		)
		(layer "In2.Cu")
	)
	(gr_arc
		(start 237.998508 -29.89834)
		(mid 238.07035 -29.868582)
		(end 238.100108 -29.79674)
		(stroke
			(width 0.0508)
			(type default)
		)
		(layer "In2.Cu")
	)
	(gr_line
		(start 237.99927 -28.368498)
		(end 238.041434 -28.326334)
		(stroke
			(width 0.0508)
			(type default)
		)
		(layer "In2.Cu")
	)
	(gr_arc
		(start 238.026194 -62.652402)
		(mid 238.080671 -62.584554)
		(end 238.100108 -62.499748)
		(stroke
			(width 0.0508)
			(type default)
		)
		(layer "In2.Cu")
	)
	(gr_line
		(start 238.040926 -33.844992)
		(end 238.04118 -33.844738)
		(stroke
			(width 0.0508)
			(type default)
		)
		(layer "In2.Cu")
	)
	(gr_arc
		(start 238.04118 -33.844738)
		(mid 238.084786 -33.779478)
		(end 238.100108 -33.702498)
		(stroke
			(width 0.0508)
			(type default)
		)
		(layer "In2.Cu")
	)
	(gr_line
		(start 238.043212 -28.324556)
		(end 238.06277 -28.304998)
		(stroke
			(width 0.0508)
			(type default)
		)
		(layer "In2.Cu")
	)
	(gr_line
		(start 238.06277 -28.279598)
		(end 238.06277 -28.304998)
		(stroke
			(width 0.0508)
			(type default)
		)
		(layer "In2.Cu")
	)
	(gr_arc
		(start 238.100108 -63.499746)
		(mid 238.176262 -63.385774)
		(end 238.202978 -63.251334)
		(stroke
			(width 0.0508)
			(type default)
		)
		(layer "In2.Cu")
	)
	(gr_line
		(start 238.100108 -37.294058)
		(end 238.100108 -37.500052)
		(stroke
			(width 0.0508)
			(type default)
		)
		(layer "In2.Cu")
	)
	(gr_arc
		(start 238.100108 -36.614608)
		(mid 238.121168 -36.720341)
		(end 238.181134 -36.809934)
		(stroke
			(width 0.0508)
			(type default)
		)
		(layer "In2.Cu")
	)
	(gr_line
		(start 238.100108 -36.500054)
		(end 238.100108 -36.614608)
		(stroke
			(width 0.0508)
			(type default)
		)
		(layer "In2.Cu")
	)
	(gr_arc
		(start 238.100108 -34.500058)
		(mid 238.178504 -34.366282)
		(end 238.1504 -34.2138)
		(stroke
			(width 0.0508)
			(type default)
		)
		(layer "In2.Cu")
	)
	(gr_line
		(start 238.100108 -33.50006)
		(end 238.100108 -33.702498)
		(stroke
			(width 0.0508)
			(type default)
		)
		(layer "In2.Cu")
	)
	(gr_arc
		(start 238.100108 -30.20314)
		(mid 238.070365 -30.131269)
		(end 237.998508 -30.10154)
		(stroke
			(width 0.0508)
			(type default)
		)
		(layer "In2.Cu")
	)
	(gr_line
		(start 238.100108 -30.20314)
		(end 238.100108 -30.500066)
		(stroke
			(width 0.0508)
			(type default)
		)
		(layer "In2.Cu")
	)
	(gr_line
		(start 238.100108 -29.500068)
		(end 238.100108 -29.79674)
		(stroke
			(width 0.0508)
			(type default)
		)
		(layer "In2.Cu")
	)
	(gr_arc
		(start 238.13135 -63.091314)
		(mid 238.069368 -63.049806)
		(end 237.996222 -63.03518)
		(stroke
			(width 0.0508)
			(type default)
		)
		(layer "In2.Cu")
	)
	(gr_line
		(start 238.13135 -63.091314)
		(end 238.14024 -63.09995)
		(stroke
			(width 0.0508)
			(type default)
		)
		(layer "In2.Cu")
	)
	(gr_arc
		(start 238.1504 -34.2138)
		(mid 238.070428 -34.135447)
		(end 237.962186 -34.106866)
		(stroke
			(width 0.0508)
			(type default)
		)
		(layer "In2.Cu")
	)
	(gr_line
		(start 238.181134 -36.809934)
		(end 238.184944 -36.813744)
		(stroke
			(width 0.0508)
			(type default)
		)
		(layer "In2.Cu")
	)
	(gr_arc
		(start 238.184944 -36.813744)
		(mid 238.27886 -36.876542)
		(end 238.389668 -36.89858)
		(stroke
			(width 0.0508)
			(type default)
		)
		(layer "In2.Cu")
	)
	(gr_arc
		(start 238.202978 -63.251334)
		(mid 238.186679 -63.169393)
		(end 238.14024 -63.09995)
		(stroke
			(width 0.0508)
			(type default)
		)
		(layer "In2.Cu")
	)
	(gr_line
		(start 238.29137 -115.66017)
		(end 238.310928 -115.63223)
		(stroke
			(width 0.06985)
			(type default)
		)
		(layer "In2.Cu")
	)
	(gr_line
		(start 238.310928 -115.63223)
		(end 238.31677 -115.59921)
		(stroke
			(width 0.06985)
			(type default)
		)
		(layer "In2.Cu")
	)
	(gr_line
		(start 238.4298 -67.3354)
		(end 238.449358 -67.315842)
		(stroke
			(width 0.0508)
			(type default)
		)
		(layer "In2.Cu")
	)
	(gr_arc
		(start 238.450374 -37.10178)
		(mid 238.250575 -37.153001)
		(end 238.100108 -37.294058)
		(stroke
			(width 0.0508)
			(type default)
		)
		(layer "In2.Cu")
	)
	(gr_line
		(start 238.451136 -67.314064)
		(end 238.493808 -67.271392)
		(stroke
			(width 0.0508)
			(type default)
		)
		(layer "In2.Cu")
	)
	(gr_line
		(start 238.4552 -29.042106)
		(end 238.500666 -29.087572)
		(stroke
			(width 0.0508)
			(type default)
		)
		(layer "In2.Cu")
	)
	(gr_line
		(start 238.4552 -28.9052)
		(end 238.4552 -29.042106)
		(stroke
			(width 0.0508)
			(type default)
		)
		(layer "In2.Cu")
	)
	(gr_line
		(start 238.4552 -28.717494)
		(end 238.4552 -28.9052)
		(stroke
			(width 0.06985)
			(type default)
		)
		(layer "In2.Cu")
	)
	(gr_line
		(start 238.493808 -67.0687)
		(end 238.493808 -67.271392)
		(stroke
			(width 0.0508)
			(type default)
		)
		(layer "In2.Cu")
	)
	(gr_line
		(start 238.67491 -61.929772)
		(end 238.754158 -61.866526)
		(stroke
			(width 0.0508)
			(type default)
		)
		(layer "In2.Cu")
	)
	(gr_line
		(start 238.697008 -67.272408)
		(end 238.738664 -67.314064)
		(stroke
			(width 0.0508)
			(type default)
		)
		(layer "In2.Cu")
	)
	(gr_line
		(start 238.706406 -28.984194)
		(end 238.706406 -29.1719)
		(stroke
			(width 0.0508)
			(type default)
		)
		(layer "In2.Cu")
	)
	(gr_line
		(start 238.706406 -28.984194)
		(end 238.711486 -28.979114)
		(stroke
			(width 0.0508)
			(type default)
		)
		(layer "In2.Cu")
	)
	(gr_line
		(start 238.715042 -28.975558)
		(end 238.7854 -28.9052)
		(stroke
			(width 0.0508)
			(type default)
		)
		(layer "In2.Cu")
	)
	(gr_line
		(start 238.721392 -88.289638)
		(end 238.724694 -88.270842)
		(stroke
			(width 0.06985)
			(type default)
		)
		(layer "In2.Cu")
	)
	(gr_line
		(start 238.721392 -88.251792)
		(end 238.724694 -88.270842)
		(stroke
			(width 0.06985)
			(type default)
		)
		(layer "In2.Cu")
	)
	(gr_line
		(start 238.740442 -67.315842)
		(end 238.76 -67.3354)
		(stroke
			(width 0.0508)
			(type default)
		)
		(layer "In2.Cu")
	)
	(gr_line
		(start 238.754158 -61.866526)
		(end 238.754666 -61.866018)
		(stroke
			(width 0.0508)
			(type default)
		)
		(layer "In2.Cu")
	)
	(gr_line
		(start 238.754666 -61.866018)
		(end 238.797846 -61.831728)
		(stroke
			(width 0.0508)
			(type default)
		)
		(layer "In2.Cu")
	)
	(gr_line
		(start 238.756698 -75.456796)
		(end 238.756698 -75.45705)
		(stroke
			(width 0.06985)
			(type default)
		)
		(layer "In2.Cu")
	)
	(gr_line
		(start 238.756698 -75.456796)
		(end 238.76 -75.438)
		(stroke
			(width 0.06985)
			(type default)
		)
		(layer "In2.Cu")
	)
	(gr_line
		(start 238.756698 -75.419204)
		(end 238.76 -75.438)
		(stroke
			(width 0.06985)
			(type default)
		)
		(layer "In2.Cu")
	)
	(gr_line
		(start 238.76 -67.3354)
		(end 238.76 -67.538092)
		(stroke
			(width 0.06985)
			(type default)
		)
		(layer "In2.Cu")
	)
	(gr_line
		(start 238.797846 -61.831728)
		(end 238.81842 -61.815726)
		(stroke
			(width 0.0508)
			(type default)
		)
		(layer "In2.Cu")
	)
	(gr_line
		(start 238.81842 -61.815726)
		(end 238.824262 -61.811154)
		(stroke
			(width 0.0508)
			(type default)
		)
		(layer "In2.Cu")
	)
	(gr_line
		(start 238.824262 -61.811154)
		(end 238.829342 -61.807344)
		(stroke
			(width 0.0508)
			(type default)
		)
		(layer "In2.Cu")
	)
	(gr_line
		(start 238.828326 -79.796894)
		(end 238.831628 -79.815944)
		(stroke
			(width 0.06985)
			(type default)
		)
		(layer "In2.Cu")
	)
	(gr_line
		(start 238.828326 -79.796894)
		(end 238.831628 -79.778098)
		(stroke
			(width 0.06985)
			(type default)
		)
		(layer "In2.Cu")
	)
	(gr_line
		(start 238.829342 -61.807344)
		(end 238.851186 -61.790072)
		(stroke
			(width 0.0508)
			(type default)
		)
		(layer "In2.Cu")
	)
	(gr_line
		(start 238.851186 -61.790072)
		(end 238.85144 -61.790072)
		(stroke
			(width 0.0508)
			(type default)
		)
		(layer "In2.Cu")
	)
	(gr_line
		(start 238.85144 -61.790072)
		(end 238.858044 -61.784738)
		(stroke
			(width 0.0508)
			(type default)
		)
		(layer "In2.Cu")
	)
	(gr_line
		(start 238.858044 -61.784738)
		(end 238.89589 -61.755274)
		(stroke
			(width 0.0508)
			(type default)
		)
		(layer "In2.Cu")
	)
	(gr_line
		(start 238.89589 -61.755274)
		(end 238.901986 -61.750702)
		(stroke
			(width 0.0508)
			(type default)
		)
		(layer "In2.Cu")
	)
	(gr_line
		(start 238.901986 -61.750702)
		(end 238.904526 -61.748416)
		(stroke
			(width 0.0508)
			(type default)
		)
		(layer "In2.Cu")
	)
	(gr_line
		(start 238.904526 -61.748416)
		(end 239.026192 -61.652404)
		(stroke
			(width 0.0508)
			(type default)
		)
		(layer "In2.Cu")
	)
	(gr_line
		(start 238.933228 -117.044978)
		(end 238.952786 -117.017038)
		(stroke
			(width 0.06985)
			(type default)
		)
		(layer "In2.Cu")
	)
	(gr_line
		(start 238.952786 -117.017038)
		(end 238.958628 -116.984018)
		(stroke
			(width 0.06985)
			(type default)
		)
		(layer "In2.Cu")
	)
	(gr_line
		(start 238.958374 -62.035182)
		(end 238.99622 -62.035182)
		(stroke
			(width 0.0508)
			(type default)
		)
		(layer "In2.Cu")
	)
	(gr_arc
		(start 239.026192 -61.652404)
		(mid 239.08067 -61.584556)
		(end 239.100106 -61.49975)
		(stroke
			(width 0.0508)
			(type default)
		)
		(layer "In2.Cu")
	)
	(gr_arc
		(start 239.100106 -62.499748)
		(mid 239.17626 -62.385776)
		(end 239.202976 -62.251336)
		(stroke
			(width 0.0508)
			(type default)
		)
		(layer "In2.Cu")
	)
	(gr_arc
		(start 239.131348 -62.091316)
		(mid 239.069366 -62.049808)
		(end 238.99622 -62.035182)
		(stroke
			(width 0.0508)
			(type default)
		)
		(layer "In2.Cu")
	)
	(gr_line
		(start 239.131348 -62.091316)
		(end 239.140238 -62.099952)
		(stroke
			(width 0.0508)
			(type default)
		)
		(layer "In2.Cu")
	)
	(gr_arc
		(start 239.202976 -62.251336)
		(mid 239.186677 -62.169395)
		(end 239.140238 -62.099952)
		(stroke
			(width 0.0508)
			(type default)
		)
		(layer "In2.Cu")
	)
	(gr_line
		(start 239.649 -36.2331)
		(end 239.649 -36.313364)
		(stroke
			(width 0.06985)
			(type default)
		)
		(layer "In2.Cu")
	)
	(gr_line
		(start 239.742726 -88.714326)
		(end 239.746028 -88.69553)
		(stroke
			(width 0.06985)
			(type default)
		)
		(layer "In2.Cu")
	)
	(gr_line
		(start 239.742726 -88.67648)
		(end 239.746028 -88.69553)
		(stroke
			(width 0.06985)
			(type default)
		)
		(layer "In2.Cu")
	)
	(gr_line
		(start 239.8522 -36.4998)
		(end 239.8522 -36.580064)
		(stroke
			(width 0.0508)
			(type default)
		)
		(layer "In2.Cu")
	)
	(gr_line
		(start 239.85474 -36.49726)
		(end 239.9792 -36.3728)
		(stroke
			(width 0.0508)
			(type default)
		)
		(layer "In2.Cu")
	)
	(gr_line
		(start 239.889538 -75.680824)
		(end 239.889538 -75.681078)
		(stroke
			(width 0.06985)
			(type default)
		)
		(layer "In2.Cu")
	)
	(gr_line
		(start 239.889538 -75.680824)
		(end 239.89284 -75.662028)
		(stroke
			(width 0.06985)
			(type default)
		)
		(layer "In2.Cu")
	)
	(gr_line
		(start 239.889538 -75.643232)
		(end 239.89284 -75.662028)
		(stroke
			(width 0.06985)
			(type default)
		)
		(layer "In2.Cu")
	)
	(gr_line
		(start 239.91189 -79.710534)
		(end 239.915192 -79.729584)
		(stroke
			(width 0.06985)
			(type default)
		)
		(layer "In2.Cu")
	)
	(gr_line
		(start 239.91189 -79.710534)
		(end 239.915192 -79.691738)
		(stroke
			(width 0.06985)
			(type default)
		)
		(layer "In2.Cu")
	)
	(gr_line
		(start 239.9792 -36.304728)
		(end 239.9792 -36.3728)
		(stroke
			(width 0.0508)
			(type default)
		)
		(layer "In2.Cu")
	)
	(gr_line
		(start 240.06429 -117.305582)
		(end 240.083848 -117.277642)
		(stroke
			(width 0.06985)
			(type default)
		)
		(layer "In2.Cu")
	)
	(gr_line
		(start 240.083848 -117.277642)
		(end 240.08969 -117.244622)
		(stroke
			(width 0.06985)
			(type default)
		)
		(layer "In2.Cu")
	)
	(gr_line
		(start 240.356898 -36.161218)
		(end 240.376456 -36.180776)
		(stroke
			(width 0.0508)
			(type default)
		)
		(layer "In2.Cu")
	)
	(gr_line
		(start 240.356898 -36.135818)
		(end 240.356898 -36.161218)
		(stroke
			(width 0.0508)
			(type default)
		)
		(layer "In2.Cu")
	)
	(gr_line
		(start 240.356898 -24.043132)
		(end 240.384584 -23.99792)
		(stroke
			(width 0.06985)
			(type default)
		)
		(layer "In2.Cu")
	)
	(gr_line
		(start 240.378234 -36.182554)
		(end 240.420398 -36.224718)
		(stroke
			(width 0.0508)
			(type default)
		)
		(layer "In2.Cu")
	)
	(gr_line
		(start 240.623598 -36.224718)
		(end 240.665762 -36.182554)
		(stroke
			(width 0.0508)
			(type default)
		)
		(layer "In2.Cu")
	)
	(gr_line
		(start 240.66754 -36.180776)
		(end 240.687098 -36.161218)
		(stroke
			(width 0.0508)
			(type default)
		)
		(layer "In2.Cu")
	)
	(gr_line
		(start 240.687098 -36.135818)
		(end 240.687098 -36.161218)
		(stroke
			(width 0.0508)
			(type default)
		)
		(layer "In2.Cu")
	)
	(gr_line
		(start 240.77676 -88.982296)
		(end 240.77676 -88.98255)
		(stroke
			(width 0.06985)
			(type default)
		)
		(layer "In2.Cu")
	)
	(gr_line
		(start 240.77676 -88.982296)
		(end 240.780062 -88.9635)
		(stroke
			(width 0.06985)
			(type default)
		)
		(layer "In2.Cu")
	)
	(gr_line
		(start 240.77676 -88.944704)
		(end 240.780062 -88.9635)
		(stroke
			(width 0.06985)
			(type default)
		)
		(layer "In2.Cu")
	)
	(gr_line
		(start 240.938812 -80.626712)
		(end 240.942114 -80.645762)
		(stroke
			(width 0.06985)
			(type default)
		)
		(layer "In2.Cu")
	)
	(gr_line
		(start 240.938812 -80.626712)
		(end 240.942114 -80.607916)
		(stroke
			(width 0.06985)
			(type default)
		)
		(layer "In2.Cu")
	)
	(gr_line
		(start 241.099848 -37.246052)
		(end 241.099848 -37.500052)
		(stroke
			(width 0.0508)
			(type default)
		)
		(layer "In2.Cu")
	)
	(gr_line
		(start 241.099848 -36.500054)
		(end 241.099848 -36.7157)
		(stroke
			(width 0.0508)
			(type default)
		)
		(layer "In2.Cu")
	)
	(gr_arc
		(start 241.2111 -37.1348)
		(mid 241.132433 -37.167385)
		(end 241.099848 -37.246052)
		(stroke
			(width 0.0508)
			(type default)
		)
		(layer "In2.Cu")
	)
	(gr_line
		(start 241.2111 -37.1348)
		(end 241.301524 -37.1348)
		(stroke
			(width 0.0508)
			(type default)
		)
		(layer "In2.Cu")
	)
	(gr_line
		(start 241.4016 -67.2338)
		(end 241.471958 -67.163442)
		(stroke
			(width 0.0508)
			(type default)
		)
		(layer "In2.Cu")
	)
	(gr_line
		(start 241.438684 -117.222016)
		(end 241.458242 -117.194076)
		(stroke
			(width 0.06985)
			(type default)
		)
		(layer "In2.Cu")
	)
	(gr_line
		(start 241.439446 -29.011626)
		(end 241.459004 -29.031184)
		(stroke
			(width 0.0508)
			(type default)
		)
		(layer "In2.Cu")
	)
	(gr_line
		(start 241.439446 -28.986226)
		(end 241.439446 -29.011626)
		(stroke
			(width 0.0508)
			(type default)
		)
		(layer "In2.Cu")
	)
	(gr_line
		(start 241.458242 -117.194076)
		(end 241.464084 -117.161056)
		(stroke
			(width 0.06985)
			(type default)
		)
		(layer "In2.Cu")
	)
	(gr_line
		(start 241.460782 -29.032962)
		(end 241.502946 -29.075126)
		(stroke
			(width 0.0508)
			(type default)
		)
		(layer "In2.Cu")
	)
	(gr_line
		(start 241.475514 -67.159886)
		(end 241.493548 -67.141852)
		(stroke
			(width 0.0508)
			(type default)
		)
		(layer "In2.Cu")
	)
	(gr_line
		(start 241.493548 -66.9671)
		(end 241.493548 -67.141852)
		(stroke
			(width 0.0508)
			(type default)
		)
		(layer "In2.Cu")
	)
	(gr_line
		(start 241.634264 -22.60092)
		(end 241.66195 -22.555708)
		(stroke
			(width 0.06985)
			(type default)
		)
		(layer "In2.Cu")
	)
	(gr_line
		(start 241.67465 -61.929772)
		(end 241.753898 -61.866526)
		(stroke
			(width 0.0508)
			(type default)
		)
		(layer "In2.Cu")
	)
	(gr_arc
		(start 241.696748 -67.173856)
		(mid 241.701296 -67.19681)
		(end 241.714274 -67.216274)
		(stroke
			(width 0.0508)
			(type default)
		)
		(layer "In2.Cu")
	)
	(gr_line
		(start 241.706146 -29.075126)
		(end 241.74831 -29.032962)
		(stroke
			(width 0.0508)
			(type default)
		)
		(layer "In2.Cu")
	)
	(gr_line
		(start 241.714274 -67.216274)
		(end 241.7318 -67.2338)
		(stroke
			(width 0.0508)
			(type default)
		)
		(layer "In2.Cu")
	)
	(gr_line
		(start 241.7318 -67.2338)
		(end 241.7318 -67.408552)
		(stroke
			(width 0.06985)
			(type default)
		)
		(layer "In2.Cu")
	)
	(gr_line
		(start 241.750088 -29.031184)
		(end 241.769646 -29.011626)
		(stroke
			(width 0.0508)
			(type default)
		)
		(layer "In2.Cu")
	)
	(gr_line
		(start 241.753898 -61.866526)
		(end 241.754406 -61.866018)
		(stroke
			(width 0.0508)
			(type default)
		)
		(layer "In2.Cu")
	)
	(gr_line
		(start 241.754406 -61.866018)
		(end 241.797586 -61.831728)
		(stroke
			(width 0.0508)
			(type default)
		)
		(layer "In2.Cu")
	)
	(gr_line
		(start 241.769646 -28.986226)
		(end 241.769646 -29.011626)
		(stroke
			(width 0.0508)
			(type default)
		)
		(layer "In2.Cu")
	)
	(gr_line
		(start 241.797586 -61.831728)
		(end 241.81816 -61.815726)
		(stroke
			(width 0.0508)
			(type default)
		)
		(layer "In2.Cu")
	)
	(gr_line
		(start 241.81816 -61.815726)
		(end 241.824002 -61.811154)
		(stroke
			(width 0.0508)
			(type default)
		)
		(layer "In2.Cu")
	)
	(gr_line
		(start 241.824002 -61.811154)
		(end 241.829082 -61.807344)
		(stroke
			(width 0.0508)
			(type default)
		)
		(layer "In2.Cu")
	)
	(gr_line
		(start 241.829082 -61.807344)
		(end 241.850926 -61.790072)
		(stroke
			(width 0.0508)
			(type default)
		)
		(layer "In2.Cu")
	)
	(gr_line
		(start 241.850926 -61.790072)
		(end 241.85118 -61.790072)
		(stroke
			(width 0.0508)
			(type default)
		)
		(layer "In2.Cu")
	)
	(gr_line
		(start 241.85118 -61.790072)
		(end 241.857784 -61.784738)
		(stroke
			(width 0.0508)
			(type default)
		)
		(layer "In2.Cu")
	)
	(gr_line
		(start 241.857784 -61.784738)
		(end 241.879628 -61.767466)
		(stroke
			(width 0.0508)
			(type default)
		)
		(layer "In2.Cu")
	)
	(gr_line
		(start 241.879628 -61.767466)
		(end 241.883692 -61.764164)
		(stroke
			(width 0.0508)
			(type default)
		)
		(layer "In2.Cu")
	)
	(gr_line
		(start 241.883692 -61.764164)
		(end 241.89563 -61.755274)
		(stroke
			(width 0.0508)
			(type default)
		)
		(layer "In2.Cu")
	)
	(gr_line
		(start 241.89563 -61.755274)
		(end 241.901726 -61.750702)
		(stroke
			(width 0.0508)
			(type default)
		)
		(layer "In2.Cu")
	)
	(gr_line
		(start 241.901726 -61.750702)
		(end 241.904266 -61.748416)
		(stroke
			(width 0.0508)
			(type default)
		)
		(layer "In2.Cu")
	)
	(gr_line
		(start 241.904266 -61.748416)
		(end 242.025932 -61.652404)
		(stroke
			(width 0.0508)
			(type default)
		)
		(layer "In2.Cu")
	)
	(gr_line
		(start 241.931698 -89.299796)
		(end 241.931698 -89.30005)
		(stroke
			(width 0.06985)
			(type default)
		)
		(layer "In2.Cu")
	)
	(gr_line
		(start 241.931698 -89.299796)
		(end 241.935 -89.281)
		(stroke
			(width 0.06985)
			(type default)
		)
		(layer "In2.Cu")
	)
	(gr_line
		(start 241.931698 -89.262204)
		(end 241.935 -89.281)
		(stroke
			(width 0.06985)
			(type default)
		)
		(layer "In2.Cu")
	)
	(gr_line
		(start 241.958114 -62.035182)
		(end 242.062508 -62.035182)
		(stroke
			(width 0.0508)
			(type default)
		)
		(layer "In2.Cu")
	)
	(gr_arc
		(start 242.025932 -61.652404)
		(mid 242.080399 -61.584553)
		(end 242.099846 -61.49975)
		(stroke
			(width 0.0508)
			(type default)
		)
		(layer "In2.Cu")
	)
	(gr_line
		(start 242.099846 -62.499748)
		(end 242.2525 -62.347094)
		(stroke
			(width 0.0508)
			(type default)
		)
		(layer "In2.Cu")
	)
	(gr_arc
		(start 242.162584 -62.076584)
		(mid 242.116655 -62.045958)
		(end 242.062508 -62.035182)
		(stroke
			(width 0.0508)
			(type default)
		)
		(layer "In2.Cu")
	)
	(gr_line
		(start 242.162584 -62.076584)
		(end 242.2525 -62.1665)
		(stroke
			(width 0.0508)
			(type default)
		)
		(layer "In2.Cu")
	)
	(gr_arc
		(start 242.2525 -62.347094)
		(mid 242.28985 -62.256834)
		(end 242.2525 -62.1665)
		(stroke
			(width 0.0508)
			(type default)
		)
		(layer "In2.Cu")
	)
	(gr_line
		(start 242.268756 -81.384394)
		(end 242.272058 -81.403444)
		(stroke
			(width 0.06985)
			(type default)
		)
		(layer "In2.Cu")
	)
	(gr_line
		(start 242.268756 -81.384394)
		(end 242.272058 -81.365598)
		(stroke
			(width 0.06985)
			(type default)
		)
		(layer "In2.Cu")
	)
	(gr_line
		(start 242.443 -67.183)
		(end 242.443 -67.373246)
		(stroke
			(width 0.06985)
			(type default)
		)
		(layer "In2.Cu")
	)
	(gr_line
		(start 242.443 -67.183)
		(end 242.462558 -67.163442)
		(stroke
			(width 0.0508)
			(type default)
		)
		(layer "In2.Cu")
	)
	(gr_line
		(start 242.464336 -67.161664)
		(end 242.493546 -67.132454)
		(stroke
			(width 0.0508)
			(type default)
		)
		(layer "In2.Cu")
	)
	(gr_line
		(start 242.485926 -20.418044)
		(end 243.054886 -20.014692)
		(stroke
			(width 0.06985)
			(type default)
		)
		(layer "In2.Cu")
	)
	(gr_arc
		(start 242.648232 -30.219142)
		(mid 242.863537 -30.376484)
		(end 243.099844 -30.500066)
		(stroke
			(width 0.0508)
			(type default)
		)
		(layer "In2.Cu")
	)
	(gr_line
		(start 242.649248 -20.710144)
		(end 242.894104 -20.7518)
		(stroke
			(width 0.06985)
			(type default)
		)
		(layer "In2.Cu")
	)
	(gr_line
		(start 242.674648 -62.92977)
		(end 242.753896 -62.866524)
		(stroke
			(width 0.0508)
			(type default)
		)
		(layer "In2.Cu")
	)
	(gr_line
		(start 242.696746 -67.106546)
		(end 242.751864 -67.161664)
		(stroke
			(width 0.0508)
			(type default)
		)
		(layer "In2.Cu")
	)
	(gr_line
		(start 242.696746 -66.9163)
		(end 242.696746 -67.106546)
		(stroke
			(width 0.0508)
			(type default)
		)
		(layer "In2.Cu")
	)
	(gr_line
		(start 242.753642 -67.163442)
		(end 242.7732 -67.183)
		(stroke
			(width 0.0508)
			(type default)
		)
		(layer "In2.Cu")
	)
	(gr_line
		(start 242.753896 -62.866524)
		(end 242.754404 -62.866016)
		(stroke
			(width 0.0508)
			(type default)
		)
		(layer "In2.Cu")
	)
	(gr_line
		(start 242.754404 -62.866016)
		(end 242.797584 -62.831726)
		(stroke
			(width 0.0508)
			(type default)
		)
		(layer "In2.Cu")
	)
	(gr_line
		(start 242.797584 -62.831726)
		(end 242.818158 -62.815724)
		(stroke
			(width 0.0508)
			(type default)
		)
		(layer "In2.Cu")
	)
	(gr_line
		(start 242.818158 -62.815724)
		(end 242.824 -62.811152)
		(stroke
			(width 0.0508)
			(type default)
		)
		(layer "In2.Cu")
	)
	(gr_line
		(start 242.824 -62.811152)
		(end 242.82908 -62.807342)
		(stroke
			(width 0.0508)
			(type default)
		)
		(layer "In2.Cu")
	)
	(gr_line
		(start 242.82908 -62.807342)
		(end 242.850924 -62.79007)
		(stroke
			(width 0.0508)
			(type default)
		)
		(layer "In2.Cu")
	)
	(gr_line
		(start 242.850924 -62.79007)
		(end 242.851178 -62.79007)
		(stroke
			(width 0.0508)
			(type default)
		)
		(layer "In2.Cu")
	)
	(gr_line
		(start 242.851178 -62.79007)
		(end 242.857782 -62.784736)
		(stroke
			(width 0.0508)
			(type default)
		)
		(layer "In2.Cu")
	)
	(gr_line
		(start 242.857782 -62.784736)
		(end 242.895628 -62.755272)
		(stroke
			(width 0.0508)
			(type default)
		)
		(layer "In2.Cu")
	)
	(gr_line
		(start 242.876578 -89.737692)
		(end 242.876578 -89.737946)
		(stroke
			(width 0.06985)
			(type default)
		)
		(layer "In2.Cu")
	)
	(gr_line
		(start 242.876578 -89.737692)
		(end 242.87988 -89.718896)
		(stroke
			(width 0.06985)
			(type default)
		)
		(layer "In2.Cu")
	)
	(gr_line
		(start 242.876578 -89.7001)
		(end 242.87988 -89.718896)
		(stroke
			(width 0.06985)
			(type default)
		)
		(layer "In2.Cu")
	)
	(gr_line
		(start 242.894104 -20.7518)
		(end 243.235988 -20.50923)
		(stroke
			(width 0.06985)
			(type default)
		)
		(layer "In2.Cu")
	)
	(gr_line
		(start 242.895628 -62.755272)
		(end 242.901724 -62.7507)
		(stroke
			(width 0.0508)
			(type default)
		)
		(layer "In2.Cu")
	)
	(gr_line
		(start 242.901724 -62.7507)
		(end 242.904264 -62.748414)
		(stroke
			(width 0.0508)
			(type default)
		)
		(layer "In2.Cu")
	)
	(gr_line
		(start 242.904264 -62.748414)
		(end 243.02593 -62.652402)
		(stroke
			(width 0.0508)
			(type default)
		)
		(layer "In2.Cu")
	)
	(gr_line
		(start 242.958112 -63.03518)
		(end 242.995958 -63.03518)
		(stroke
			(width 0.0508)
			(type default)
		)
		(layer "In2.Cu")
	)
	(gr_line
		(start 242.97259 -117.906038)
		(end 242.992148 -117.878098)
		(stroke
			(width 0.06985)
			(type default)
		)
		(layer "In2.Cu")
	)
	(gr_line
		(start 242.9764 -24.486362)
		(end 243.044472 -24.41829)
		(stroke
			(width 0.06985)
			(type default)
		)
		(layer "In2.Cu")
	)
	(gr_line
		(start 242.992148 -117.878098)
		(end 242.99799 -117.845078)
		(stroke
			(width 0.06985)
			(type default)
		)
		(layer "In2.Cu")
	)
	(gr_line
		(start 243.024914 -28.39085)
		(end 243.12626 -28.289504)
		(stroke
			(width 0.0508)
			(type default)
		)
		(layer "In2.Cu")
	)
	(gr_arc
		(start 243.02593 -62.652402)
		(mid 243.080402 -62.584554)
		(end 243.099844 -62.499748)
		(stroke
			(width 0.0508)
			(type default)
		)
		(layer "In2.Cu")
	)
	(gr_line
		(start 243.069618 -28.058618)
		(end 243.170964 -27.957272)
		(stroke
			(width 0.06985)
			(type default)
		)
		(layer "In2.Cu")
	)
	(gr_arc
		(start 243.099844 -63.499746)
		(mid 243.175981 -63.385768)
		(end 243.202714 -63.251334)
		(stroke
			(width 0.0508)
			(type default)
		)
		(layer "In2.Cu")
	)
	(gr_line
		(start 243.099844 -29.500068)
		(end 243.099844 -29.916628)
		(stroke
			(width 0.0508)
			(type default)
		)
		(layer "In2.Cu")
	)
	(gr_line
		(start 243.12626 -28.289504)
		(end 243.203222 -28.289504)
		(stroke
			(width 0.0508)
			(type default)
		)
		(layer "In2.Cu")
	)
	(gr_arc
		(start 243.131086 -63.091314)
		(mid 243.069095 -63.049838)
		(end 242.995958 -63.03518)
		(stroke
			(width 0.0508)
			(type default)
		)
		(layer "In2.Cu")
	)
	(gr_line
		(start 243.131086 -63.091314)
		(end 243.139976 -63.09995)
		(stroke
			(width 0.0508)
			(type default)
		)
		(layer "In2.Cu")
	)
	(gr_arc
		(start 243.202714 -63.251334)
		(mid 243.186372 -63.169417)
		(end 243.139976 -63.09995)
		(stroke
			(width 0.0508)
			(type default)
		)
		(layer "In2.Cu")
	)
	(gr_line
		(start 243.208048 -28.289504)
		(end 243.305838 -28.289504)
		(stroke
			(width 0.0508)
			(type default)
		)
		(layer "In2.Cu")
	)
	(gr_line
		(start 243.235988 -20.50923)
		(end 243.277644 -20.264628)
		(stroke
			(width 0.06985)
			(type default)
		)
		(layer "In2.Cu")
	)
	(gr_line
		(start 243.439442 -67.183)
		(end 243.439442 -67.376802)
		(stroke
			(width 0.06985)
			(type default)
		)
		(layer "In2.Cu")
	)
	(gr_line
		(start 243.439442 -67.183)
		(end 243.459 -67.163442)
		(stroke
			(width 0.0508)
			(type default)
		)
		(layer "In2.Cu")
	)
	(gr_line
		(start 243.460524 -19.727164)
		(end 244.027706 -19.324828)
		(stroke
			(width 0.06985)
			(type default)
		)
		(layer "In2.Cu")
	)
	(gr_line
		(start 243.460778 -67.161664)
		(end 243.493544 -67.128898)
		(stroke
			(width 0.0508)
			(type default)
		)
		(layer "In2.Cu")
	)
	(gr_line
		(start 243.467636 -81.361534)
		(end 243.470938 -81.380584)
		(stroke
			(width 0.06985)
			(type default)
		)
		(layer "In2.Cu")
	)
	(gr_line
		(start 243.467636 -81.361534)
		(end 243.470938 -81.342738)
		(stroke
			(width 0.06985)
			(type default)
		)
		(layer "In2.Cu")
	)
	(gr_line
		(start 243.623084 -20.019518)
		(end 243.86794 -20.061174)
		(stroke
			(width 0.06985)
			(type default)
		)
		(layer "In2.Cu")
	)
	(gr_line
		(start 243.674646 -61.929772)
		(end 243.753894 -61.866526)
		(stroke
			(width 0.0508)
			(type default)
		)
		(layer "In2.Cu")
	)
	(gr_line
		(start 243.682266 -119.784622)
		(end 243.701824 -119.756682)
		(stroke
			(width 0.06985)
			(type default)
		)
		(layer "In2.Cu")
	)
	(gr_line
		(start 243.696744 -67.110102)
		(end 243.748306 -67.161664)
		(stroke
			(width 0.0508)
			(type default)
		)
		(layer "In2.Cu")
	)
	(gr_line
		(start 243.696744 -66.9163)
		(end 243.696744 -67.110102)
		(stroke
			(width 0.0508)
			(type default)
		)
		(layer "In2.Cu")
	)
	(gr_line
		(start 243.701824 -119.756682)
		(end 243.707666 -119.723662)
		(stroke
			(width 0.06985)
			(type default)
		)
		(layer "In2.Cu")
	)
	(gr_line
		(start 243.750084 -67.163442)
		(end 243.769642 -67.183)
		(stroke
			(width 0.0508)
			(type default)
		)
		(layer "In2.Cu")
	)
	(gr_line
		(start 243.753894 -61.866526)
		(end 243.754402 -61.866018)
		(stroke
			(width 0.0508)
			(type default)
		)
		(layer "In2.Cu")
	)
	(gr_line
		(start 243.754402 -61.866018)
		(end 243.797582 -61.831728)
		(stroke
			(width 0.0508)
			(type default)
		)
		(layer "In2.Cu")
	)
	(gr_line
		(start 243.797582 -61.831728)
		(end 243.818156 -61.815726)
		(stroke
			(width 0.0508)
			(type default)
		)
		(layer "In2.Cu")
	)
	(gr_line
		(start 243.818156 -61.815726)
		(end 243.823998 -61.811154)
		(stroke
			(width 0.0508)
			(type default)
		)
		(layer "In2.Cu")
	)
	(gr_line
		(start 243.823998 -61.811154)
		(end 243.829078 -61.807344)
		(stroke
			(width 0.0508)
			(type default)
		)
		(layer "In2.Cu")
	)
	(gr_line
		(start 243.829078 -61.807344)
		(end 243.850922 -61.790072)
		(stroke
			(width 0.0508)
			(type default)
		)
		(layer "In2.Cu")
	)
	(gr_line
		(start 243.850922 -61.790072)
		(end 243.851176 -61.790072)
		(stroke
			(width 0.0508)
			(type default)
		)
		(layer "In2.Cu")
	)
	(gr_line
		(start 243.851176 -61.790072)
		(end 243.85778 -61.784738)
		(stroke
			(width 0.0508)
			(type default)
		)
		(layer "In2.Cu")
	)
	(gr_line
		(start 243.85778 -61.784738)
		(end 243.895626 -61.755274)
		(stroke
			(width 0.0508)
			(type default)
		)
		(layer "In2.Cu")
	)
	(gr_line
		(start 243.86794 -20.061174)
		(end 244.209824 -19.818604)
		(stroke
			(width 0.06985)
			(type default)
		)
		(layer "In2.Cu")
	)
	(gr_line
		(start 243.895626 -61.755274)
		(end 243.901722 -61.750702)
		(stroke
			(width 0.0508)
			(type default)
		)
		(layer "In2.Cu")
	)
	(gr_line
		(start 243.901722 -61.750702)
		(end 243.904262 -61.748416)
		(stroke
			(width 0.0508)
			(type default)
		)
		(layer "In2.Cu")
	)
	(gr_line
		(start 243.904262 -61.748416)
		(end 244.025928 -61.652404)
		(stroke
			(width 0.0508)
			(type default)
		)
		(layer "In2.Cu")
	)
	(gr_line
		(start 243.916708 -88.86444)
		(end 243.92001 -88.845644)
		(stroke
			(width 0.06985)
			(type default)
		)
		(layer "In2.Cu")
	)
	(gr_line
		(start 243.916708 -88.826594)
		(end 243.92001 -88.845644)
		(stroke
			(width 0.06985)
			(type default)
		)
		(layer "In2.Cu")
	)
	(gr_line
		(start 243.95811 -62.035182)
		(end 243.995956 -62.035182)
		(stroke
			(width 0.0508)
			(type default)
		)
		(layer "In2.Cu")
	)
	(gr_line
		(start 243.978176 -73.59269)
		(end 243.978176 -73.592944)
		(stroke
			(width 0.06985)
			(type default)
		)
		(layer "In2.Cu")
	)
	(gr_line
		(start 243.978176 -73.59269)
		(end 243.981478 -73.573894)
		(stroke
			(width 0.06985)
			(type default)
		)
		(layer "In2.Cu")
	)
	(gr_line
		(start 243.978176 -73.555098)
		(end 243.981478 -73.573894)
		(stroke
			(width 0.06985)
			(type default)
		)
		(layer "In2.Cu")
	)
	(gr_arc
		(start 244.025928 -61.652404)
		(mid 244.080396 -61.584553)
		(end 244.099842 -61.49975)
		(stroke
			(width 0.0508)
			(type default)
		)
		(layer "In2.Cu")
	)
	(gr_arc
		(start 244.099842 -62.499748)
		(mid 244.175996 -62.385776)
		(end 244.202712 -62.251336)
		(stroke
			(width 0.0508)
			(type default)
		)
		(layer "In2.Cu")
	)
	(gr_line
		(start 244.099842 -31.203138)
		(end 244.099842 -31.500064)
		(stroke
			(width 0.0508)
			(type default)
		)
		(layer "In2.Cu")
	)
	(gr_arc
		(start 244.099842 -30.796738)
		(mid 244.129616 -30.868541)
		(end 244.201442 -30.898338)
		(stroke
			(width 0.0508)
			(type default)
		)
		(layer "In2.Cu")
	)
	(gr_line
		(start 244.099842 -30.500066)
		(end 244.099842 -30.796738)
		(stroke
			(width 0.0508)
			(type default)
		)
		(layer "In2.Cu")
	)
	(gr_arc
		(start 244.131084 -62.091316)
		(mid 244.069102 -62.049808)
		(end 243.995956 -62.035182)
		(stroke
			(width 0.0508)
			(type default)
		)
		(layer "In2.Cu")
	)
	(gr_line
		(start 244.131084 -62.091316)
		(end 244.139974 -62.099952)
		(stroke
			(width 0.0508)
			(type default)
		)
		(layer "In2.Cu")
	)
	(gr_line
		(start 244.1575 -28.316936)
		(end 244.177058 -28.336494)
		(stroke
			(width 0.0508)
			(type default)
		)
		(layer "In2.Cu")
	)
	(gr_line
		(start 244.1575 -25.080468)
		(end 244.225572 -25.012396)
		(stroke
			(width 0.06985)
			(type default)
		)
		(layer "In2.Cu")
	)
	(gr_line
		(start 244.16258 -29.842206)
		(end 244.199664 -29.87929)
		(stroke
			(width 0.0508)
			(type default)
		)
		(layer "In2.Cu")
	)
	(gr_line
		(start 244.178836 -28.338272)
		(end 244.236748 -28.396184)
		(stroke
			(width 0.0508)
			(type default)
		)
		(layer "In2.Cu")
	)
	(gr_arc
		(start 244.201442 -31.101538)
		(mid 244.1296 -31.131296)
		(end 244.099842 -31.203138)
		(stroke
			(width 0.0508)
			(type default)
		)
		(layer "In2.Cu")
	)
	(gr_arc
		(start 244.202712 -62.251336)
		(mid 244.186413 -62.169395)
		(end 244.139974 -62.099952)
		(stroke
			(width 0.0508)
			(type default)
		)
		(layer "In2.Cu")
	)
	(gr_line
		(start 244.209824 -19.818604)
		(end 244.25148 -19.574002)
		(stroke
			(width 0.06985)
			(type default)
		)
		(layer "In2.Cu")
	)
	(gr_line
		(start 244.236748 -28.761436)
		(end 244.236748 -28.80614)
		(stroke
			(width 0.0508)
			(type default)
		)
		(layer "In2.Cu")
	)
	(gr_line
		(start 244.236748 -28.396184)
		(end 244.236748 -28.583636)
		(stroke
			(width 0.0508)
			(type default)
		)
		(layer "In2.Cu")
	)
	(gr_line
		(start 244.344698 -121.179336)
		(end 244.364256 -121.151396)
		(stroke
			(width 0.06985)
			(type default)
		)
		(layer "In2.Cu")
	)
	(gr_line
		(start 244.364256 -121.151396)
		(end 244.370098 -121.118376)
		(stroke
			(width 0.06985)
			(type default)
		)
		(layer "In2.Cu")
	)
	(gr_line
		(start 244.36578 -28.964636)
		(end 244.36578 -29.00934)
		(stroke
			(width 0.0508)
			(type default)
		)
		(layer "In2.Cu")
	)
	(gr_line
		(start 244.430042 -67.183)
		(end 244.4496 -67.163442)
		(stroke
			(width 0.0508)
			(type default)
		)
		(layer "In2.Cu")
	)
	(gr_line
		(start 244.439948 -28.364688)
		(end 244.466364 -28.338272)
		(stroke
			(width 0.0508)
			(type default)
		)
		(layer "In2.Cu")
	)
	(gr_line
		(start 244.451378 -67.161664)
		(end 244.493542 -67.1195)
		(stroke
			(width 0.0508)
			(type default)
		)
		(layer "In2.Cu")
	)
	(gr_line
		(start 244.468142 -28.336494)
		(end 244.4877 -28.316936)
		(stroke
			(width 0.0508)
			(type default)
		)
		(layer "In2.Cu")
	)
	(gr_line
		(start 244.4877 -28.129484)
		(end 244.4877 -28.316936)
		(stroke
			(width 0.06985)
			(type default)
		)
		(layer "In2.Cu")
	)
	(gr_line
		(start 244.6528 -29.52242)
		(end 245.028212 -30.428438)
		(stroke
			(width 0.06985)
			(type default)
		)
		(layer "In2.Cu")
	)
	(gr_line
		(start 244.6528 -29.23413)
		(end 244.6528 -29.52242)
		(stroke
			(width 0.06985)
			(type default)
		)
		(layer "In2.Cu")
	)
	(gr_line
		(start 244.674644 -62.92977)
		(end 244.753892 -62.866524)
		(stroke
			(width 0.0508)
			(type default)
		)
		(layer "In2.Cu")
	)
	(gr_line
		(start 244.678454 -81.534)
		(end 244.681756 -81.55305)
		(stroke
			(width 0.06985)
			(type default)
		)
		(layer "In2.Cu")
	)
	(gr_line
		(start 244.678454 -81.534)
		(end 244.681756 -81.515204)
		(stroke
			(width 0.06985)
			(type default)
		)
		(layer "In2.Cu")
	)
	(gr_line
		(start 244.696742 -67.1195)
		(end 244.738906 -67.161664)
		(stroke
			(width 0.0508)
			(type default)
		)
		(layer "In2.Cu")
	)
	(gr_line
		(start 244.740684 -67.163442)
		(end 244.760242 -67.183)
		(stroke
			(width 0.0508)
			(type default)
		)
		(layer "In2.Cu")
	)
	(gr_arc
		(start 244.7417 -29.0195)
		(mid 244.675902 -29.117973)
		(end 244.6528 -29.23413)
		(stroke
			(width 0.06985)
			(type default)
		)
		(layer "In2.Cu")
	)
	(gr_line
		(start 244.7417 -29.0195)
		(end 244.799104 -28.96235)
		(stroke
			(width 0.06985)
			(type default)
		)
		(layer "In2.Cu")
	)
	(gr_line
		(start 244.753892 -62.866524)
		(end 244.7544 -62.866016)
		(stroke
			(width 0.0508)
			(type default)
		)
		(layer "In2.Cu")
	)
	(gr_line
		(start 244.7544 -62.866016)
		(end 244.79758 -62.831726)
		(stroke
			(width 0.0508)
			(type default)
		)
		(layer "In2.Cu")
	)
	(gr_line
		(start 244.79758 -62.831726)
		(end 244.818154 -62.815724)
		(stroke
			(width 0.0508)
			(type default)
		)
		(layer "In2.Cu")
	)
	(gr_arc
		(start 244.799104 -28.96235)
		(mid 244.858661 -28.883995)
		(end 244.89537 -28.792678)
		(stroke
			(width 0.06985)
			(type default)
		)
		(layer "In2.Cu")
	)
	(gr_line
		(start 244.818154 -62.815724)
		(end 244.823996 -62.811152)
		(stroke
			(width 0.0508)
			(type default)
		)
		(layer "In2.Cu")
	)
	(gr_line
		(start 244.823996 -62.811152)
		(end 244.829076 -62.807342)
		(stroke
			(width 0.0508)
			(type default)
		)
		(layer "In2.Cu")
	)
	(gr_line
		(start 244.829076 -62.807342)
		(end 244.85092 -62.79007)
		(stroke
			(width 0.0508)
			(type default)
		)
		(layer "In2.Cu")
	)
	(gr_line
		(start 244.85092 -62.79007)
		(end 244.851174 -62.79007)
		(stroke
			(width 0.0508)
			(type default)
		)
		(layer "In2.Cu")
	)
	(gr_line
		(start 244.851174 -62.79007)
		(end 244.857778 -62.784736)
		(stroke
			(width 0.0508)
			(type default)
		)
		(layer "In2.Cu")
	)
	(gr_line
		(start 244.857778 -62.784736)
		(end 244.895624 -62.755272)
		(stroke
			(width 0.0508)
			(type default)
		)
		(layer "In2.Cu")
	)
	(gr_arc
		(start 244.89537 -28.792678)
		(mid 244.903923 -28.747697)
		(end 244.9068 -28.702)
		(stroke
			(width 0.06985)
			(type default)
		)
		(layer "In2.Cu")
	)
	(gr_line
		(start 244.895624 -62.755272)
		(end 244.90172 -62.7507)
		(stroke
			(width 0.0508)
			(type default)
		)
		(layer "In2.Cu")
	)
	(gr_line
		(start 244.90172 -62.7507)
		(end 244.90426 -62.748414)
		(stroke
			(width 0.0508)
			(type default)
		)
		(layer "In2.Cu")
	)
	(gr_line
		(start 244.90426 -62.748414)
		(end 245.025926 -62.652402)
		(stroke
			(width 0.0508)
			(type default)
		)
		(layer "In2.Cu")
	)
	(gr_line
		(start 244.9068 -26.001726)
		(end 244.974872 -25.933654)
		(stroke
			(width 0.06985)
			(type default)
		)
		(layer "In2.Cu")
	)
	(gr_line
		(start 244.958108 -63.03518)
		(end 244.995954 -63.03518)
		(stroke
			(width 0.0508)
			(type default)
		)
		(layer "In2.Cu")
	)
	(gr_arc
		(start 245.025926 -62.652402)
		(mid 245.080398 -62.584554)
		(end 245.09984 -62.499748)
		(stroke
			(width 0.0508)
			(type default)
		)
		(layer "In2.Cu")
	)
	(gr_line
		(start 245.028212 -30.428438)
		(end 245.09984 -30.500066)
		(stroke
			(width 0.06985)
			(type default)
		)
		(layer "In2.Cu")
	)
	(gr_arc
		(start 245.09984 -63.499746)
		(mid 245.175978 -63.385768)
		(end 245.20271 -63.251334)
		(stroke
			(width 0.0508)
			(type default)
		)
		(layer "In2.Cu")
	)
	(gr_arc
		(start 245.09984 -29.500068)
		(mid 245.201348 -29.348095)
		(end 245.237 -29.168852)
		(stroke
			(width 0.06985)
			(type default)
		)
		(layer "In2.Cu")
	)
	(gr_line
		(start 245.106698 -88.791796)
		(end 245.106698 -88.79205)
		(stroke
			(width 0.06985)
			(type default)
		)
		(layer "In2.Cu")
	)
	(gr_line
		(start 245.106698 -88.791796)
		(end 245.11 -88.773)
		(stroke
			(width 0.06985)
			(type default)
		)
		(layer "In2.Cu")
	)
	(gr_line
		(start 245.106698 -88.754204)
		(end 245.11 -88.773)
		(stroke
			(width 0.06985)
			(type default)
		)
		(layer "In2.Cu")
	)
	(gr_arc
		(start 245.131082 -63.091314)
		(mid 245.069091 -63.049839)
		(end 244.995954 -63.03518)
		(stroke
			(width 0.0508)
			(type default)
		)
		(layer "In2.Cu")
	)
	(gr_line
		(start 245.131082 -63.091314)
		(end 245.139972 -63.09995)
		(stroke
			(width 0.0508)
			(type default)
		)
		(layer "In2.Cu")
	)
	(gr_line
		(start 245.154704 -73.697084)
		(end 245.154704 -73.697338)
		(stroke
			(width 0.06985)
			(type default)
		)
		(layer "In2.Cu")
	)
	(gr_line
		(start 245.154704 -73.697084)
		(end 245.158006 -73.678288)
		(stroke
			(width 0.06985)
			(type default)
		)
		(layer "In2.Cu")
	)
	(gr_line
		(start 245.154704 -73.659492)
		(end 245.158006 -73.678288)
		(stroke
			(width 0.06985)
			(type default)
		)
		(layer "In2.Cu")
	)
	(gr_arc
		(start 245.20271 -63.251334)
		(mid 245.186368 -63.169418)
		(end 245.139972 -63.09995)
		(stroke
			(width 0.0508)
			(type default)
		)
		(layer "In2.Cu")
	)
	(gr_line
		(start 245.237 -29.03474)
		(end 245.237 -29.168852)
		(stroke
			(width 0.06985)
			(type default)
		)
		(layer "In2.Cu")
	)
	(gr_line
		(start 245.330218 -122.05716)
		(end 245.349776 -122.02922)
		(stroke
			(width 0.06985)
			(type default)
		)
		(layer "In2.Cu")
	)
	(gr_line
		(start 245.349776 -122.02922)
		(end 245.355618 -121.9962)
		(stroke
			(width 0.06985)
			(type default)
		)
		(layer "In2.Cu")
	)
	(gr_line
		(start 245.439438 -67.182238)
		(end 245.439438 -67.37604)
		(stroke
			(width 0.06985)
			(type default)
		)
		(layer "In2.Cu")
	)
	(gr_line
		(start 245.439438 -67.182238)
		(end 245.458996 -67.16268)
		(stroke
			(width 0.0508)
			(type default)
		)
		(layer "In2.Cu")
	)
	(gr_line
		(start 245.460774 -67.160902)
		(end 245.49354 -67.128136)
		(stroke
			(width 0.0508)
			(type default)
		)
		(layer "In2.Cu")
	)
	(gr_arc
		(start 245.618 -30.7086)
		(mid 245.674902 -30.994664)
		(end 245.836948 -31.237174)
		(stroke
			(width 0.06985)
			(type default)
		)
		(layer "In2.Cu")
	)
	(gr_line
		(start 245.618 -30.1752)
		(end 245.618 -30.7086)
		(stroke
			(width 0.06985)
			(type default)
		)
		(layer "In2.Cu")
	)
	(gr_line
		(start 245.618 -30.1752)
		(end 245.71706 -30.07614)
		(stroke
			(width 0.06985)
			(type default)
		)
		(layer "In2.Cu")
	)
	(gr_line
		(start 245.674642 -61.929772)
		(end 245.75389 -61.866526)
		(stroke
			(width 0.0508)
			(type default)
		)
		(layer "In2.Cu")
	)
	(gr_line
		(start 245.69674 -67.10934)
		(end 245.748302 -67.160902)
		(stroke
			(width 0.0508)
			(type default)
		)
		(layer "In2.Cu")
	)
	(gr_line
		(start 245.69674 -66.915538)
		(end 245.69674 -67.10934)
		(stroke
			(width 0.0508)
			(type default)
		)
		(layer "In2.Cu")
	)
	(gr_line
		(start 245.7196 -26.8732)
		(end 245.787672 -26.805128)
		(stroke
			(width 0.06985)
			(type default)
		)
		(layer "In2.Cu")
	)
	(gr_line
		(start 245.75008 -67.16268)
		(end 245.769638 -67.182238)
		(stroke
			(width 0.0508)
			(type default)
		)
		(layer "In2.Cu")
	)
	(gr_line
		(start 245.75389 -61.866526)
		(end 245.754398 -61.866018)
		(stroke
			(width 0.0508)
			(type default)
		)
		(layer "In2.Cu")
	)
	(gr_line
		(start 245.754398 -61.866018)
		(end 245.797578 -61.831728)
		(stroke
			(width 0.0508)
			(type default)
		)
		(layer "In2.Cu")
	)
	(gr_line
		(start 245.797578 -61.831728)
		(end 245.818152 -61.815726)
		(stroke
			(width 0.0508)
			(type default)
		)
		(layer "In2.Cu")
	)
	(gr_line
		(start 245.818152 -61.815726)
		(end 245.823994 -61.811154)
		(stroke
			(width 0.0508)
			(type default)
		)
		(layer "In2.Cu")
	)
	(gr_line
		(start 245.823994 -61.811154)
		(end 245.829074 -61.807344)
		(stroke
			(width 0.0508)
			(type default)
		)
		(layer "In2.Cu")
	)
	(gr_line
		(start 245.829074 -61.807344)
		(end 245.850918 -61.790072)
		(stroke
			(width 0.0508)
			(type default)
		)
		(layer "In2.Cu")
	)
	(gr_line
		(start 245.836948 -31.237174)
		(end 246.099838 -31.500064)
		(stroke
			(width 0.06985)
			(type default)
		)
		(layer "In2.Cu")
	)
	(gr_line
		(start 245.850918 -61.790072)
		(end 245.851172 -61.790072)
		(stroke
			(width 0.0508)
			(type default)
		)
		(layer "In2.Cu")
	)
	(gr_line
		(start 245.851172 -61.790072)
		(end 245.857776 -61.784738)
		(stroke
			(width 0.0508)
			(type default)
		)
		(layer "In2.Cu")
	)
	(gr_line
		(start 245.857776 -61.784738)
		(end 245.895622 -61.755274)
		(stroke
			(width 0.0508)
			(type default)
		)
		(layer "In2.Cu")
	)
	(gr_line
		(start 245.895622 -61.755274)
		(end 245.901718 -61.750702)
		(stroke
			(width 0.0508)
			(type default)
		)
		(layer "In2.Cu")
	)
	(gr_line
		(start 245.901718 -61.750702)
		(end 245.904258 -61.748416)
		(stroke
			(width 0.0508)
			(type default)
		)
		(layer "In2.Cu")
	)
	(gr_line
		(start 245.904258 -61.748416)
		(end 246.025924 -61.652404)
		(stroke
			(width 0.0508)
			(type default)
		)
		(layer "In2.Cu")
	)
	(gr_line
		(start 245.958106 -62.035182)
		(end 245.995952 -62.035182)
		(stroke
			(width 0.0508)
			(type default)
		)
		(layer "In2.Cu")
	)
	(gr_arc
		(start 246.025924 -61.652404)
		(mid 246.080396 -61.584556)
		(end 246.099838 -61.49975)
		(stroke
			(width 0.0508)
			(type default)
		)
		(layer "In2.Cu")
	)
	(gr_arc
		(start 246.0498 -30.379162)
		(mid 246.062812 -30.444579)
		(end 246.099838 -30.500066)
		(stroke
			(width 0.06985)
			(type default)
		)
		(layer "In2.Cu")
	)
	(gr_line
		(start 246.09171 -80.257396)
		(end 246.095012 -80.276446)
		(stroke
			(width 0.06985)
			(type default)
		)
		(layer "In2.Cu")
	)
	(gr_line
		(start 246.09171 -80.257396)
		(end 246.095012 -80.2386)
		(stroke
			(width 0.06985)
			(type default)
		)
		(layer "In2.Cu")
	)
	(gr_arc
		(start 246.099838 -62.499748)
		(mid 246.175977 -62.385771)
		(end 246.202708 -62.251336)
		(stroke
			(width 0.0508)
			(type default)
		)
		(layer "In2.Cu")
	)
	(gr_line
		(start 246.099838 -37.500052)
		(end 246.696738 -36.903152)
		(stroke
			(width 0.0508)
			(type default)
		)
		(layer "In2.Cu")
	)
	(gr_line
		(start 246.099838 -34.500058)
		(end 246.490998 -34.108898)
		(stroke
			(width 0.0508)
			(type default)
		)
		(layer "In2.Cu")
	)
	(gr_arc
		(start 246.13108 -62.091316)
		(mid 246.069089 -62.049841)
		(end 245.995952 -62.035182)
		(stroke
			(width 0.0508)
			(type default)
		)
		(layer "In2.Cu")
	)
	(gr_line
		(start 246.13108 -62.091316)
		(end 246.13997 -62.099952)
		(stroke
			(width 0.0508)
			(type default)
		)
		(layer "In2.Cu")
	)
	(gr_arc
		(start 246.202708 -62.251336)
		(mid 246.186366 -62.169419)
		(end 246.13997 -62.099952)
		(stroke
			(width 0.0508)
			(type default)
		)
		(layer "In2.Cu")
	)
	(gr_line
		(start 246.376698 -89.299796)
		(end 246.376698 -89.30005)
		(stroke
			(width 0.06985)
			(type default)
		)
		(layer "In2.Cu")
	)
	(gr_line
		(start 246.376698 -89.299796)
		(end 246.38 -89.281)
		(stroke
			(width 0.06985)
			(type default)
		)
		(layer "In2.Cu")
	)
	(gr_line
		(start 246.376698 -89.262204)
		(end 246.38 -89.281)
		(stroke
			(width 0.06985)
			(type default)
		)
		(layer "In2.Cu")
	)
	(gr_line
		(start 246.376698 -73.805796)
		(end 246.376698 -73.80605)
		(stroke
			(width 0.06985)
			(type default)
		)
		(layer "In2.Cu")
	)
	(gr_line
		(start 246.376698 -73.805796)
		(end 246.38 -73.787)
		(stroke
			(width 0.06985)
			(type default)
		)
		(layer "In2.Cu")
	)
	(gr_line
		(start 246.376698 -73.768204)
		(end 246.38 -73.787)
		(stroke
			(width 0.06985)
			(type default)
		)
		(layer "In2.Cu")
	)
	(gr_line
		(start 246.384318 -123.062746)
		(end 246.403876 -123.034806)
		(stroke
			(width 0.06985)
			(type default)
		)
		(layer "In2.Cu")
	)
	(gr_line
		(start 246.403876 -123.034806)
		(end 246.409718 -123.001786)
		(stroke
			(width 0.06985)
			(type default)
		)
		(layer "In2.Cu")
	)
	(gr_line
		(start 246.430038 -67.233038)
		(end 246.449596 -67.21348)
		(stroke
			(width 0.0508)
			(type default)
		)
		(layer "In2.Cu")
	)
	(gr_line
		(start 246.451374 -67.211702)
		(end 246.493538 -67.169538)
		(stroke
			(width 0.0508)
			(type default)
		)
		(layer "In2.Cu")
	)
	(gr_line
		(start 246.67464 -62.92977)
		(end 246.753888 -62.866524)
		(stroke
			(width 0.0508)
			(type default)
		)
		(layer "In2.Cu")
	)
	(gr_line
		(start 246.696738 -67.169538)
		(end 246.738902 -67.211702)
		(stroke
			(width 0.0508)
			(type default)
		)
		(layer "In2.Cu")
	)
	(gr_line
		(start 246.696738 -34.312098)
		(end 246.696738 -36.903152)
		(stroke
			(width 0.0508)
			(type default)
		)
		(layer "In2.Cu")
	)
	(gr_line
		(start 246.74068 -67.21348)
		(end 246.760238 -67.233038)
		(stroke
			(width 0.0508)
			(type default)
		)
		(layer "In2.Cu")
	)
	(gr_line
		(start 246.753888 -62.866524)
		(end 246.754396 -62.866016)
		(stroke
			(width 0.0508)
			(type default)
		)
		(layer "In2.Cu")
	)
	(gr_line
		(start 246.754396 -62.866016)
		(end 246.797576 -62.831726)
		(stroke
			(width 0.0508)
			(type default)
		)
		(layer "In2.Cu")
	)
	(gr_line
		(start 246.797576 -62.831726)
		(end 246.81815 -62.815724)
		(stroke
			(width 0.0508)
			(type default)
		)
		(layer "In2.Cu")
	)
	(gr_line
		(start 246.81815 -62.815724)
		(end 246.823992 -62.811152)
		(stroke
			(width 0.0508)
			(type default)
		)
		(layer "In2.Cu")
	)
	(gr_line
		(start 246.823992 -62.811152)
		(end 246.829072 -62.807342)
		(stroke
			(width 0.0508)
			(type default)
		)
		(layer "In2.Cu")
	)
	(gr_line
		(start 246.829072 -62.807342)
		(end 246.850916 -62.79007)
		(stroke
			(width 0.0508)
			(type default)
		)
		(layer "In2.Cu")
	)
	(gr_line
		(start 246.850916 -62.79007)
		(end 246.85117 -62.79007)
		(stroke
			(width 0.0508)
			(type default)
		)
		(layer "In2.Cu")
	)
	(gr_line
		(start 246.85117 -62.79007)
		(end 246.857774 -62.784736)
		(stroke
			(width 0.0508)
			(type default)
		)
		(layer "In2.Cu")
	)
	(gr_line
		(start 246.857774 -62.784736)
		(end 246.89562 -62.755272)
		(stroke
			(width 0.0508)
			(type default)
		)
		(layer "In2.Cu")
	)
	(gr_line
		(start 246.89562 -62.755272)
		(end 246.901716 -62.7507)
		(stroke
			(width 0.0508)
			(type default)
		)
		(layer "In2.Cu")
	)
	(gr_line
		(start 246.901716 -62.7507)
		(end 246.904256 -62.748414)
		(stroke
			(width 0.0508)
			(type default)
		)
		(layer "In2.Cu")
	)
	(gr_line
		(start 246.904256 -62.748414)
		(end 247.025922 -62.652402)
		(stroke
			(width 0.0508)
			(type default)
		)
		(layer "In2.Cu")
	)
	(gr_line
		(start 246.958104 -63.03518)
		(end 246.99595 -63.03518)
		(stroke
			(width 0.0508)
			(type default)
		)
		(layer "In2.Cu")
	)
	(gr_arc
		(start 247.025922 -62.652402)
		(mid 247.080394 -62.584554)
		(end 247.099836 -62.499748)
		(stroke
			(width 0.0508)
			(type default)
		)
		(layer "In2.Cu")
	)
	(gr_line
		(start 247.085866 -80.335628)
		(end 247.089168 -80.354678)
		(stroke
			(width 0.06985)
			(type default)
		)
		(layer "In2.Cu")
	)
	(gr_line
		(start 247.085866 -80.335628)
		(end 247.089168 -80.316832)
		(stroke
			(width 0.06985)
			(type default)
		)
		(layer "In2.Cu")
	)
	(gr_arc
		(start 247.099836 -63.499746)
		(mid 247.175975 -63.385769)
		(end 247.202706 -63.251334)
		(stroke
			(width 0.0508)
			(type default)
		)
		(layer "In2.Cu")
	)
	(gr_arc
		(start 247.099836 -30.500066)
		(mid 247.477582 -29.814962)
		(end 247.608344 -29.04363)
		(stroke
			(width 0.06985)
			(type default)
		)
		(layer "In2.Cu")
	)
	(gr_arc
		(start 247.099836 -29.500068)
		(mid 247.231997 -29.288647)
		(end 247.278144 -29.04363)
		(stroke
			(width 0.06985)
			(type default)
		)
		(layer "In2.Cu")
	)
	(gr_arc
		(start 247.131078 -63.091314)
		(mid 247.069087 -63.049841)
		(end 246.99595 -63.03518)
		(stroke
			(width 0.0508)
			(type default)
		)
		(layer "In2.Cu")
	)
	(gr_line
		(start 247.131078 -63.091314)
		(end 247.139968 -63.09995)
		(stroke
			(width 0.0508)
			(type default)
		)
		(layer "In2.Cu")
	)
	(gr_arc
		(start 247.202706 -63.251334)
		(mid 247.186364 -63.169418)
		(end 247.139968 -63.09995)
		(stroke
			(width 0.0508)
			(type default)
		)
		(layer "In2.Cu")
	)
	(gr_line
		(start 247.278144 -26.971498)
		(end 247.346216 -26.903426)
		(stroke
			(width 0.06985)
			(type default)
		)
		(layer "In2.Cu")
	)
	(gr_line
		(start 247.4214 -67.183)
		(end 247.440958 -67.163442)
		(stroke
			(width 0.0508)
			(type default)
		)
		(layer "In2.Cu")
	)
	(gr_line
		(start 247.442736 -67.161664)
		(end 247.493536 -67.110864)
		(stroke
			(width 0.0508)
			(type default)
		)
		(layer "In2.Cu")
	)
	(gr_line
		(start 247.493536 -66.9163)
		(end 247.493536 -67.110864)
		(stroke
			(width 0.0508)
			(type default)
		)
		(layer "In2.Cu")
	)
	(gr_line
		(start 247.562116 -73.820782)
		(end 247.562116 -73.821036)
		(stroke
			(width 0.06985)
			(type default)
		)
		(layer "In2.Cu")
	)
	(gr_line
		(start 247.562116 -73.820782)
		(end 247.565418 -73.801986)
		(stroke
			(width 0.06985)
			(type default)
		)
		(layer "In2.Cu")
	)
	(gr_line
		(start 247.562116 -73.78319)
		(end 247.565418 -73.801986)
		(stroke
			(width 0.06985)
			(type default)
		)
		(layer "In2.Cu")
	)
	(gr_line
		(start 247.674638 -61.929772)
		(end 247.753886 -61.866526)
		(stroke
			(width 0.0508)
			(type default)
		)
		(layer "In2.Cu")
	)
	(gr_line
		(start 247.696736 -67.128136)
		(end 247.730264 -67.161664)
		(stroke
			(width 0.0508)
			(type default)
		)
		(layer "In2.Cu")
	)
	(gr_line
		(start 247.732042 -67.163442)
		(end 247.7516 -67.183)
		(stroke
			(width 0.0508)
			(type default)
		)
		(layer "In2.Cu")
	)
	(gr_line
		(start 247.7516 -67.183)
		(end 247.7516 -67.377564)
		(stroke
			(width 0.06985)
			(type default)
		)
		(layer "In2.Cu")
	)
	(gr_line
		(start 247.753886 -61.866526)
		(end 247.754394 -61.866018)
		(stroke
			(width 0.0508)
			(type default)
		)
		(layer "In2.Cu")
	)
	(gr_line
		(start 247.754394 -61.866018)
		(end 247.797574 -61.831728)
		(stroke
			(width 0.0508)
			(type default)
		)
		(layer "In2.Cu")
	)
	(gr_line
		(start 247.797574 -61.831728)
		(end 247.818148 -61.815726)
		(stroke
			(width 0.0508)
			(type default)
		)
		(layer "In2.Cu")
	)
	(gr_line
		(start 247.818148 -61.815726)
		(end 247.82399 -61.811154)
		(stroke
			(width 0.0508)
			(type default)
		)
		(layer "In2.Cu")
	)
	(gr_line
		(start 247.82399 -61.811154)
		(end 247.82907 -61.807344)
		(stroke
			(width 0.0508)
			(type default)
		)
		(layer "In2.Cu")
	)
	(gr_line
		(start 247.82907 -61.807344)
		(end 247.850914 -61.790072)
		(stroke
			(width 0.0508)
			(type default)
		)
		(layer "In2.Cu")
	)
	(gr_line
		(start 247.850914 -61.790072)
		(end 247.851168 -61.790072)
		(stroke
			(width 0.0508)
			(type default)
		)
		(layer "In2.Cu")
	)
	(gr_line
		(start 247.851168 -61.790072)
		(end 247.857772 -61.784738)
		(stroke
			(width 0.0508)
			(type default)
		)
		(layer "In2.Cu")
	)
	(gr_line
		(start 247.857772 -61.784738)
		(end 247.895618 -61.755274)
		(stroke
			(width 0.0508)
			(type default)
		)
		(layer "In2.Cu")
	)
	(gr_line
		(start 247.895618 -61.755274)
		(end 247.901714 -61.750702)
		(stroke
			(width 0.0508)
			(type default)
		)
		(layer "In2.Cu")
	)
	(gr_line
		(start 247.901714 -61.750702)
		(end 247.904254 -61.748416)
		(stroke
			(width 0.0508)
			(type default)
		)
		(layer "In2.Cu")
	)
	(gr_line
		(start 247.904254 -61.748416)
		(end 248.02592 -61.652404)
		(stroke
			(width 0.0508)
			(type default)
		)
		(layer "In2.Cu")
	)
	(gr_line
		(start 247.958102 -62.035182)
		(end 247.995948 -62.035182)
		(stroke
			(width 0.0508)
			(type default)
		)
		(layer "In2.Cu")
	)
	(gr_line
		(start 247.99671 -80.526382)
		(end 248.000012 -80.545432)
		(stroke
			(width 0.06985)
			(type default)
		)
		(layer "In2.Cu")
	)
	(gr_line
		(start 247.99671 -80.526382)
		(end 248.000012 -80.507586)
		(stroke
			(width 0.06985)
			(type default)
		)
		(layer "In2.Cu")
	)
	(gr_line
		(start 248.010172 -27.909774)
		(end 248.078244 -27.841702)
		(stroke
			(width 0.06985)
			(type default)
		)
		(layer "In2.Cu")
	)
	(gr_line
		(start 248.023126 -89.345516)
		(end 248.023126 -89.34577)
		(stroke
			(width 0.06985)
			(type default)
		)
		(layer "In2.Cu")
	)
	(gr_line
		(start 248.023126 -89.345516)
		(end 248.026428 -89.32672)
		(stroke
			(width 0.06985)
			(type default)
		)
		(layer "In2.Cu")
	)
	(gr_line
		(start 248.023126 -89.307924)
		(end 248.026428 -89.32672)
		(stroke
			(width 0.06985)
			(type default)
		)
		(layer "In2.Cu")
	)
	(gr_arc
		(start 248.02592 -61.652404)
		(mid 248.080392 -61.584556)
		(end 248.099834 -61.49975)
		(stroke
			(width 0.0508)
			(type default)
		)
		(layer "In2.Cu")
	)
	(gr_arc
		(start 248.099834 -62.499748)
		(mid 248.175974 -62.385771)
		(end 248.202704 -62.251336)
		(stroke
			(width 0.0508)
			(type default)
		)
		(layer "In2.Cu")
	)
	(gr_arc
		(start 248.099834 -31.500064)
		(mid 248.379921 -31.104886)
		(end 248.513346 -30.639258)
		(stroke
			(width 0.06985)
			(type default)
		)
		(layer "In2.Cu")
	)
	(gr_arc
		(start 248.099834 -30.500066)
		(mid 248.133209 -30.334415)
		(end 248.10974 -30.167072)
		(stroke
			(width 0.06985)
			(type default)
		)
		(layer "In2.Cu")
	)
	(gr_arc
		(start 248.131076 -62.091316)
		(mid 248.069085 -62.049843)
		(end 247.995948 -62.035182)
		(stroke
			(width 0.0508)
			(type default)
		)
		(layer "In2.Cu")
	)
	(gr_line
		(start 248.131076 -62.091316)
		(end 248.139966 -62.099952)
		(stroke
			(width 0.0508)
			(type default)
		)
		(layer "In2.Cu")
	)
	(gr_arc
		(start 248.202704 -62.251336)
		(mid 248.186362 -62.16942)
		(end 248.139966 -62.099952)
		(stroke
			(width 0.0508)
			(type default)
		)
		(layer "In2.Cu")
	)
	(gr_line
		(start 248.4374 -67.2084)
		(end 248.4374 -67.404234)
		(stroke
			(width 0.06985)
			(type default)
		)
		(layer "In2.Cu")
	)
	(gr_line
		(start 248.4374 -67.2084)
		(end 248.456958 -67.188842)
		(stroke
			(width 0.0508)
			(type default)
		)
		(layer "In2.Cu")
	)
	(gr_line
		(start 248.458736 -67.187064)
		(end 248.493534 -67.152266)
		(stroke
			(width 0.0508)
			(type default)
		)
		(layer "In2.Cu")
	)
	(gr_arc
		(start 248.513346 -30.639258)
		(mid 248.506981 -30.347085)
		(end 248.424446 -30.066742)
		(stroke
			(width 0.06985)
			(type default)
		)
		(layer "In2.Cu")
	)
	(gr_line
		(start 248.56186 -73.86828)
		(end 248.56186 -73.868534)
		(stroke
			(width 0.06985)
			(type default)
		)
		(layer "In2.Cu")
	)
	(gr_line
		(start 248.56186 -73.86828)
		(end 248.565162 -73.849484)
		(stroke
			(width 0.06985)
			(type default)
		)
		(layer "In2.Cu")
	)
	(gr_line
		(start 248.56186 -73.830688)
		(end 248.565162 -73.849484)
		(stroke
			(width 0.06985)
			(type default)
		)
		(layer "In2.Cu")
	)
	(gr_arc
		(start 248.665238 -29.42971)
		(mid 248.778027 -30.007323)
		(end 249.099832 -30.500066)
		(stroke
			(width 0.06985)
			(type default)
		)
		(layer "In2.Cu")
	)
	(gr_line
		(start 248.665238 -29.19476)
		(end 248.665238 -29.42971)
		(stroke
			(width 0.06985)
			(type default)
		)
		(layer "In2.Cu")
	)
	(gr_line
		(start 248.674636 -62.92977)
		(end 248.753884 -62.866524)
		(stroke
			(width 0.0508)
			(type default)
		)
		(layer "In2.Cu")
	)
	(gr_line
		(start 248.696734 -67.137534)
		(end 248.746264 -67.187064)
		(stroke
			(width 0.0508)
			(type default)
		)
		(layer "In2.Cu")
	)
	(gr_line
		(start 248.696734 -66.9417)
		(end 248.696734 -67.137534)
		(stroke
			(width 0.0508)
			(type default)
		)
		(layer "In2.Cu")
	)
	(gr_line
		(start 248.748042 -67.188842)
		(end 248.7676 -67.2084)
		(stroke
			(width 0.0508)
			(type default)
		)
		(layer "In2.Cu")
	)
	(gr_line
		(start 248.753884 -62.866524)
		(end 248.754392 -62.866016)
		(stroke
			(width 0.0508)
			(type default)
		)
		(layer "In2.Cu")
	)
	(gr_line
		(start 248.754392 -62.866016)
		(end 248.797572 -62.831726)
		(stroke
			(width 0.0508)
			(type default)
		)
		(layer "In2.Cu")
	)
	(gr_line
		(start 248.797572 -62.831726)
		(end 248.818146 -62.815724)
		(stroke
			(width 0.0508)
			(type default)
		)
		(layer "In2.Cu")
	)
	(gr_line
		(start 248.818146 -62.815724)
		(end 248.823988 -62.811152)
		(stroke
			(width 0.0508)
			(type default)
		)
		(layer "In2.Cu")
	)
	(gr_line
		(start 248.823988 -62.811152)
		(end 248.829068 -62.807342)
		(stroke
			(width 0.0508)
			(type default)
		)
		(layer "In2.Cu")
	)
	(gr_line
		(start 248.829068 -62.807342)
		(end 248.850912 -62.79007)
		(stroke
			(width 0.0508)
			(type default)
		)
		(layer "In2.Cu")
	)
	(gr_line
		(start 248.850912 -62.79007)
		(end 248.851166 -62.79007)
		(stroke
			(width 0.0508)
			(type default)
		)
		(layer "In2.Cu")
	)
	(gr_line
		(start 248.851166 -62.79007)
		(end 248.85777 -62.784736)
		(stroke
			(width 0.0508)
			(type default)
		)
		(layer "In2.Cu")
	)
	(gr_line
		(start 248.85777 -62.784736)
		(end 248.895616 -62.755272)
		(stroke
			(width 0.0508)
			(type default)
		)
		(layer "In2.Cu")
	)
	(gr_line
		(start 248.895616 -62.755272)
		(end 248.901712 -62.7507)
		(stroke
			(width 0.0508)
			(type default)
		)
		(layer "In2.Cu")
	)
	(gr_line
		(start 248.901712 -62.7507)
		(end 248.904252 -62.748414)
		(stroke
			(width 0.0508)
			(type default)
		)
		(layer "In2.Cu")
	)
	(gr_line
		(start 248.904252 -62.748414)
		(end 249.025918 -62.652402)
		(stroke
			(width 0.0508)
			(type default)
		)
		(layer "In2.Cu")
	)
	(gr_line
		(start 248.9581 -63.03518)
		(end 248.995946 -63.03518)
		(stroke
			(width 0.0508)
			(type default)
		)
		(layer "In2.Cu")
	)
	(gr_arc
		(start 249.025918 -62.652402)
		(mid 249.080388 -62.584552)
		(end 249.099832 -62.499748)
		(stroke
			(width 0.0508)
			(type default)
		)
		(layer "In2.Cu")
	)
	(gr_line
		(start 249.033792 -89.517982)
		(end 249.033792 -89.518236)
		(stroke
			(width 0.06985)
			(type default)
		)
		(layer "In2.Cu")
	)
	(gr_line
		(start 249.033792 -89.517982)
		(end 249.037094 -89.499186)
		(stroke
			(width 0.06985)
			(type default)
		)
		(layer "In2.Cu")
	)
	(gr_line
		(start 249.033792 -89.48039)
		(end 249.037094 -89.499186)
		(stroke
			(width 0.06985)
			(type default)
		)
		(layer "In2.Cu")
	)
	(gr_arc
		(start 249.099832 -63.499746)
		(mid 249.175986 -63.385774)
		(end 249.202702 -63.251334)
		(stroke
			(width 0.0508)
			(type default)
		)
		(layer "In2.Cu")
	)
	(gr_arc
		(start 249.131074 -63.091314)
		(mid 249.069092 -63.049806)
		(end 248.995946 -63.03518)
		(stroke
			(width 0.0508)
			(type default)
		)
		(layer "In2.Cu")
	)
	(gr_line
		(start 249.131074 -63.091314)
		(end 249.139964 -63.09995)
		(stroke
			(width 0.0508)
			(type default)
		)
		(layer "In2.Cu")
	)
	(gr_arc
		(start 249.202702 -63.251334)
		(mid 249.186403 -63.169393)
		(end 249.139964 -63.09995)
		(stroke
			(width 0.0508)
			(type default)
		)
		(layer "In2.Cu")
	)
	(gr_line
		(start 249.542046 -73.665334)
		(end 249.542046 -73.665588)
		(stroke
			(width 0.06985)
			(type default)
		)
		(layer "In2.Cu")
	)
	(gr_line
		(start 249.542046 -73.665334)
		(end 249.545348 -73.646538)
		(stroke
			(width 0.06985)
			(type default)
		)
		(layer "In2.Cu")
	)
	(gr_line
		(start 249.542046 -73.627742)
		(end 249.545348 -73.646538)
		(stroke
			(width 0.06985)
			(type default)
		)
		(layer "In2.Cu")
	)
	(gr_line
		(start 249.6312 -30.3022)
		(end 249.6312 -30.7848)
		(stroke
			(width 0.06985)
			(type default)
		)
		(layer "In2.Cu")
	)
	(gr_line
		(start 249.6312 -30.3022)
		(end 249.771916 -30.161484)
		(stroke
			(width 0.06985)
			(type default)
		)
		(layer "In2.Cu")
	)
	(gr_line
		(start 249.805698 -31.205678)
		(end 249.812556 -31.21279)
		(stroke
			(width 0.06985)
			(type default)
		)
		(layer "In2.Cu")
	)
	(gr_line
		(start 249.812556 -31.21279)
		(end 250.09983 -31.500064)
		(stroke
			(width 0.06985)
			(type default)
		)
		(layer "In2.Cu")
	)
	(gr_line
		(start 249.903996 -80.455008)
		(end 249.907298 -80.474058)
		(stroke
			(width 0.06985)
			(type default)
		)
		(layer "In2.Cu")
	)
	(gr_line
		(start 249.903996 -80.455008)
		(end 249.907298 -80.436212)
		(stroke
			(width 0.06985)
			(type default)
		)
		(layer "In2.Cu")
	)
	(gr_line
		(start 249.926602 -89.605866)
		(end 249.926602 -89.60612)
		(stroke
			(width 0.06985)
			(type default)
		)
		(layer "In2.Cu")
	)
	(gr_line
		(start 249.926602 -89.605866)
		(end 249.929904 -89.58707)
		(stroke
			(width 0.06985)
			(type default)
		)
		(layer "In2.Cu")
	)
	(gr_line
		(start 249.926602 -89.568274)
		(end 249.929904 -89.58707)
		(stroke
			(width 0.06985)
			(type default)
		)
		(layer "In2.Cu")
	)
	(gr_line
		(start 250.09983 -39.500048)
		(end 250.524264 -39.075614)
		(stroke
			(width 0.0508)
			(type default)
		)
		(layer "In2.Cu")
	)
	(gr_line
		(start 250.09983 -36.500054)
		(end 250.705112 -35.894772)
		(stroke
			(width 0.0508)
			(type default)
		)
		(layer "In2.Cu")
	)
	(gr_arc
		(start 250.2408 -30.159706)
		(mid 250.136458 -30.315864)
		(end 250.09983 -30.500066)
		(stroke
			(width 0.06985)
			(type default)
		)
		(layer "In2.Cu")
	)
	(gr_line
		(start 250.4186 -67.183)
		(end 250.438158 -67.163442)
		(stroke
			(width 0.0508)
			(type default)
		)
		(layer "In2.Cu")
	)
	(gr_line
		(start 250.439936 -67.161664)
		(end 250.49353 -67.10807)
		(stroke
			(width 0.0508)
			(type default)
		)
		(layer "In2.Cu")
	)
	(gr_line
		(start 250.49353 -66.9163)
		(end 250.49353 -67.10807)
		(stroke
			(width 0.0508)
			(type default)
		)
		(layer "In2.Cu")
	)
	(gr_line
		(start 250.524264 -36.464748)
		(end 250.524264 -39.075614)
		(stroke
			(width 0.0508)
			(type default)
		)
		(layer "In2.Cu")
	)
	(gr_line
		(start 250.524264 -36.464748)
		(end 250.8885 -36.100512)
		(stroke
			(width 0.0508)
			(type default)
		)
		(layer "In2.Cu")
	)
	(gr_line
		(start 250.674632 -61.929772)
		(end 250.75388 -61.866526)
		(stroke
			(width 0.0508)
			(type default)
		)
		(layer "In2.Cu")
	)
	(gr_line
		(start 250.69673 -67.13093)
		(end 250.727464 -67.161664)
		(stroke
			(width 0.0508)
			(type default)
		)
		(layer "In2.Cu")
	)
	(gr_line
		(start 250.729242 -67.163442)
		(end 250.7488 -67.183)
		(stroke
			(width 0.0508)
			(type default)
		)
		(layer "In2.Cu")
	)
	(gr_line
		(start 250.7488 -67.183)
		(end 250.7488 -67.37477)
		(stroke
			(width 0.06985)
			(type default)
		)
		(layer "In2.Cu")
	)
	(gr_line
		(start 250.75388 -61.866526)
		(end 250.754388 -61.866018)
		(stroke
			(width 0.0508)
			(type default)
		)
		(layer "In2.Cu")
	)
	(gr_line
		(start 250.754388 -61.866018)
		(end 250.797568 -61.831728)
		(stroke
			(width 0.0508)
			(type default)
		)
		(layer "In2.Cu")
	)
	(gr_line
		(start 250.797568 -61.831728)
		(end 250.818142 -61.815726)
		(stroke
			(width 0.0508)
			(type default)
		)
		(layer "In2.Cu")
	)
	(gr_line
		(start 250.818142 -61.815726)
		(end 250.823984 -61.811154)
		(stroke
			(width 0.0508)
			(type default)
		)
		(layer "In2.Cu")
	)
	(gr_line
		(start 250.823984 -61.811154)
		(end 250.829064 -61.807344)
		(stroke
			(width 0.0508)
			(type default)
		)
		(layer "In2.Cu")
	)
	(gr_line
		(start 250.829064 -61.807344)
		(end 250.850908 -61.790072)
		(stroke
			(width 0.0508)
			(type default)
		)
		(layer "In2.Cu")
	)
	(gr_line
		(start 250.850908 -61.790072)
		(end 250.851162 -61.790072)
		(stroke
			(width 0.0508)
			(type default)
		)
		(layer "In2.Cu")
	)
	(gr_line
		(start 250.851162 -61.790072)
		(end 250.857766 -61.784738)
		(stroke
			(width 0.0508)
			(type default)
		)
		(layer "In2.Cu")
	)
	(gr_line
		(start 250.857766 -61.784738)
		(end 250.895612 -61.755274)
		(stroke
			(width 0.0508)
			(type default)
		)
		(layer "In2.Cu")
	)
	(gr_line
		(start 250.88596 -13.564108)
		(end 250.9139 -13.54455)
		(stroke
			(width 0.06985)
			(type default)
		)
		(layer "In2.Cu")
	)
	(gr_line
		(start 250.895612 -61.755274)
		(end 250.901708 -61.750702)
		(stroke
			(width 0.0508)
			(type default)
		)
		(layer "In2.Cu")
	)
	(gr_line
		(start 250.901708 -61.750702)
		(end 250.904248 -61.748416)
		(stroke
			(width 0.0508)
			(type default)
		)
		(layer "In2.Cu")
	)
	(gr_line
		(start 250.904248 -61.748416)
		(end 251.025914 -61.652404)
		(stroke
			(width 0.0508)
			(type default)
		)
		(layer "In2.Cu")
	)
	(gr_line
		(start 250.9139 -13.54455)
		(end 250.94692 -13.538708)
		(stroke
			(width 0.06985)
			(type default)
		)
		(layer "In2.Cu")
	)
	(gr_line
		(start 250.95708 -14.83487)
		(end 251.003308 -14.788642)
		(stroke
			(width 0.06985)
			(type default)
		)
		(layer "In2.Cu")
	)
	(gr_line
		(start 250.958096 -62.035182)
		(end 250.995942 -62.035182)
		(stroke
			(width 0.0508)
			(type default)
		)
		(layer "In2.Cu")
	)
	(gr_line
		(start 250.994418 -80.099154)
		(end 250.99772 -80.118204)
		(stroke
			(width 0.06985)
			(type default)
		)
		(layer "In2.Cu")
	)
	(gr_line
		(start 250.994418 -80.099154)
		(end 250.99772 -80.080358)
		(stroke
			(width 0.06985)
			(type default)
		)
		(layer "In2.Cu")
	)
	(gr_line
		(start 251.003308 -14.788642)
		(end 251.06757 -14.777212)
		(stroke
			(width 0.06985)
			(type default)
		)
		(layer "In2.Cu")
	)
	(gr_arc
		(start 251.025914 -61.652404)
		(mid 251.080386 -61.584556)
		(end 251.099828 -61.49975)
		(stroke
			(width 0.0508)
			(type default)
		)
		(layer "In2.Cu")
	)
	(gr_arc
		(start 251.099828 -62.499748)
		(mid 251.175948 -62.385766)
		(end 251.202698 -62.251336)
		(stroke
			(width 0.0508)
			(type default)
		)
		(layer "In2.Cu")
	)
	(gr_arc
		(start 251.13107 -62.091316)
		(mid 251.069078 -62.049845)
		(end 250.995942 -62.035182)
		(stroke
			(width 0.0508)
			(type default)
		)
		(layer "In2.Cu")
	)
	(gr_line
		(start 251.13107 -62.091316)
		(end 251.13996 -62.099952)
		(stroke
			(width 0.0508)
			(type default)
		)
		(layer "In2.Cu")
	)
	(gr_arc
		(start 251.202698 -62.251336)
		(mid 251.186356 -62.16942)
		(end 251.13996 -62.099952)
		(stroke
			(width 0.0508)
			(type default)
		)
		(layer "In2.Cu")
	)
	(gr_line
		(start 251.275342 -13.480796)
		(end 251.41301 -13.456666)
		(stroke
			(width 0.06985)
			(type default)
		)
		(layer "In2.Cu")
	)
	(gr_line
		(start 251.332746 -13.80617)
		(end 251.47016 -13.781786)
		(stroke
			(width 0.06985)
			(type default)
		)
		(layer "In2.Cu")
	)
	(gr_line
		(start 251.41301 -13.456666)
		(end 256.168144 -12.618212)
		(stroke
			(width 0.06985)
			(type default)
		)
		(layer "In2.Cu")
	)
	(gr_line
		(start 251.430536 -67.204336)
		(end 251.430536 -67.407028)
		(stroke
			(width 0.06985)
			(type default)
		)
		(layer "In2.Cu")
	)
	(gr_line
		(start 251.430536 -67.204336)
		(end 251.450094 -67.184778)
		(stroke
			(width 0.0508)
			(type default)
		)
		(layer "In2.Cu")
	)
	(gr_line
		(start 251.451872 -67.183)
		(end 251.493528 -67.141344)
		(stroke
			(width 0.0508)
			(type default)
		)
		(layer "In2.Cu")
	)
	(gr_line
		(start 251.456698 -87.394796)
		(end 251.456698 -87.39505)
		(stroke
			(width 0.06985)
			(type default)
		)
		(layer "In2.Cu")
	)
	(gr_line
		(start 251.456698 -87.394796)
		(end 251.46 -87.376)
		(stroke
			(width 0.06985)
			(type default)
		)
		(layer "In2.Cu")
	)
	(gr_line
		(start 251.456698 -87.357204)
		(end 251.46 -87.376)
		(stroke
			(width 0.06985)
			(type default)
		)
		(layer "In2.Cu")
	)
	(gr_line
		(start 251.456698 -73.551796)
		(end 251.456698 -73.55205)
		(stroke
			(width 0.06985)
			(type default)
		)
		(layer "In2.Cu")
	)
	(gr_line
		(start 251.456698 -73.551796)
		(end 251.46 -73.533)
		(stroke
			(width 0.06985)
			(type default)
		)
		(layer "In2.Cu")
	)
	(gr_line
		(start 251.456698 -73.514204)
		(end 251.46 -73.533)
		(stroke
			(width 0.06985)
			(type default)
		)
		(layer "In2.Cu")
	)
	(gr_line
		(start 251.47016 -13.781786)
		(end 257.080258 -12.79271)
		(stroke
			(width 0.06985)
			(type default)
		)
		(layer "In2.Cu")
	)
	(gr_line
		(start 251.67463 -62.92977)
		(end 251.753878 -62.866524)
		(stroke
			(width 0.0508)
			(type default)
		)
		(layer "In2.Cu")
	)
	(gr_line
		(start 251.696728 -67.140328)
		(end 251.7394 -67.183)
		(stroke
			(width 0.0508)
			(type default)
		)
		(layer "In2.Cu")
	)
	(gr_line
		(start 251.696728 -66.937636)
		(end 251.696728 -67.140328)
		(stroke
			(width 0.0508)
			(type default)
		)
		(layer "In2.Cu")
	)
	(gr_line
		(start 251.741178 -67.184778)
		(end 251.760736 -67.204336)
		(stroke
			(width 0.0508)
			(type default)
		)
		(layer "In2.Cu")
	)
	(gr_line
		(start 251.753878 -62.866524)
		(end 251.754386 -62.866016)
		(stroke
			(width 0.0508)
			(type default)
		)
		(layer "In2.Cu")
	)
	(gr_line
		(start 251.754386 -62.866016)
		(end 251.797566 -62.831726)
		(stroke
			(width 0.0508)
			(type default)
		)
		(layer "In2.Cu")
	)
	(gr_line
		(start 251.769118 -15.693644)
		(end 251.816362 -15.6464)
		(stroke
			(width 0.06985)
			(type default)
		)
		(layer "In2.Cu")
	)
	(gr_line
		(start 251.797566 -62.831726)
		(end 251.81814 -62.815724)
		(stroke
			(width 0.0508)
			(type default)
		)
		(layer "In2.Cu")
	)
	(gr_line
		(start 251.816362 -15.6464)
		(end 251.881132 -15.635732)
		(stroke
			(width 0.06985)
			(type default)
		)
		(layer "In2.Cu")
	)
	(gr_line
		(start 251.81814 -62.815724)
		(end 251.823982 -62.811152)
		(stroke
			(width 0.0508)
			(type default)
		)
		(layer "In2.Cu")
	)
	(gr_line
		(start 251.823982 -62.811152)
		(end 251.829062 -62.807342)
		(stroke
			(width 0.0508)
			(type default)
		)
		(layer "In2.Cu")
	)
	(gr_line
		(start 251.829062 -62.807342)
		(end 251.850906 -62.79007)
		(stroke
			(width 0.0508)
			(type default)
		)
		(layer "In2.Cu")
	)
	(gr_line
		(start 251.850906 -62.79007)
		(end 251.85116 -62.79007)
		(stroke
			(width 0.0508)
			(type default)
		)
		(layer "In2.Cu")
	)
	(gr_line
		(start 251.85116 -62.79007)
		(end 251.857764 -62.784736)
		(stroke
			(width 0.0508)
			(type default)
		)
		(layer "In2.Cu")
	)
	(gr_line
		(start 251.857764 -62.784736)
		(end 251.89561 -62.755272)
		(stroke
			(width 0.0508)
			(type default)
		)
		(layer "In2.Cu")
	)
	(gr_line
		(start 251.89561 -62.755272)
		(end 251.901706 -62.7507)
		(stroke
			(width 0.0508)
			(type default)
		)
		(layer "In2.Cu")
	)
	(gr_line
		(start 251.901706 -62.7507)
		(end 251.904246 -62.748414)
		(stroke
			(width 0.0508)
			(type default)
		)
		(layer "In2.Cu")
	)
	(gr_line
		(start 251.904246 -62.748414)
		(end 252.025912 -62.652402)
		(stroke
			(width 0.0508)
			(type default)
		)
		(layer "In2.Cu")
	)
	(gr_line
		(start 251.958094 -63.03518)
		(end 251.99594 -63.03518)
		(stroke
			(width 0.0508)
			(type default)
		)
		(layer "In2.Cu")
	)
	(gr_arc
		(start 252.025912 -62.652402)
		(mid 252.080384 -62.584552)
		(end 252.099826 -62.499748)
		(stroke
			(width 0.0508)
			(type default)
		)
		(layer "In2.Cu")
	)
	(gr_arc
		(start 252.099826 -63.499746)
		(mid 252.175946 -63.385764)
		(end 252.202696 -63.251334)
		(stroke
			(width 0.0508)
			(type default)
		)
		(layer "In2.Cu")
	)
	(gr_arc
		(start 252.131068 -63.091314)
		(mid 252.069076 -63.049844)
		(end 251.99594 -63.03518)
		(stroke
			(width 0.0508)
			(type default)
		)
		(layer "In2.Cu")
	)
	(gr_line
		(start 252.131068 -63.091314)
		(end 252.139958 -63.09995)
		(stroke
			(width 0.0508)
			(type default)
		)
		(layer "In2.Cu")
	)
	(gr_arc
		(start 252.202696 -63.251334)
		(mid 252.186353 -63.169418)
		(end 252.139958 -63.09995)
		(stroke
			(width 0.0508)
			(type default)
		)
		(layer "In2.Cu")
	)
	(gr_line
		(start 252.450854 -67.208654)
		(end 252.450854 -67.391026)
		(stroke
			(width 0.06985)
			(type default)
		)
		(layer "In2.Cu")
	)
	(gr_line
		(start 252.450854 -67.208654)
		(end 252.470412 -67.189096)
		(stroke
			(width 0.0508)
			(type default)
		)
		(layer "In2.Cu")
	)
	(gr_line
		(start 252.47219 -67.187318)
		(end 252.493526 -67.165982)
		(stroke
			(width 0.0508)
			(type default)
		)
		(layer "In2.Cu")
	)
	(gr_line
		(start 252.499876 -73.464674)
		(end 252.499876 -73.464928)
		(stroke
			(width 0.06985)
			(type default)
		)
		(layer "In2.Cu")
	)
	(gr_line
		(start 252.499876 -73.464674)
		(end 252.503178 -73.445878)
		(stroke
			(width 0.06985)
			(type default)
		)
		(layer "In2.Cu")
	)
	(gr_line
		(start 252.499876 -73.427082)
		(end 252.503178 -73.445878)
		(stroke
			(width 0.06985)
			(type default)
		)
		(layer "In2.Cu")
	)
	(gr_line
		(start 252.604524 -16.633444)
		(end 252.651768 -16.5862)
		(stroke
			(width 0.06985)
			(type default)
		)
		(layer "In2.Cu")
	)
	(gr_line
		(start 252.648974 -87.6173)
		(end 252.648974 -87.617554)
		(stroke
			(width 0.06985)
			(type default)
		)
		(layer "In2.Cu")
	)
	(gr_line
		(start 252.648974 -87.6173)
		(end 252.652276 -87.598504)
		(stroke
			(width 0.06985)
			(type default)
		)
		(layer "In2.Cu")
	)
	(gr_line
		(start 252.648974 -87.579708)
		(end 252.652276 -87.598504)
		(stroke
			(width 0.06985)
			(type default)
		)
		(layer "In2.Cu")
	)
	(gr_line
		(start 252.651768 -16.5862)
		(end 252.716538 -16.575532)
		(stroke
			(width 0.06985)
			(type default)
		)
		(layer "In2.Cu")
	)
	(gr_line
		(start 252.674628 -61.929772)
		(end 252.753876 -61.866526)
		(stroke
			(width 0.0508)
			(type default)
		)
		(layer "In2.Cu")
	)
	(gr_line
		(start 252.696726 -67.124326)
		(end 252.759718 -67.187318)
		(stroke
			(width 0.0508)
			(type default)
		)
		(layer "In2.Cu")
	)
	(gr_line
		(start 252.696726 -66.941954)
		(end 252.696726 -67.124326)
		(stroke
			(width 0.0508)
			(type default)
		)
		(layer "In2.Cu")
	)
	(gr_line
		(start 252.753876 -61.866526)
		(end 252.754384 -61.866018)
		(stroke
			(width 0.0508)
			(type default)
		)
		(layer "In2.Cu")
	)
	(gr_line
		(start 252.754384 -61.866018)
		(end 252.797564 -61.831728)
		(stroke
			(width 0.0508)
			(type default)
		)
		(layer "In2.Cu")
	)
	(gr_line
		(start 252.761496 -67.189096)
		(end 252.781054 -67.208654)
		(stroke
			(width 0.0508)
			(type default)
		)
		(layer "In2.Cu")
	)
	(gr_line
		(start 252.797564 -61.831728)
		(end 252.818138 -61.815726)
		(stroke
			(width 0.0508)
			(type default)
		)
		(layer "In2.Cu")
	)
	(gr_line
		(start 252.818138 -61.815726)
		(end 252.82398 -61.811154)
		(stroke
			(width 0.0508)
			(type default)
		)
		(layer "In2.Cu")
	)
	(gr_line
		(start 252.82398 -61.811154)
		(end 252.82906 -61.807344)
		(stroke
			(width 0.0508)
			(type default)
		)
		(layer "In2.Cu")
	)
	(gr_line
		(start 252.82906 -61.807344)
		(end 252.850904 -61.790072)
		(stroke
			(width 0.0508)
			(type default)
		)
		(layer "In2.Cu")
	)
	(gr_line
		(start 252.850904 -61.790072)
		(end 252.851158 -61.790072)
		(stroke
			(width 0.0508)
			(type default)
		)
		(layer "In2.Cu")
	)
	(gr_line
		(start 252.851158 -61.790072)
		(end 252.857762 -61.784738)
		(stroke
			(width 0.0508)
			(type default)
		)
		(layer "In2.Cu")
	)
	(gr_line
		(start 252.857762 -61.784738)
		(end 252.895608 -61.755274)
		(stroke
			(width 0.0508)
			(type default)
		)
		(layer "In2.Cu")
	)
	(gr_line
		(start 252.895608 -61.755274)
		(end 252.901704 -61.750702)
		(stroke
			(width 0.0508)
			(type default)
		)
		(layer "In2.Cu")
	)
	(gr_line
		(start 252.901704 -61.750702)
		(end 252.904244 -61.748416)
		(stroke
			(width 0.0508)
			(type default)
		)
		(layer "In2.Cu")
	)
	(gr_line
		(start 252.904244 -61.748416)
		(end 253.02591 -61.652404)
		(stroke
			(width 0.0508)
			(type default)
		)
		(layer "In2.Cu")
	)
	(gr_line
		(start 252.954282 -17.954244)
		(end 253.001526 -17.907)
		(stroke
			(width 0.06985)
			(type default)
		)
		(layer "In2.Cu")
	)
	(gr_line
		(start 252.958092 -62.035182)
		(end 252.995938 -62.035182)
		(stroke
			(width 0.0508)
			(type default)
		)
		(layer "In2.Cu")
	)
	(gr_line
		(start 253.001526 -17.907)
		(end 253.066296 -17.896332)
		(stroke
			(width 0.06985)
			(type default)
		)
		(layer "In2.Cu")
	)
	(gr_arc
		(start 253.02591 -61.652404)
		(mid 253.080382 -61.584556)
		(end 253.099824 -61.49975)
		(stroke
			(width 0.0508)
			(type default)
		)
		(layer "In2.Cu")
	)
	(gr_arc
		(start 253.099824 -62.499748)
		(mid 253.175945 -62.385766)
		(end 253.202694 -62.251336)
		(stroke
			(width 0.0508)
			(type default)
		)
		(layer "In2.Cu")
	)
	(gr_arc
		(start 253.131066 -62.091316)
		(mid 253.069074 -62.049846)
		(end 252.995938 -62.035182)
		(stroke
			(width 0.0508)
			(type default)
		)
		(layer "In2.Cu")
	)
	(gr_line
		(start 253.131066 -62.091316)
		(end 253.139956 -62.099952)
		(stroke
			(width 0.0508)
			(type default)
		)
		(layer "In2.Cu")
	)
	(gr_arc
		(start 253.202694 -62.251336)
		(mid 253.186352 -62.16942)
		(end 253.139956 -62.099952)
		(stroke
			(width 0.0508)
			(type default)
		)
		(layer "In2.Cu")
	)
	(gr_line
		(start 253.343156 -19.249644)
		(end 253.3904 -19.2024)
		(stroke
			(width 0.06985)
			(type default)
		)
		(layer "In2.Cu")
	)
	(gr_line
		(start 253.3904 -19.2024)
		(end 253.45517 -19.191732)
		(stroke
			(width 0.06985)
			(type default)
		)
		(layer "In2.Cu")
	)
	(gr_line
		(start 253.422658 -22.497288)
		(end 253.469394 -22.450552)
		(stroke
			(width 0.06985)
			(type default)
		)
		(layer "In2.Cu")
	)
	(gr_line
		(start 253.4539 -67.291204)
		(end 253.4539 -67.433444)
		(stroke
			(width 0.06985)
			(type default)
		)
		(layer "In2.Cu")
	)
	(gr_line
		(start 253.4539 -67.291204)
		(end 253.492 -67.253104)
		(stroke
			(width 0.0508)
			(type default)
		)
		(layer "In2.Cu")
	)
	(gr_line
		(start 253.469394 -22.450552)
		(end 253.534164 -22.439376)
		(stroke
			(width 0.06985)
			(type default)
		)
		(layer "In2.Cu")
	)
	(gr_line
		(start 253.490984 -23.724616)
		(end 253.555754 -23.71344)
		(stroke
			(width 0.06985)
			(type default)
		)
		(layer "In2.Cu")
	)
	(gr_line
		(start 253.537466 -27.859736)
		(end 253.57963 -27.9019)
		(stroke
			(width 0.0508)
			(type default)
		)
		(layer "In2.Cu")
	)
	(gr_line
		(start 253.537466 -27.656536)
		(end 253.57963 -27.614372)
		(stroke
			(width 0.0508)
			(type default)
		)
		(layer "In2.Cu")
	)
	(gr_line
		(start 253.581408 -27.903678)
		(end 253.689866 -28.012136)
		(stroke
			(width 0.0508)
			(type default)
		)
		(layer "In2.Cu")
	)
	(gr_line
		(start 253.581408 -27.612594)
		(end 253.689866 -27.504136)
		(stroke
			(width 0.0508)
			(type default)
		)
		(layer "In2.Cu")
	)
	(gr_line
		(start 253.628398 -20.621244)
		(end 253.675642 -20.574)
		(stroke
			(width 0.06985)
			(type default)
		)
		(layer "In2.Cu")
	)
	(gr_line
		(start 253.674626 -62.92977)
		(end 253.753874 -62.866524)
		(stroke
			(width 0.0508)
			(type default)
		)
		(layer "In2.Cu")
	)
	(gr_line
		(start 253.675642 -20.574)
		(end 253.740412 -20.563332)
		(stroke
			(width 0.06985)
			(type default)
		)
		(layer "In2.Cu")
	)
	(gr_line
		(start 253.68504 -76.265024)
		(end 253.687834 -76.280518)
		(stroke
			(width 0.06985)
			(type default)
		)
		(layer "In2.Cu")
	)
	(gr_line
		(start 253.687834 -76.280518)
		(end 253.688342 -76.28128)
		(stroke
			(width 0.06985)
			(type default)
		)
		(layer "In2.Cu")
	)
	(gr_line
		(start 253.688342 -76.28128)
		(end 253.690882 -76.282296)
		(stroke
			(width 0.06985)
			(type default)
		)
		(layer "In2.Cu")
	)
	(gr_line
		(start 253.689866 -28.012136)
		(end 253.715266 -28.012136)
		(stroke
			(width 0.0508)
			(type default)
		)
		(layer "In2.Cu")
	)
	(gr_line
		(start 253.689866 -27.504136)
		(end 253.715266 -27.504136)
		(stroke
			(width 0.0508)
			(type default)
		)
		(layer "In2.Cu")
	)
	(gr_line
		(start 253.696724 -67.024504)
		(end 253.696724 -67.166744)
		(stroke
			(width 0.0508)
			(type default)
		)
		(layer "In2.Cu")
	)
	(gr_line
		(start 253.753874 -62.866524)
		(end 253.754382 -62.866016)
		(stroke
			(width 0.0508)
			(type default)
		)
		(layer "In2.Cu")
	)
	(gr_line
		(start 253.754382 -62.866016)
		(end 253.797562 -62.831726)
		(stroke
			(width 0.0508)
			(type default)
		)
		(layer "In2.Cu")
	)
	(gr_line
		(start 253.783084 -67.253104)
		(end 253.7841 -67.25412)
		(stroke
			(width 0.0508)
			(type default)
		)
		(layer "In2.Cu")
	)
	(gr_line
		(start 253.797562 -62.831726)
		(end 253.818136 -62.815724)
		(stroke
			(width 0.0508)
			(type default)
		)
		(layer "In2.Cu")
	)
	(gr_line
		(start 253.818136 -62.815724)
		(end 253.823978 -62.811152)
		(stroke
			(width 0.0508)
			(type default)
		)
		(layer "In2.Cu")
	)
	(gr_line
		(start 253.823978 -62.811152)
		(end 253.829058 -62.807342)
		(stroke
			(width 0.0508)
			(type default)
		)
		(layer "In2.Cu")
	)
	(gr_line
		(start 253.829058 -62.807342)
		(end 253.850902 -62.79007)
		(stroke
			(width 0.0508)
			(type default)
		)
		(layer "In2.Cu")
	)
	(gr_line
		(start 253.850902 -62.79007)
		(end 253.851156 -62.79007)
		(stroke
			(width 0.0508)
			(type default)
		)
		(layer "In2.Cu")
	)
	(gr_line
		(start 253.851156 -62.79007)
		(end 253.85776 -62.784736)
		(stroke
			(width 0.0508)
			(type default)
		)
		(layer "In2.Cu")
	)
	(gr_line
		(start 253.85776 -62.784736)
		(end 253.895606 -62.755272)
		(stroke
			(width 0.0508)
			(type default)
		)
		(layer "In2.Cu")
	)
	(gr_line
		(start 253.895606 -62.755272)
		(end 253.901702 -62.7507)
		(stroke
			(width 0.0508)
			(type default)
		)
		(layer "In2.Cu")
	)
	(gr_line
		(start 253.901702 -62.7507)
		(end 253.904242 -62.748414)
		(stroke
			(width 0.0508)
			(type default)
		)
		(layer "In2.Cu")
	)
	(gr_line
		(start 253.904242 -62.748414)
		(end 254.025908 -62.652402)
		(stroke
			(width 0.0508)
			(type default)
		)
		(layer "In2.Cu")
	)
	(gr_line
		(start 253.95809 -63.03518)
		(end 253.995936 -63.03518)
		(stroke
			(width 0.0508)
			(type default)
		)
		(layer "In2.Cu")
	)
	(gr_arc
		(start 254.025908 -62.652402)
		(mid 254.080381 -62.584553)
		(end 254.099822 -62.499748)
		(stroke
			(width 0.0508)
			(type default)
		)
		(layer "In2.Cu")
	)
	(gr_line
		(start 254.09525 -72.99071)
		(end 254.097282 -73.00214)
		(stroke
			(width 0.06985)
			(type default)
		)
		(layer "In2.Cu")
	)
	(gr_line
		(start 254.097282 -73.00214)
		(end 254.09779 -73.003156)
		(stroke
			(width 0.06985)
			(type default)
		)
		(layer "In2.Cu")
	)
	(gr_line
		(start 254.09779 -73.003156)
		(end 254.099568 -73.003918)
		(stroke
			(width 0.06985)
			(type default)
		)
		(layer "In2.Cu")
	)
	(gr_arc
		(start 254.099822 -63.499746)
		(mid 254.175943 -63.385764)
		(end 254.202692 -63.251334)
		(stroke
			(width 0.0508)
			(type default)
		)
		(layer "In2.Cu")
	)
	(gr_line
		(start 254.099822 -59.499754)
		(end 254.24638 -59.499754)
		(stroke
			(width 0.0508)
			(type default)
		)
		(layer "In2.Cu")
	)
	(gr_line
		(start 254.099822 -40.500046)
		(end 254.576834 -40.023034)
		(stroke
			(width 0.0508)
			(type default)
		)
		(layer "In2.Cu")
	)
	(gr_line
		(start 254.099822 -38.50005)
		(end 254.333248 -38.50005)
		(stroke
			(width 0.0508)
			(type default)
		)
		(layer "In2.Cu")
	)
	(gr_line
		(start 254.099822 -36.500054)
		(end 254.545338 -36.054538)
		(stroke
			(width 0.0508)
			(type default)
		)
		(layer "In2.Cu")
	)
	(gr_arc
		(start 254.131064 -63.091314)
		(mid 254.069072 -63.049845)
		(end 253.995936 -63.03518)
		(stroke
			(width 0.0508)
			(type default)
		)
		(layer "In2.Cu")
	)
	(gr_line
		(start 254.131064 -63.091314)
		(end 254.139954 -63.09995)
		(stroke
			(width 0.0508)
			(type default)
		)
		(layer "In2.Cu")
	)
	(gr_arc
		(start 254.202692 -63.251334)
		(mid 254.186349 -63.169419)
		(end 254.139954 -63.09995)
		(stroke
			(width 0.0508)
			(type default)
		)
		(layer "In2.Cu")
	)
	(gr_arc
		(start 254.333248 -38.50005)
		(mid 254.492518 -38.420303)
		(end 254.556768 -38.254178)
		(stroke
			(width 0.0508)
			(type default)
		)
		(layer "In2.Cu")
	)
	(gr_arc
		(start 254.3683 -59.5503)
		(mid 254.312379 -59.512863)
		(end 254.24638 -59.499754)
		(stroke
			(width 0.0508)
			(type default)
		)
		(layer "In2.Cu")
	)
	(gr_line
		(start 254.3683 -59.5503)
		(end 254.4191 -59.6011)
		(stroke
			(width 0.0508)
			(type default)
		)
		(layer "In2.Cu")
	)
	(gr_line
		(start 254.4191 -59.6011)
		(end 254.445516 -59.627262)
		(stroke
			(width 0.0508)
			(type default)
		)
		(layer "In2.Cu")
	)
	(gr_line
		(start 254.4318 -67.183)
		(end 254.4318 -67.384422)
		(stroke
			(width 0.06985)
			(type default)
		)
		(layer "In2.Cu")
	)
	(gr_line
		(start 254.4318 -67.1703)
		(end 254.4318 -67.183)
		(stroke
			(width 0.0508)
			(type default)
		)
		(layer "In2.Cu")
	)
	(gr_line
		(start 254.4318 -67.1703)
		(end 254.445008 -67.157092)
		(stroke
			(width 0.0508)
			(type default)
		)
		(layer "In2.Cu")
	)
	(gr_line
		(start 254.446786 -67.155314)
		(end 254.493522 -67.108578)
		(stroke
			(width 0.0508)
			(type default)
		)
		(layer "In2.Cu")
	)
	(gr_arc
		(start 254.50292 -59.7662)
		(mid 254.488018 -59.691032)
		(end 254.445516 -59.627262)
		(stroke
			(width 0.0508)
			(type default)
		)
		(layer "In2.Cu")
	)
	(gr_line
		(start 254.50292 -59.7662)
		(end 254.50292 -59.91606)
		(stroke
			(width 0.0508)
			(type default)
		)
		(layer "In2.Cu")
	)
	(gr_line
		(start 254.543052 -24.7904)
		(end 254.608838 -24.779732)
		(stroke
			(width 0.06985)
			(type default)
		)
		(layer "In2.Cu")
	)
	(gr_line
		(start 254.585978 -60.830714)
		(end 254.586232 -60.830714)
		(stroke
			(width 0.0508)
			(type default)
		)
		(layer "In2.Cu")
	)
	(gr_arc
		(start 254.638048 -57.817258)
		(mid 254.412272 -57.585036)
		(end 254.099822 -57.499758)
		(stroke
			(width 0.0508)
			(type default)
		)
		(layer "In2.Cu")
	)
	(gr_line
		(start 254.638048 -57.817258)
		(end 254.695452 -57.921144)
		(stroke
			(width 0.0508)
			(type default)
		)
		(layer "In2.Cu")
	)
	(gr_arc
		(start 254.638048 -55.817262)
		(mid 254.412272 -55.585046)
		(end 254.099822 -55.499762)
		(stroke
			(width 0.0508)
			(type default)
		)
		(layer "In2.Cu")
	)
	(gr_line
		(start 254.638048 -55.817262)
		(end 254.695452 -55.921148)
		(stroke
			(width 0.0508)
			(type default)
		)
		(layer "In2.Cu")
	)
	(gr_arc
		(start 254.638048 -53.817266)
		(mid 254.412272 -53.58505)
		(end 254.099822 -53.499766)
		(stroke
			(width 0.0508)
			(type default)
		)
		(layer "In2.Cu")
	)
	(gr_line
		(start 254.638048 -53.817266)
		(end 254.695452 -53.921152)
		(stroke
			(width 0.0508)
			(type default)
		)
		(layer "In2.Cu")
	)
	(gr_arc
		(start 254.638048 -50.817272)
		(mid 254.412272 -50.585056)
		(end 254.099822 -50.499772)
		(stroke
			(width 0.0508)
			(type default)
		)
		(layer "In2.Cu")
	)
	(gr_line
		(start 254.638048 -50.817272)
		(end 254.695452 -50.921158)
		(stroke
			(width 0.0508)
			(type default)
		)
		(layer "In2.Cu")
	)
	(gr_arc
		(start 254.638048 -48.817276)
		(mid 254.412275 -48.585048)
		(end 254.099822 -48.499776)
		(stroke
			(width 0.0508)
			(type default)
		)
		(layer "In2.Cu")
	)
	(gr_line
		(start 254.638048 -48.817276)
		(end 254.695452 -48.921162)
		(stroke
			(width 0.0508)
			(type default)
		)
		(layer "In2.Cu")
	)
	(gr_arc
		(start 254.638048 -45.817536)
		(mid 254.412272 -45.58532)
		(end 254.099822 -45.500036)
		(stroke
			(width 0.0508)
			(type default)
		)
		(layer "In2.Cu")
	)
	(gr_line
		(start 254.638048 -45.817536)
		(end 254.695452 -45.921422)
		(stroke
			(width 0.0508)
			(type default)
		)
		(layer "In2.Cu")
	)
	(gr_arc
		(start 254.638048 -43.81754)
		(mid 254.412272 -43.585324)
		(end 254.099822 -43.50004)
		(stroke
			(width 0.0508)
			(type default)
		)
		(layer "In2.Cu")
	)
	(gr_line
		(start 254.638048 -43.81754)
		(end 254.695452 -43.921426)
		(stroke
			(width 0.0508)
			(type default)
		)
		(layer "In2.Cu")
	)
	(gr_line
		(start 254.674624 -61.929772)
		(end 254.753872 -61.866526)
		(stroke
			(width 0.0508)
			(type default)
		)
		(layer "In2.Cu")
	)
	(gr_line
		(start 254.696722 -67.117722)
		(end 254.734314 -67.155314)
		(stroke
			(width 0.0508)
			(type default)
		)
		(layer "In2.Cu")
	)
	(gr_line
		(start 254.696722 -66.9163)
		(end 254.696722 -67.117722)
		(stroke
			(width 0.0508)
			(type default)
		)
		(layer "In2.Cu")
	)
	(gr_arc
		(start 254.70612 -60.575444)
		(mid 254.706567 -60.589189)
		(end 254.707898 -60.602876)
		(stroke
			(width 0.0508)
			(type default)
		)
		(layer "In2.Cu")
	)
	(gr_arc
		(start 254.707898 -60.602876)
		(mid 254.727891 -60.668944)
		(end 254.768096 -60.72505)
		(stroke
			(width 0.0508)
			(type default)
		)
		(layer "In2.Cu")
	)
	(gr_line
		(start 254.736092 -67.157092)
		(end 254.762 -67.183)
		(stroke
			(width 0.0508)
			(type default)
		)
		(layer "In2.Cu")
	)
	(gr_line
		(start 254.753872 -61.866526)
		(end 254.75438 -61.866018)
		(stroke
			(width 0.0508)
			(type default)
		)
		(layer "In2.Cu")
	)
	(gr_line
		(start 254.75438 -61.866018)
		(end 254.79756 -61.831728)
		(stroke
			(width 0.0508)
			(type default)
		)
		(layer "In2.Cu")
	)
	(gr_line
		(start 254.761746 -61.005974)
		(end 254.772414 -61.016642)
		(stroke
			(width 0.0508)
			(type default)
		)
		(layer "In2.Cu")
	)
	(gr_line
		(start 254.79756 -61.831728)
		(end 254.818134 -61.815726)
		(stroke
			(width 0.0508)
			(type default)
		)
		(layer "In2.Cu")
	)
	(gr_line
		(start 254.818134 -61.815726)
		(end 254.823976 -61.811154)
		(stroke
			(width 0.0508)
			(type default)
		)
		(layer "In2.Cu")
	)
	(gr_line
		(start 254.823976 -61.811154)
		(end 254.829056 -61.807344)
		(stroke
			(width 0.0508)
			(type default)
		)
		(layer "In2.Cu")
	)
	(gr_line
		(start 254.829056 -61.807344)
		(end 254.8509 -61.790072)
		(stroke
			(width 0.0508)
			(type default)
		)
		(layer "In2.Cu")
	)
	(gr_line
		(start 254.8509 -61.790072)
		(end 254.851154 -61.790072)
		(stroke
			(width 0.0508)
			(type default)
		)
		(layer "In2.Cu")
	)
	(gr_line
		(start 254.851154 -61.790072)
		(end 254.857758 -61.784738)
		(stroke
			(width 0.0508)
			(type default)
		)
		(layer "In2.Cu")
	)
	(gr_line
		(start 254.854202 -57.745376)
		(end 254.854202 -57.747916)
		(stroke
			(width 0.0508)
			(type default)
		)
		(layer "In2.Cu")
	)
	(gr_line
		(start 254.854202 -55.74538)
		(end 254.854202 -55.74792)
		(stroke
			(width 0.0508)
			(type default)
		)
		(layer "In2.Cu")
	)
	(gr_line
		(start 254.854202 -53.745384)
		(end 254.854202 -53.747924)
		(stroke
			(width 0.0508)
			(type default)
		)
		(layer "In2.Cu")
	)
	(gr_line
		(start 254.854202 -50.74539)
		(end 254.854202 -50.74793)
		(stroke
			(width 0.0508)
			(type default)
		)
		(layer "In2.Cu")
	)
	(gr_line
		(start 254.854202 -48.745394)
		(end 254.854202 -48.747934)
		(stroke
			(width 0.0508)
			(type default)
		)
		(layer "In2.Cu")
	)
	(gr_line
		(start 254.854202 -45.745654)
		(end 254.854202 -45.748194)
		(stroke
			(width 0.0508)
			(type default)
		)
		(layer "In2.Cu")
	)
	(gr_line
		(start 254.854202 -43.745658)
		(end 254.854202 -43.748198)
		(stroke
			(width 0.0508)
			(type default)
		)
		(layer "In2.Cu")
	)
	(gr_line
		(start 254.857758 -61.784738)
		(end 254.895604 -61.755274)
		(stroke
			(width 0.0508)
			(type default)
		)
		(layer "In2.Cu")
	)
	(gr_arc
		(start 254.866394 -39.903146)
		(mid 254.709705 -39.934313)
		(end 254.576834 -40.023034)
		(stroke
			(width 0.0508)
			(type default)
		)
		(layer "In2.Cu")
	)
	(gr_line
		(start 254.866394 -39.903146)
		(end 255.44526 -39.903146)
		(stroke
			(width 0.0508)
			(type default)
		)
		(layer "In2.Cu")
	)
	(gr_arc
		(start 254.867664 -59.732164)
		(mid 254.748133 -59.910915)
		(end 254.70612 -60.1218)
		(stroke
			(width 0.0508)
			(type default)
		)
		(layer "In2.Cu")
	)
	(gr_line
		(start 254.867664 -59.732164)
		(end 255.09982 -59.499754)
		(stroke
			(width 0.0508)
			(type default)
		)
		(layer "In2.Cu")
	)
	(gr_line
		(start 254.895604 -61.755274)
		(end 254.9017 -61.750702)
		(stroke
			(width 0.0508)
			(type default)
		)
		(layer "In2.Cu")
	)
	(gr_line
		(start 254.9017 -61.750702)
		(end 254.90424 -61.748416)
		(stroke
			(width 0.0508)
			(type default)
		)
		(layer "In2.Cu")
	)
	(gr_line
		(start 254.90424 -61.748416)
		(end 255.025906 -61.652404)
		(stroke
			(width 0.0508)
			(type default)
		)
		(layer "In2.Cu")
	)
	(gr_arc
		(start 254.93345 -35.893756)
		(mid 254.723397 -35.935538)
		(end 254.545338 -36.054538)
		(stroke
			(width 0.0508)
			(type default)
		)
		(layer "In2.Cu")
	)
	(gr_line
		(start 254.93345 -35.893756)
		(end 255.585214 -35.893756)
		(stroke
			(width 0.0508)
			(type default)
		)
		(layer "In2.Cu")
	)
	(gr_line
		(start 254.958088 -62.035182)
		(end 254.97917 -62.035182)
		(stroke
			(width 0.0508)
			(type default)
		)
		(layer "In2.Cu")
	)
	(gr_arc
		(start 254.981202 -33.899602)
		(mid 254.447969 -34.064001)
		(end 254.099822 -34.500058)
		(stroke
			(width 0.0508)
			(type default)
		)
		(layer "In2.Cu")
	)
	(gr_arc
		(start 254.990092 -60.891674)
		(mid 254.996178 -60.892408)
		(end 255.002284 -60.892944)
		(stroke
			(width 0.0508)
			(type default)
		)
		(layer "In2.Cu")
	)
	(gr_arc
		(start 255.002284 -60.892944)
		(mid 255.007614 -60.893279)
		(end 255.012952 -60.893452)
		(stroke
			(width 0.0508)
			(type default)
		)
		(layer "In2.Cu")
	)
	(gr_line
		(start 255.01727 -72.586342)
		(end 255.023112 -72.619362)
		(stroke
			(width 0.06985)
			(type default)
		)
		(layer "In2.Cu")
	)
	(gr_line
		(start 255.023112 -72.619362)
		(end 255.04267 -72.647302)
		(stroke
			(width 0.06985)
			(type default)
		)
		(layer "In2.Cu")
	)
	(gr_arc
		(start 255.025906 -61.652404)
		(mid 255.080378 -61.584556)
		(end 255.09982 -61.49975)
		(stroke
			(width 0.0508)
			(type default)
		)
		(layer "In2.Cu")
	)
	(gr_line
		(start 255.049274 -34.500058)
		(end 255.09982 -34.500058)
		(stroke
			(width 0.0508)
			(type default)
		)
		(layer "In2.Cu")
	)
	(gr_arc
		(start 255.049274 -34.102802)
		(mid 254.850646 -34.30143)
		(end 255.049274 -34.500058)
		(stroke
			(width 0.0508)
			(type default)
		)
		(layer "In2.Cu")
	)
	(gr_arc
		(start 255.056386 -62.067186)
		(mid 255.020963 -62.043503)
		(end 254.97917 -62.035182)
		(stroke
			(width 0.0508)
			(type default)
		)
		(layer "In2.Cu")
	)
	(gr_line
		(start 255.056386 -62.067186)
		(end 255.143 -62.1538)
		(stroke
			(width 0.0508)
			(type default)
		)
		(layer "In2.Cu")
	)
	(gr_line
		(start 255.09982 -62.499748)
		(end 255.143 -62.456568)
		(stroke
			(width 0.0508)
			(type default)
		)
		(layer "In2.Cu")
	)
	(gr_line
		(start 255.09982 -58.499756)
		(end 255.491996 -58.891678)
		(stroke
			(width 0.0508)
			(type default)
		)
		(layer "In2.Cu")
	)
	(gr_arc
		(start 255.09982 -57.499758)
		(mid 254.92612 -57.571689)
		(end 254.854202 -57.745376)
		(stroke
			(width 0.0508)
			(type default)
		)
		(layer "In2.Cu")
	)
	(gr_arc
		(start 255.09982 -55.499762)
		(mid 254.926122 -55.571694)
		(end 254.854202 -55.74538)
		(stroke
			(width 0.0508)
			(type default)
		)
		(layer "In2.Cu")
	)
	(gr_arc
		(start 255.09982 -53.499766)
		(mid 254.926123 -53.571698)
		(end 254.854202 -53.745384)
		(stroke
			(width 0.0508)
			(type default)
		)
		(layer "In2.Cu")
	)
	(gr_arc
		(start 255.09982 -50.499772)
		(mid 254.926125 -50.571704)
		(end 254.854202 -50.74539)
		(stroke
			(width 0.0508)
			(type default)
		)
		(layer "In2.Cu")
	)
	(gr_line
		(start 255.09982 -46.500034)
		(end 255.364488 -46.764702)
		(stroke
			(width 0.06985)
			(type default)
		)
		(layer "In2.Cu")
	)
	(gr_arc
		(start 255.09982 -45.500036)
		(mid 254.926113 -45.571966)
		(end 254.854202 -45.745654)
		(stroke
			(width 0.0508)
			(type default)
		)
		(layer "In2.Cu")
	)
	(gr_arc
		(start 255.09982 -43.50004)
		(mid 254.926114 -43.57197)
		(end 254.854202 -43.745658)
		(stroke
			(width 0.0508)
			(type default)
		)
		(layer "In2.Cu")
	)
	(gr_line
		(start 255.09982 -40.500046)
		(end 255.382014 -40.217598)
		(stroke
			(width 0.0508)
			(type default)
		)
		(layer "In2.Cu")
	)
	(gr_line
		(start 255.09982 -39.500048)
		(end 255.567434 -39.032434)
		(stroke
			(width 0.0508)
			(type default)
		)
		(layer "In2.Cu")
	)
	(gr_arc
		(start 255.09982 -37.500052)
		(mid 255.349886 -37.494099)
		(end 255.4732 -37.276532)
		(stroke
			(width 0.0508)
			(type default)
		)
		(layer "In2.Cu")
	)
	(gr_line
		(start 255.09982 -36.500054)
		(end 255.29921 -36.300664)
		(stroke
			(width 0.0508)
			(type default)
		)
		(layer "In2.Cu")
	)
	(gr_line
		(start 255.09982 -35.490658)
		(end 255.09982 -35.500056)
		(stroke
			(width 0.0508)
			(type default)
		)
		(layer "In2.Cu")
	)
	(gr_arc
		(start 255.09982 -33.50006)
		(mid 255.381424 -33.383401)
		(end 255.498092 -33.101788)
		(stroke
			(width 0.0508)
			(type default)
		)
		(layer "In2.Cu")
	)
	(gr_arc
		(start 255.143 -62.456568)
		(mid 255.205689 -62.305189)
		(end 255.143 -62.1538)
		(stroke
			(width 0.0508)
			(type default)
		)
		(layer "In2.Cu")
	)
	(gr_arc
		(start 255.27381 -35.073336)
		(mid 255.145065 -35.26459)
		(end 255.09982 -35.490658)
		(stroke
			(width 0.0508)
			(type default)
		)
		(layer "In2.Cu")
	)
	(gr_line
		(start 255.27381 -35.073336)
		(end 255.274826 -35.07232)
		(stroke
			(width 0.0508)
			(type default)
		)
		(layer "In2.Cu")
	)
	(gr_arc
		(start 255.321054 -54.503828)
		(mid 255.210456 -54.500783)
		(end 255.09982 -54.499764)
		(stroke
			(width 0.0508)
			(type default)
		)
		(layer "In2.Cu")
	)
	(gr_line
		(start 255.4478 -67.183)
		(end 255.4478 -67.36842)
		(stroke
			(width 0.06985)
			(type default)
		)
		(layer "In2.Cu")
	)
	(gr_line
		(start 255.4478 -67.183)
		(end 255.467358 -67.163442)
		(stroke
			(width 0.0508)
			(type default)
		)
		(layer "In2.Cu")
	)
	(gr_line
		(start 255.469136 -67.161664)
		(end 255.49352 -67.13728)
		(stroke
			(width 0.0508)
			(type default)
		)
		(layer "In2.Cu")
	)
	(gr_arc
		(start 255.628902 -54.711346)
		(mid 255.506706 -54.560499)
		(end 255.321054 -54.503828)
		(stroke
			(width 0.0508)
			(type default)
		)
		(layer "In2.Cu")
	)
	(gr_arc
		(start 255.638046 -56.81726)
		(mid 255.41227 -56.585038)
		(end 255.09982 -56.49976)
		(stroke
			(width 0.0508)
			(type default)
		)
		(layer "In2.Cu")
	)
	(gr_line
		(start 255.638046 -56.81726)
		(end 255.69545 -56.921146)
		(stroke
			(width 0.0508)
			(type default)
		)
		(layer "In2.Cu")
	)
	(gr_arc
		(start 255.638046 -52.817268)
		(mid 255.412271 -52.585043)
		(end 255.09982 -52.499768)
		(stroke
			(width 0.0508)
			(type default)
		)
		(layer "In2.Cu")
	)
	(gr_line
		(start 255.638046 -52.817268)
		(end 255.69545 -52.921154)
		(stroke
			(width 0.0508)
			(type default)
		)
		(layer "In2.Cu")
	)
	(gr_arc
		(start 255.638046 -49.817274)
		(mid 255.412272 -49.585047)
		(end 255.09982 -49.499774)
		(stroke
			(width 0.0508)
			(type default)
		)
		(layer "In2.Cu")
	)
	(gr_line
		(start 255.638046 -49.817274)
		(end 255.69545 -49.92116)
		(stroke
			(width 0.0508)
			(type default)
		)
		(layer "In2.Cu")
	)
	(gr_arc
		(start 255.638046 -44.817538)
		(mid 255.41227 -44.585322)
		(end 255.09982 -44.500038)
		(stroke
			(width 0.0508)
			(type default)
		)
		(layer "In2.Cu")
	)
	(gr_line
		(start 255.638046 -44.817538)
		(end 255.69545 -44.921424)
		(stroke
			(width 0.0508)
			(type default)
		)
		(layer "In2.Cu")
	)
	(gr_arc
		(start 255.638046 -42.817542)
		(mid 255.412268 -42.585327)
		(end 255.09982 -42.500042)
		(stroke
			(width 0.0508)
			(type default)
		)
		(layer "In2.Cu")
	)
	(gr_line
		(start 255.638046 -42.817542)
		(end 255.69545 -42.921428)
		(stroke
			(width 0.0508)
			(type default)
		)
		(layer "In2.Cu")
	)
	(gr_arc
		(start 255.651 -40.106346)
		(mid 255.505436 -40.135207)
		(end 255.382014 -40.217598)
		(stroke
			(width 0.0508)
			(type default)
		)
		(layer "In2.Cu")
	)
	(gr_line
		(start 255.674622 -62.92977)
		(end 255.75387 -62.866524)
		(stroke
			(width 0.0508)
			(type default)
		)
		(layer "In2.Cu")
	)
	(gr_line
		(start 255.682242 -13.963396)
		(end 255.701038 -13.960094)
		(stroke
			(width 0.06985)
			(type default)
		)
		(layer "In2.Cu")
	)
	(gr_arc
		(start 255.685798 -34.903156)
		(mid 255.463591 -34.947107)
		(end 255.274826 -35.07232)
		(stroke
			(width 0.0508)
			(type default)
		)
		(layer "In2.Cu")
	)
	(gr_line
		(start 255.685798 -34.903156)
		(end 256.119376 -34.903156)
		(stroke
			(width 0.0508)
			(type default)
		)
		(layer "In2.Cu")
	)
	(gr_line
		(start 255.69672 -67.10172)
		(end 255.756664 -67.161664)
		(stroke
			(width 0.0508)
			(type default)
		)
		(layer "In2.Cu")
	)
	(gr_line
		(start 255.69672 -66.9163)
		(end 255.69672 -67.10172)
		(stroke
			(width 0.0508)
			(type default)
		)
		(layer "In2.Cu")
	)
	(gr_line
		(start 255.701038 -13.960094)
		(end 255.719834 -13.963396)
		(stroke
			(width 0.06985)
			(type default)
		)
		(layer "In2.Cu")
	)
	(gr_arc
		(start 255.701292 -33.101534)
		(mid 255.818031 -33.383306)
		(end 256.099818 -33.50006)
		(stroke
			(width 0.0508)
			(type default)
		)
		(layer "In2.Cu")
	)
	(gr_line
		(start 255.75387 -62.866524)
		(end 255.754378 -62.866016)
		(stroke
			(width 0.0508)
			(type default)
		)
		(layer "In2.Cu")
	)
	(gr_line
		(start 255.754378 -62.866016)
		(end 255.797558 -62.831726)
		(stroke
			(width 0.0508)
			(type default)
		)
		(layer "In2.Cu")
	)
	(gr_line
		(start 255.758442 -67.163442)
		(end 255.778 -67.183)
		(stroke
			(width 0.0508)
			(type default)
		)
		(layer "In2.Cu")
	)
	(gr_line
		(start 255.78562 -14.97965)
		(end 255.805686 -14.976348)
		(stroke
			(width 0.06985)
			(type default)
		)
		(layer "In2.Cu")
	)
	(gr_arc
		(start 255.790954 -36.096956)
		(mid 255.524816 -36.149894)
		(end 255.29921 -36.300664)
		(stroke
			(width 0.0508)
			(type default)
		)
		(layer "In2.Cu")
	)
	(gr_line
		(start 255.797558 -62.831726)
		(end 255.818132 -62.815724)
		(stroke
			(width 0.0508)
			(type default)
		)
		(layer "In2.Cu")
	)
	(gr_line
		(start 255.805686 -14.976348)
		(end 255.825244 -14.980412)
		(stroke
			(width 0.06985)
			(type default)
		)
		(layer "In2.Cu")
	)
	(gr_line
		(start 255.818132 -62.815724)
		(end 255.823974 -62.811152)
		(stroke
			(width 0.0508)
			(type default)
		)
		(layer "In2.Cu")
	)
	(gr_line
		(start 255.823974 -62.811152)
		(end 255.829054 -62.807342)
		(stroke
			(width 0.0508)
			(type default)
		)
		(layer "In2.Cu")
	)
	(gr_line
		(start 255.829054 -62.807342)
		(end 255.850898 -62.79007)
		(stroke
			(width 0.0508)
			(type default)
		)
		(layer "In2.Cu")
	)
	(gr_line
		(start 255.83515 -46.764702)
		(end 256.099818 -46.500034)
		(stroke
			(width 0.06985)
			(type default)
		)
		(layer "In2.Cu")
	)
	(gr_line
		(start 255.850898 -62.79007)
		(end 255.851152 -62.79007)
		(stroke
			(width 0.0508)
			(type default)
		)
		(layer "In2.Cu")
	)
	(gr_line
		(start 255.851152 -62.79007)
		(end 255.857756 -62.784736)
		(stroke
			(width 0.0508)
			(type default)
		)
		(layer "In2.Cu")
	)
	(gr_line
		(start 255.851914 -37.500052)
		(end 256.099818 -37.500052)
		(stroke
			(width 0.0508)
			(type default)
		)
		(layer "In2.Cu")
	)
	(gr_arc
		(start 255.8542 -58.747914)
		(mid 255.859121 -58.786597)
		(end 255.873504 -58.822844)
		(stroke
			(width 0.0508)
			(type default)
		)
		(layer "In2.Cu")
	)
	(gr_line
		(start 255.8542 -58.745374)
		(end 255.8542 -58.747914)
		(stroke
			(width 0.0508)
			(type default)
		)
		(layer "In2.Cu")
	)
	(gr_line
		(start 255.8542 -56.745378)
		(end 255.8542 -56.747918)
		(stroke
			(width 0.0508)
			(type default)
		)
		(layer "In2.Cu")
	)
	(gr_line
		(start 255.8542 -54.745382)
		(end 255.8542 -54.747922)
		(stroke
			(width 0.0508)
			(type default)
		)
		(layer "In2.Cu")
	)
	(gr_line
		(start 255.8542 -52.745386)
		(end 255.8542 -52.747926)
		(stroke
			(width 0.0508)
			(type default)
		)
		(layer "In2.Cu")
	)
	(gr_line
		(start 255.8542 -49.745392)
		(end 255.8542 -49.747932)
		(stroke
			(width 0.0508)
			(type default)
		)
		(layer "In2.Cu")
	)
	(gr_line
		(start 255.8542 -44.745656)
		(end 255.8542 -44.748196)
		(stroke
			(width 0.0508)
			(type default)
		)
		(layer "In2.Cu")
	)
	(gr_line
		(start 255.8542 -42.74566)
		(end 255.8542 -42.7482)
		(stroke
			(width 0.0508)
			(type default)
		)
		(layer "In2.Cu")
	)
	(gr_line
		(start 255.857756 -62.784736)
		(end 255.895602 -62.755272)
		(stroke
			(width 0.0508)
			(type default)
		)
		(layer "In2.Cu")
	)
	(gr_arc
		(start 255.873504 -58.822844)
		(mid 255.930394 -58.88139)
		(end 256.00914 -58.902854)
		(stroke
			(width 0.0508)
			(type default)
		)
		(layer "In2.Cu")
	)
	(gr_line
		(start 255.887728 -71.761604)
		(end 255.89357 -71.794624)
		(stroke
			(width 0.06985)
			(type default)
		)
		(layer "In2.Cu")
	)
	(gr_line
		(start 255.89357 -71.794624)
		(end 255.913128 -71.822564)
		(stroke
			(width 0.06985)
			(type default)
		)
		(layer "In2.Cu")
	)
	(gr_line
		(start 255.895602 -62.755272)
		(end 255.901698 -62.7507)
		(stroke
			(width 0.0508)
			(type default)
		)
		(layer "In2.Cu")
	)
	(gr_line
		(start 255.901698 -62.7507)
		(end 255.904238 -62.748414)
		(stroke
			(width 0.0508)
			(type default)
		)
		(layer "In2.Cu")
	)
	(gr_arc
		(start 255.902206 -38.89375)
		(mid 255.721022 -38.92979)
		(end 255.567434 -39.032434)
		(stroke
			(width 0.0508)
			(type default)
		)
		(layer "In2.Cu")
	)
	(gr_line
		(start 255.902206 -38.89375)
		(end 256.46126 -38.89375)
		(stroke
			(width 0.0508)
			(type default)
		)
		(layer "In2.Cu")
	)
	(gr_line
		(start 255.904238 -62.748414)
		(end 256.025904 -62.652402)
		(stroke
			(width 0.0508)
			(type default)
		)
		(layer "In2.Cu")
	)
	(gr_line
		(start 255.958086 -63.03518)
		(end 255.995932 -63.03518)
		(stroke
			(width 0.0508)
			(type default)
		)
		(layer "In2.Cu")
	)
	(gr_arc
		(start 256.025904 -62.652402)
		(mid 256.080378 -62.584553)
		(end 256.099818 -62.499748)
		(stroke
			(width 0.0508)
			(type default)
		)
		(layer "In2.Cu")
	)
	(gr_arc
		(start 256.099818 -63.499746)
		(mid 256.175939 -63.385764)
		(end 256.202688 -63.251334)
		(stroke
			(width 0.0508)
			(type default)
		)
		(layer "In2.Cu")
	)
	(gr_arc
		(start 256.099818 -58.499756)
		(mid 255.926119 -58.571688)
		(end 255.8542 -58.745374)
		(stroke
			(width 0.0508)
			(type default)
		)
		(layer "In2.Cu")
	)
	(gr_arc
		(start 256.099818 -44.500038)
		(mid 255.926113 -44.571969)
		(end 255.8542 -44.745656)
		(stroke
			(width 0.0508)
			(type default)
		)
		(layer "In2.Cu")
	)
	(gr_line
		(start 256.099818 -39.500048)
		(end 256.386838 -39.213028)
		(stroke
			(width 0.0508)
			(type default)
		)
		(layer "In2.Cu")
	)
	(gr_line
		(start 256.099818 -35.331654)
		(end 256.099818 -35.500056)
		(stroke
			(width 0.0508)
			(type default)
		)
		(layer "In2.Cu")
	)
	(gr_arc
		(start 256.13106 -63.091314)
		(mid 256.069068 -63.049846)
		(end 255.995932 -63.03518)
		(stroke
			(width 0.0508)
			(type default)
		)
		(layer "In2.Cu")
	)
	(gr_line
		(start 256.13106 -63.091314)
		(end 256.13995 -63.09995)
		(stroke
			(width 0.0508)
			(type default)
		)
		(layer "In2.Cu")
	)
	(gr_arc
		(start 256.202688 -63.251334)
		(mid 256.186345 -63.169419)
		(end 256.13995 -63.09995)
		(stroke
			(width 0.0508)
			(type default)
		)
		(layer "In2.Cu")
	)
	(gr_arc
		(start 256.325116 -35.106356)
		(mid 256.165806 -35.172344)
		(end 256.099818 -35.331654)
		(stroke
			(width 0.0508)
			(type default)
		)
		(layer "In2.Cu")
	)
	(gr_line
		(start 256.4384 -67.183)
		(end 256.4384 -67.377818)
		(stroke
			(width 0.06985)
			(type default)
		)
		(layer "In2.Cu")
	)
	(gr_line
		(start 256.4384 -67.183)
		(end 256.457958 -67.163442)
		(stroke
			(width 0.0508)
			(type default)
		)
		(layer "In2.Cu")
	)
	(gr_line
		(start 256.451608 -15.947898)
		(end 256.471674 -15.944596)
		(stroke
			(width 0.06985)
			(type default)
		)
		(layer "In2.Cu")
	)
	(gr_line
		(start 256.459736 -67.161664)
		(end 256.493518 -67.127882)
		(stroke
			(width 0.0508)
			(type default)
		)
		(layer "In2.Cu")
	)
	(gr_line
		(start 256.471674 -15.944596)
		(end 256.491232 -15.94866)
		(stroke
			(width 0.06985)
			(type default)
		)
		(layer "In2.Cu")
	)
	(gr_arc
		(start 256.667 -39.09695)
		(mid 256.515366 -39.127112)
		(end 256.386838 -39.213028)
		(stroke
			(width 0.0508)
			(type default)
		)
		(layer "In2.Cu")
	)
	(gr_line
		(start 256.67462 -61.929772)
		(end 256.753868 -61.866526)
		(stroke
			(width 0.0508)
			(type default)
		)
		(layer "In2.Cu")
	)
	(gr_line
		(start 256.69494 -70.719696)
		(end 256.700782 -70.752716)
		(stroke
			(width 0.06985)
			(type default)
		)
		(layer "In2.Cu")
	)
	(gr_line
		(start 256.696718 -67.111118)
		(end 256.747264 -67.161664)
		(stroke
			(width 0.0508)
			(type default)
		)
		(layer "In2.Cu")
	)
	(gr_line
		(start 256.696718 -66.9163)
		(end 256.696718 -67.111118)
		(stroke
			(width 0.0508)
			(type default)
		)
		(layer "In2.Cu")
	)
	(gr_line
		(start 256.700782 -70.752716)
		(end 256.72034 -70.780656)
		(stroke
			(width 0.06985)
			(type default)
		)
		(layer "In2.Cu")
	)
	(gr_line
		(start 256.749042 -67.163442)
		(end 256.7686 -67.183)
		(stroke
			(width 0.0508)
			(type default)
		)
		(layer "In2.Cu")
	)
	(gr_line
		(start 256.753868 -61.866526)
		(end 256.754376 -61.866018)
		(stroke
			(width 0.0508)
			(type default)
		)
		(layer "In2.Cu")
	)
	(gr_line
		(start 256.754376 -61.866018)
		(end 256.797556 -61.831728)
		(stroke
			(width 0.0508)
			(type default)
		)
		(layer "In2.Cu")
	)
	(gr_line
		(start 256.797556 -61.831728)
		(end 256.81813 -61.815726)
		(stroke
			(width 0.0508)
			(type default)
		)
		(layer "In2.Cu")
	)
	(gr_line
		(start 256.801366 -17.268698)
		(end 256.821432 -17.265396)
		(stroke
			(width 0.06985)
			(type default)
		)
		(layer "In2.Cu")
	)
	(gr_line
		(start 256.81813 -61.815726)
		(end 256.823972 -61.811154)
		(stroke
			(width 0.0508)
			(type default)
		)
		(layer "In2.Cu")
	)
	(gr_line
		(start 256.821432 -17.265396)
		(end 256.84099 -17.26946)
		(stroke
			(width 0.06985)
			(type default)
		)
		(layer "In2.Cu")
	)
	(gr_line
		(start 256.823972 -61.811154)
		(end 256.829052 -61.807344)
		(stroke
			(width 0.0508)
			(type default)
		)
		(layer "In2.Cu")
	)
	(gr_line
		(start 256.829052 -61.807344)
		(end 256.850896 -61.790072)
		(stroke
			(width 0.0508)
			(type default)
		)
		(layer "In2.Cu")
	)
	(gr_line
		(start 256.850896 -61.790072)
		(end 256.85115 -61.790072)
		(stroke
			(width 0.0508)
			(type default)
		)
		(layer "In2.Cu")
	)
	(gr_line
		(start 256.85115 -61.790072)
		(end 256.857754 -61.784738)
		(stroke
			(width 0.0508)
			(type default)
		)
		(layer "In2.Cu")
	)
	(gr_line
		(start 256.857754 -61.784738)
		(end 256.8956 -61.755274)
		(stroke
			(width 0.0508)
			(type default)
		)
		(layer "In2.Cu")
	)
	(gr_line
		(start 256.8956 -61.755274)
		(end 256.901696 -61.750702)
		(stroke
			(width 0.0508)
			(type default)
		)
		(layer "In2.Cu")
	)
	(gr_line
		(start 256.901696 -61.750702)
		(end 256.904236 -61.748416)
		(stroke
			(width 0.0508)
			(type default)
		)
		(layer "In2.Cu")
	)
	(gr_line
		(start 256.904236 -61.748416)
		(end 257.025902 -61.652404)
		(stroke
			(width 0.0508)
			(type default)
		)
		(layer "In2.Cu")
	)
	(gr_line
		(start 256.958084 -62.035182)
		(end 256.99593 -62.035182)
		(stroke
			(width 0.0508)
			(type default)
		)
		(layer "In2.Cu")
	)
	(gr_arc
		(start 257.025902 -61.652404)
		(mid 257.080374 -61.584556)
		(end 257.099816 -61.49975)
		(stroke
			(width 0.0508)
			(type default)
		)
		(layer "In2.Cu")
	)
	(gr_arc
		(start 257.099816 -62.499748)
		(mid 257.175939 -62.385766)
		(end 257.202686 -62.251336)
		(stroke
			(width 0.0508)
			(type default)
		)
		(layer "In2.Cu")
	)
	(gr_arc
		(start 257.131058 -62.091316)
		(mid 257.069066 -62.049849)
		(end 256.99593 -62.035182)
		(stroke
			(width 0.0508)
			(type default)
		)
		(layer "In2.Cu")
	)
	(gr_line
		(start 257.131058 -62.091316)
		(end 257.139948 -62.099952)
		(stroke
			(width 0.0508)
			(type default)
		)
		(layer "In2.Cu")
	)
	(gr_line
		(start 257.19024 -18.564098)
		(end 257.210306 -18.560796)
		(stroke
			(width 0.06985)
			(type default)
		)
		(layer "In2.Cu")
	)
	(gr_arc
		(start 257.202686 -62.251336)
		(mid 257.186343 -62.169421)
		(end 257.139948 -62.099952)
		(stroke
			(width 0.0508)
			(type default)
		)
		(layer "In2.Cu")
	)
	(gr_line
		(start 257.210306 -18.560796)
		(end 257.229864 -18.56486)
		(stroke
			(width 0.06985)
			(type default)
		)
		(layer "In2.Cu")
	)
	(gr_line
		(start 257.295142 -21.791168)
		(end 257.316478 -21.787358)
		(stroke
			(width 0.06985)
			(type default)
		)
		(layer "In2.Cu")
	)
	(gr_line
		(start 257.316478 -21.787358)
		(end 257.338322 -21.791676)
		(stroke
			(width 0.06985)
			(type default)
		)
		(layer "In2.Cu")
	)
	(gr_line
		(start 257.4544 -67.2338)
		(end 257.4544 -67.412616)
		(stroke
			(width 0.06985)
			(type default)
		)
		(layer "In2.Cu")
	)
	(gr_line
		(start 257.4544 -67.2338)
		(end 257.473958 -67.214242)
		(stroke
			(width 0.0508)
			(type default)
		)
		(layer "In2.Cu")
	)
	(gr_line
		(start 257.475482 -19.935698)
		(end 257.495548 -19.932396)
		(stroke
			(width 0.06985)
			(type default)
		)
		(layer "In2.Cu")
	)
	(gr_line
		(start 257.475736 -67.212464)
		(end 257.493516 -67.194684)
		(stroke
			(width 0.0508)
			(type default)
		)
		(layer "In2.Cu")
	)
	(gr_line
		(start 257.495548 -19.932396)
		(end 257.515106 -19.93646)
		(stroke
			(width 0.06985)
			(type default)
		)
		(layer "In2.Cu")
	)
	(gr_line
		(start 257.561588 -69.87413)
		(end 257.56743 -69.90715)
		(stroke
			(width 0.06985)
			(type default)
		)
		(layer "In2.Cu")
	)
	(gr_line
		(start 257.56743 -69.90715)
		(end 257.586988 -69.93509)
		(stroke
			(width 0.06985)
			(type default)
		)
		(layer "In2.Cu")
	)
	(gr_line
		(start 257.674618 -62.92977)
		(end 257.753866 -62.866524)
		(stroke
			(width 0.0508)
			(type default)
		)
		(layer "In2.Cu")
	)
	(gr_line
		(start 257.696716 -67.145916)
		(end 257.763264 -67.212464)
		(stroke
			(width 0.0508)
			(type default)
		)
		(layer "In2.Cu")
	)
	(gr_line
		(start 257.696716 -66.9671)
		(end 257.696716 -67.145916)
		(stroke
			(width 0.0508)
			(type default)
		)
		(layer "In2.Cu")
	)
	(gr_line
		(start 257.753866 -62.866524)
		(end 257.754374 -62.866016)
		(stroke
			(width 0.0508)
			(type default)
		)
		(layer "In2.Cu")
	)
	(gr_line
		(start 257.754374 -62.866016)
		(end 257.797554 -62.831726)
		(stroke
			(width 0.0508)
			(type default)
		)
		(layer "In2.Cu")
	)
	(gr_line
		(start 257.765042 -67.214242)
		(end 257.7846 -67.2338)
		(stroke
			(width 0.0508)
			(type default)
		)
		(layer "In2.Cu")
	)
	(gr_line
		(start 257.797554 -62.831726)
		(end 257.818128 -62.815724)
		(stroke
			(width 0.0508)
			(type default)
		)
		(layer "In2.Cu")
	)
	(gr_line
		(start 257.818128 -62.815724)
		(end 257.82397 -62.811152)
		(stroke
			(width 0.0508)
			(type default)
		)
		(layer "In2.Cu")
	)
	(gr_line
		(start 257.82397 -62.811152)
		(end 257.82905 -62.807342)
		(stroke
			(width 0.0508)
			(type default)
		)
		(layer "In2.Cu")
	)
	(gr_line
		(start 257.82905 -62.807342)
		(end 257.850894 -62.79007)
		(stroke
			(width 0.0508)
			(type default)
		)
		(layer "In2.Cu")
	)
	(gr_line
		(start 257.850894 -62.79007)
		(end 257.851148 -62.79007)
		(stroke
			(width 0.0508)
			(type default)
		)
		(layer "In2.Cu")
	)
	(gr_line
		(start 257.851148 -62.79007)
		(end 257.857752 -62.784736)
		(stroke
			(width 0.0508)
			(type default)
		)
		(layer "In2.Cu")
	)
	(gr_line
		(start 257.856482 -22.972268)
		(end 257.877818 -22.968458)
		(stroke
			(width 0.06985)
			(type default)
		)
		(layer "In2.Cu")
	)
	(gr_line
		(start 257.857752 -62.784736)
		(end 257.895598 -62.755272)
		(stroke
			(width 0.0508)
			(type default)
		)
		(layer "In2.Cu")
	)
	(gr_line
		(start 257.877818 -22.968458)
		(end 257.899662 -22.972776)
		(stroke
			(width 0.06985)
			(type default)
		)
		(layer "In2.Cu")
	)
	(gr_line
		(start 257.895598 -62.755272)
		(end 257.901694 -62.7507)
		(stroke
			(width 0.0508)
			(type default)
		)
		(layer "In2.Cu")
	)
	(gr_line
		(start 257.901694 -62.7507)
		(end 257.904234 -62.748414)
		(stroke
			(width 0.0508)
			(type default)
		)
		(layer "In2.Cu")
	)
	(gr_line
		(start 257.904234 -62.748414)
		(end 258.0259 -62.652402)
		(stroke
			(width 0.0508)
			(type default)
		)
		(layer "In2.Cu")
	)
	(gr_line
		(start 257.958082 -63.03518)
		(end 257.995928 -63.03518)
		(stroke
			(width 0.0508)
			(type default)
		)
		(layer "In2.Cu")
	)
	(gr_arc
		(start 258.0259 -62.652402)
		(mid 258.080372 -62.584554)
		(end 258.099814 -62.499748)
		(stroke
			(width 0.0508)
			(type default)
		)
		(layer "In2.Cu")
	)
	(gr_arc
		(start 258.099814 -63.499746)
		(mid 258.175968 -63.385774)
		(end 258.202684 -63.251334)
		(stroke
			(width 0.0508)
			(type default)
		)
		(layer "In2.Cu")
	)
	(gr_arc
		(start 258.131056 -63.091314)
		(mid 258.069074 -63.049806)
		(end 257.995928 -63.03518)
		(stroke
			(width 0.0508)
			(type default)
		)
		(layer "In2.Cu")
	)
	(gr_line
		(start 258.131056 -63.091314)
		(end 258.139946 -63.09995)
		(stroke
			(width 0.0508)
			(type default)
		)
		(layer "In2.Cu")
	)
	(gr_arc
		(start 258.202684 -63.251334)
		(mid 258.186385 -63.169393)
		(end 258.139946 -63.09995)
		(stroke
			(width 0.0508)
			(type default)
		)
		(layer "In2.Cu")
	)
	(gr_line
		(start 258.299204 -14.754098)
		(end 258.318 -14.7574)
		(stroke
			(width 0.06985)
			(type default)
		)
		(layer "In2.Cu")
	)
	(gr_line
		(start 258.304792 -24.184864)
		(end 258.323334 -24.181816)
		(stroke
			(width 0.06985)
			(type default)
		)
		(layer "In2.Cu")
	)
	(gr_line
		(start 258.318 -14.7574)
		(end 258.336796 -14.754098)
		(stroke
			(width 0.06985)
			(type default)
		)
		(layer "In2.Cu")
	)
	(gr_line
		(start 258.323334 -24.181816)
		(end 258.341622 -24.185626)
		(stroke
			(width 0.06985)
			(type default)
		)
		(layer "In2.Cu")
	)
	(gr_line
		(start 258.400296 -36.099496)
		(end 258.557776 -36.256976)
		(stroke
			(width 0.0508)
			(type default)
		)
		(layer "In2.Cu")
	)
	(gr_arc
		(start 258.417314 -34.903156)
		(mid 258.556986 -34.875374)
		(end 258.675378 -34.796222)
		(stroke
			(width 0.0508)
			(type default)
		)
		(layer "In2.Cu")
	)
	(gr_line
		(start 258.557776 -36.256976)
		(end 258.7244 -36.256976)
		(stroke
			(width 0.0508)
			(type default)
		)
		(layer "In2.Cu")
	)
	(gr_line
		(start 258.603496 -35.893756)
		(end 258.67868 -35.893756)
		(stroke
			(width 0.0508)
			(type default)
		)
		(layer "In2.Cu")
	)
	(gr_line
		(start 258.623054 -35.106356)
		(end 258.7244 -35.106356)
		(stroke
			(width 0.0508)
			(type default)
		)
		(layer "In2.Cu")
	)
	(gr_line
		(start 258.67868 -35.893756)
		(end 258.7117 -35.926776)
		(stroke
			(width 0.0508)
			(type default)
		)
		(layer "In2.Cu")
	)
	(gr_arc
		(start 258.7244 -35.106356)
		(mid 258.824336 -35.086503)
		(end 258.909058 -35.029902)
		(stroke
			(width 0.0508)
			(type default)
		)
		(layer "In2.Cu")
	)
	(gr_line
		(start 258.961636 -15.944596)
		(end 258.99364 -15.950946)
		(stroke
			(width 0.06985)
			(type default)
		)
		(layer "In2.Cu")
	)
	(gr_line
		(start 258.99364 -15.950946)
		(end 259.02539 -15.94358)
		(stroke
			(width 0.06985)
			(type default)
		)
		(layer "In2.Cu")
	)
	(gr_line
		(start 259.089906 -40.675306)
		(end 259.1308 -40.7162)
		(stroke
			(width 0.0508)
			(type default)
		)
		(layer "In2.Cu")
	)
	(gr_line
		(start 259.091684 -40.386)
		(end 259.2578 -40.386)
		(stroke
			(width 0.0508)
			(type default)
		)
		(layer "In2.Cu")
	)
	(gr_line
		(start 259.1308 -40.7162)
		(end 259.2832 -40.7162)
		(stroke
			(width 0.0508)
			(type default)
		)
		(layer "In2.Cu")
	)
	(gr_line
		(start 259.3213 -57.902856)
		(end 259.520944 -57.902856)
		(stroke
			(width 0.0508)
			(type default)
		)
		(layer "In2.Cu")
	)
	(gr_line
		(start 259.3213 -48.902874)
		(end 259.503926 -48.902874)
		(stroke
			(width 0.0508)
			(type default)
		)
		(layer "In2.Cu")
	)
	(gr_line
		(start 259.3213 -38.1)
		(end 259.334 -38.1)
		(stroke
			(width 0.0508)
			(type default)
		)
		(layer "In2.Cu")
	)
	(gr_line
		(start 259.334 -38.1)
		(end 259.388864 -38.154864)
		(stroke
			(width 0.0508)
			(type default)
		)
		(layer "In2.Cu")
	)
	(gr_line
		(start 259.3594 -37.8968)
		(end 259.388864 -37.867336)
		(stroke
			(width 0.0508)
			(type default)
		)
		(layer "In2.Cu")
	)
	(gr_line
		(start 259.390642 -38.156642)
		(end 259.402072 -38.168072)
		(stroke
			(width 0.0508)
			(type default)
		)
		(layer "In2.Cu")
	)
	(gr_line
		(start 259.390642 -37.865558)
		(end 259.418328 -37.837872)
		(stroke
			(width 0.0508)
			(type default)
		)
		(layer "In2.Cu")
	)
	(gr_line
		(start 259.3975 -36.900104)
		(end 259.423662 -36.900104)
		(stroke
			(width 0.0508)
			(type default)
		)
		(layer "In2.Cu")
	)
	(gr_line
		(start 259.418328 -37.837872)
		(end 259.588 -37.837872)
		(stroke
			(width 0.0508)
			(type default)
		)
		(layer "In2.Cu")
	)
	(gr_line
		(start 259.422138 -44.903136)
		(end 259.642102 -44.903136)
		(stroke
			(width 0.0508)
			(type default)
		)
		(layer "In2.Cu")
	)
	(gr_line
		(start 259.423662 -36.900104)
		(end 259.481066 -36.8427)
		(stroke
			(width 0.0508)
			(type default)
		)
		(layer "In2.Cu")
	)
	(gr_line
		(start 259.424678 -31.9024)
		(end 259.4864 -31.9024)
		(stroke
			(width 0.0508)
			(type default)
		)
		(layer "In2.Cu")
	)
	(gr_arc
		(start 259.44195 -45.903134)
		(mid 259.548491 -45.881957)
		(end 259.6388 -45.8216)
		(stroke
			(width 0.0508)
			(type default)
		)
		(layer "In2.Cu")
	)
	(gr_line
		(start 259.446776 -50.90287)
		(end 259.68833 -50.90287)
		(stroke
			(width 0.0508)
			(type default)
		)
		(layer "In2.Cu")
	)
	(gr_line
		(start 259.446776 -49.902872)
		(end 259.646928 -49.902872)
		(stroke
			(width 0.0508)
			(type default)
		)
		(layer "In2.Cu")
	)
	(gr_line
		(start 259.454396 -37.103304)
		(end 259.481066 -37.129974)
		(stroke
			(width 0.0508)
			(type default)
		)
		(layer "In2.Cu")
	)
	(gr_line
		(start 259.4737 -53.106066)
		(end 259.658866 -53.106066)
		(stroke
			(width 0.0508)
			(type default)
		)
		(layer "In2.Cu")
	)
	(gr_line
		(start 259.482844 -37.131752)
		(end 259.511546 -37.160454)
		(stroke
			(width 0.0508)
			(type default)
		)
		(layer "In2.Cu")
	)
	(gr_line
		(start 259.482844 -36.840922)
		(end 259.493512 -36.830254)
		(stroke
			(width 0.0508)
			(type default)
		)
		(layer "In2.Cu")
	)
	(gr_line
		(start 259.4864 -31.9024)
		(end 259.617464 -31.771336)
		(stroke
			(width 0.0508)
			(type default)
		)
		(layer "In2.Cu")
	)
	(gr_line
		(start 259.493512 -36.830254)
		(end 259.6642 -36.830254)
		(stroke
			(width 0.0508)
			(type default)
		)
		(layer "In2.Cu")
	)
	(gr_line
		(start 259.503926 -48.902874)
		(end 259.566664 -48.840136)
		(stroke
			(width 0.0508)
			(type default)
		)
		(layer "In2.Cu")
	)
	(gr_line
		(start 259.506212 -43.903138)
		(end 259.77469 -43.903138)
		(stroke
			(width 0.0508)
			(type default)
		)
		(layer "In2.Cu")
	)
	(gr_line
		(start 259.511546 -37.160454)
		(end 259.6642 -37.160454)
		(stroke
			(width 0.0508)
			(type default)
		)
		(layer "In2.Cu")
	)
	(gr_line
		(start 259.518404 -33.096962)
		(end 259.71119 -33.096962)
		(stroke
			(width 0.0508)
			(type default)
		)
		(layer "In2.Cu")
	)
	(gr_line
		(start 259.520944 -57.902856)
		(end 259.566664 -57.857136)
		(stroke
			(width 0.0508)
			(type default)
		)
		(layer "In2.Cu")
	)
	(gr_line
		(start 259.522214 -61.099192)
		(end 259.602732 -61.17971)
		(stroke
			(width 0.0508)
			(type default)
		)
		(layer "In2.Cu")
	)
	(gr_line
		(start 259.528056 -58.106056)
		(end 259.566664 -58.144664)
		(stroke
			(width 0.0508)
			(type default)
		)
		(layer "In2.Cu")
	)
	(gr_line
		(start 259.545074 -49.106074)
		(end 259.566664 -49.127664)
		(stroke
			(width 0.0508)
			(type default)
		)
		(layer "In2.Cu")
	)
	(gr_line
		(start 259.548376 -56.902858)
		(end 259.758942 -56.902858)
		(stroke
			(width 0.0508)
			(type default)
		)
		(layer "In2.Cu")
	)
	(gr_line
		(start 259.548376 -55.90286)
		(end 259.64134 -55.90286)
		(stroke
			(width 0.0508)
			(type default)
		)
		(layer "In2.Cu")
	)
	(gr_line
		(start 259.548376 -53.902864)
		(end 259.660136 -53.902864)
		(stroke
			(width 0.0508)
			(type default)
		)
		(layer "In2.Cu")
	)
	(gr_line
		(start 259.568442 -58.146442)
		(end 259.588 -58.166)
		(stroke
			(width 0.0508)
			(type default)
		)
		(layer "In2.Cu")
	)
	(gr_line
		(start 259.568442 -57.855358)
		(end 259.588 -57.8358)
		(stroke
			(width 0.0508)
			(type default)
		)
		(layer "In2.Cu")
	)
	(gr_line
		(start 259.568442 -49.129442)
		(end 259.588 -49.149)
		(stroke
			(width 0.0508)
			(type default)
		)
		(layer "In2.Cu")
	)
	(gr_line
		(start 259.568442 -48.838358)
		(end 259.588 -48.8188)
		(stroke
			(width 0.0508)
			(type default)
		)
		(layer "In2.Cu")
	)
	(gr_line
		(start 259.588 -58.166)
		(end 259.787644 -58.166)
		(stroke
			(width 0.06985)
			(type default)
		)
		(layer "In2.Cu")
	)
	(gr_line
		(start 259.588 -49.149)
		(end 259.770626 -49.149)
		(stroke
			(width 0.06985)
			(type default)
		)
		(layer "In2.Cu")
	)
	(gr_line
		(start 259.588 -37.837872)
		(end 259.6007 -37.837872)
		(stroke
			(width 0.06985)
			(type default)
		)
		(layer "In2.Cu")
	)
	(gr_line
		(start 259.602732 -61.17971)
		(end 259.774944 -61.330078)
		(stroke
			(width 0.0508)
			(type default)
		)
		(layer "In2.Cu")
	)
	(gr_line
		(start 259.61086 -43.10634)
		(end 259.653024 -43.148504)
		(stroke
			(width 0.0508)
			(type default)
		)
		(layer "In2.Cu")
	)
	(gr_line
		(start 259.61086 -42.90314)
		(end 259.653024 -42.860976)
		(stroke
			(width 0.0508)
			(type default)
		)
		(layer "In2.Cu")
	)
	(gr_line
		(start 259.622036 -16.91132)
		(end 259.646674 -16.9164)
		(stroke
			(width 0.06985)
			(type default)
		)
		(layer "In2.Cu")
	)
	(gr_line
		(start 259.634736 -45.106336)
		(end 259.680456 -45.152056)
		(stroke
			(width 0.0508)
			(type default)
		)
		(layer "In2.Cu")
	)
	(gr_line
		(start 259.642102 -44.903136)
		(end 259.680456 -44.864782)
		(stroke
			(width 0.0508)
			(type default)
		)
		(layer "In2.Cu")
	)
	(gr_line
		(start 259.64388 -55.90032)
		(end 259.7404 -55.8038)
		(stroke
			(width 0.0508)
			(type default)
		)
		(layer "In2.Cu")
	)
	(gr_line
		(start 259.646674 -16.9164)
		(end 259.671312 -16.91132)
		(stroke
			(width 0.06985)
			(type default)
		)
		(layer "In2.Cu")
	)
	(gr_line
		(start 259.646928 -49.902872)
		(end 259.692902 -49.856898)
		(stroke
			(width 0.0508)
			(type default)
		)
		(layer "In2.Cu")
	)
	(gr_line
		(start 259.648706 -32.027622)
		(end 259.6896 -32.027622)
		(stroke
			(width 0.0508)
			(type default)
		)
		(layer "In2.Cu")
	)
	(gr_line
		(start 259.650484 -31.738316)
		(end 259.691378 -31.697422)
		(stroke
			(width 0.0508)
			(type default)
		)
		(layer "In2.Cu")
	)
	(gr_line
		(start 259.654548 -50.106072)
		(end 259.692902 -50.144426)
		(stroke
			(width 0.0508)
			(type default)
		)
		(layer "In2.Cu")
	)
	(gr_line
		(start 259.654802 -43.150282)
		(end 259.67436 -43.16984)
		(stroke
			(width 0.0508)
			(type default)
		)
		(layer "In2.Cu")
	)
	(gr_line
		(start 259.654802 -42.859198)
		(end 259.67436 -42.83964)
		(stroke
			(width 0.0508)
			(type default)
		)
		(layer "In2.Cu")
	)
	(gr_line
		(start 259.658866 -53.106066)
		(end 259.719064 -53.166264)
		(stroke
			(width 0.0508)
			(type default)
		)
		(layer "In2.Cu")
	)
	(gr_line
		(start 259.662676 -53.900324)
		(end 259.7404 -53.8226)
		(stroke
			(width 0.0508)
			(type default)
		)
		(layer "In2.Cu")
	)
	(gr_line
		(start 259.663946 -51.10607)
		(end 259.713476 -51.1556)
		(stroke
			(width 0.0508)
			(type default)
		)
		(layer "In2.Cu")
	)
	(gr_line
		(start 259.6642 -37.160454)
		(end 259.690362 -37.160454)
		(stroke
			(width 0.06985)
			(type default)
		)
		(layer "In2.Cu")
	)
	(gr_line
		(start 259.68071 -59.108594)
		(end 259.877814 -59.305698)
		(stroke
			(width 0.0508)
			(type default)
		)
		(layer "In2.Cu")
	)
	(gr_line
		(start 259.682234 -45.153834)
		(end 259.688838 -45.160438)
		(stroke
			(width 0.0508)
			(type default)
		)
		(layer "In2.Cu")
	)
	(gr_line
		(start 259.682234 -44.863004)
		(end 259.715 -44.830238)
		(stroke
			(width 0.0508)
			(type default)
		)
		(layer "In2.Cu")
	)
	(gr_line
		(start 259.68833 -50.90287)
		(end 259.718302 -50.872898)
		(stroke
			(width 0.0508)
			(type default)
		)
		(layer "In2.Cu")
	)
	(gr_line
		(start 259.688838 -45.160438)
		(end 259.908802 -45.160438)
		(stroke
			(width 0.06985)
			(type default)
		)
		(layer "In2.Cu")
	)
	(gr_line
		(start 259.691378 -32.027622)
		(end 259.7531 -32.027622)
		(stroke
			(width 0.06985)
			(type default)
		)
		(layer "In2.Cu")
	)
	(gr_line
		(start 259.69468 -50.146204)
		(end 259.713476 -50.165)
		(stroke
			(width 0.0508)
			(type default)
		)
		(layer "In2.Cu")
	)
	(gr_line
		(start 259.69468 -49.85512)
		(end 259.715 -49.8348)
		(stroke
			(width 0.0508)
			(type default)
		)
		(layer "In2.Cu")
	)
	(gr_line
		(start 259.694934 -52.902866)
		(end 259.719064 -52.878736)
		(stroke
			(width 0.0508)
			(type default)
		)
		(layer "In2.Cu")
	)
	(gr_line
		(start 259.71119 -33.096962)
		(end 259.757418 -33.14319)
		(stroke
			(width 0.0508)
			(type default)
		)
		(layer "In2.Cu")
	)
	(gr_line
		(start 259.713476 -51.1556)
		(end 259.95503 -51.1556)
		(stroke
			(width 0.06985)
			(type default)
		)
		(layer "In2.Cu")
	)
	(gr_line
		(start 259.713476 -50.165)
		(end 259.913628 -50.165)
		(stroke
			(width 0.06985)
			(type default)
		)
		(layer "In2.Cu")
	)
	(gr_arc
		(start 259.713476 -46.1518)
		(mid 259.663132 -46.118161)
		(end 259.603748 -46.106334)
		(stroke
			(width 0.0508)
			(type default)
		)
		(layer "In2.Cu")
	)
	(gr_line
		(start 259.71881 -44.106338)
		(end 259.772912 -44.16044)
		(stroke
			(width 0.0508)
			(type default)
		)
		(layer "In2.Cu")
	)
	(gr_line
		(start 259.719318 -32.893762)
		(end 259.757418 -32.855662)
		(stroke
			(width 0.0508)
			(type default)
		)
		(layer "In2.Cu")
	)
	(gr_line
		(start 259.72008 -50.87112)
		(end 259.7658 -50.8254)
		(stroke
			(width 0.0508)
			(type default)
		)
		(layer "In2.Cu")
	)
	(gr_line
		(start 259.720842 -53.168042)
		(end 259.7404 -53.1876)
		(stroke
			(width 0.0508)
			(type default)
		)
		(layer "In2.Cu")
	)
	(gr_line
		(start 259.720842 -52.876958)
		(end 259.7404 -52.8574)
		(stroke
			(width 0.0508)
			(type default)
		)
		(layer "In2.Cu")
	)
	(gr_line
		(start 259.725414 -60.893452)
		(end 259.78358 -60.893452)
		(stroke
			(width 0.0508)
			(type default)
		)
		(layer "In2.Cu")
	)
	(gr_line
		(start 259.7404 -52.8574)
		(end 259.925566 -52.8574)
		(stroke
			(width 0.06985)
			(type default)
		)
		(layer "In2.Cu")
	)
	(gr_line
		(start 259.751576 -55.106062)
		(end 259.807202 -55.161688)
		(stroke
			(width 0.0508)
			(type default)
		)
		(layer "In2.Cu")
	)
	(gr_line
		(start 259.758942 -56.902858)
		(end 259.807202 -56.854598)
		(stroke
			(width 0.0508)
			(type default)
		)
		(layer "In2.Cu")
	)
	(gr_line
		(start 259.759196 -33.144968)
		(end 259.785104 -33.170876)
		(stroke
			(width 0.0508)
			(type default)
		)
		(layer "In2.Cu")
	)
	(gr_line
		(start 259.759196 -32.853884)
		(end 259.772404 -32.840676)
		(stroke
			(width 0.0508)
			(type default)
		)
		(layer "In2.Cu")
	)
	(gr_line
		(start 259.76326 -39.49446)
		(end 259.804154 -39.535354)
		(stroke
			(width 0.0508)
			(type default)
		)
		(layer "In2.Cu")
	)
	(gr_line
		(start 259.765038 -39.205154)
		(end 260.0198 -39.205154)
		(stroke
			(width 0.0508)
			(type default)
		)
		(layer "In2.Cu")
	)
	(gr_line
		(start 259.76834 -54.106064)
		(end 259.815076 -54.1528)
		(stroke
			(width 0.0508)
			(type default)
		)
		(layer "In2.Cu")
	)
	(gr_line
		(start 259.771134 -57.106058)
		(end 259.807202 -57.142126)
		(stroke
			(width 0.0508)
			(type default)
		)
		(layer "In2.Cu")
	)
	(gr_line
		(start 259.772404 -32.840676)
		(end 259.785104 -32.840676)
		(stroke
			(width 0.0508)
			(type default)
		)
		(layer "In2.Cu")
	)
	(gr_line
		(start 259.772912 -44.16044)
		(end 260.04139 -44.16044)
		(stroke
			(width 0.06985)
			(type default)
		)
		(layer "In2.Cu")
	)
	(gr_line
		(start 259.77469 -43.903138)
		(end 259.788914 -43.888914)
		(stroke
			(width 0.0508)
			(type default)
		)
		(layer "In2.Cu")
	)
	(gr_line
		(start 259.7785 -54.902862)
		(end 259.807202 -54.87416)
		(stroke
			(width 0.0508)
			(type default)
		)
		(layer "In2.Cu")
	)
	(gr_line
		(start 259.78358 -60.893452)
		(end 259.820664 -60.930536)
		(stroke
			(width 0.0508)
			(type default)
		)
		(layer "In2.Cu")
	)
	(gr_line
		(start 259.785104 -32.840676)
		(end 259.97789 -32.840676)
		(stroke
			(width 0.06985)
			(type default)
		)
		(layer "In2.Cu")
	)
	(gr_line
		(start 259.787136 -56.10606)
		(end 259.815076 -56.134)
		(stroke
			(width 0.0508)
			(type default)
		)
		(layer "In2.Cu")
	)
	(gr_line
		(start 259.790692 -43.887136)
		(end 259.847588 -43.83024)
		(stroke
			(width 0.0508)
			(type default)
		)
		(layer "In2.Cu")
	)
	(gr_line
		(start 259.804154 -39.535354)
		(end 260.0325 -39.535354)
		(stroke
			(width 0.0508)
			(type default)
		)
		(layer "In2.Cu")
	)
	(gr_line
		(start 259.80898 -57.143904)
		(end 259.815076 -57.15)
		(stroke
			(width 0.0508)
			(type default)
		)
		(layer "In2.Cu")
	)
	(gr_line
		(start 259.80898 -56.85282)
		(end 259.842 -56.8198)
		(stroke
			(width 0.0508)
			(type default)
		)
		(layer "In2.Cu")
	)
	(gr_line
		(start 259.80898 -55.163466)
		(end 259.815076 -55.169562)
		(stroke
			(width 0.0508)
			(type default)
		)
		(layer "In2.Cu")
	)
	(gr_line
		(start 259.80898 -54.872382)
		(end 259.842 -54.839362)
		(stroke
			(width 0.0508)
			(type default)
		)
		(layer "In2.Cu")
	)
	(gr_line
		(start 259.815076 -57.15)
		(end 260.025642 -57.15)
		(stroke
			(width 0.06985)
			(type default)
		)
		(layer "In2.Cu")
	)
	(gr_line
		(start 259.815076 -56.134)
		(end 259.90804 -56.134)
		(stroke
			(width 0.06985)
			(type default)
		)
		(layer "In2.Cu")
	)
	(gr_line
		(start 259.815076 -54.1528)
		(end 259.926836 -54.1528)
		(stroke
			(width 0.06985)
			(type default)
		)
		(layer "In2.Cu")
	)
	(gr_line
		(start 259.820664 -60.930536)
		(end 259.992368 -61.081412)
		(stroke
			(width 0.0508)
			(type default)
		)
		(layer "In2.Cu")
	)
	(gr_line
		(start 259.877814 -59.305698)
		(end 259.887212 -59.34456)
		(stroke
			(width 0.0508)
			(type default)
		)
		(layer "In2.Cu")
	)
	(gr_line
		(start 259.88391 -58.902854)
		(end 259.907786 -58.902854)
		(stroke
			(width 0.0508)
			(type default)
		)
		(layer "In2.Cu")
	)
	(gr_line
		(start 259.887212 -59.34456)
		(end 259.908802 -59.357514)
		(stroke
			(width 0.0508)
			(type default)
		)
		(layer "In2.Cu")
	)
	(gr_line
		(start 259.907786 -58.902854)
		(end 260.079744 -59.074812)
		(stroke
			(width 0.0508)
			(type default)
		)
		(layer "In2.Cu")
	)
	(gr_line
		(start 259.971794 -18.23212)
		(end 259.996432 -18.2372)
		(stroke
			(width 0.06985)
			(type default)
		)
		(layer "In2.Cu")
	)
	(gr_line
		(start 259.996432 -18.2372)
		(end 260.02107 -18.23212)
		(stroke
			(width 0.06985)
			(type default)
		)
		(layer "In2.Cu")
	)
	(gr_line
		(start 260.330696 -89.615264)
		(end 260.332728 -89.619836)
		(stroke
			(width 0.06985)
			(type default)
		)
		(layer "In2.Cu")
	)
	(gr_line
		(start 260.332728 -89.619836)
		(end 260.333236 -89.6239)
		(stroke
			(width 0.06985)
			(type default)
		)
		(layer "In2.Cu")
	)
	(gr_line
		(start 260.360668 -19.52752)
		(end 260.385306 -19.5326)
		(stroke
			(width 0.06985)
			(type default)
		)
		(layer "In2.Cu")
	)
	(gr_line
		(start 260.385306 -19.5326)
		(end 260.409944 -19.52752)
		(stroke
			(width 0.06985)
			(type default)
		)
		(layer "In2.Cu")
	)
	(gr_line
		(start 260.462776 -22.753066)
		(end 260.487414 -22.758146)
		(stroke
			(width 0.06985)
			(type default)
		)
		(layer "In2.Cu")
	)
	(gr_line
		(start 260.487414 -22.758146)
		(end 260.512052 -22.753066)
		(stroke
			(width 0.06985)
			(type default)
		)
		(layer "In2.Cu")
	)
	(gr_line
		(start 260.64591 -20.89912)
		(end 260.670548 -20.9042)
		(stroke
			(width 0.06985)
			(type default)
		)
		(layer "In2.Cu")
	)
	(gr_line
		(start 261.024624 -23.933912)
		(end 261.049262 -23.938992)
		(stroke
			(width 0.06985)
			(type default)
		)
		(layer "In2.Cu")
	)
	(gr_line
		(start 261.031482 -30.369764)
		(end 261.13994 -30.478222)
		(stroke
			(width 0.0508)
			(type default)
		)
		(layer "In2.Cu")
	)
	(gr_line
		(start 261.031482 -30.344364)
		(end 261.031482 -30.369764)
		(stroke
			(width 0.0508)
			(type default)
		)
		(layer "In2.Cu")
	)
	(gr_line
		(start 261.049262 -23.938992)
		(end 261.0739 -23.933912)
		(stroke
			(width 0.06985)
			(type default)
		)
		(layer "In2.Cu")
	)
	(gr_line
		(start 261.141718 -30.48)
		(end 261.183882 -30.522164)
		(stroke
			(width 0.0508)
			(type default)
		)
		(layer "In2.Cu")
	)
	(gr_line
		(start 261.387082 -30.522164)
		(end 261.429246 -30.48)
		(stroke
			(width 0.0508)
			(type default)
		)
		(layer "In2.Cu")
	)
	(gr_line
		(start 261.40918 -25.135586)
		(end 261.430008 -25.139904)
		(stroke
			(width 0.06985)
			(type default)
		)
		(layer "In2.Cu")
	)
	(gr_line
		(start 261.430008 -25.139904)
		(end 261.45109 -25.136094)
		(stroke
			(width 0.06985)
			(type default)
		)
		(layer "In2.Cu")
	)
	(gr_line
		(start 261.431024 -30.478222)
		(end 261.539482 -30.369764)
		(stroke
			(width 0.0508)
			(type default)
		)
		(layer "In2.Cu")
	)
	(gr_line
		(start 261.539482 -30.344364)
		(end 261.539482 -30.369764)
		(stroke
			(width 0.0508)
			(type default)
		)
		(layer "In2.Cu")
	)
	(gr_line
		(start 261.822692 -40.386)
		(end 261.834376 -40.38981)
		(stroke
			(width 0.06985)
			(type default)
		)
		(layer "In2.Cu")
	)
	(gr_line
		(start 261.885176 -39.205154)
		(end 261.892796 -39.20744)
		(stroke
			(width 0.06985)
			(type default)
		)
		(layer "In2.Cu")
	)
	(gr_line
		(start 261.996428 -84.72297)
		(end 262.015986 -84.75091)
		(stroke
			(width 0.06985)
			(type default)
		)
		(layer "In2.Cu")
	)
	(gr_line
		(start 262.000238 -212.711284)
		(end 262.00354 -212.730842)
		(stroke
			(width 0.06985)
			(type default)
		)
		(layer "In2.Cu")
	)
	(gr_line
		(start 262.000238 -212.711284)
		(end 262.00354 -212.692488)
		(stroke
			(width 0.06985)
			(type default)
		)
		(layer "In2.Cu")
	)
	(gr_line
		(start 262.015986 -84.75091)
		(end 262.021828 -84.78393)
		(stroke
			(width 0.06985)
			(type default)
		)
		(layer "In2.Cu")
	)
	(gr_line
		(start 262.37565 -11.85926)
		(end 262.40867 -11.853418)
		(stroke
			(width 0.06985)
			(type default)
		)
		(layer "In2.Cu")
	)
	(gr_line
		(start 262.40867 -11.853418)
		(end 262.43661 -11.83386)
		(stroke
			(width 0.06985)
			(type default)
		)
		(layer "In2.Cu")
	)
	(gr_line
		(start 262.568436 -58.251598)
		(end 262.601456 -58.25744)
		(stroke
			(width 0.06985)
			(type default)
		)
		(layer "In2.Cu")
	)
	(gr_line
		(start 262.601456 -58.25744)
		(end 262.629396 -58.276998)
		(stroke
			(width 0.06985)
			(type default)
		)
		(layer "In2.Cu")
	)
	(gr_line
		(start 262.821674 -15.944596)
		(end 262.846312 -15.949676)
		(stroke
			(width 0.06985)
			(type default)
		)
		(layer "In2.Cu")
	)
	(gr_line
		(start 262.82269 -37.837872)
		(end 262.834628 -37.841936)
		(stroke
			(width 0.06985)
			(type default)
		)
		(layer "In2.Cu")
	)
	(gr_line
		(start 262.893556 -222.294704)
		(end 262.950706 -222.237808)
		(stroke
			(width 0.06985)
			(type default)
		)
		(layer "In2.Cu")
	)
	(gr_line
		(start 262.91413 -36.830254)
		(end 262.920988 -36.83254)
		(stroke
			(width 0.06985)
			(type default)
		)
		(layer "In2.Cu")
	)
	(gr_arc
		(start 262.950706 -222.237808)
		(mid 263.087046 -222.033622)
		(end 263.134856 -221.7928)
		(stroke
			(width 0.06985)
			(type default)
		)
		(layer "In2.Cu")
	)
	(gr_line
		(start 263.171432 -17.265396)
		(end 263.19607 -17.270476)
		(stroke
			(width 0.06985)
			(type default)
		)
		(layer "In2.Cu")
	)
	(gr_line
		(start 263.38784 -13.863574)
		(end 263.452102 -13.852144)
		(stroke
			(width 0.06985)
			(type default)
		)
		(layer "In2.Cu")
	)
	(gr_arc
		(start 263.465056 -221.7928)
		(mid 263.512851 -222.033631)
		(end 263.649206 -222.237808)
		(stroke
			(width 0.06985)
			(type default)
		)
		(layer "In2.Cu")
	)
	(gr_line
		(start 263.520174 -35.570922)
		(end 263.527032 -35.573208)
		(stroke
			(width 0.06985)
			(type default)
		)
		(layer "In2.Cu")
	)
	(gr_line
		(start 263.560306 -18.560796)
		(end 263.584944 -18.565876)
		(stroke
			(width 0.06985)
			(type default)
		)
		(layer "In2.Cu")
	)
	(gr_line
		(start 263.6266 -27.559)
		(end 263.697466 -27.488134)
		(stroke
			(width 0.0635)
			(type default)
		)
		(layer "In2.Cu")
	)
	(gr_line
		(start 263.637268 -21.791676)
		(end 263.661906 -21.786596)
		(stroke
			(width 0.06985)
			(type default)
		)
		(layer "In2.Cu")
	)
	(gr_line
		(start 263.649206 -222.237808)
		(end 263.706356 -222.294704)
		(stroke
			(width 0.06985)
			(type default)
		)
		(layer "In2.Cu")
	)
	(gr_line
		(start 263.661906 -21.786596)
		(end 263.686544 -21.791676)
		(stroke
			(width 0.06985)
			(type default)
		)
		(layer "In2.Cu")
	)
	(gr_line
		(start 263.83996 -32.214312)
		(end 263.85901 -32.218122)
		(stroke
			(width 0.06985)
			(type default)
		)
		(layer "In2.Cu")
	)
	(gr_line
		(start 263.845548 -19.932396)
		(end 263.870186 -19.937476)
		(stroke
			(width 0.06985)
			(type default)
		)
		(layer "In2.Cu")
	)
	(gr_line
		(start 263.85901 -32.218122)
		(end 263.877806 -32.215074)
		(stroke
			(width 0.06985)
			(type default)
		)
		(layer "In2.Cu")
	)
	(gr_line
		(start 264.092436 -14.75994)
		(end 264.143998 -14.748002)
		(stroke
			(width 0.06985)
			(type default)
		)
		(layer "In2.Cu")
	)
	(gr_line
		(start 264.143998 -14.748002)
		(end 264.182098 -14.709902)
		(stroke
			(width 0.06985)
			(type default)
		)
		(layer "In2.Cu")
	)
	(gr_line
		(start 264.197846 -22.972776)
		(end 264.223246 -22.967696)
		(stroke
			(width 0.06985)
			(type default)
		)
		(layer "In2.Cu")
	)
	(gr_line
		(start 264.223246 -22.967696)
		(end 264.24763 -22.972522)
		(stroke
			(width 0.06985)
			(type default)
		)
		(layer "In2.Cu")
	)
	(gr_line
		(start 264.419334 -27.488134)
		(end 264.4902 -27.559)
		(stroke
			(width 0.0635)
			(type default)
		)
		(layer "In2.Cu")
	)
	(gr_line
		(start 264.424668 -57.52846)
		(end 264.457688 -57.534302)
		(stroke
			(width 0.06985)
			(type default)
		)
		(layer "In2.Cu")
	)
	(gr_line
		(start 264.457688 -57.534302)
		(end 264.485628 -57.55386)
		(stroke
			(width 0.06985)
			(type default)
		)
		(layer "In2.Cu")
	)
	(gr_line
		(start 264.954004 -56.603392)
		(end 264.987024 -56.609234)
		(stroke
			(width 0.06985)
			(type default)
		)
		(layer "In2.Cu")
	)
	(gr_line
		(start 264.987024 -56.609234)
		(end 265.014964 -56.628792)
		(stroke
			(width 0.06985)
			(type default)
		)
		(layer "In2.Cu")
	)
	(gr_line
		(start 265.019028 -201.462386)
		(end 265.02233 -201.481436)
		(stroke
			(width 0.06985)
			(type default)
		)
		(layer "In2.Cu")
	)
	(gr_line
		(start 265.019028 -201.462386)
		(end 265.02233 -201.44359)
		(stroke
			(width 0.06985)
			(type default)
		)
		(layer "In2.Cu")
	)
	(gr_line
		(start 265.087354 -24.15921)
		(end 265.10615 -24.155908)
		(stroke
			(width 0.06985)
			(type default)
		)
		(layer "In2.Cu")
	)
	(gr_line
		(start 265.10615 -24.155908)
		(end 265.124946 -24.15921)
		(stroke
			(width 0.06985)
			(type default)
		)
		(layer "In2.Cu")
	)
	(gr_line
		(start 265.276584 -11.560302)
		(end 265.32332 -11.547856)
		(stroke
			(width 0.06985)
			(type default)
		)
		(layer "In2.Cu")
	)
	(gr_line
		(start 265.3538 -27.559)
		(end 265.424666 -27.629866)
		(stroke
			(width 0.0635)
			(type default)
		)
		(layer "In2.Cu")
	)
	(gr_line
		(start 265.358626 -13.066014)
		(end 265.404854 -13.019786)
		(stroke
			(width 0.06985)
			(type default)
		)
		(layer "In2.Cu")
	)
	(gr_line
		(start 265.404854 -13.019786)
		(end 265.469116 -13.008356)
		(stroke
			(width 0.06985)
			(type default)
		)
		(layer "In2.Cu")
	)
	(gr_line
		(start 265.739626 -216.878916)
		(end 265.742928 -216.897966)
		(stroke
			(width 0.06985)
			(type default)
		)
		(layer "In2.Cu")
	)
	(gr_line
		(start 265.739626 -216.878916)
		(end 265.742928 -216.86012)
		(stroke
			(width 0.06985)
			(type default)
		)
		(layer "In2.Cu")
	)
	(gr_line
		(start 265.803634 -11.417554)
		(end 266.477242 -11.235182)
		(stroke
			(width 0.06985)
			(type default)
		)
		(layer "In2.Cu")
	)
	(gr_line
		(start 265.85545 -11.748262)
		(end 266.070588 -11.87196)
		(stroke
			(width 0.06985)
			(type default)
		)
		(layer "In2.Cu")
	)
	(gr_line
		(start 265.996674 -16.9164)
		(end 266.021312 -16.91132)
		(stroke
			(width 0.06985)
			(type default)
		)
		(layer "In2.Cu")
	)
	(gr_line
		(start 266.009882 -33.780984)
		(end 266.03071 -33.785302)
		(stroke
			(width 0.06985)
			(type default)
		)
		(layer "In2.Cu")
	)
	(gr_line
		(start 266.03071 -33.785302)
		(end 266.051792 -33.781492)
		(stroke
			(width 0.06985)
			(type default)
		)
		(layer "In2.Cu")
	)
	(gr_line
		(start 266.056364 -9.299448)
		(end 266.092432 -9.274048)
		(stroke
			(width 0.06985)
			(type default)
		)
		(layer "In2.Cu")
	)
	(gr_line
		(start 266.070588 -11.87196)
		(end 266.47521 -11.762232)
		(stroke
			(width 0.06985)
			(type default)
		)
		(layer "In2.Cu")
	)
	(gr_line
		(start 266.092432 -9.274048)
		(end 266.11199 -9.23417)
		(stroke
			(width 0.06985)
			(type default)
		)
		(layer "In2.Cu")
	)
	(gr_line
		(start 266.093702 -222.294704)
		(end 266.150852 -222.237808)
		(stroke
			(width 0.06985)
			(type default)
		)
		(layer "In2.Cu")
	)
	(gr_line
		(start 266.146534 -27.629866)
		(end 266.2174 -27.559)
		(stroke
			(width 0.0635)
			(type default)
		)
		(layer "In2.Cu")
	)
	(gr_arc
		(start 266.150852 -222.237808)
		(mid 266.287189 -222.033622)
		(end 266.335002 -221.7928)
		(stroke
			(width 0.06985)
			(type default)
		)
		(layer "In2.Cu")
	)
	(gr_line
		(start 266.16152 -55.434484)
		(end 266.19454 -55.440326)
		(stroke
			(width 0.06985)
			(type default)
		)
		(layer "In2.Cu")
	)
	(gr_line
		(start 266.19454 -55.440326)
		(end 266.22248 -55.459884)
		(stroke
			(width 0.06985)
			(type default)
		)
		(layer "In2.Cu")
	)
	(gr_line
		(start 266.33043 -19.451574)
		(end 266.355068 -19.456654)
		(stroke
			(width 0.06985)
			(type default)
		)
		(layer "In2.Cu")
	)
	(gr_line
		(start 266.346432 -18.2372)
		(end 266.37107 -18.23212)
		(stroke
			(width 0.06985)
			(type default)
		)
		(layer "In2.Cu")
	)
	(gr_line
		(start 266.355068 -19.456654)
		(end 266.379706 -19.451574)
		(stroke
			(width 0.06985)
			(type default)
		)
		(layer "In2.Cu")
	)
	(gr_line
		(start 266.47521 -11.762232)
		(end 266.598908 -11.547094)
		(stroke
			(width 0.06985)
			(type default)
		)
		(layer "In2.Cu")
	)
	(gr_line
		(start 266.632182 -36.8554)
		(end 266.672822 -36.867592)
		(stroke
			(width 0.06985)
			(type default)
		)
		(layer "In2.Cu")
	)
	(gr_arc
		(start 266.665202 -221.7928)
		(mid 266.712993 -222.033634)
		(end 266.849352 -222.237808)
		(stroke
			(width 0.06985)
			(type default)
		)
		(layer "In2.Cu")
	)
	(gr_line
		(start 266.66698 -54.350158)
		(end 266.7 -54.356)
		(stroke
			(width 0.06985)
			(type default)
		)
		(layer "In2.Cu")
	)
	(gr_line
		(start 266.672822 -36.867592)
		(end 266.714224 -36.85921)
		(stroke
			(width 0.06985)
			(type default)
		)
		(layer "In2.Cu")
	)
	(gr_line
		(start 266.7 -54.356)
		(end 266.72794 -54.375558)
		(stroke
			(width 0.06985)
			(type default)
		)
		(layer "In2.Cu")
	)
	(gr_line
		(start 266.849352 -222.237808)
		(end 266.906502 -222.294704)
		(stroke
			(width 0.06985)
			(type default)
		)
		(layer "In2.Cu")
	)
	(gr_line
		(start 266.866116 -22.764242)
		(end 266.887198 -22.760432)
		(stroke
			(width 0.06985)
			(type default)
		)
		(layer "In2.Cu")
	)
	(gr_line
		(start 266.895834 -65.933828)
		(end 266.911328 -65.94475)
		(stroke
			(width 0.06985)
			(type default)
		)
		(layer "In2.Cu")
	)
	(gr_line
		(start 266.911328 -65.94475)
		(end 266.92225 -65.960244)
		(stroke
			(width 0.06985)
			(type default)
		)
		(layer "In2.Cu")
	)
	(gr_line
		(start 266.956032 -11.105642)
		(end 267.626592 -10.924286)
		(stroke
			(width 0.06985)
			(type default)
		)
		(layer "In2.Cu")
	)
	(gr_line
		(start 266.99591 -20.89912)
		(end 267.020548 -20.9042)
		(stroke
			(width 0.06985)
			(type default)
		)
		(layer "In2.Cu")
	)
	(gr_line
		(start 267.007594 -11.43635)
		(end 267.222986 -11.559794)
		(stroke
			(width 0.06985)
			(type default)
		)
		(layer "In2.Cu")
	)
	(gr_line
		(start 267.020548 -20.9042)
		(end 267.045186 -20.89912)
		(stroke
			(width 0.06985)
			(type default)
		)
		(layer "In2.Cu")
	)
	(gr_line
		(start 267.19784 -35.365944)
		(end 267.218668 -35.370262)
		(stroke
			(width 0.06985)
			(type default)
		)
		(layer "In2.Cu")
	)
	(gr_line
		(start 267.218668 -35.370262)
		(end 267.23975 -35.366452)
		(stroke
			(width 0.06985)
			(type default)
		)
		(layer "In2.Cu")
	)
	(gr_line
		(start 267.222986 -11.559794)
		(end 267.627608 -11.45032)
		(stroke
			(width 0.06985)
			(type default)
		)
		(layer "In2.Cu")
	)
	(gr_line
		(start 267.30198 -53.334158)
		(end 267.335 -53.34)
		(stroke
			(width 0.06985)
			(type default)
		)
		(layer "In2.Cu")
	)
	(gr_line
		(start 267.335 -53.34)
		(end 267.36294 -53.359558)
		(stroke
			(width 0.06985)
			(type default)
		)
		(layer "In2.Cu")
	)
	(gr_line
		(start 267.627608 -11.45032)
		(end 267.750798 -11.235182)
		(stroke
			(width 0.06985)
			(type default)
		)
		(layer "In2.Cu")
	)
	(gr_line
		(start 267.649706 -5.634736)
		(end 267.722858 -5.546852)
		(stroke
			(width 0.06985)
			(type default)
		)
		(layer "In2.Cu")
	)
	(gr_line
		(start 268.233144 -52.203096)
		(end 268.266164 -52.208938)
		(stroke
			(width 0.06985)
			(type default)
		)
		(layer "In2.Cu")
	)
	(gr_line
		(start 268.266164 -52.208938)
		(end 268.294104 -52.228496)
		(stroke
			(width 0.06985)
			(type default)
		)
		(layer "In2.Cu")
	)
	(gr_line
		(start 268.360398 -11.067542)
		(end 268.407134 -11.055096)
		(stroke
			(width 0.06985)
			(type default)
		)
		(layer "In2.Cu")
	)
	(gr_line
		(start 268.4399 -12.820142)
		(end 268.473936 -12.814046)
		(stroke
			(width 0.06985)
			(type default)
		)
		(layer "In2.Cu")
	)
	(gr_line
		(start 268.473936 -12.814046)
		(end 268.501876 -12.794234)
		(stroke
			(width 0.06985)
			(type default)
		)
		(layer "In2.Cu")
	)
	(gr_line
		(start 268.539722 -10.358628)
		(end 268.539722 -10.455148)
		(stroke
			(width 0.06985)
			(type default)
		)
		(layer "In2.Cu")
	)
	(gr_line
		(start 268.585442 -91.41206)
		(end 268.605 -91.44)
		(stroke
			(width 0.06985)
			(type default)
		)
		(layer "In2.Cu")
	)
	(gr_line
		(start 268.605 -91.44)
		(end 268.610842 -91.47302)
		(stroke
			(width 0.06985)
			(type default)
		)
		(layer "In2.Cu")
	)
	(gr_line
		(start 268.773148 -10.688828)
		(end 268.773402 -10.688828)
		(stroke
			(width 0.06985)
			(type default)
		)
		(layer "In2.Cu")
	)
	(gr_line
		(start 268.798294 -16.019272)
		(end 268.822932 -16.024352)
		(stroke
			(width 0.06985)
			(type default)
		)
		(layer "In2.Cu")
	)
	(gr_line
		(start 268.826742 -64.902842)
		(end 268.842236 -64.913764)
		(stroke
			(width 0.06985)
			(type default)
		)
		(layer "In2.Cu")
	)
	(gr_line
		(start 268.842236 -64.913764)
		(end 268.853158 -64.929258)
		(stroke
			(width 0.06985)
			(type default)
		)
		(layer "In2.Cu")
	)
	(gr_line
		(start 268.925294 -51.33467)
		(end 268.958314 -51.340512)
		(stroke
			(width 0.06985)
			(type default)
		)
		(layer "In2.Cu")
	)
	(gr_line
		(start 268.958314 -51.340512)
		(end 268.986254 -51.36007)
		(stroke
			(width 0.06985)
			(type default)
		)
		(layer "In2.Cu")
	)
	(gr_line
		(start 269.341092 -20.103338)
		(end 269.36573 -20.098258)
		(stroke
			(width 0.06985)
			(type default)
		)
		(layer "In2.Cu")
	)
	(gr_line
		(start 269.34414 -50.397918)
		(end 269.37716 -50.40376)
		(stroke
			(width 0.06985)
			(type default)
		)
		(layer "In2.Cu")
	)
	(gr_line
		(start 269.36573 -20.098258)
		(end 269.390368 -20.103338)
		(stroke
			(width 0.06985)
			(type default)
		)
		(layer "In2.Cu")
	)
	(gr_line
		(start 269.373604 -5.947156)
		(end 269.5448 -6.118352)
		(stroke
			(width 0.06985)
			(type default)
		)
		(layer "In2.Cu")
	)
	(gr_line
		(start 269.373604 -5.476748)
		(end 269.5448 -5.305552)
		(stroke
			(width 0.06985)
			(type default)
		)
		(layer "In2.Cu")
	)
	(gr_line
		(start 269.37716 -50.40376)
		(end 269.4051 -50.423318)
		(stroke
			(width 0.06985)
			(type default)
		)
		(layer "In2.Cu")
	)
	(gr_line
		(start 269.521432 -17.265396)
		(end 269.54607 -17.270476)
		(stroke
			(width 0.06985)
			(type default)
		)
		(layer "In2.Cu")
	)
	(gr_line
		(start 269.848584 -43.388788)
		(end 269.887192 -43.401488)
		(stroke
			(width 0.06985)
			(type default)
		)
		(layer "In2.Cu")
	)
	(gr_line
		(start 269.855442 -91.15806)
		(end 269.875 -91.186)
		(stroke
			(width 0.06985)
			(type default)
		)
		(layer "In2.Cu")
	)
	(gr_line
		(start 269.875 -91.186)
		(end 269.880842 -91.21902)
		(stroke
			(width 0.06985)
			(type default)
		)
		(layer "In2.Cu")
	)
	(gr_line
		(start 269.887192 -43.401488)
		(end 269.927578 -43.395138)
		(stroke
			(width 0.06985)
			(type default)
		)
		(layer "In2.Cu")
	)
	(gr_line
		(start 269.983712 -42.001694)
		(end 270.023336 -42.013886)
		(stroke
			(width 0.06985)
			(type default)
		)
		(layer "In2.Cu")
	)
	(gr_line
		(start 270.011652 -49.07026)
		(end 270.044672 -49.076102)
		(stroke
			(width 0.06985)
			(type default)
		)
		(layer "In2.Cu")
	)
	(gr_line
		(start 270.023336 -42.013886)
		(end 270.064484 -42.005504)
		(stroke
			(width 0.06985)
			(type default)
		)
		(layer "In2.Cu")
	)
	(gr_line
		(start 270.044672 -49.076102)
		(end 270.072612 -49.09566)
		(stroke
			(width 0.06985)
			(type default)
		)
		(layer "In2.Cu")
	)
	(gr_line
		(start 270.084804 -18.374106)
		(end 270.109442 -18.369026)
		(stroke
			(width 0.06985)
			(type default)
		)
		(layer "In2.Cu")
	)
	(gr_line
		(start 270.096742 -63.505842)
		(end 270.112236 -63.516764)
		(stroke
			(width 0.06985)
			(type default)
		)
		(layer "In2.Cu")
	)
	(gr_line
		(start 270.109442 -18.369026)
		(end 270.13408 -18.374106)
		(stroke
			(width 0.06985)
			(type default)
		)
		(layer "In2.Cu")
	)
	(gr_line
		(start 270.112236 -63.516764)
		(end 270.123158 -63.532258)
		(stroke
			(width 0.06985)
			(type default)
		)
		(layer "In2.Cu")
	)
	(gr_line
		(start 270.516604 -8.995156)
		(end 270.6878 -9.166352)
		(stroke
			(width 0.06985)
			(type default)
		)
		(layer "In2.Cu")
	)
	(gr_line
		(start 270.516604 -8.524748)
		(end 270.6878 -8.353552)
		(stroke
			(width 0.06985)
			(type default)
		)
		(layer "In2.Cu")
	)
	(gr_line
		(start 270.60144 -40.758618)
		(end 270.646906 -40.773604)
		(stroke
			(width 0.06985)
			(type default)
		)
		(layer "In2.Cu")
	)
	(gr_line
		(start 270.646906 -40.773604)
		(end 270.693896 -40.764206)
		(stroke
			(width 0.06985)
			(type default)
		)
		(layer "In2.Cu")
	)
	(gr_line
		(start 270.683482 -47.631604)
		(end 270.716502 -47.637446)
		(stroke
			(width 0.06985)
			(type default)
		)
		(layer "In2.Cu")
	)
	(gr_line
		(start 270.716502 -47.637446)
		(end 270.744442 -47.657004)
		(stroke
			(width 0.06985)
			(type default)
		)
		(layer "In2.Cu")
	)
	(gr_line
		(start 271.036288 -39.64305)
		(end 271.078706 -39.656004)
		(stroke
			(width 0.06985)
			(type default)
		)
		(layer "In2.Cu")
	)
	(gr_line
		(start 271.078706 -39.656004)
		(end 271.121886 -39.647368)
		(stroke
			(width 0.06985)
			(type default)
		)
		(layer "In2.Cu")
	)
	(gr_line
		(start 271.125442 -90.77706)
		(end 271.145 -90.805)
		(stroke
			(width 0.06985)
			(type default)
		)
		(layer "In2.Cu")
	)
	(gr_line
		(start 271.127982 -46.71822)
		(end 271.161002 -46.724062)
		(stroke
			(width 0.06985)
			(type default)
		)
		(layer "In2.Cu")
	)
	(gr_line
		(start 271.145 -90.805)
		(end 271.150842 -90.83802)
		(stroke
			(width 0.06985)
			(type default)
		)
		(layer "In2.Cu")
	)
	(gr_line
		(start 271.161002 -46.724062)
		(end 271.188942 -46.74362)
		(stroke
			(width 0.06985)
			(type default)
		)
		(layer "In2.Cu")
	)
	(gr_line
		(start 271.485868 -21.61413)
		(end 271.504664 -21.610828)
		(stroke
			(width 0.06985)
			(type default)
		)
		(layer "In2.Cu")
	)
	(gr_line
		(start 271.504664 -21.610828)
		(end 271.52346 -21.61413)
		(stroke
			(width 0.06985)
			(type default)
		)
		(layer "In2.Cu")
	)
	(gr_line
		(start 271.592802 -62.530228)
		(end 271.608296 -62.54115)
		(stroke
			(width 0.06985)
			(type default)
		)
		(layer "In2.Cu")
	)
	(gr_line
		(start 271.595596 -201.070464)
		(end 271.598898 -201.089514)
		(stroke
			(width 0.06985)
			(type default)
		)
		(layer "In2.Cu")
	)
	(gr_line
		(start 271.595596 -201.070464)
		(end 271.598898 -201.051668)
		(stroke
			(width 0.06985)
			(type default)
		)
		(layer "In2.Cu")
	)
	(gr_line
		(start 271.608296 -62.54115)
		(end 271.619218 -62.556644)
		(stroke
			(width 0.06985)
			(type default)
		)
		(layer "In2.Cu")
	)
	(gr_line
		(start 271.760442 -72.87006)
		(end 271.78 -72.898)
		(stroke
			(width 0.06985)
			(type default)
		)
		(layer "In2.Cu")
	)
	(gr_line
		(start 271.78 -72.898)
		(end 271.785842 -72.93102)
		(stroke
			(width 0.06985)
			(type default)
		)
		(layer "In2.Cu")
	)
	(gr_line
		(start 271.946116 -45.862494)
		(end 271.983454 -45.869098)
		(stroke
			(width 0.06985)
			(type default)
		)
		(layer "In2.Cu")
	)
	(gr_line
		(start 271.983454 -45.869098)
		(end 272.013426 -45.89145)
		(stroke
			(width 0.06985)
			(type default)
		)
		(layer "In2.Cu")
	)
	(gr_line
		(start 272.058892 -44.89196)
		(end 272.091912 -44.897802)
		(stroke
			(width 0.06985)
			(type default)
		)
		(layer "In2.Cu")
	)
	(gr_line
		(start 272.091912 -44.897802)
		(end 272.119852 -44.91736)
		(stroke
			(width 0.06985)
			(type default)
		)
		(layer "In2.Cu")
	)
	(gr_line
		(start 272.183098 -156.863796)
		(end 272.183098 -156.86405)
		(stroke
			(width 0.06985)
			(type default)
		)
		(layer "In2.Cu")
	)
	(gr_line
		(start 272.183098 -156.863796)
		(end 272.1864 -156.845)
		(stroke
			(width 0.06985)
			(type default)
		)
		(layer "In2.Cu")
	)
	(gr_line
		(start 272.183098 -156.826204)
		(end 272.1864 -156.845)
		(stroke
			(width 0.06985)
			(type default)
		)
		(layer "In2.Cu")
	)
	(gr_line
		(start 272.437352 -215.108536)
		(end 272.440654 -215.127586)
		(stroke
			(width 0.06985)
			(type default)
		)
		(layer "In2.Cu")
	)
	(gr_line
		(start 272.437352 -215.108536)
		(end 272.440654 -215.08974)
		(stroke
			(width 0.06985)
			(type default)
		)
		(layer "In2.Cu")
	)
	(gr_line
		(start 272.467832 -21.05533)
		(end 272.48866 -21.059648)
		(stroke
			(width 0.06985)
			(type default)
		)
		(layer "In2.Cu")
	)
	(gr_line
		(start 272.48866 -21.059648)
		(end 272.509742 -21.055838)
		(stroke
			(width 0.06985)
			(type default)
		)
		(layer "In2.Cu")
	)
	(gr_line
		(start 272.49374 -222.294704)
		(end 272.55089 -222.237808)
		(stroke
			(width 0.06985)
			(type default)
		)
		(layer "In2.Cu")
	)
	(gr_arc
		(start 272.55089 -222.237808)
		(mid 272.68723 -222.033622)
		(end 272.73504 -221.7928)
		(stroke
			(width 0.06985)
			(type default)
		)
		(layer "In2.Cu")
	)
	(gr_line
		(start 272.623026 -90.833702)
		(end 272.642584 -90.861642)
		(stroke
			(width 0.06985)
			(type default)
		)
		(layer "In2.Cu")
	)
	(gr_line
		(start 272.642584 -90.861642)
		(end 272.648426 -90.894662)
		(stroke
			(width 0.06985)
			(type default)
		)
		(layer "In2.Cu")
	)
	(gr_arc
		(start 273.06524 -221.9198)
		(mid 273.130803 -222.142709)
		(end 273.30654 -222.294704)
		(stroke
			(width 0.06985)
			(type default)
		)
		(layer "In2.Cu")
	)
	(gr_line
		(start 273.081242 -18.313908)
		(end 273.10207 -18.318226)
		(stroke
			(width 0.06985)
			(type default)
		)
		(layer "In2.Cu")
	)
	(gr_line
		(start 273.10207 -18.318226)
		(end 273.123152 -18.314416)
		(stroke
			(width 0.06985)
			(type default)
		)
		(layer "In2.Cu")
	)
	(gr_line
		(start 273.199098 -208.298796)
		(end 273.199098 -208.29905)
		(stroke
			(width 0.06985)
			(type default)
		)
		(layer "In2.Cu")
	)
	(gr_line
		(start 273.199098 -208.298796)
		(end 273.2024 -208.28)
		(stroke
			(width 0.06985)
			(type default)
		)
		(layer "In2.Cu")
	)
	(gr_line
		(start 273.199098 -208.261204)
		(end 273.2024 -208.28)
		(stroke
			(width 0.06985)
			(type default)
		)
		(layer "In2.Cu")
	)
	(gr_line
		(start 273.33321 -218.324176)
		(end 273.33321 -218.32443)
		(stroke
			(width 0.06985)
			(type default)
		)
		(layer "In2.Cu")
	)
	(gr_line
		(start 273.33321 -218.324176)
		(end 273.336512 -218.30538)
		(stroke
			(width 0.06985)
			(type default)
		)
		(layer "In2.Cu")
	)
	(gr_line
		(start 273.33321 -218.286584)
		(end 273.336512 -218.30538)
		(stroke
			(width 0.06985)
			(type default)
		)
		(layer "In2.Cu")
	)
	(gr_line
		(start 273.36877 -62.478158)
		(end 273.384264 -62.48908)
		(stroke
			(width 0.06985)
			(type default)
		)
		(layer "In2.Cu")
	)
	(gr_line
		(start 273.369024 -17.270222)
		(end 273.390106 -17.266412)
		(stroke
			(width 0.06985)
			(type default)
		)
		(layer "In2.Cu")
	)
	(gr_line
		(start 273.384264 -62.48908)
		(end 273.395186 -62.504574)
		(stroke
			(width 0.06985)
			(type default)
		)
		(layer "In2.Cu")
	)
	(gr_line
		(start 273.680428 -19.419824)
		(end 273.701256 -19.424142)
		(stroke
			(width 0.06985)
			(type default)
		)
		(layer "In2.Cu")
	)
	(gr_line
		(start 273.701256 -19.424142)
		(end 273.722338 -19.420332)
		(stroke
			(width 0.06985)
			(type default)
		)
		(layer "In2.Cu")
	)
	(gr_line
		(start 273.931888 -22.374352)
		(end 273.950684 -22.377654)
		(stroke
			(width 0.06985)
			(type default)
		)
		(layer "In2.Cu")
	)
	(gr_line
		(start 273.950684 -22.377654)
		(end 273.96948 -22.374352)
		(stroke
			(width 0.06985)
			(type default)
		)
		(layer "In2.Cu")
	)
	(gr_line
		(start 273.971766 -152.594056)
		(end 273.971766 -152.59431)
		(stroke
			(width 0.06985)
			(type default)
		)
		(layer "In2.Cu")
	)
	(gr_line
		(start 273.971766 -152.594056)
		(end 273.975068 -152.57526)
		(stroke
			(width 0.06985)
			(type default)
		)
		(layer "In2.Cu")
	)
	(gr_line
		(start 273.971766 -152.556464)
		(end 273.975068 -152.57526)
		(stroke
			(width 0.06985)
			(type default)
		)
		(layer "In2.Cu")
	)
	(gr_line
		(start 274.03806 -196.89191)
		(end 274.041362 -196.91096)
		(stroke
			(width 0.06985)
			(type default)
		)
		(layer "In2.Cu")
	)
	(gr_line
		(start 274.03806 -196.89191)
		(end 274.041362 -196.873114)
		(stroke
			(width 0.06985)
			(type default)
		)
		(layer "In2.Cu")
	)
	(gr_line
		(start 274.211288 -25.282652)
		(end 274.231862 -25.286716)
		(stroke
			(width 0.06985)
			(type default)
		)
		(layer "In2.Cu")
	)
	(gr_line
		(start 274.231862 -25.286716)
		(end 274.252944 -25.282906)
		(stroke
			(width 0.06985)
			(type default)
		)
		(layer "In2.Cu")
	)
	(gr_line
		(start 274.34921 -8.237982)
		(end 274.427696 -8.182102)
		(stroke
			(width 0.06985)
			(type default)
		)
		(layer "In2.Cu")
	)
	(gr_line
		(start 274.3835 -61.174122)
		(end 274.398994 -61.185044)
		(stroke
			(width 0.06985)
			(type default)
		)
		(layer "In2.Cu")
	)
	(gr_line
		(start 274.388326 -72.834246)
		(end 274.407884 -72.862186)
		(stroke
			(width 0.06985)
			(type default)
		)
		(layer "In2.Cu")
	)
	(gr_line
		(start 274.398994 -61.185044)
		(end 274.409916 -61.200538)
		(stroke
			(width 0.06985)
			(type default)
		)
		(layer "In2.Cu")
	)
	(gr_line
		(start 274.407884 -72.862186)
		(end 274.413726 -72.895206)
		(stroke
			(width 0.06985)
			(type default)
		)
		(layer "In2.Cu")
	)
	(gr_line
		(start 274.427696 -8.182102)
		(end 274.523708 -8.19912)
		(stroke
			(width 0.06985)
			(type default)
		)
		(layer "In2.Cu")
	)
	(gr_line
		(start 274.674838 -17.039844)
		(end 274.707858 -17.034002)
		(stroke
			(width 0.06985)
			(type default)
		)
		(layer "In2.Cu")
	)
	(gr_line
		(start 274.707858 -17.034002)
		(end 274.735798 -17.014444)
		(stroke
			(width 0.06985)
			(type default)
		)
		(layer "In2.Cu")
	)
	(gr_line
		(start 275.438616 -216.196926)
		(end 275.441918 -216.215976)
		(stroke
			(width 0.06985)
			(type default)
		)
		(layer "In2.Cu")
	)
	(gr_line
		(start 275.438616 -216.196926)
		(end 275.441918 -216.17813)
		(stroke
			(width 0.06985)
			(type default)
		)
		(layer "In2.Cu")
	)
	(gr_line
		(start 275.633434 -60.611004)
		(end 275.648928 -60.621926)
		(stroke
			(width 0.06985)
			(type default)
		)
		(layer "In2.Cu")
	)
	(gr_line
		(start 275.648928 -60.621926)
		(end 275.65985 -60.63742)
		(stroke
			(width 0.06985)
			(type default)
		)
		(layer "In2.Cu")
	)
	(gr_line
		(start 275.693632 -222.294704)
		(end 275.750782 -222.237808)
		(stroke
			(width 0.06985)
			(type default)
		)
		(layer "In2.Cu")
	)
	(gr_line
		(start 275.747734 -71.565008)
		(end 275.767292 -71.592948)
		(stroke
			(width 0.06985)
			(type default)
		)
		(layer "In2.Cu")
	)
	(gr_arc
		(start 275.750782 -222.237808)
		(mid 275.887112 -222.03362)
		(end 275.934932 -221.7928)
		(stroke
			(width 0.06985)
			(type default)
		)
		(layer "In2.Cu")
	)
	(gr_line
		(start 275.767292 -71.592948)
		(end 275.773134 -71.625968)
		(stroke
			(width 0.06985)
			(type default)
		)
		(layer "In2.Cu")
	)
	(gr_line
		(start 275.999702 -42.107866)
		(end 276.014942 -42.105326)
		(stroke
			(width 0.06985)
			(type default)
		)
		(layer "In2.Cu")
	)
	(gr_line
		(start 276.014942 -42.105326)
		(end 276.03069 -42.10812)
		(stroke
			(width 0.06985)
			(type default)
		)
		(layer "In2.Cu")
	)
	(gr_line
		(start 276.22119 -8.83412)
		(end 276.239986 -8.837422)
		(stroke
			(width 0.06985)
			(type default)
		)
		(layer "In2.Cu")
	)
	(gr_line
		(start 276.239986 -8.837422)
		(end 276.258782 -8.83412)
		(stroke
			(width 0.06985)
			(type default)
		)
		(layer "In2.Cu")
	)
	(gr_arc
		(start 276.265132 -221.7928)
		(mid 276.312925 -222.033632)
		(end 276.449282 -222.237808)
		(stroke
			(width 0.06985)
			(type default)
		)
		(layer "In2.Cu")
	)
	(gr_line
		(start 276.344634 -40.412924)
		(end 276.369272 -40.407844)
		(stroke
			(width 0.06985)
			(type default)
		)
		(layer "In2.Cu")
	)
	(gr_line
		(start 276.369272 -40.407844)
		(end 276.39391 -40.412924)
		(stroke
			(width 0.06985)
			(type default)
		)
		(layer "In2.Cu")
	)
	(gr_line
		(start 276.449282 -222.237808)
		(end 276.506432 -222.294704)
		(stroke
			(width 0.06985)
			(type default)
		)
		(layer "In2.Cu")
	)
	(gr_line
		(start 276.56663 -59.804046)
		(end 276.582124 -59.814968)
		(stroke
			(width 0.06985)
			(type default)
		)
		(layer "In2.Cu")
	)
	(gr_line
		(start 276.582124 -59.814968)
		(end 276.593046 -59.830462)
		(stroke
			(width 0.06985)
			(type default)
		)
		(layer "In2.Cu")
	)
	(gr_line
		(start 276.814026 -15.559278)
		(end 276.82952 -15.548356)
		(stroke
			(width 0.06985)
			(type default)
		)
		(layer "In2.Cu")
	)
	(gr_line
		(start 276.82952 -15.548356)
		(end 276.840442 -15.532862)
		(stroke
			(width 0.06985)
			(type default)
		)
		(layer "In2.Cu")
	)
	(gr_line
		(start 276.916134 -21.519388)
		(end 276.93493 -21.516086)
		(stroke
			(width 0.06985)
			(type default)
		)
		(layer "In2.Cu")
	)
	(gr_line
		(start 276.93493 -21.516086)
		(end 276.953726 -21.519388)
		(stroke
			(width 0.06985)
			(type default)
		)
		(layer "In2.Cu")
	)
	(gr_line
		(start 276.972268 -39.17188)
		(end 276.996906 -39.1668)
		(stroke
			(width 0.06985)
			(type default)
		)
		(layer "In2.Cu")
	)
	(gr_line
		(start 276.996906 -39.1668)
		(end 277.021544 -39.17188)
		(stroke
			(width 0.06985)
			(type default)
		)
		(layer "In2.Cu")
	)
	(gr_line
		(start 277.09114 -19.912584)
		(end 277.109936 -19.909282)
		(stroke
			(width 0.06985)
			(type default)
		)
		(layer "In2.Cu")
	)
	(gr_line
		(start 277.109936 -19.909282)
		(end 277.12924 -19.912584)
		(stroke
			(width 0.06985)
			(type default)
		)
		(layer "In2.Cu")
	)
	(gr_line
		(start 277.404068 -38.05428)
		(end 277.428706 -38.0492)
		(stroke
			(width 0.06985)
			(type default)
		)
		(layer "In2.Cu")
	)
	(gr_line
		(start 277.428706 -38.0492)
		(end 277.453344 -38.05428)
		(stroke
			(width 0.06985)
			(type default)
		)
		(layer "In2.Cu")
	)
	(gr_line
		(start 277.460456 -58.646822)
		(end 277.47595 -58.657744)
		(stroke
			(width 0.06985)
			(type default)
		)
		(layer "In2.Cu")
	)
	(gr_line
		(start 277.47595 -58.657744)
		(end 277.486872 -58.673238)
		(stroke
			(width 0.06985)
			(type default)
		)
		(layer "In2.Cu")
	)
	(gr_line
		(start 277.63597 -24.350726)
		(end 277.654766 -24.347424)
		(stroke
			(width 0.06985)
			(type default)
		)
		(layer "In2.Cu")
	)
	(gr_line
		(start 277.654766 -24.347424)
		(end 277.673562 -24.350726)
		(stroke
			(width 0.06985)
			(type default)
		)
		(layer "In2.Cu")
	)
	(gr_line
		(start 277.746968 -14.238478)
		(end 277.766526 -14.210538)
		(stroke
			(width 0.06985)
			(type default)
		)
		(layer "In2.Cu")
	)
	(gr_line
		(start 277.766526 -14.210538)
		(end 277.772368 -14.177518)
		(stroke
			(width 0.06985)
			(type default)
		)
		(layer "In2.Cu")
	)
	(gr_line
		(start 277.802594 -17.489424)
		(end 277.835614 -17.483582)
		(stroke
			(width 0.06985)
			(type default)
		)
		(layer "In2.Cu")
	)
	(gr_line
		(start 277.835614 -17.483582)
		(end 277.863554 -17.464024)
		(stroke
			(width 0.06985)
			(type default)
		)
		(layer "In2.Cu")
	)
	(gr_line
		(start 278.044148 -10.73277)
		(end 278.050244 -10.698734)
		(stroke
			(width 0.06985)
			(type default)
		)
		(layer "In2.Cu")
	)
	(gr_line
		(start 278.050244 -10.698734)
		(end 278.069802 -10.670794)
		(stroke
			(width 0.06985)
			(type default)
		)
		(layer "In2.Cu")
	)
	(gr_line
		(start 278.176228 -33.439608)
		(end 278.200104 -33.43529)
		(stroke
			(width 0.06985)
			(type default)
		)
		(layer "In2.Cu")
	)
	(gr_line
		(start 278.200104 -33.43529)
		(end 278.220678 -33.42259)
		(stroke
			(width 0.06985)
			(type default)
		)
		(layer "In2.Cu")
	)
	(gr_line
		(start 278.284178 -72.075548)
		(end 278.303736 -72.103488)
		(stroke
			(width 0.06985)
			(type default)
		)
		(layer "In2.Cu")
	)
	(gr_line
		(start 278.303736 -72.103488)
		(end 278.309578 -72.136508)
		(stroke
			(width 0.06985)
			(type default)
		)
		(layer "In2.Cu")
	)
	(gr_line
		(start 278.454866 -8.44677)
		(end 278.487886 -8.440928)
		(stroke
			(width 0.06985)
			(type default)
		)
		(layer "In2.Cu")
	)
	(gr_line
		(start 278.471122 -206.8195)
		(end 278.474424 -206.83855)
		(stroke
			(width 0.06985)
			(type default)
		)
		(layer "In2.Cu")
	)
	(gr_line
		(start 278.471122 -206.8195)
		(end 278.474424 -206.800704)
		(stroke
			(width 0.06985)
			(type default)
		)
		(layer "In2.Cu")
	)
	(gr_line
		(start 278.487886 -8.440928)
		(end 278.515318 -8.421878)
		(stroke
			(width 0.06985)
			(type default)
		)
		(layer "In2.Cu")
	)
	(gr_line
		(start 278.496522 -58.019188)
		(end 278.512016 -58.03011)
		(stroke
			(width 0.06985)
			(type default)
		)
		(layer "In2.Cu")
	)
	(gr_line
		(start 278.500586 -216.640664)
		(end 278.503888 -216.659714)
		(stroke
			(width 0.06985)
			(type default)
		)
		(layer "In2.Cu")
	)
	(gr_line
		(start 278.500586 -216.640664)
		(end 278.503888 -216.621868)
		(stroke
			(width 0.06985)
			(type default)
		)
		(layer "In2.Cu")
	)
	(gr_line
		(start 278.512016 -58.03011)
		(end 278.522938 -58.045604)
		(stroke
			(width 0.06985)
			(type default)
		)
		(layer "In2.Cu")
	)
	(gr_line
		(start 278.831548 -31.528004)
		(end 278.864568 -31.522162)
		(stroke
			(width 0.06985)
			(type default)
		)
		(layer "In2.Cu")
	)
	(gr_line
		(start 278.86279 -9.537954)
		(end 278.872696 -9.523984)
		(stroke
			(width 0.06985)
			(type default)
		)
		(layer "In2.Cu")
	)
	(gr_line
		(start 278.864568 -31.522162)
		(end 278.892508 -31.502604)
		(stroke
			(width 0.06985)
			(type default)
		)
		(layer "In2.Cu")
	)
	(gr_line
		(start 278.872696 -9.523984)
		(end 278.886666 -9.514332)
		(stroke
			(width 0.06985)
			(type default)
		)
		(layer "In2.Cu")
	)
	(gr_line
		(start 278.893778 -222.294704)
		(end 278.950928 -222.237808)
		(stroke
			(width 0.06985)
			(type default)
		)
		(layer "In2.Cu")
	)
	(gr_arc
		(start 278.950928 -222.237808)
		(mid 279.087268 -222.033622)
		(end 279.135078 -221.7928)
		(stroke
			(width 0.06985)
			(type default)
		)
		(layer "In2.Cu")
	)
	(gr_line
		(start 279.128982 -57.232042)
		(end 279.144476 -57.242964)
		(stroke
			(width 0.06985)
			(type default)
		)
		(layer "In2.Cu")
	)
	(gr_line
		(start 279.144476 -57.242964)
		(end 279.155398 -57.258458)
		(stroke
			(width 0.06985)
			(type default)
		)
		(layer "In2.Cu")
	)
	(gr_line
		(start 279.39492 -15.988284)
		(end 279.42286 -15.968726)
		(stroke
			(width 0.06985)
			(type default)
		)
		(layer "In2.Cu")
	)
	(gr_line
		(start 279.422352 -20.317206)
		(end 279.430734 -20.318476)
		(stroke
			(width 0.06985)
			(type default)
		)
		(layer "In2.Cu")
	)
	(gr_line
		(start 279.42286 -15.968726)
		(end 279.45588 -15.962884)
		(stroke
			(width 0.06985)
			(type default)
		)
		(layer "In2.Cu")
	)
	(gr_line
		(start 279.430734 -20.318476)
		(end 279.438608 -20.32254)
		(stroke
			(width 0.06985)
			(type default)
		)
		(layer "In2.Cu")
	)
	(gr_arc
		(start 279.465278 -221.7928)
		(mid 279.513074 -222.03363)
		(end 279.649428 -222.237808)
		(stroke
			(width 0.06985)
			(type default)
		)
		(layer "In2.Cu")
	)
	(gr_line
		(start 279.484074 -34.30524)
		(end 279.513284 -34.299398)
		(stroke
			(width 0.06985)
			(type default)
		)
		(layer "In2.Cu")
	)
	(gr_line
		(start 279.513284 -34.299398)
		(end 279.538176 -34.282126)
		(stroke
			(width 0.06985)
			(type default)
		)
		(layer "In2.Cu")
	)
	(gr_line
		(start 279.649428 -222.237808)
		(end 279.706578 -222.294704)
		(stroke
			(width 0.06985)
			(type default)
		)
		(layer "In2.Cu")
	)
	(gr_line
		(start 279.649428 -8.979916)
		(end 279.677368 -8.960358)
		(stroke
			(width 0.06985)
			(type default)
		)
		(layer "In2.Cu")
	)
	(gr_line
		(start 279.677368 -8.960358)
		(end 279.710388 -8.954516)
		(stroke
			(width 0.06985)
			(type default)
		)
		(layer "In2.Cu")
	)
	(gr_arc
		(start 279.794462 -18.146776)
		(mid 280.041347 -18.097653)
		(end 280.250646 -17.9578)
		(stroke
			(width 0.06985)
			(type default)
		)
		(layer "In2.Cu")
	)
	(gr_line
		(start 279.889712 -7.055866)
		(end 279.917652 -7.036308)
		(stroke
			(width 0.06985)
			(type default)
		)
		(layer "In2.Cu")
	)
	(gr_line
		(start 279.917652 -7.036308)
		(end 279.950672 -7.030466)
		(stroke
			(width 0.06985)
			(type default)
		)
		(layer "In2.Cu")
	)
	(gr_line
		(start 279.930098 -155.70708)
		(end 279.930098 -155.707334)
		(stroke
			(width 0.06985)
			(type default)
		)
		(layer "In2.Cu")
	)
	(gr_line
		(start 279.930098 -155.70708)
		(end 279.9334 -155.688284)
		(stroke
			(width 0.06985)
			(type default)
		)
		(layer "In2.Cu")
	)
	(gr_line
		(start 279.930098 -155.669488)
		(end 279.9334 -155.688284)
		(stroke
			(width 0.06985)
			(type default)
		)
		(layer "In2.Cu")
	)
	(gr_line
		(start 279.978104 -71.905876)
		(end 279.997662 -71.933816)
		(stroke
			(width 0.06985)
			(type default)
		)
		(layer "In2.Cu")
	)
	(gr_line
		(start 279.997662 -71.933816)
		(end 280.003504 -71.966836)
		(stroke
			(width 0.06985)
			(type default)
		)
		(layer "In2.Cu")
	)
	(gr_arc
		(start 280.110184 -18.64233)
		(mid 279.927673 -18.520473)
		(end 279.71242 -18.477738)
		(stroke
			(width 0.06985)
			(type default)
		)
		(layer "In2.Cu")
	)
	(gr_line
		(start 280.110184 -18.64233)
		(end 280.2382 -18.7706)
		(stroke
			(width 0.06985)
			(type default)
		)
		(layer "In2.Cu")
	)
	(gr_line
		(start 280.13025 -30.232604)
		(end 280.15819 -30.213046)
		(stroke
			(width 0.06985)
			(type default)
		)
		(layer "In2.Cu")
	)
	(gr_line
		(start 280.15819 -30.213046)
		(end 280.19121 -30.207204)
		(stroke
			(width 0.06985)
			(type default)
		)
		(layer "In2.Cu")
	)
	(gr_line
		(start 280.16835 -56.164734)
		(end 280.183844 -56.175656)
		(stroke
			(width 0.06985)
			(type default)
		)
		(layer "In2.Cu")
	)
	(gr_line
		(start 280.183844 -56.175656)
		(end 280.194766 -56.19115)
		(stroke
			(width 0.06985)
			(type default)
		)
		(layer "In2.Cu")
	)
	(gr_line
		(start 280.862278 -15.714726)
		(end 280.881074 -15.711424)
		(stroke
			(width 0.06985)
			(type default)
		)
		(layer "In2.Cu")
	)
	(gr_line
		(start 280.865834 -54.744112)
		(end 280.881328 -54.755034)
		(stroke
			(width 0.06985)
			(type default)
		)
		(layer "In2.Cu")
	)
	(gr_line
		(start 280.881074 -15.711424)
		(end 280.89987 -15.714726)
		(stroke
			(width 0.06985)
			(type default)
		)
		(layer "In2.Cu")
	)
	(gr_line
		(start 280.881328 -54.755034)
		(end 280.89225 -54.770528)
		(stroke
			(width 0.06985)
			(type default)
		)
		(layer "In2.Cu")
	)
	(gr_line
		(start 280.930096 -31.364174)
		(end 280.933652 -31.362142)
		(stroke
			(width 0.06985)
			(type default)
		)
		(layer "In2.Cu")
	)
	(gr_line
		(start 280.933652 -31.362142)
		(end 280.937462 -31.360872)
		(stroke
			(width 0.06985)
			(type default)
		)
		(layer "In2.Cu")
	)
	(gr_line
		(start 280.959814 -8.734298)
		(end 280.97861 -8.730996)
		(stroke
			(width 0.06985)
			(type default)
		)
		(layer "In2.Cu")
	)
	(gr_line
		(start 280.97861 -8.730996)
		(end 280.997406 -8.734298)
		(stroke
			(width 0.06985)
			(type default)
		)
		(layer "In2.Cu")
	)
	(gr_line
		(start 281.052524 -21.502878)
		(end 281.086052 -21.519642)
		(stroke
			(width 0.06985)
			(type default)
		)
		(layer "In2.Cu")
	)
	(gr_line
		(start 281.363674 -204.202284)
		(end 281.366976 -204.221334)
		(stroke
			(width 0.06985)
			(type default)
		)
		(layer "In2.Cu")
	)
	(gr_line
		(start 281.363674 -204.202284)
		(end 281.366976 -204.183488)
		(stroke
			(width 0.06985)
			(type default)
		)
		(layer "In2.Cu")
	)
	(gr_line
		(start 281.44216 -156.80563)
		(end 281.44216 -156.805884)
		(stroke
			(width 0.06985)
			(type default)
		)
		(layer "In2.Cu")
	)
	(gr_line
		(start 281.44216 -156.80563)
		(end 281.445462 -156.786834)
		(stroke
			(width 0.06985)
			(type default)
		)
		(layer "In2.Cu")
	)
	(gr_line
		(start 281.44216 -156.768038)
		(end 281.445462 -156.786834)
		(stroke
			(width 0.06985)
			(type default)
		)
		(layer "In2.Cu")
	)
	(gr_line
		(start 281.659838 -71.55434)
		(end 281.679396 -71.58228)
		(stroke
			(width 0.06985)
			(type default)
		)
		(layer "In2.Cu")
	)
	(gr_line
		(start 281.679396 -71.58228)
		(end 281.685238 -71.6153)
		(stroke
			(width 0.06985)
			(type default)
		)
		(layer "In2.Cu")
	)
	(gr_line
		(start 281.79268 -216.378536)
		(end 281.795982 -216.397586)
		(stroke
			(width 0.06985)
			(type default)
		)
		(layer "In2.Cu")
	)
	(gr_line
		(start 281.79268 -216.378536)
		(end 281.795982 -216.35974)
		(stroke
			(width 0.06985)
			(type default)
		)
		(layer "In2.Cu")
	)
	(gr_line
		(start 281.85237 -54.210204)
		(end 281.867864 -54.221126)
		(stroke
			(width 0.06985)
			(type default)
		)
		(layer "In2.Cu")
	)
	(gr_line
		(start 281.867864 -54.221126)
		(end 281.878786 -54.23662)
		(stroke
			(width 0.06985)
			(type default)
		)
		(layer "In2.Cu")
	)
	(gr_line
		(start 281.99715 -13.60932)
		(end 282.000452 -13.628624)
		(stroke
			(width 0.06985)
			(type default)
		)
		(layer "In2.Cu")
	)
	(gr_line
		(start 281.99715 -13.60932)
		(end 282.000452 -13.590524)
		(stroke
			(width 0.06985)
			(type default)
		)
		(layer "In2.Cu")
	)
	(gr_line
		(start 282.049728 -8.919718)
		(end 282.082748 -8.92556)
		(stroke
			(width 0.06985)
			(type default)
		)
		(layer "In2.Cu")
	)
	(gr_line
		(start 282.062682 -13.981684)
		(end 282.068524 -14.014704)
		(stroke
			(width 0.06985)
			(type default)
		)
		(layer "In2.Cu")
	)
	(gr_line
		(start 282.068524 -14.014704)
		(end 282.087828 -14.04239)
		(stroke
			(width 0.06985)
			(type default)
		)
		(layer "In2.Cu")
	)
	(gr_line
		(start 282.082748 -8.92556)
		(end 282.110688 -8.945118)
		(stroke
			(width 0.06985)
			(type default)
		)
		(layer "In2.Cu")
	)
	(gr_line
		(start 282.09367 -222.294704)
		(end 282.15082 -222.237808)
		(stroke
			(width 0.06985)
			(type default)
		)
		(layer "In2.Cu")
	)
	(gr_line
		(start 282.098496 -13.034264)
		(end 282.104592 -13.000228)
		(stroke
			(width 0.06985)
			(type default)
		)
		(layer "In2.Cu")
	)
	(gr_line
		(start 282.104592 -13.000228)
		(end 282.124658 -12.971526)
		(stroke
			(width 0.06985)
			(type default)
		)
		(layer "In2.Cu")
	)
	(gr_arc
		(start 282.15082 -222.237808)
		(mid 282.28716 -222.033622)
		(end 282.33497 -221.7928)
		(stroke
			(width 0.06985)
			(type default)
		)
		(layer "In2.Cu")
	)
	(gr_line
		(start 282.163012 -51.949604)
		(end 282.177236 -51.959764)
		(stroke
			(width 0.06985)
			(type default)
		)
		(layer "In2.Cu")
	)
	(gr_line
		(start 282.177236 -51.959764)
		(end 282.187396 -51.973988)
		(stroke
			(width 0.06985)
			(type default)
		)
		(layer "In2.Cu")
	)
	(gr_line
		(start 282.260802 -14.289024)
		(end 282.270962 -14.303248)
		(stroke
			(width 0.06985)
			(type default)
		)
		(layer "In2.Cu")
	)
	(gr_line
		(start 282.266136 -15.955518)
		(end 282.299156 -15.96136)
		(stroke
			(width 0.06985)
			(type default)
		)
		(layer "In2.Cu")
	)
	(gr_line
		(start 282.270962 -14.303248)
		(end 282.28544 -14.313408)
		(stroke
			(width 0.06985)
			(type default)
		)
		(layer "In2.Cu")
	)
	(gr_arc
		(start 282.291536 -21.123656)
		(mid 282.53701 -20.852568)
		(end 282.6258 -20.4978)
		(stroke
			(width 0.06985)
			(type default)
		)
		(layer "In2.Cu")
	)
	(gr_line
		(start 282.299156 -15.96136)
		(end 282.327096 -15.980918)
		(stroke
			(width 0.06985)
			(type default)
		)
		(layer "In2.Cu")
	)
	(gr_line
		(start 282.345384 -21.519642)
		(end 282.409646 -21.46173)
		(stroke
			(width 0.06985)
			(type default)
		)
		(layer "In2.Cu")
	)
	(gr_line
		(start 282.443428 -70.325742)
		(end 282.462986 -70.353682)
		(stroke
			(width 0.06985)
			(type default)
		)
		(layer "In2.Cu")
	)
	(gr_line
		(start 282.460446 -31.832804)
		(end 282.483052 -31.816802)
		(stroke
			(width 0.06985)
			(type default)
		)
		(layer "In2.Cu")
	)
	(gr_line
		(start 282.462986 -70.353682)
		(end 282.468828 -70.386702)
		(stroke
			(width 0.06985)
			(type default)
		)
		(layer "In2.Cu")
	)
	(gr_line
		(start 282.483052 -31.816802)
		(end 282.510992 -31.81096)
		(stroke
			(width 0.06985)
			(type default)
		)
		(layer "In2.Cu")
	)
	(gr_line
		(start 282.64485 -43.669458)
		(end 282.679648 -43.676062)
		(stroke
			(width 0.06985)
			(type default)
		)
		(layer "In2.Cu")
	)
	(gr_arc
		(start 282.66517 -221.7928)
		(mid 282.712979 -222.033622)
		(end 282.84932 -222.237808)
		(stroke
			(width 0.06985)
			(type default)
		)
		(layer "In2.Cu")
	)
	(gr_line
		(start 282.679648 -43.676062)
		(end 282.713938 -43.666664)
		(stroke
			(width 0.06985)
			(type default)
		)
		(layer "In2.Cu")
	)
	(gr_line
		(start 282.712668 -42.013124)
		(end 282.737306 -42.018204)
		(stroke
			(width 0.06985)
			(type default)
		)
		(layer "In2.Cu")
	)
	(gr_line
		(start 282.737306 -42.018204)
		(end 282.761944 -42.013124)
		(stroke
			(width 0.06985)
			(type default)
		)
		(layer "In2.Cu")
	)
	(gr_line
		(start 282.773882 -14.655546)
		(end 282.801822 -14.675104)
		(stroke
			(width 0.06985)
			(type default)
		)
		(layer "In2.Cu")
	)
	(gr_line
		(start 282.801822 -14.675104)
		(end 282.834842 -14.680946)
		(stroke
			(width 0.06985)
			(type default)
		)
		(layer "In2.Cu")
	)
	(gr_line
		(start 282.84932 -222.237808)
		(end 282.90647 -222.294704)
		(stroke
			(width 0.06985)
			(type default)
		)
		(layer "In2.Cu")
	)
	(gr_arc
		(start 283.169868 -21.101812)
		(mid 282.815071 -21.171155)
		(end 282.512516 -21.36902)
		(stroke
			(width 0.06985)
			(type default)
		)
		(layer "In2.Cu")
	)
	(gr_line
		(start 283.259022 -9.749028)
		(end 283.274516 -9.75995)
		(stroke
			(width 0.06985)
			(type default)
		)
		(layer "In2.Cu")
	)
	(gr_line
		(start 283.274516 -9.75995)
		(end 283.285438 -9.775444)
		(stroke
			(width 0.06985)
			(type default)
		)
		(layer "In2.Cu")
	)
	(gr_line
		(start 283.346906 -40.773604)
		(end 283.371544 -40.768524)
		(stroke
			(width 0.06985)
			(type default)
		)
		(layer "In2.Cu")
	)
	(gr_line
		(start 283.540962 -10.140696)
		(end 283.56052 -10.168636)
		(stroke
			(width 0.06985)
			(type default)
		)
		(layer "In2.Cu")
	)
	(gr_line
		(start 283.56052 -10.168636)
		(end 283.566362 -10.201656)
		(stroke
			(width 0.06985)
			(type default)
		)
		(layer "In2.Cu")
	)
	(gr_line
		(start 283.581602 -11.467084)
		(end 283.60116 -11.439144)
		(stroke
			(width 0.06985)
			(type default)
		)
		(layer "In2.Cu")
	)
	(gr_line
		(start 283.60116 -11.439144)
		(end 283.607002 -11.406124)
		(stroke
			(width 0.06985)
			(type default)
		)
		(layer "In2.Cu")
	)
	(gr_line
		(start 283.689552 -10.938002)
		(end 283.689552 -10.938256)
		(stroke
			(width 0.06985)
			(type default)
		)
		(layer "In2.Cu")
	)
	(gr_line
		(start 283.689552 -10.938002)
		(end 283.692854 -10.919206)
		(stroke
			(width 0.06985)
			(type default)
		)
		(layer "In2.Cu")
	)
	(gr_line
		(start 283.689552 -10.90041)
		(end 283.692854 -10.919206)
		(stroke
			(width 0.06985)
			(type default)
		)
		(layer "In2.Cu")
	)
	(gr_line
		(start 283.778706 -39.656004)
		(end 283.803344 -39.650924)
		(stroke
			(width 0.06985)
			(type default)
		)
		(layer "In2.Cu")
	)
	(gr_line
		(start 283.79928 -70.122288)
		(end 283.818838 -70.150228)
		(stroke
			(width 0.06985)
			(type default)
		)
		(layer "In2.Cu")
	)
	(gr_line
		(start 283.818838 -70.150228)
		(end 283.82468 -70.183248)
		(stroke
			(width 0.06985)
			(type default)
		)
		(layer "In2.Cu")
	)
	(gr_line
		(start 283.826204 -14.855698)
		(end 283.845 -14.859)
		(stroke
			(width 0.06985)
			(type default)
		)
		(layer "In2.Cu")
	)
	(gr_line
		(start 283.845 -14.859)
		(end 283.863796 -14.855698)
		(stroke
			(width 0.06985)
			(type default)
		)
		(layer "In2.Cu")
	)
	(gr_line
		(start 284.34284 -14.435582)
		(end 284.361636 -14.43228)
		(stroke
			(width 0.06985)
			(type default)
		)
		(layer "In2.Cu")
	)
	(gr_line
		(start 284.34919 -29.474414)
		(end 284.367986 -29.471112)
		(stroke
			(width 0.06985)
			(type default)
		)
		(layer "In2.Cu")
	)
	(gr_line
		(start 284.361636 -14.43228)
		(end 284.380432 -14.435582)
		(stroke
			(width 0.06985)
			(type default)
		)
		(layer "In2.Cu")
	)
	(gr_line
		(start 284.367986 -29.471112)
		(end 284.386782 -29.474414)
		(stroke
			(width 0.06985)
			(type default)
		)
		(layer "In2.Cu")
	)
	(gr_line
		(start 284.384242 -23.165054)
		(end 284.403038 -23.168356)
		(stroke
			(width 0.06985)
			(type default)
		)
		(layer "In2.Cu")
	)
	(gr_line
		(start 284.395164 -30.33776)
		(end 284.4292 -30.3276)
		(stroke
			(width 0.06985)
			(type default)
		)
		(layer "In2.Cu")
	)
	(gr_line
		(start 284.403038 -23.168356)
		(end 284.421834 -23.165054)
		(stroke
			(width 0.06985)
			(type default)
		)
		(layer "In2.Cu")
	)
	(gr_line
		(start 284.4292 -30.3276)
		(end 284.46476 -30.333696)
		(stroke
			(width 0.06985)
			(type default)
		)
		(layer "In2.Cu")
	)
	(gr_line
		(start 284.518608 -28.609798)
		(end 284.537404 -28.60675)
		(stroke
			(width 0.06985)
			(type default)
		)
		(layer "In2.Cu")
	)
	(gr_line
		(start 285.050738 -216.100152)
		(end 285.05404 -216.119202)
		(stroke
			(width 0.06985)
			(type default)
		)
		(layer "In2.Cu")
	)
	(gr_line
		(start 285.050738 -216.100152)
		(end 285.05404 -216.081356)
		(stroke
			(width 0.06985)
			(type default)
		)
		(layer "In2.Cu")
	)
	(gr_line
		(start 285.071566 -31.277814)
		(end 285.09341 -31.273242)
		(stroke
			(width 0.06985)
			(type default)
		)
		(layer "In2.Cu")
	)
	(gr_line
		(start 285.09341 -31.273242)
		(end 285.116016 -31.277306)
		(stroke
			(width 0.06985)
			(type default)
		)
		(layer "In2.Cu")
	)
	(gr_line
		(start 285.200852 -170.55592)
		(end 285.200852 -170.556174)
		(stroke
			(width 0.06985)
			(type default)
		)
		(layer "In2.Cu")
	)
	(gr_line
		(start 285.200852 -170.55592)
		(end 285.204154 -170.537124)
		(stroke
			(width 0.06985)
			(type default)
		)
		(layer "In2.Cu")
	)
	(gr_line
		(start 285.200852 -170.518328)
		(end 285.204154 -170.537124)
		(stroke
			(width 0.06985)
			(type default)
		)
		(layer "In2.Cu")
	)
	(gr_line
		(start 285.2928 -200.223374)
		(end 285.296102 -200.242424)
		(stroke
			(width 0.06985)
			(type default)
		)
		(layer "In2.Cu")
	)
	(gr_line
		(start 285.2928 -200.223374)
		(end 285.296102 -200.204578)
		(stroke
			(width 0.06985)
			(type default)
		)
		(layer "In2.Cu")
	)
	(gr_line
		(start 285.293562 -222.294704)
		(end 285.350712 -222.237808)
		(stroke
			(width 0.06985)
			(type default)
		)
		(layer "In2.Cu")
	)
	(gr_line
		(start 285.296102 -200.24217)
		(end 285.296102 -200.242424)
		(stroke
			(width 0.06985)
			(type default)
		)
		(layer "In2.Cu")
	)
	(gr_arc
		(start 285.350712 -222.237808)
		(mid 285.487036 -222.033619)
		(end 285.534862 -221.7928)
		(stroke
			(width 0.06985)
			(type default)
		)
		(layer "In2.Cu")
	)
	(gr_line
		(start 285.508954 -70.129908)
		(end 285.528512 -70.157848)
		(stroke
			(width 0.06985)
			(type default)
		)
		(layer "In2.Cu")
	)
	(gr_line
		(start 285.528512 -70.157848)
		(end 285.534354 -70.190868)
		(stroke
			(width 0.06985)
			(type default)
		)
		(layer "In2.Cu")
	)
	(gr_line
		(start 285.52902 -26.35885)
		(end 285.546038 -26.3652)
		(stroke
			(width 0.06985)
			(type default)
		)
		(layer "In2.Cu")
	)
	(gr_arc
		(start 285.865062 -221.7928)
		(mid 285.912871 -222.033622)
		(end 286.049212 -222.237808)
		(stroke
			(width 0.06985)
			(type default)
		)
		(layer "In2.Cu")
	)
	(gr_line
		(start 286.030162 -18.977356)
		(end 286.058102 -18.996914)
		(stroke
			(width 0.06985)
			(type default)
		)
		(layer "In2.Cu")
	)
	(gr_line
		(start 286.049212 -222.237808)
		(end 286.106362 -222.294704)
		(stroke
			(width 0.06985)
			(type default)
		)
		(layer "In2.Cu")
	)
	(gr_line
		(start 286.058102 -18.996914)
		(end 286.091122 -19.002756)
		(stroke
			(width 0.06985)
			(type default)
		)
		(layer "In2.Cu")
	)
	(gr_line
		(start 286.601154 -205.783688)
		(end 286.601154 -205.783942)
		(stroke
			(width 0.06985)
			(type default)
		)
		(layer "In2.Cu")
	)
	(gr_line
		(start 286.601154 -205.783688)
		(end 286.604456 -205.764892)
		(stroke
			(width 0.06985)
			(type default)
		)
		(layer "In2.Cu")
	)
	(gr_line
		(start 286.601154 -205.746096)
		(end 286.604456 -205.764892)
		(stroke
			(width 0.06985)
			(type default)
		)
		(layer "In2.Cu")
	)
	(gr_line
		(start 286.678116 -69.69252)
		(end 286.697674 -69.72046)
		(stroke
			(width 0.06985)
			(type default)
		)
		(layer "In2.Cu")
	)
	(gr_line
		(start 286.697674 -69.72046)
		(end 286.703516 -69.75348)
		(stroke
			(width 0.06985)
			(type default)
		)
		(layer "In2.Cu")
	)
	(gr_line
		(start 286.79648 -14.861794)
		(end 286.860742 -14.873224)
		(stroke
			(width 0.06985)
			(type default)
		)
		(layer "In2.Cu")
	)
	(gr_line
		(start 286.860742 -14.873224)
		(end 286.90697 -14.919452)
		(stroke
			(width 0.06985)
			(type default)
		)
		(layer "In2.Cu")
	)
	(gr_line
		(start 287.148016 -31.971488)
		(end 287.166812 -31.97479)
		(stroke
			(width 0.06985)
			(type default)
		)
		(layer "In2.Cu")
	)
	(gr_line
		(start 287.159446 -173.23562)
		(end 287.159446 -173.235874)
		(stroke
			(width 0.06985)
			(type default)
		)
		(layer "In2.Cu")
	)
	(gr_line
		(start 287.159446 -173.23562)
		(end 287.162748 -173.216824)
		(stroke
			(width 0.06985)
			(type default)
		)
		(layer "In2.Cu")
	)
	(gr_line
		(start 287.159446 -173.198028)
		(end 287.162748 -173.216824)
		(stroke
			(width 0.06985)
			(type default)
		)
		(layer "In2.Cu")
	)
	(gr_line
		(start 287.166812 -31.97479)
		(end 287.185608 -31.971488)
		(stroke
			(width 0.06985)
			(type default)
		)
		(layer "In2.Cu")
	)
	(gr_line
		(start 287.255204 -22.329902)
		(end 287.274 -22.3266)
		(stroke
			(width 0.06985)
			(type default)
		)
		(layer "In2.Cu")
	)
	(gr_line
		(start 287.274 -22.3266)
		(end 287.292796 -22.329902)
		(stroke
			(width 0.06985)
			(type default)
		)
		(layer "In2.Cu")
	)
	(gr_line
		(start 287.313624 -31.155894)
		(end 287.32607 -31.157926)
		(stroke
			(width 0.06985)
			(type default)
		)
		(layer "In2.Cu")
	)
	(gr_line
		(start 287.32607 -31.157926)
		(end 287.338008 -31.156148)
		(stroke
			(width 0.06985)
			(type default)
		)
		(layer "In2.Cu")
	)
	(gr_line
		(start 287.373822 -40.7543)
		(end 287.39465 -40.749982)
		(stroke
			(width 0.06985)
			(type default)
		)
		(layer "In2.Cu")
	)
	(gr_line
		(start 287.39465 -40.749982)
		(end 287.415732 -40.753792)
		(stroke
			(width 0.06985)
			(type default)
		)
		(layer "In2.Cu")
	)
	(gr_line
		(start 287.39465 -30.340554)
		(end 287.411922 -30.343602)
		(stroke
			(width 0.06985)
			(type default)
		)
		(layer "In2.Cu")
	)
	(gr_line
		(start 287.411922 -30.343602)
		(end 287.428432 -30.340808)
		(stroke
			(width 0.06985)
			(type default)
		)
		(layer "In2.Cu")
	)
	(gr_line
		(start 287.440624 -29.524198)
		(end 287.459166 -29.528008)
		(stroke
			(width 0.06985)
			(type default)
		)
		(layer "In2.Cu")
	)
	(gr_line
		(start 287.455864 -39.614856)
		(end 287.482534 -39.609522)
		(stroke
			(width 0.06985)
			(type default)
		)
		(layer "In2.Cu")
	)
	(gr_line
		(start 287.459166 -29.528008)
		(end 287.477708 -29.52496)
		(stroke
			(width 0.06985)
			(type default)
		)
		(layer "In2.Cu")
	)
	(gr_line
		(start 287.482534 -39.609522)
		(end 287.509204 -39.614856)
		(stroke
			(width 0.06985)
			(type default)
		)
		(layer "In2.Cu")
	)
	(gr_line
		(start 287.538922 -38.566852)
		(end 287.565592 -38.561518)
		(stroke
			(width 0.06985)
			(type default)
		)
		(layer "In2.Cu")
	)
	(gr_line
		(start 287.559496 -69.260974)
		(end 287.579054 -69.288914)
		(stroke
			(width 0.06985)
			(type default)
		)
		(layer "In2.Cu")
	)
	(gr_line
		(start 287.565592 -38.561518)
		(end 287.592262 -38.566852)
		(stroke
			(width 0.06985)
			(type default)
		)
		(layer "In2.Cu")
	)
	(gr_line
		(start 287.579054 -69.288914)
		(end 287.584896 -69.321934)
		(stroke
			(width 0.06985)
			(type default)
		)
		(layer "In2.Cu")
	)
	(gr_line
		(start 287.679892 -28.472384)
		(end 287.698688 -28.475686)
		(stroke
			(width 0.06985)
			(type default)
		)
		(layer "In2.Cu")
	)
	(gr_line
		(start 287.698688 -28.475686)
		(end 287.717484 -28.472384)
		(stroke
			(width 0.06985)
			(type default)
		)
		(layer "In2.Cu")
	)
	(gr_line
		(start 287.775396 -41.95191)
		(end 287.808416 -41.94302)
		(stroke
			(width 0.06985)
			(type default)
		)
		(layer "In2.Cu")
	)
	(gr_line
		(start 287.808416 -41.94302)
		(end 287.810194 -41.943274)
		(stroke
			(width 0.06985)
			(type default)
		)
		(layer "In2.Cu")
	)
	(gr_line
		(start 287.810194 -41.943274)
		(end 287.840166 -41.949116)
		(stroke
			(width 0.06985)
			(type default)
		)
		(layer "In2.Cu")
	)
	(gr_line
		(start 287.82137 -42.281602)
		(end 287.82264 -42.281348)
		(stroke
			(width 0.06985)
			(type default)
		)
		(layer "In2.Cu")
	)
	(gr_line
		(start 287.82264 -42.281348)
		(end 287.822386 -42.281856)
		(stroke
			(width 0.06985)
			(type default)
		)
		(layer "In2.Cu")
	)
	(gr_line
		(start 287.866328 -41.953942)
		(end 287.903412 -41.961054)
		(stroke
			(width 0.06985)
			(type default)
		)
		(layer "In2.Cu")
	)
	(gr_line
		(start 288.086038 -202.506072)
		(end 288.08934 -202.525122)
		(stroke
			(width 0.06985)
			(type default)
		)
		(layer "In2.Cu")
	)
	(gr_line
		(start 288.086038 -202.506072)
		(end 288.08934 -202.487276)
		(stroke
			(width 0.06985)
			(type default)
		)
		(layer "In2.Cu")
	)
	(gr_line
		(start 288.201608 -16.681196)
		(end 288.526982 -17.00657)
		(stroke
			(width 0.06985)
			(type default)
		)
		(layer "In2.Cu")
	)
	(gr_line
		(start 288.247582 -216.544906)
		(end 288.250884 -216.563956)
		(stroke
			(width 0.06985)
			(type default)
		)
		(layer "In2.Cu")
	)
	(gr_line
		(start 288.247582 -216.544906)
		(end 288.250884 -216.52611)
		(stroke
			(width 0.06985)
			(type default)
		)
		(layer "In2.Cu")
	)
	(gr_arc
		(start 288.384488 -17.729962)
		(mid 288.64857 -17.406275)
		(end 288.526982 -17.00657)
		(stroke
			(width 0.06985)
			(type default)
		)
		(layer "In2.Cu")
	)
	(gr_line
		(start 288.384488 -13.930122)
		(end 288.63925 -13.930122)
		(stroke
			(width 0.06985)
			(type default)
		)
		(layer "In2.Cu")
	)
	(gr_arc
		(start 288.40811 -16.420338)
		(mid 288.79324 -16.552707)
		(end 289.134296 -16.330168)
		(stroke
			(width 0.06985)
			(type default)
		)
		(layer "In2.Cu")
	)
	(gr_line
		(start 288.493708 -222.294704)
		(end 288.550858 -222.237808)
		(stroke
			(width 0.06985)
			(type default)
		)
		(layer "In2.Cu")
	)
	(gr_arc
		(start 288.550858 -222.237808)
		(mid 288.687194 -222.033622)
		(end 288.735008 -221.7928)
		(stroke
			(width 0.06985)
			(type default)
		)
		(layer "In2.Cu")
	)
	(gr_line
		(start 288.585148 -13.147548)
		(end 289.083496 -13.645896)
		(stroke
			(width 0.06985)
			(type default)
		)
		(layer "In2.Cu")
	)
	(gr_line
		(start 288.736024 -5.481574)
		(end 288.75482 -5.478272)
		(stroke
			(width 0.06985)
			(type default)
		)
		(layer "In2.Cu")
	)
	(gr_line
		(start 288.75482 -5.478272)
		(end 288.773616 -5.481574)
		(stroke
			(width 0.06985)
			(type default)
		)
		(layer "In2.Cu")
	)
	(gr_arc
		(start 288.777426 -13.945362)
		(mid 288.70876 -13.933914)
		(end 288.63925 -13.930122)
		(stroke
			(width 0.06985)
			(type default)
		)
		(layer "In2.Cu")
	)
	(gr_line
		(start 288.865564 -68.575174)
		(end 288.885122 -68.603114)
		(stroke
			(width 0.06985)
			(type default)
		)
		(layer "In2.Cu")
	)
	(gr_line
		(start 288.885122 -68.603114)
		(end 288.890964 -68.636134)
		(stroke
			(width 0.06985)
			(type default)
		)
		(layer "In2.Cu")
	)
	(gr_arc
		(start 289.065208 -221.9452)
		(mid 289.085064 -222.045132)
		(end 289.141662 -222.129858)
		(stroke
			(width 0.06985)
			(type default)
		)
		(layer "In2.Cu")
	)
	(gr_arc
		(start 289.08502 -14.11478)
		(mid 288.94325 -14.008235)
		(end 288.777426 -13.945362)
		(stroke
			(width 0.06985)
			(type default)
		)
		(layer "In2.Cu")
	)
	(gr_line
		(start 289.117532 -31.295848)
		(end 289.134042 -31.2928)
		(stroke
			(width 0.06985)
			(type default)
		)
		(layer "In2.Cu")
	)
	(gr_line
		(start 289.134042 -31.2928)
		(end 289.150298 -31.295848)
		(stroke
			(width 0.06985)
			(type default)
		)
		(layer "In2.Cu")
	)
	(gr_arc
		(start 289.134296 -12.530074)
		(mid 288.568442 -12.579848)
		(end 288.585148 -13.147548)
		(stroke
			(width 0.06985)
			(type default)
		)
		(layer "In2.Cu")
	)
	(gr_line
		(start 289.141662 -222.129858)
		(end 289.306508 -222.294704)
		(stroke
			(width 0.06985)
			(type default)
		)
		(layer "In2.Cu")
	)
	(gr_line
		(start 289.325304 -30.471872)
		(end 289.3441 -30.46857)
		(stroke
			(width 0.06985)
			(type default)
		)
		(layer "In2.Cu")
	)
	(gr_line
		(start 289.3441 -30.46857)
		(end 289.36315 -30.471872)
		(stroke
			(width 0.06985)
			(type default)
		)
		(layer "In2.Cu")
	)
	(gr_line
		(start 289.344862 -207.779874)
		(end 289.344862 -207.780128)
		(stroke
			(width 0.06985)
			(type default)
		)
		(layer "In2.Cu")
	)
	(gr_line
		(start 289.344862 -207.779874)
		(end 289.348164 -207.761078)
		(stroke
			(width 0.06985)
			(type default)
		)
		(layer "In2.Cu")
	)
	(gr_line
		(start 289.344862 -207.742282)
		(end 289.348164 -207.761078)
		(stroke
			(width 0.06985)
			(type default)
		)
		(layer "In2.Cu")
	)
	(gr_arc
		(start 289.497262 -14.059662)
		(mid 289.527577 -14.089304)
		(end 289.558476 -14.118336)
		(stroke
			(width 0.06985)
			(type default)
		)
		(layer "In2.Cu")
	)
	(gr_line
		(start 289.501326 -29.65196)
		(end 289.517836 -29.649166)
		(stroke
			(width 0.06985)
			(type default)
		)
		(layer "In2.Cu")
	)
	(gr_line
		(start 289.517836 -29.649166)
		(end 289.535108 -29.652214)
		(stroke
			(width 0.06985)
			(type default)
		)
		(layer "In2.Cu")
	)
	(gr_line
		(start 289.6235 -67.240404)
		(end 289.643058 -67.268344)
		(stroke
			(width 0.06985)
			(type default)
		)
		(layer "In2.Cu")
	)
	(gr_line
		(start 289.643058 -67.268344)
		(end 289.6489 -67.301364)
		(stroke
			(width 0.06985)
			(type default)
		)
		(layer "In2.Cu")
	)
	(gr_line
		(start 289.847782 -27.760676)
		(end 289.86861 -27.756358)
		(stroke
			(width 0.06985)
			(type default)
		)
		(layer "In2.Cu")
	)
	(gr_line
		(start 289.86861 -27.756358)
		(end 289.889692 -27.760168)
		(stroke
			(width 0.06985)
			(type default)
		)
		(layer "In2.Cu")
	)
	(gr_line
		(start 289.876484 -23.121112)
		(end 289.89528 -23.124414)
		(stroke
			(width 0.06985)
			(type default)
		)
		(layer "In2.Cu")
	)
	(gr_line
		(start 289.89528 -23.124414)
		(end 289.914076 -23.121112)
		(stroke
			(width 0.06985)
			(type default)
		)
		(layer "In2.Cu")
	)
	(gr_line
		(start 289.907472 -28.802076)
		(end 289.926014 -28.799028)
		(stroke
			(width 0.06985)
			(type default)
		)
		(layer "In2.Cu")
	)
	(gr_line
		(start 289.926014 -28.799028)
		(end 289.944556 -28.802838)
		(stroke
			(width 0.06985)
			(type default)
		)
		(layer "In2.Cu")
	)
	(gr_line
		(start 289.926268 -175.850042)
		(end 289.926268 -175.850296)
		(stroke
			(width 0.06985)
			(type default)
		)
		(layer "In2.Cu")
	)
	(gr_line
		(start 289.926268 -175.850042)
		(end 289.92957 -175.831246)
		(stroke
			(width 0.06985)
			(type default)
		)
		(layer "In2.Cu")
	)
	(gr_line
		(start 289.926268 -175.81245)
		(end 289.92957 -175.831246)
		(stroke
			(width 0.06985)
			(type default)
		)
		(layer "In2.Cu")
	)
	(gr_line
		(start 290.35883 -66.347848)
		(end 290.378388 -66.375788)
		(stroke
			(width 0.06985)
			(type default)
		)
		(layer "In2.Cu")
	)
	(gr_line
		(start 290.378388 -66.375788)
		(end 290.38423 -66.408808)
		(stroke
			(width 0.06985)
			(type default)
		)
		(layer "In2.Cu")
	)
	(gr_line
		(start 290.730686 -15.103602)
		(end 290.753038 -15.112746)
		(stroke
			(width 0.06985)
			(type default)
		)
		(layer "In2.Cu")
	)
	(gr_line
		(start 291.02812 -5.879084)
		(end 291.06114 -5.884926)
		(stroke
			(width 0.06985)
			(type default)
		)
		(layer "In2.Cu")
	)
	(gr_arc
		(start 291.053774 -18.227548)
		(mid 290.934904 -17.902243)
		(end 290.63442 -17.729962)
		(stroke
			(width 0.06985)
			(type default)
		)
		(layer "In2.Cu")
	)
	(gr_line
		(start 291.06114 -5.884926)
		(end 291.08908 -5.904484)
		(stroke
			(width 0.06985)
			(type default)
		)
		(layer "In2.Cu")
	)
	(gr_line
		(start 291.283136 -66.316098)
		(end 291.301424 -66.34226)
		(stroke
			(width 0.06985)
			(type default)
		)
		(layer "In2.Cu")
	)
	(gr_line
		(start 291.301424 -66.34226)
		(end 291.307266 -66.374264)
		(stroke
			(width 0.06985)
			(type default)
		)
		(layer "In2.Cu")
	)
	(gr_line
		(start 291.333174 -15.112746)
		(end 291.356034 -15.103348)
		(stroke
			(width 0.06985)
			(type default)
		)
		(layer "In2.Cu")
	)
	(gr_line
		(start 291.384482 -16.330168)
		(end 291.384482 -17.894808)
		(stroke
			(width 0.06985)
			(type default)
		)
		(layer "In2.Cu")
	)
	(gr_line
		(start 291.51834 -203.33081)
		(end 291.521642 -203.34986)
		(stroke
			(width 0.06985)
			(type default)
		)
		(layer "In2.Cu")
	)
	(gr_line
		(start 291.51834 -203.33081)
		(end 291.521642 -203.312014)
		(stroke
			(width 0.06985)
			(type default)
		)
		(layer "In2.Cu")
	)
	(gr_line
		(start 291.6936 -222.294704)
		(end 291.75075 -222.237808)
		(stroke
			(width 0.06985)
			(type default)
		)
		(layer "In2.Cu")
	)
	(gr_line
		(start 291.718746 -215.156542)
		(end 291.722048 -215.175592)
		(stroke
			(width 0.06985)
			(type default)
		)
		(layer "In2.Cu")
	)
	(gr_line
		(start 291.718746 -215.156542)
		(end 291.722048 -215.137746)
		(stroke
			(width 0.06985)
			(type default)
		)
		(layer "In2.Cu")
	)
	(gr_arc
		(start 291.75075 -222.237808)
		(mid 291.887066 -222.033616)
		(end 291.9349 -221.7928)
		(stroke
			(width 0.06985)
			(type default)
		)
		(layer "In2.Cu")
	)
	(gr_line
		(start 292.002718 -65.946782)
		(end 292.01999 -65.97142)
		(stroke
			(width 0.06985)
			(type default)
		)
		(layer "In2.Cu")
	)
	(gr_line
		(start 292.01999 -65.97142)
		(end 292.025578 -66.000884)
		(stroke
			(width 0.06985)
			(type default)
		)
		(layer "In2.Cu")
	)
	(gr_line
		(start 292.067488 -14.8082)
		(end 292.090602 -14.798802)
		(stroke
			(width 0.06985)
			(type default)
		)
		(layer "In2.Cu")
	)
	(gr_line
		(start 292.090602 -14.798802)
		(end 292.108382 -14.781022)
		(stroke
			(width 0.06985)
			(type default)
		)
		(layer "In2.Cu")
	)
	(gr_arc
		(start 292.2651 -221.7928)
		(mid 292.312891 -222.033634)
		(end 292.44925 -222.237808)
		(stroke
			(width 0.06985)
			(type default)
		)
		(layer "In2.Cu")
	)
	(gr_line
		(start 292.42893 -26.09596)
		(end 292.46195 -26.090118)
		(stroke
			(width 0.06985)
			(type default)
		)
		(layer "In2.Cu")
	)
	(gr_line
		(start 292.44925 -222.237808)
		(end 292.5064 -222.294704)
		(stroke
			(width 0.06985)
			(type default)
		)
		(layer "In2.Cu")
	)
	(gr_line
		(start 292.457378 -217.480642)
		(end 292.457378 -217.480896)
		(stroke
			(width 0.06985)
			(type default)
		)
		(layer "In2.Cu")
	)
	(gr_line
		(start 292.457378 -217.480642)
		(end 292.46068 -217.461846)
		(stroke
			(width 0.06985)
			(type default)
		)
		(layer "In2.Cu")
	)
	(gr_line
		(start 292.457378 -217.44305)
		(end 292.46068 -217.461846)
		(stroke
			(width 0.06985)
			(type default)
		)
		(layer "In2.Cu")
	)
	(gr_line
		(start 292.46195 -26.090118)
		(end 292.48989 -26.07056)
		(stroke
			(width 0.06985)
			(type default)
		)
		(layer "In2.Cu")
	)
	(gr_line
		(start 292.656006 -28.583128)
		(end 292.674802 -28.58643)
		(stroke
			(width 0.06985)
			(type default)
		)
		(layer "In2.Cu")
	)
	(gr_line
		(start 292.667436 -207.982566)
		(end 292.667436 -207.98282)
		(stroke
			(width 0.06985)
			(type default)
		)
		(layer "In2.Cu")
	)
	(gr_line
		(start 292.667436 -207.982566)
		(end 292.670738 -207.96377)
		(stroke
			(width 0.06985)
			(type default)
		)
		(layer "In2.Cu")
	)
	(gr_line
		(start 292.667436 -207.944974)
		(end 292.670738 -207.96377)
		(stroke
			(width 0.06985)
			(type default)
		)
		(layer "In2.Cu")
	)
	(gr_line
		(start 292.674802 -28.58643)
		(end 292.693598 -28.583128)
		(stroke
			(width 0.06985)
			(type default)
		)
		(layer "In2.Cu")
	)
	(gr_line
		(start 292.690042 -22.631654)
		(end 292.723062 -22.625812)
		(stroke
			(width 0.06985)
			(type default)
		)
		(layer "In2.Cu")
	)
	(gr_line
		(start 292.723062 -22.625812)
		(end 292.749986 -22.606762)
		(stroke
			(width 0.06985)
			(type default)
		)
		(layer "In2.Cu")
	)
	(gr_line
		(start 292.832282 -7.125208)
		(end 292.847776 -7.13613)
		(stroke
			(width 0.06985)
			(type default)
		)
		(layer "In2.Cu")
	)
	(gr_line
		(start 292.841172 -177.440844)
		(end 292.841172 -177.441098)
		(stroke
			(width 0.06985)
			(type default)
		)
		(layer "In2.Cu")
	)
	(gr_line
		(start 292.841172 -177.440844)
		(end 292.844474 -177.422048)
		(stroke
			(width 0.06985)
			(type default)
		)
		(layer "In2.Cu")
	)
	(gr_line
		(start 292.841172 -177.403252)
		(end 292.844474 -177.422048)
		(stroke
			(width 0.06985)
			(type default)
		)
		(layer "In2.Cu")
	)
	(gr_line
		(start 292.847776 -7.13613)
		(end 292.858698 -7.151624)
		(stroke
			(width 0.06985)
			(type default)
		)
		(layer "In2.Cu")
	)
	(gr_line
		(start 292.951662 -29.74086)
		(end 292.9763 -29.74594)
		(stroke
			(width 0.06985)
			(type default)
		)
		(layer "In2.Cu")
	)
	(gr_line
		(start 292.9763 -29.74594)
		(end 293.00043 -29.741114)
		(stroke
			(width 0.06985)
			(type default)
		)
		(layer "In2.Cu")
	)
	(gr_line
		(start 293.458392 -13.431266)
		(end 293.468806 -13.406374)
		(stroke
			(width 0.06985)
			(type default)
		)
		(layer "In2.Cu")
	)
	(gr_line
		(start 293.59479 -25.296876)
		(end 293.610284 -25.285954)
		(stroke
			(width 0.06985)
			(type default)
		)
		(layer "In2.Cu")
	)
	(gr_line
		(start 293.610284 -25.285954)
		(end 293.621206 -25.27046)
		(stroke
			(width 0.06985)
			(type default)
		)
		(layer "In2.Cu")
	)
	(gr_line
		(start 293.706042 -21.93671)
		(end 293.720012 -21.927058)
		(stroke
			(width 0.06985)
			(type default)
		)
		(layer "In2.Cu")
	)
	(gr_line
		(start 293.720012 -21.927058)
		(end 293.730426 -21.912326)
		(stroke
			(width 0.06985)
			(type default)
		)
		(layer "In2.Cu")
	)
	(gr_line
		(start 293.853108 -8.571992)
		(end 293.889176 -8.623554)
		(stroke
			(width 0.06985)
			(type default)
		)
		(layer "In2.Cu")
	)
	(gr_line
		(start 293.879778 -12.41425)
		(end 293.889176 -12.391136)
		(stroke
			(width 0.06985)
			(type default)
		)
		(layer "In2.Cu")
	)
	(gr_line
		(start 293.913306 -32.460438)
		(end 293.929562 -32.463486)
		(stroke
			(width 0.06985)
			(type default)
		)
		(layer "In2.Cu")
	)
	(gr_line
		(start 293.929562 -32.463486)
		(end 293.946072 -32.460438)
		(stroke
			(width 0.06985)
			(type default)
		)
		(layer "In2.Cu")
	)
	(gr_line
		(start 294.016684 -30.777434)
		(end 294.03548 -30.780736)
		(stroke
			(width 0.06985)
			(type default)
		)
		(layer "In2.Cu")
	)
	(gr_line
		(start 294.03548 -30.780736)
		(end 294.054276 -30.777434)
		(stroke
			(width 0.06985)
			(type default)
		)
		(layer "In2.Cu")
	)
	(gr_line
		(start 294.041068 -17.789652)
		(end 294.04437 -17.808448)
		(stroke
			(width 0.06985)
			(type default)
		)
		(layer "In2.Cu")
	)
	(gr_line
		(start 294.041068 -17.789652)
		(end 294.04437 -17.770856)
		(stroke
			(width 0.06985)
			(type default)
		)
		(layer "In2.Cu")
	)
	(gr_line
		(start 294.04437 -17.770602)
		(end 294.04437 -17.770856)
		(stroke
			(width 0.06985)
			(type default)
		)
		(layer "In2.Cu")
	)
	(gr_line
		(start 294.092122 -31.641034)
		(end 294.110918 -31.644336)
		(stroke
			(width 0.06985)
			(type default)
		)
		(layer "In2.Cu")
	)
	(gr_line
		(start 294.110918 -31.644336)
		(end 294.129714 -31.641034)
		(stroke
			(width 0.06985)
			(type default)
		)
		(layer "In2.Cu")
	)
	(gr_line
		(start 294.183054 -16.984726)
		(end 294.191182 -16.938498)
		(stroke
			(width 0.06985)
			(type default)
		)
		(layer "In2.Cu")
	)
	(gr_line
		(start 294.191182 -16.938498)
		(end 294.2209 -16.902176)
		(stroke
			(width 0.06985)
			(type default)
		)
		(layer "In2.Cu")
	)
	(gr_line
		(start 294.270684 -21.140928)
		(end 294.290242 -21.112988)
		(stroke
			(width 0.06985)
			(type default)
		)
		(layer "In2.Cu")
	)
	(gr_line
		(start 294.290242 -21.112988)
		(end 294.296084 -21.079968)
		(stroke
			(width 0.06985)
			(type default)
		)
		(layer "In2.Cu")
	)
	(gr_line
		(start 294.445182 -28.274264)
		(end 294.478202 -28.268422)
		(stroke
			(width 0.06985)
			(type default)
		)
		(layer "In2.Cu")
	)
	(gr_line
		(start 294.478202 -28.268422)
		(end 294.506142 -28.248864)
		(stroke
			(width 0.06985)
			(type default)
		)
		(layer "In2.Cu")
	)
	(gr_line
		(start 294.623236 -19.226022)
		(end 294.626538 -19.207226)
		(stroke
			(width 0.06985)
			(type default)
		)
		(layer "In2.Cu")
	)
	(gr_line
		(start 294.623236 -19.188176)
		(end 294.626538 -19.207226)
		(stroke
			(width 0.06985)
			(type default)
		)
		(layer "In2.Cu")
	)
	(gr_line
		(start 294.661336 -16.364204)
		(end 294.684958 -16.335248)
		(stroke
			(width 0.06985)
			(type default)
		)
		(layer "In2.Cu")
	)
	(gr_line
		(start 294.684958 -16.335248)
		(end 294.719248 -16.319754)
		(stroke
			(width 0.06985)
			(type default)
		)
		(layer "In2.Cu")
	)
	(gr_line
		(start 294.893746 -222.294704)
		(end 294.950896 -222.237808)
		(stroke
			(width 0.06985)
			(type default)
		)
		(layer "In2.Cu")
	)
	(gr_arc
		(start 294.950896 -222.237808)
		(mid 295.087223 -222.03362)
		(end 295.135046 -221.7928)
		(stroke
			(width 0.06985)
			(type default)
		)
		(layer "In2.Cu")
	)
	(gr_line
		(start 295.152826 -204.15758)
		(end 295.156128 -204.176884)
		(stroke
			(width 0.06985)
			(type default)
		)
		(layer "In2.Cu")
	)
	(gr_line
		(start 295.152826 -204.15758)
		(end 295.156128 -204.138784)
		(stroke
			(width 0.06985)
			(type default)
		)
		(layer "In2.Cu")
	)
	(gr_line
		(start 295.282874 -30.560772)
		(end 295.315894 -30.55493)
		(stroke
			(width 0.06985)
			(type default)
		)
		(layer "In2.Cu")
	)
	(gr_line
		(start 295.315894 -30.55493)
		(end 295.343834 -30.535372)
		(stroke
			(width 0.06985)
			(type default)
		)
		(layer "In2.Cu")
	)
	(gr_line
		(start 295.36644 -27.646376)
		(end 295.381934 -27.635454)
		(stroke
			(width 0.06985)
			(type default)
		)
		(layer "In2.Cu")
	)
	(gr_line
		(start 295.381934 -27.635454)
		(end 295.392856 -27.61996)
		(stroke
			(width 0.06985)
			(type default)
		)
		(layer "In2.Cu")
	)
	(gr_line
		(start 295.422066 -183.096916)
		(end 295.422066 -183.09717)
		(stroke
			(width 0.06985)
			(type default)
		)
		(layer "In2.Cu")
	)
	(gr_line
		(start 295.422066 -183.096916)
		(end 295.425368 -183.07812)
		(stroke
			(width 0.06985)
			(type default)
		)
		(layer "In2.Cu")
	)
	(gr_line
		(start 295.422066 -183.059324)
		(end 295.425368 -183.07812)
		(stroke
			(width 0.06985)
			(type default)
		)
		(layer "In2.Cu")
	)
	(gr_arc
		(start 295.465246 -221.7928)
		(mid 295.513055 -222.033622)
		(end 295.649396 -222.237808)
		(stroke
			(width 0.06985)
			(type default)
		)
		(layer "In2.Cu")
	)
	(gr_line
		(start 295.515284 -22.565106)
		(end 295.534842 -22.537166)
		(stroke
			(width 0.06985)
			(type default)
		)
		(layer "In2.Cu")
	)
	(gr_line
		(start 295.534842 -22.537166)
		(end 295.540684 -22.504146)
		(stroke
			(width 0.06985)
			(type default)
		)
		(layer "In2.Cu")
	)
	(gr_line
		(start 295.58615 -20.343622)
		(end 295.60266 -20.250658)
		(stroke
			(width 0.06985)
			(type default)
		)
		(layer "In2.Cu")
	)
	(gr_line
		(start 295.60266 -20.250658)
		(end 295.67886 -20.195032)
		(stroke
			(width 0.06985)
			(type default)
		)
		(layer "In2.Cu")
	)
	(gr_line
		(start 295.649396 -222.237808)
		(end 295.706546 -222.294704)
		(stroke
			(width 0.06985)
			(type default)
		)
		(layer "In2.Cu")
	)
	(gr_line
		(start 295.894252 -26.903934)
		(end 295.91381 -26.875994)
		(stroke
			(width 0.06985)
			(type default)
		)
		(layer "In2.Cu")
	)
	(gr_line
		(start 295.91381 -26.875994)
		(end 295.919652 -26.842974)
		(stroke
			(width 0.06985)
			(type default)
		)
		(layer "In2.Cu")
	)
	(gr_line
		(start 295.922954 -31.325058)
		(end 295.955466 -31.319216)
		(stroke
			(width 0.06985)
			(type default)
		)
		(layer "In2.Cu")
	)
	(gr_line
		(start 295.955466 -31.319216)
		(end 295.982644 -31.300166)
		(stroke
			(width 0.06985)
			(type default)
		)
		(layer "In2.Cu")
	)
	(gr_line
		(start 295.9989 -24.490934)
		(end 296.004742 -24.457914)
		(stroke
			(width 0.06985)
			(type default)
		)
		(layer "In2.Cu")
	)
	(gr_line
		(start 296.004742 -24.457914)
		(end 296.0243 -24.429974)
		(stroke
			(width 0.06985)
			(type default)
		)
		(layer "In2.Cu")
	)
	(gr_line
		(start 296.008298 -29.139388)
		(end 296.037 -29.1338)
		(stroke
			(width 0.06985)
			(type default)
		)
		(layer "In2.Cu")
	)
	(gr_line
		(start 296.037 -29.1338)
		(end 296.061892 -29.116528)
		(stroke
			(width 0.06985)
			(type default)
		)
		(layer "In2.Cu")
	)
	(gr_line
		(start 296.119296 -29.589476)
		(end 296.146982 -29.570172)
		(stroke
			(width 0.06985)
			(type default)
		)
		(layer "In2.Cu")
	)
	(gr_line
		(start 296.146982 -29.570172)
		(end 296.179748 -29.56433)
		(stroke
			(width 0.06985)
			(type default)
		)
		(layer "In2.Cu")
	)
	(gr_line
		(start 296.67581 -28.283154)
		(end 296.70375 -28.263596)
		(stroke
			(width 0.06985)
			(type default)
		)
		(layer "In2.Cu")
	)
	(gr_line
		(start 296.70375 -28.263596)
		(end 296.73677 -28.257754)
		(stroke
			(width 0.06985)
			(type default)
		)
		(layer "In2.Cu")
	)
	(gr_line
		(start 296.771314 -30.344618)
		(end 296.799254 -30.32506)
		(stroke
			(width 0.06985)
			(type default)
		)
		(layer "In2.Cu")
	)
	(gr_line
		(start 296.799254 -30.32506)
		(end 296.832274 -30.319218)
		(stroke
			(width 0.06985)
			(type default)
		)
		(layer "In2.Cu")
	)
	(gr_line
		(start 296.907966 -19.300698)
		(end 296.925746 -19.287744)
		(stroke
			(width 0.06985)
			(type default)
		)
		(layer "In2.Cu")
	)
	(gr_line
		(start 296.916856 -23.155148)
		(end 296.927778 -23.139654)
		(stroke
			(width 0.06985)
			(type default)
		)
		(layer "In2.Cu")
	)
	(gr_line
		(start 296.925746 -19.287744)
		(end 296.947082 -19.28241)
		(stroke
			(width 0.06985)
			(type default)
		)
		(layer "In2.Cu")
	)
	(gr_line
		(start 296.927778 -23.139654)
		(end 296.943272 -23.128732)
		(stroke
			(width 0.06985)
			(type default)
		)
		(layer "In2.Cu")
	)
	(gr_line
		(start 296.935398 -212.415374)
		(end 296.935398 -212.415628)
		(stroke
			(width 0.06985)
			(type default)
		)
		(layer "In2.Cu")
	)
	(gr_line
		(start 296.935398 -212.415374)
		(end 296.9387 -212.396578)
		(stroke
			(width 0.06985)
			(type default)
		)
		(layer "In2.Cu")
	)
	(gr_line
		(start 296.935398 -212.377528)
		(end 296.9387 -212.396578)
		(stroke
			(width 0.06985)
			(type default)
		)
		(layer "In2.Cu")
	)
	(gr_line
		(start 297.503088 -15.070074)
		(end 297.565064 -15.042388)
		(stroke
			(width 0.06985)
			(type default)
		)
		(layer "In2.Cu")
	)
	(gr_line
		(start 297.542204 -28.115768)
		(end 297.561 -28.112466)
		(stroke
			(width 0.06985)
			(type default)
		)
		(layer "In2.Cu")
	)
	(gr_line
		(start 297.561 -28.112466)
		(end 297.579796 -28.115768)
		(stroke
			(width 0.06985)
			(type default)
		)
		(layer "In2.Cu")
	)
	(gr_line
		(start 297.565064 -15.042388)
		(end 297.631612 -15.056612)
		(stroke
			(width 0.06985)
			(type default)
		)
		(layer "In2.Cu")
	)
	(gr_line
		(start 297.770042 -22.549866)
		(end 297.797982 -22.530308)
		(stroke
			(width 0.06985)
			(type default)
		)
		(layer "In2.Cu")
	)
	(gr_line
		(start 297.797982 -22.530308)
		(end 297.831002 -22.524466)
		(stroke
			(width 0.06985)
			(type default)
		)
		(layer "In2.Cu")
	)
	(gr_line
		(start 297.84167 -42.066464)
		(end 297.869102 -42.072052)
		(stroke
			(width 0.06985)
			(type default)
		)
		(layer "In2.Cu")
	)
	(gr_line
		(start 297.869102 -42.072052)
		(end 297.895772 -42.06621)
		(stroke
			(width 0.06985)
			(type default)
		)
		(layer "In2.Cu")
	)
	(gr_line
		(start 297.979084 -31.414212)
		(end 297.99788 -31.41091)
		(stroke
			(width 0.06985)
			(type default)
		)
		(layer "In2.Cu")
	)
	(gr_line
		(start 297.99788 -31.41091)
		(end 298.016676 -31.414212)
		(stroke
			(width 0.06985)
			(type default)
		)
		(layer "In2.Cu")
	)
	(gr_line
		(start 298.15155 -41.059608)
		(end 298.178982 -41.065196)
		(stroke
			(width 0.06985)
			(type default)
		)
		(layer "In2.Cu")
	)
	(gr_line
		(start 298.178982 -41.065196)
		(end 298.205652 -41.059354)
		(stroke
			(width 0.06985)
			(type default)
		)
		(layer "In2.Cu")
	)
	(gr_line
		(start 298.255944 -29.198316)
		(end 298.27474 -29.195014)
		(stroke
			(width 0.06985)
			(type default)
		)
		(layer "In2.Cu")
	)
	(gr_line
		(start 298.27474 -29.195014)
		(end 298.29379 -29.198316)
		(stroke
			(width 0.06985)
			(type default)
		)
		(layer "In2.Cu")
	)
	(gr_line
		(start 298.28871 -15.198344)
		(end 298.311062 -15.20317)
		(stroke
			(width 0.06985)
			(type default)
		)
		(layer "In2.Cu")
	)
	(gr_line
		(start 298.311062 -15.20317)
		(end 298.330366 -15.21587)
		(stroke
			(width 0.06985)
			(type default)
		)
		(layer "In2.Cu")
	)
	(gr_line
		(start 298.316904 -30.057598)
		(end 298.3357 -30.054296)
		(stroke
			(width 0.06985)
			(type default)
		)
		(layer "In2.Cu")
	)
	(gr_line
		(start 298.3357 -30.054296)
		(end 298.354496 -30.057598)
		(stroke
			(width 0.06985)
			(type default)
		)
		(layer "In2.Cu")
	)
	(gr_line
		(start 298.534836 -186.877706)
		(end 298.534836 -186.87796)
		(stroke
			(width 0.06985)
			(type default)
		)
		(layer "In2.Cu")
	)
	(gr_line
		(start 298.534836 -186.877706)
		(end 298.538138 -186.85891)
		(stroke
			(width 0.06985)
			(type default)
		)
		(layer "In2.Cu")
	)
	(gr_line
		(start 298.534836 -186.840114)
		(end 298.538138 -186.85891)
		(stroke
			(width 0.06985)
			(type default)
		)
		(layer "In2.Cu")
	)
	(gr_line
		(start 298.774866 -22.358096)
		(end 298.793662 -22.354794)
		(stroke
			(width 0.06985)
			(type default)
		)
		(layer "In2.Cu")
	)
	(gr_line
		(start 298.793662 -22.354794)
		(end 298.812458 -22.358096)
		(stroke
			(width 0.06985)
			(type default)
		)
		(layer "In2.Cu")
	)
	(gr_line
		(start 299.263816 -18.682462)
		(end 299.311314 -18.67027)
		(stroke
			(width 0.06985)
			(type default)
		)
		(layer "In2.Cu")
	)
	(gr_line
		(start 299.311314 -18.67027)
		(end 299.358304 -18.683478)
		(stroke
			(width 0.06985)
			(type default)
		)
		(layer "In2.Cu")
	)
	(gr_line
		(start 299.377354 -16.472916)
		(end 299.377608 -16.472916)
		(stroke
			(width 0.06985)
			(type default)
		)
		(layer "In2.Cu")
	)
	(gr_arc
		(start 299.384466 -17.729962)
		(mid 299.336733 -17.230906)
		(end 299.14469 -16.76781)
		(stroke
			(width 0.06985)
			(type default)
		)
		(layer "In2.Cu")
	)
	(gr_line
		(start 299.413422 -43.204892)
		(end 299.432218 -43.208194)
		(stroke
			(width 0.06985)
			(type default)
		)
		(layer "In2.Cu")
	)
	(gr_line
		(start 299.432218 -43.208194)
		(end 299.451014 -43.204892)
		(stroke
			(width 0.06985)
			(type default)
		)
		(layer "In2.Cu")
	)
	(gr_arc
		(start 299.61078 -16.799052)
		(mid 300.06351 -16.777802)
		(end 300.134274 -16.330168)
		(stroke
			(width 0.06985)
			(type default)
		)
		(layer "In2.Cu")
	)
	(gr_line
		(start 300.038516 -205.166976)
		(end 300.041818 -205.186026)
		(stroke
			(width 0.06985)
			(type default)
		)
		(layer "In2.Cu")
	)
	(gr_line
		(start 300.038516 -205.166976)
		(end 300.041818 -205.14818)
		(stroke
			(width 0.06985)
			(type default)
		)
		(layer "In2.Cu")
	)
	(gr_line
		(start 300.38929 -215.410796)
		(end 300.392592 -215.429846)
		(stroke
			(width 0.06985)
			(type default)
		)
		(layer "In2.Cu")
	)
	(gr_line
		(start 300.38929 -215.410796)
		(end 300.392592 -215.392)
		(stroke
			(width 0.06985)
			(type default)
		)
		(layer "In2.Cu")
	)
	(gr_line
		(start 300.48454 -219.155518)
		(end 300.487842 -219.174568)
		(stroke
			(width 0.06985)
			(type default)
		)
		(layer "In2.Cu")
	)
	(gr_line
		(start 300.48454 -219.155518)
		(end 300.487842 -219.136722)
		(stroke
			(width 0.06985)
			(type default)
		)
		(layer "In2.Cu")
	)
	(gr_line
		(start 300.493684 -222.294704)
		(end 300.550834 -222.237808)
		(stroke
			(width 0.06985)
			(type default)
		)
		(layer "In2.Cu")
	)
	(gr_line
		(start 300.510956 -44.718732)
		(end 300.53788 -44.723812)
		(stroke
			(width 0.06985)
			(type default)
		)
		(layer "In2.Cu")
	)
	(gr_line
		(start 300.52264 -19.356578)
		(end 300.552358 -19.36496)
		(stroke
			(width 0.06985)
			(type default)
		)
		(layer "In2.Cu")
	)
	(gr_line
		(start 300.53788 -44.723812)
		(end 300.56455 -44.718224)
		(stroke
			(width 0.06985)
			(type default)
		)
		(layer "In2.Cu")
	)
	(gr_arc
		(start 300.550834 -222.237808)
		(mid 300.687174 -222.033622)
		(end 300.734984 -221.7928)
		(stroke
			(width 0.06985)
			(type default)
		)
		(layer "In2.Cu")
	)
	(gr_line
		(start 300.552358 -19.36496)
		(end 300.585124 -19.360388)
		(stroke
			(width 0.06985)
			(type default)
		)
		(layer "In2.Cu")
	)
	(gr_line
		(start 300.637448 -23.015448)
		(end 300.656244 -23.01875)
		(stroke
			(width 0.06985)
			(type default)
		)
		(layer "In2.Cu")
	)
	(gr_line
		(start 300.656244 -23.01875)
		(end 300.67504 -23.015448)
		(stroke
			(width 0.06985)
			(type default)
		)
		(layer "In2.Cu")
	)
	(gr_line
		(start 300.73219 -29.007054)
		(end 300.750986 -29.010356)
		(stroke
			(width 0.06985)
			(type default)
		)
		(layer "In2.Cu")
	)
	(gr_line
		(start 300.750986 -29.010356)
		(end 300.769782 -29.007054)
		(stroke
			(width 0.06985)
			(type default)
		)
		(layer "In2.Cu")
	)
	(gr_arc
		(start 301.065184 -221.7928)
		(mid 301.11298 -222.033629)
		(end 301.249334 -222.237808)
		(stroke
			(width 0.06985)
			(type default)
		)
		(layer "In2.Cu")
	)
	(gr_line
		(start 301.09922 -217.572082)
		(end 301.09922 -217.572336)
		(stroke
			(width 0.06985)
			(type default)
		)
		(layer "In2.Cu")
	)
	(gr_line
		(start 301.09922 -217.572082)
		(end 301.102522 -217.553286)
		(stroke
			(width 0.06985)
			(type default)
		)
		(layer "In2.Cu")
	)
	(gr_line
		(start 301.09922 -217.53449)
		(end 301.102522 -217.553286)
		(stroke
			(width 0.06985)
			(type default)
		)
		(layer "In2.Cu")
	)
	(gr_line
		(start 301.132748 -32.299148)
		(end 301.151544 -32.30245)
		(stroke
			(width 0.06985)
			(type default)
		)
		(layer "In2.Cu")
	)
	(gr_line
		(start 301.151544 -32.30245)
		(end 301.17034 -32.299148)
		(stroke
			(width 0.06985)
			(type default)
		)
		(layer "In2.Cu")
	)
	(gr_line
		(start 301.16018 -40.43172)
		(end 301.183802 -40.42664)
		(stroke
			(width 0.06985)
			(type default)
		)
		(layer "In2.Cu")
	)
	(gr_line
		(start 301.170086 -30.040834)
		(end 301.188882 -30.044136)
		(stroke
			(width 0.06985)
			(type default)
		)
		(layer "In2.Cu")
	)
	(gr_line
		(start 301.183802 -40.42664)
		(end 301.202852 -40.413686)
		(stroke
			(width 0.06985)
			(type default)
		)
		(layer "In2.Cu")
	)
	(gr_line
		(start 301.188882 -30.044136)
		(end 301.207678 -30.040834)
		(stroke
			(width 0.06985)
			(type default)
		)
		(layer "In2.Cu")
	)
	(gr_line
		(start 301.249334 -222.237808)
		(end 301.306484 -222.294704)
		(stroke
			(width 0.06985)
			(type default)
		)
		(layer "In2.Cu")
	)
	(gr_line
		(start 301.51959 -19.235166)
		(end 301.53483 -19.233134)
		(stroke
			(width 0.06985)
			(type default)
		)
		(layer "In2.Cu")
	)
	(gr_line
		(start 301.53483 -19.233134)
		(end 301.5488 -19.226276)
		(stroke
			(width 0.06985)
			(type default)
		)
		(layer "In2.Cu")
	)
	(gr_line
		(start 301.813722 -41.233598)
		(end 301.833534 -41.229534)
		(stroke
			(width 0.06985)
			(type default)
		)
		(layer "In2.Cu")
	)
	(gr_line
		(start 301.833534 -41.229534)
		(end 301.851314 -41.218104)
		(stroke
			(width 0.06985)
			(type default)
		)
		(layer "In2.Cu")
	)
	(gr_arc
		(start 301.889922 -16.58112)
		(mid 301.90225 -16.870768)
		(end 302.087026 -17.0942)
		(stroke
			(width 0.06985)
			(type default)
		)
		(layer "In2.Cu")
	)
	(gr_line
		(start 301.928784 -196.34962)
		(end 301.928784 -196.349874)
		(stroke
			(width 0.06985)
			(type default)
		)
		(layer "In2.Cu")
	)
	(gr_line
		(start 301.928784 -196.34962)
		(end 301.932086 -196.330824)
		(stroke
			(width 0.06985)
			(type default)
		)
		(layer "In2.Cu")
	)
	(gr_line
		(start 301.928784 -196.312028)
		(end 301.932086 -196.330824)
		(stroke
			(width 0.06985)
			(type default)
		)
		(layer "In2.Cu")
	)
	(gr_line
		(start 302.062388 -13.253212)
		(end 302.616616 -13.807694)
		(stroke
			(width 0.06985)
			(type default)
		)
		(layer "In2.Cu")
	)
	(gr_line
		(start 302.115728 -31.056326)
		(end 302.134524 -31.059628)
		(stroke
			(width 0.06985)
			(type default)
		)
		(layer "In2.Cu")
	)
	(gr_line
		(start 302.134524 -31.059628)
		(end 302.15332 -31.056326)
		(stroke
			(width 0.06985)
			(type default)
		)
		(layer "In2.Cu")
	)
	(gr_line
		(start 302.137318 -18.931128)
		(end 302.167544 -18.915888)
		(stroke
			(width 0.06985)
			(type default)
		)
		(layer "In2.Cu")
	)
	(gr_line
		(start 302.167544 -18.915888)
		(end 302.188626 -18.889726)
		(stroke
			(width 0.06985)
			(type default)
		)
		(layer "In2.Cu")
	)
	(gr_arc
		(start 302.264318 -16.303244)
		(mid 302.030263 -16.379063)
		(end 301.889922 -16.58112)
		(stroke
			(width 0.06985)
			(type default)
		)
		(layer "In2.Cu")
	)
	(gr_line
		(start 302.264318 -16.303244)
		(end 302.38446 -16.330168)
		(stroke
			(width 0.06985)
			(type default)
		)
		(layer "In2.Cu")
	)
	(gr_arc
		(start 302.38446 -12.530074)
		(mid 301.974791 -12.780959)
		(end 302.062388 -13.253212)
		(stroke
			(width 0.06985)
			(type default)
		)
		(layer "In2.Cu")
	)
	(gr_arc
		(start 302.410368 -14.068806)
		(mid 302.044167 -13.877562)
		(end 301.634398 -13.930122)
		(stroke
			(width 0.06985)
			(type default)
		)
		(layer "In2.Cu")
	)
	(gr_line
		(start 302.41621 -17.28343)
		(end 302.416464 -17.28343)
		(stroke
			(width 0.06985)
			(type default)
		)
		(layer "In2.Cu")
	)
	(gr_line
		(start 302.64354 -22.668484)
		(end 302.67656 -22.662642)
		(stroke
			(width 0.06985)
			(type default)
		)
		(layer "In2.Cu")
	)
	(gr_line
		(start 302.67656 -22.662642)
		(end 302.7045 -22.643084)
		(stroke
			(width 0.06985)
			(type default)
		)
		(layer "In2.Cu")
	)
	(gr_line
		(start 303.108106 -28.594812)
		(end 303.141126 -28.58897)
		(stroke
			(width 0.06985)
			(type default)
		)
		(layer "In2.Cu")
	)
	(gr_line
		(start 303.534826 -22.061678)
		(end 303.55032 -22.050756)
		(stroke
			(width 0.06985)
			(type default)
		)
		(layer "In2.Cu")
	)
	(gr_line
		(start 303.53508 -213.676992)
		(end 303.538382 -213.696042)
		(stroke
			(width 0.06985)
			(type default)
		)
		(layer "In2.Cu")
	)
	(gr_line
		(start 303.53508 -213.676992)
		(end 303.538382 -213.658196)
		(stroke
			(width 0.06985)
			(type default)
		)
		(layer "In2.Cu")
	)
	(gr_line
		(start 303.55032 -22.050756)
		(end 303.561242 -22.035262)
		(stroke
			(width 0.06985)
			(type default)
		)
		(layer "In2.Cu")
	)
	(gr_arc
		(start 303.7332 -220.2942)
		(mid 303.883545 -219.939455)
		(end 303.934876 -219.5576)
		(stroke
			(width 0.06985)
			(type default)
		)
		(layer "In2.Cu")
	)
	(gr_line
		(start 303.908968 -25.052528)
		(end 303.91227 -25.071324)
		(stroke
			(width 0.06985)
			(type default)
		)
		(layer "In2.Cu")
	)
	(gr_line
		(start 303.908968 -25.052528)
		(end 303.91227 -25.033732)
		(stroke
			(width 0.06985)
			(type default)
		)
		(layer "In2.Cu")
	)
	(gr_line
		(start 303.911508 -28.049728)
		(end 303.927002 -28.038806)
		(stroke
			(width 0.06985)
			(type default)
		)
		(layer "In2.Cu")
	)
	(gr_line
		(start 303.91227 -25.033478)
		(end 303.91227 -25.033732)
		(stroke
			(width 0.06985)
			(type default)
		)
		(layer "In2.Cu")
	)
	(gr_line
		(start 303.927002 -28.038806)
		(end 303.937924 -28.023312)
		(stroke
			(width 0.06985)
			(type default)
		)
		(layer "In2.Cu")
	)
	(gr_line
		(start 303.98212 -15.173452)
		(end 303.982374 -15.17396)
		(stroke
			(width 0.06985)
			(type default)
		)
		(layer "In2.Cu")
	)
	(gr_line
		(start 303.982374 -15.17396)
		(end 303.99355 -15.237714)
		(stroke
			(width 0.06985)
			(type default)
		)
		(layer "In2.Cu")
	)
	(gr_line
		(start 304.016156 -29.545788)
		(end 304.049176 -29.539946)
		(stroke
			(width 0.06985)
			(type default)
		)
		(layer "In2.Cu")
	)
	(gr_line
		(start 304.049176 -29.539946)
		(end 304.077116 -29.520388)
		(stroke
			(width 0.06985)
			(type default)
		)
		(layer "In2.Cu")
	)
	(gr_arc
		(start 304.265076 -219.59062)
		(mid 304.338083 -219.957653)
		(end 304.546 -220.2688)
		(stroke
			(width 0.06985)
			(type default)
		)
		(layer "In2.Cu")
	)
	(gr_line
		(start 304.342292 -22.596094)
		(end 304.348134 -22.563074)
		(stroke
			(width 0.06985)
			(type default)
		)
		(layer "In2.Cu")
	)
	(gr_line
		(start 304.348134 -22.563074)
		(end 304.367692 -22.535134)
		(stroke
			(width 0.06985)
			(type default)
		)
		(layer "In2.Cu")
	)
	(gr_line
		(start 304.350166 -27.434286)
		(end 304.369724 -27.406346)
		(stroke
			(width 0.06985)
			(type default)
		)
		(layer "In2.Cu")
	)
	(gr_line
		(start 304.369724 -27.406346)
		(end 304.375566 -27.373326)
		(stroke
			(width 0.06985)
			(type default)
		)
		(layer "In2.Cu")
	)
	(gr_line
		(start 304.511202 -26.603706)
		(end 304.514504 -26.58491)
		(stroke
			(width 0.06985)
			(type default)
		)
		(layer "In2.Cu")
	)
	(gr_line
		(start 304.511202 -26.56586)
		(end 304.511202 -26.566114)
		(stroke
			(width 0.06985)
			(type default)
		)
		(layer "In2.Cu")
	)
	(gr_line
		(start 304.511202 -26.56586)
		(end 304.514504 -26.58491)
		(stroke
			(width 0.06985)
			(type default)
		)
		(layer "In2.Cu")
	)
	(gr_line
		(start 304.59299 -30.62605)
		(end 304.62601 -30.620208)
		(stroke
			(width 0.06985)
			(type default)
		)
		(layer "In2.Cu")
	)
	(gr_line
		(start 304.62601 -30.620208)
		(end 304.65395 -30.60065)
		(stroke
			(width 0.06985)
			(type default)
		)
		(layer "In2.Cu")
	)
	(gr_line
		(start 305.018694 -24.9047)
		(end 305.021996 -24.923496)
		(stroke
			(width 0.06985)
			(type default)
		)
		(layer "In2.Cu")
	)
	(gr_line
		(start 305.018694 -24.9047)
		(end 305.021996 -24.885904)
		(stroke
			(width 0.06985)
			(type default)
		)
		(layer "In2.Cu")
	)
	(gr_line
		(start 305.021996 -24.88565)
		(end 305.021996 -24.885904)
		(stroke
			(width 0.06985)
			(type default)
		)
		(layer "In2.Cu")
	)
	(gr_line
		(start 305.299364 -205.575662)
		(end 305.299364 -205.575916)
		(stroke
			(width 0.06985)
			(type default)
		)
		(layer "In2.Cu")
	)
	(gr_line
		(start 305.299364 -205.575662)
		(end 305.302666 -205.556866)
		(stroke
			(width 0.06985)
			(type default)
		)
		(layer "In2.Cu")
	)
	(gr_line
		(start 305.299364 -205.53807)
		(end 305.302666 -205.556866)
		(stroke
			(width 0.06985)
			(type default)
		)
		(layer "In2.Cu")
	)
	(gr_line
		(start 305.333908 -38.55974)
		(end 305.374548 -38.5191)
		(stroke
			(width 0.06985)
			(type default)
		)
		(layer "In2.Cu")
	)
	(gr_line
		(start 305.347624 -23.039324)
		(end 305.353466 -23.006304)
		(stroke
			(width 0.06985)
			(type default)
		)
		(layer "In2.Cu")
	)
	(gr_line
		(start 305.353466 -23.006304)
		(end 305.373024 -22.978364)
		(stroke
			(width 0.06985)
			(type default)
		)
		(layer "In2.Cu")
	)
	(gr_line
		(start 305.374548 -38.5191)
		(end 305.436524 -38.5191)
		(stroke
			(width 0.06985)
			(type default)
		)
		(layer "In2.Cu")
	)
	(gr_line
		(start 305.398932 -21.638006)
		(end 305.435 -21.586444)
		(stroke
			(width 0.06985)
			(type default)
		)
		(layer "In2.Cu")
	)
	(gr_line
		(start 305.405536 -28.145486)
		(end 305.424586 -28.118562)
		(stroke
			(width 0.06985)
			(type default)
		)
		(layer "In2.Cu")
	)
	(gr_line
		(start 305.424586 -28.118562)
		(end 305.430428 -28.085542)
		(stroke
			(width 0.06985)
			(type default)
		)
		(layer "In2.Cu")
	)
	(gr_line
		(start 305.669188 -26.729436)
		(end 305.67249 -26.710386)
		(stroke
			(width 0.06985)
			(type default)
		)
		(layer "In2.Cu")
	)
	(gr_line
		(start 305.669188 -26.691336)
		(end 305.669188 -26.69159)
		(stroke
			(width 0.06985)
			(type default)
		)
		(layer "In2.Cu")
	)
	(gr_line
		(start 305.669188 -26.691336)
		(end 305.67249 -26.710386)
		(stroke
			(width 0.06985)
			(type default)
		)
		(layer "In2.Cu")
	)
	(gr_line
		(start 305.689 -29.875988)
		(end 305.704494 -29.865066)
		(stroke
			(width 0.06985)
			(type default)
		)
		(layer "In2.Cu")
	)
	(gr_line
		(start 305.704494 -29.865066)
		(end 305.715416 -29.849572)
		(stroke
			(width 0.06985)
			(type default)
		)
		(layer "In2.Cu")
	)
	(gr_line
		(start 306.055014 -24.827992)
		(end 306.058316 -24.846788)
		(stroke
			(width 0.06985)
			(type default)
		)
		(layer "In2.Cu")
	)
	(gr_line
		(start 306.055014 -24.827992)
		(end 306.058316 -24.808942)
		(stroke
			(width 0.06985)
			(type default)
		)
		(layer "In2.Cu")
	)
	(gr_line
		(start 306.058316 -24.808942)
		(end 306.058316 -24.809196)
		(stroke
			(width 0.06985)
			(type default)
		)
		(layer "In2.Cu")
	)
	(gr_line
		(start 306.147978 -24.300434)
		(end 306.15382 -24.267414)
		(stroke
			(width 0.06985)
			(type default)
		)
		(layer "In2.Cu")
	)
	(gr_line
		(start 306.15382 -24.267414)
		(end 306.173378 -24.239474)
		(stroke
			(width 0.06985)
			(type default)
		)
		(layer "In2.Cu")
	)
	(gr_line
		(start 306.414932 -22.065996)
		(end 306.451 -22.014434)
		(stroke
			(width 0.06985)
			(type default)
		)
		(layer "In2.Cu")
	)
	(gr_line
		(start 306.515516 -28.70708)
		(end 306.535074 -28.67914)
		(stroke
			(width 0.06985)
			(type default)
		)
		(layer "In2.Cu")
	)
	(gr_line
		(start 306.535074 -28.67914)
		(end 306.540916 -28.64612)
		(stroke
			(width 0.06985)
			(type default)
		)
		(layer "In2.Cu")
	)
	(gr_line
		(start 306.625752 -36.775136)
		(end 306.64912 -36.759388)
		(stroke
			(width 0.06985)
			(type default)
		)
		(layer "In2.Cu")
	)
	(gr_line
		(start 306.64912 -36.759388)
		(end 306.664614 -36.73602)
		(stroke
			(width 0.06985)
			(type default)
		)
		(layer "In2.Cu")
	)
	(gr_line
		(start 306.79898 -27.182572)
		(end 306.802282 -27.163776)
		(stroke
			(width 0.06985)
			(type default)
		)
		(layer "In2.Cu")
	)
	(gr_line
		(start 306.79898 -27.144726)
		(end 306.802282 -27.163776)
		(stroke
			(width 0.06985)
			(type default)
		)
		(layer "In2.Cu")
	)
	(gr_line
		(start 307.0098 -21.3868)
		(end 307.013102 -21.405596)
		(stroke
			(width 0.06985)
			(type default)
		)
		(layer "In2.Cu")
	)
	(gr_line
		(start 307.0098 -21.3868)
		(end 307.013102 -21.36775)
		(stroke
			(width 0.06985)
			(type default)
		)
		(layer "In2.Cu")
	)
	(gr_line
		(start 307.013102 -21.36775)
		(end 307.013102 -21.368004)
		(stroke
			(width 0.06985)
			(type default)
		)
		(layer "In2.Cu")
	)
	(gr_line
		(start 307.16093 -23.405084)
		(end 307.180488 -23.377144)
		(stroke
			(width 0.06985)
			(type default)
		)
		(layer "In2.Cu")
	)
	(gr_line
		(start 307.180488 -23.377144)
		(end 307.18633 -23.344124)
		(stroke
			(width 0.06985)
			(type default)
		)
		(layer "In2.Cu")
	)
	(gr_line
		(start 307.198014 -20.31873)
		(end 307.203856 -20.28571)
		(stroke
			(width 0.06985)
			(type default)
		)
		(layer "In2.Cu")
	)
	(gr_line
		(start 307.203856 -20.28571)
		(end 307.223414 -20.25777)
		(stroke
			(width 0.06985)
			(type default)
		)
		(layer "In2.Cu")
	)
	(gr_line
		(start 307.434996 -21.9329)
		(end 307.438298 -21.914104)
		(stroke
			(width 0.06985)
			(type default)
		)
		(layer "In2.Cu")
	)
	(gr_line
		(start 307.434996 -21.895054)
		(end 307.438298 -21.914104)
		(stroke
			(width 0.06985)
			(type default)
		)
		(layer "In2.Cu")
	)
	(gr_line
		(start 307.496464 -196.648324)
		(end 307.502306 -196.681344)
		(stroke
			(width 0.06985)
			(type default)
		)
		(layer "In2.Cu")
	)
	(gr_line
		(start 307.502306 -196.681344)
		(end 307.521864 -196.709284)
		(stroke
			(width 0.06985)
			(type default)
		)
		(layer "In2.Cu")
	)
	(gr_line
		(start 307.605684 -19.711924)
		(end 307.606446 -19.710908)
		(stroke
			(width 0.06985)
			(type default)
		)
		(layer "In2.Cu")
	)
	(gr_line
		(start 307.606446 -19.710908)
		(end 307.606954 -19.7104)
		(stroke
			(width 0.06985)
			(type default)
		)
		(layer "In2.Cu")
	)
	(gr_line
		(start 307.620162 -214.930736)
		(end 307.626004 -214.963756)
		(stroke
			(width 0.06985)
			(type default)
		)
		(layer "In2.Cu")
	)
	(gr_line
		(start 307.626004 -214.963756)
		(end 307.645562 -214.991696)
		(stroke
			(width 0.06985)
			(type default)
		)
		(layer "In2.Cu")
	)
	(gr_line
		(start 307.79466 -191.269874)
		(end 307.800502 -191.302894)
		(stroke
			(width 0.06985)
			(type default)
		)
		(layer "In2.Cu")
	)
	(gr_line
		(start 307.800502 -191.302894)
		(end 307.82006 -191.330834)
		(stroke
			(width 0.06985)
			(type default)
		)
		(layer "In2.Cu")
	)
	(gr_line
		(start 307.868066 -210.2358)
		(end 307.871368 -210.25485)
		(stroke
			(width 0.06985)
			(type default)
		)
		(layer "In2.Cu")
	)
	(gr_line
		(start 307.868066 -210.2358)
		(end 307.871368 -210.217004)
		(stroke
			(width 0.06985)
			(type default)
		)
		(layer "In2.Cu")
	)
	(gr_line
		(start 308.248812 -19.154648)
		(end 308.311042 -19.1008)
		(stroke
			(width 0.06985)
			(type default)
		)
		(layer "In2.Cu")
	)
	(gr_line
		(start 308.271164 -188.541152)
		(end 308.277006 -188.574172)
		(stroke
			(width 0.06985)
			(type default)
		)
		(layer "In2.Cu")
	)
	(gr_line
		(start 308.277006 -188.574172)
		(end 308.296564 -188.602112)
		(stroke
			(width 0.06985)
			(type default)
		)
		(layer "In2.Cu")
	)
	(gr_line
		(start 308.35854 -209.357722)
		(end 308.35854 -209.357976)
		(stroke
			(width 0.06985)
			(type default)
		)
		(layer "In2.Cu")
	)
	(gr_line
		(start 308.35854 -209.357722)
		(end 308.361842 -209.338926)
		(stroke
			(width 0.06985)
			(type default)
		)
		(layer "In2.Cu")
	)
	(gr_line
		(start 308.35854 -209.32013)
		(end 308.361842 -209.338926)
		(stroke
			(width 0.06985)
			(type default)
		)
		(layer "In2.Cu")
	)
	(gr_line
		(start 308.574694 -214.243158)
		(end 308.580536 -214.276178)
		(stroke
			(width 0.06985)
			(type default)
		)
		(layer "In2.Cu")
	)
	(gr_line
		(start 308.580536 -214.276178)
		(end 308.600094 -214.304118)
		(stroke
			(width 0.06985)
			(type default)
		)
		(layer "In2.Cu")
	)
	(gr_line
		(start 309.412894 -186.925204)
		(end 309.418736 -186.958224)
		(stroke
			(width 0.06985)
			(type default)
		)
		(layer "In2.Cu")
	)
	(gr_line
		(start 309.418736 -186.958224)
		(end 309.438294 -186.986164)
		(stroke
			(width 0.06985)
			(type default)
		)
		(layer "In2.Cu")
	)
	(gr_line
		(start 309.503826 -18.46072)
		(end 309.50408 -18.46072)
		(stroke
			(width 0.06985)
			(type default)
		)
		(layer "In2.Cu")
	)
	(gr_line
		(start 309.506874 -31.828232)
		(end 309.559452 -31.74873)
		(stroke
			(width 0.06985)
			(type default)
		)
		(layer "In2.Cu")
	)
	(gr_line
		(start 309.543958 -182.034434)
		(end 309.5498 -182.067454)
		(stroke
			(width 0.06985)
			(type default)
		)
		(layer "In2.Cu")
	)
	(gr_line
		(start 309.5498 -182.067454)
		(end 309.569358 -182.095394)
		(stroke
			(width 0.06985)
			(type default)
		)
		(layer "In2.Cu")
	)
	(gr_line
		(start 309.559452 -31.74873)
		(end 309.652416 -31.728918)
		(stroke
			(width 0.06985)
			(type default)
		)
		(layer "In2.Cu")
	)
	(gr_line
		(start 309.737506 -18.22704)
		(end 309.73776 -18.22704)
		(stroke
			(width 0.06985)
			(type default)
		)
		(layer "In2.Cu")
	)
	(gr_line
		(start 309.854346 -37.742114)
		(end 309.904892 -37.73297)
		(stroke
			(width 0.06985)
			(type default)
		)
		(layer "In2.Cu")
	)
	(gr_line
		(start 309.919624 -37.73043)
		(end 309.919878 -37.73043)
		(stroke
			(width 0.06985)
			(type default)
		)
		(layer "In2.Cu")
	)
	(gr_line
		(start 309.919878 -37.73043)
		(end 309.921148 -37.7317)
		(stroke
			(width 0.06985)
			(type default)
		)
		(layer "In2.Cu")
	)
	(gr_line
		(start 309.921148 -37.7317)
		(end 309.922672 -37.7317)
		(stroke
			(width 0.06985)
			(type default)
		)
		(layer "In2.Cu")
	)
	(gr_line
		(start 309.93588 -38.062916)
		(end 309.93715 -38.061646)
		(stroke
			(width 0.06985)
			(type default)
		)
		(layer "In2.Cu")
	)
	(gr_line
		(start 309.93715 -38.061646)
		(end 309.938674 -38.061646)
		(stroke
			(width 0.06985)
			(type default)
		)
		(layer "In2.Cu")
	)
	(gr_line
		(start 309.938674 -38.061646)
		(end 309.944262 -38.061392)
		(stroke
			(width 0.06985)
			(type default)
		)
		(layer "In2.Cu")
	)
	(gr_line
		(start 310.077612 -30.728666)
		(end 310.110632 -30.722824)
		(stroke
			(width 0.06985)
			(type default)
		)
		(layer "In2.Cu")
	)
	(gr_line
		(start 310.07812 -38.054788)
		(end 310.078374 -38.054788)
		(stroke
			(width 0.06985)
			(type default)
		)
		(layer "In2.Cu")
	)
	(gr_line
		(start 310.110632 -30.722824)
		(end 310.138572 -30.703266)
		(stroke
			(width 0.06985)
			(type default)
		)
		(layer "In2.Cu")
	)
	(gr_line
		(start 310.132476 -216.492836)
		(end 310.143398 -216.50833)
		(stroke
			(width 0.06985)
			(type default)
		)
		(layer "In2.Cu")
	)
	(gr_line
		(start 310.143398 -216.50833)
		(end 310.158892 -216.519252)
		(stroke
			(width 0.06985)
			(type default)
		)
		(layer "In2.Cu")
	)
	(gr_line
		(start 310.242966 -180.888386)
		(end 310.248808 -180.921406)
		(stroke
			(width 0.06985)
			(type default)
		)
		(layer "In2.Cu")
	)
	(gr_line
		(start 310.248808 -180.921406)
		(end 310.268366 -180.949346)
		(stroke
			(width 0.06985)
			(type default)
		)
		(layer "In2.Cu")
	)
	(gr_arc
		(start 310.310022 -13.750544)
		(mid 310.329393 -13.847725)
		(end 310.384444 -13.930122)
		(stroke
			(width 0.06985)
			(type default)
		)
		(layer "In2.Cu")
	)
	(gr_line
		(start 310.310022 -13.577316)
		(end 310.310022 -13.750544)
		(stroke
			(width 0.06985)
			(type default)
		)
		(layer "In2.Cu")
	)
	(gr_arc
		(start 310.526938 -13.3604)
		(mid 310.373536 -13.423921)
		(end 310.310022 -13.577316)
		(stroke
			(width 0.06985)
			(type default)
		)
		(layer "In2.Cu")
	)
	(gr_line
		(start 310.526938 -13.3604)
		(end 310.640222 -13.3604)
		(stroke
			(width 0.06985)
			(type default)
		)
		(layer "In2.Cu")
	)
	(gr_arc
		(start 310.887872 -13.463016)
		(mid 310.77426 -13.387065)
		(end 310.640222 -13.3604)
		(stroke
			(width 0.06985)
			(type default)
		)
		(layer "In2.Cu")
	)
	(gr_line
		(start 310.887872 -13.463016)
		(end 310.927242 -13.502386)
		(stroke
			(width 0.06985)
			(type default)
		)
		(layer "In2.Cu")
	)
	(gr_arc
		(start 310.928004 -17.30756)
		(mid 310.483765 -17.296985)
		(end 310.384444 -17.729962)
		(stroke
			(width 0.06985)
			(type default)
		)
		(layer "In2.Cu")
	)
	(gr_arc
		(start 311.134506 -16.330168)
		(mid 311.15084 -16.817169)
		(end 311.322974 -17.273016)
		(stroke
			(width 0.06985)
			(type default)
		)
		(layer "In2.Cu")
	)
	(gr_arc
		(start 311.134506 -13.083286)
		(mid 311.138051 -13.137102)
		(end 311.14873 -13.189966)
		(stroke
			(width 0.06985)
			(type default)
		)
		(layer "In2.Cu")
	)
	(gr_line
		(start 311.134506 -12.530074)
		(end 311.134506 -13.083286)
		(stroke
			(width 0.06985)
			(type default)
		)
		(layer "In2.Cu")
	)
	(gr_arc
		(start 311.14873 -13.189966)
		(mid 311.149357 -13.192381)
		(end 311.15 -13.194792)
		(stroke
			(width 0.06985)
			(type default)
		)
		(layer "In2.Cu")
	)
	(gr_arc
		(start 311.15 -13.194792)
		(mid 311.151127 -13.198353)
		(end 311.152286 -13.201904)
		(stroke
			(width 0.06985)
			(type default)
		)
		(layer "In2.Cu")
	)
	(gr_arc
		(start 311.152286 -13.201904)
		(mid 311.180287 -13.269767)
		(end 311.220104 -13.331444)
		(stroke
			(width 0.06985)
			(type default)
		)
		(layer "In2.Cu")
	)
	(gr_line
		(start 311.332626 -180.31968)
		(end 311.338468 -180.352192)
		(stroke
			(width 0.06985)
			(type default)
		)
		(layer "In2.Cu")
	)
	(gr_line
		(start 311.338468 -180.352192)
		(end 311.357518 -180.37937)
		(stroke
			(width 0.06985)
			(type default)
		)
		(layer "In2.Cu")
	)
	(gr_arc
		(start 311.38749 -13.816076)
		(mid 311.362841 -13.62127)
		(end 311.290716 -13.438632)
		(stroke
			(width 0.06985)
			(type default)
		)
		(layer "In2.Cu")
	)
	(gr_line
		(start 311.463436 -31.681674)
		(end 311.489598 -31.676086)
		(stroke
			(width 0.06985)
			(type default)
		)
		(layer "In2.Cu")
	)
	(gr_line
		(start 311.489598 -31.676086)
		(end 311.511442 -31.660846)
		(stroke
			(width 0.06985)
			(type default)
		)
		(layer "In2.Cu")
	)
	(gr_line
		(start 311.69356 -222.294704)
		(end 311.75071 -222.237808)
		(stroke
			(width 0.06985)
			(type default)
		)
		(layer "In2.Cu")
	)
	(gr_arc
		(start 311.75071 -222.237808)
		(mid 311.88705 -222.033622)
		(end 311.93486 -221.7928)
		(stroke
			(width 0.06985)
			(type default)
		)
		(layer "In2.Cu")
	)
	(gr_line
		(start 312.228992 -220.961204)
		(end 312.26506 -221.012766)
		(stroke
			(width 0.06985)
			(type default)
		)
		(layer "In2.Cu")
	)
	(gr_arc
		(start 312.26506 -221.7928)
		(mid 312.312855 -222.033631)
		(end 312.44921 -222.237808)
		(stroke
			(width 0.06985)
			(type default)
		)
		(layer "In2.Cu")
	)
	(gr_line
		(start 312.329576 -28.7655)
		(end 312.357516 -28.745942)
		(stroke
			(width 0.06985)
			(type default)
		)
		(layer "In2.Cu")
	)
	(gr_line
		(start 312.357516 -28.745942)
		(end 312.390536 -28.7401)
		(stroke
			(width 0.06985)
			(type default)
		)
		(layer "In2.Cu")
	)
	(gr_line
		(start 312.44921 -222.237808)
		(end 312.50636 -222.294704)
		(stroke
			(width 0.06985)
			(type default)
		)
		(layer "In2.Cu")
	)
	(gr_line
		(start 312.634376 -17.729962)
		(end 312.78703 -17.577308)
		(stroke
			(width 0.06985)
			(type default)
		)
		(layer "In2.Cu")
	)
	(gr_line
		(start 312.634376 -13.930122)
		(end 312.679588 -13.821156)
		(stroke
			(width 0.06985)
			(type default)
		)
		(layer "In2.Cu")
	)
	(gr_arc
		(start 312.786268 -13.691108)
		(mid 312.723299 -13.74823)
		(end 312.679588 -13.821156)
		(stroke
			(width 0.06985)
			(type default)
		)
		(layer "In2.Cu")
	)
	(gr_arc
		(start 312.904632 -13.642086)
		(mid 312.840573 -13.654821)
		(end 312.786268 -13.691108)
		(stroke
			(width 0.06985)
			(type default)
		)
		(layer "In2.Cu")
	)
	(gr_line
		(start 312.904632 -13.642086)
		(end 313.015884 -13.642086)
		(stroke
			(width 0.06985)
			(type default)
		)
		(layer "In2.Cu")
	)
	(gr_arc
		(start 313.026298 -17.478248)
		(mid 312.896799 -17.503953)
		(end 312.78703 -17.577308)
		(stroke
			(width 0.06985)
			(type default)
		)
		(layer "In2.Cu")
	)
	(gr_line
		(start 313.026298 -17.478248)
		(end 313.066176 -17.478248)
		(stroke
			(width 0.06985)
			(type default)
		)
		(layer "In2.Cu")
	)
	(gr_arc
		(start 313.121294 -17.48917)
		(mid 313.09427 -17.48101)
		(end 313.066176 -17.478248)
		(stroke
			(width 0.06985)
			(type default)
		)
		(layer "In2.Cu")
	)
	(gr_arc
		(start 313.171586 -13.706602)
		(mid 313.100154 -13.658853)
		(end 313.015884 -13.642086)
		(stroke
			(width 0.06985)
			(type default)
		)
		(layer "In2.Cu")
	)
	(gr_line
		(start 313.171586 -13.706602)
		(end 313.222132 -13.757148)
		(stroke
			(width 0.06985)
			(type default)
		)
		(layer "In2.Cu")
	)
	(gr_line
		(start 313.311286 -180.124608)
		(end 313.317128 -180.155088)
		(stroke
			(width 0.06985)
			(type default)
		)
		(layer "In2.Cu")
	)
	(gr_line
		(start 313.317128 -180.155088)
		(end 313.334908 -180.180234)
		(stroke
			(width 0.06985)
			(type default)
		)
		(layer "In2.Cu")
	)
	(gr_arc
		(start 313.384438 -17.144746)
		(mid 313.390513 -17.200804)
		(end 313.408568 -17.25422)
		(stroke
			(width 0.06985)
			(type default)
		)
		(layer "In2.Cu")
	)
	(gr_line
		(start 313.384438 -16.330168)
		(end 313.384438 -17.144746)
		(stroke
			(width 0.06985)
			(type default)
		)
		(layer "In2.Cu")
	)
	(gr_arc
		(start 313.384438 -13.344906)
		(mid 313.404179 -13.444149)
		(end 313.460384 -13.528294)
		(stroke
			(width 0.06985)
			(type default)
		)
		(layer "In2.Cu")
	)
	(gr_line
		(start 313.384438 -12.530074)
		(end 313.384438 -13.344906)
		(stroke
			(width 0.06985)
			(type default)
		)
		(layer "In2.Cu")
	)
	(gr_arc
		(start 313.408568 -17.25422)
		(mid 313.408821 -17.254855)
		(end 313.409076 -17.25549)
		(stroke
			(width 0.06985)
			(type default)
		)
		(layer "In2.Cu")
	)
	(gr_arc
		(start 313.409076 -17.25549)
		(mid 313.412164 -17.261757)
		(end 313.415426 -17.267936)
		(stroke
			(width 0.06985)
			(type default)
		)
		(layer "In2.Cu")
	)
	(gr_arc
		(start 313.415426 -17.267936)
		(mid 313.417429 -17.271635)
		(end 313.41949 -17.275302)
		(stroke
			(width 0.06985)
			(type default)
		)
		(layer "In2.Cu")
	)
	(gr_arc
		(start 313.41949 -17.275302)
		(mid 313.428086 -17.289046)
		(end 313.437524 -17.302226)
		(stroke
			(width 0.06985)
			(type default)
		)
		(layer "In2.Cu")
	)
	(gr_arc
		(start 313.437524 -17.302226)
		(mid 313.446252 -17.313014)
		(end 313.455558 -17.323308)
		(stroke
			(width 0.06985)
			(type default)
		)
		(layer "In2.Cu")
	)
	(gr_line
		(start 313.449716 -17.328134)
		(end 313.455558 -17.323308)
		(stroke
			(width 0.06985)
			(type default)
		)
		(layer "In2.Cu")
	)
	(gr_arc
		(start 313.460384 -13.528294)
		(mid 313.462028 -13.529952)
		(end 313.463686 -13.531596)
		(stroke
			(width 0.06985)
			(type default)
		)
		(layer "In2.Cu")
	)
	(gr_line
		(start 313.69254 -38.822884)
		(end 313.722004 -38.829234)
		(stroke
			(width 0.06985)
			(type default)
		)
		(layer "In2.Cu")
	)
	(gr_line
		(start 313.720988 -28.841192)
		(end 313.754008 -28.83535)
		(stroke
			(width 0.06985)
			(type default)
		)
		(layer "In2.Cu")
	)
	(gr_line
		(start 313.722004 -38.829234)
		(end 313.751468 -38.822884)
		(stroke
			(width 0.06985)
			(type default)
		)
		(layer "In2.Cu")
	)
	(gr_line
		(start 313.754008 -28.83535)
		(end 313.781948 -28.815792)
		(stroke
			(width 0.06985)
			(type default)
		)
		(layer "In2.Cu")
	)
	(gr_line
		(start 314.244482 -218.976194)
		(end 314.258706 -218.986354)
		(stroke
			(width 0.06985)
			(type default)
		)
		(layer "In2.Cu")
	)
	(gr_line
		(start 314.258706 -218.986354)
		(end 314.268358 -219.000324)
		(stroke
			(width 0.06985)
			(type default)
		)
		(layer "In2.Cu")
	)
	(gr_line
		(start 314.784994 -38.603174)
		(end 314.804806 -38.59911)
		(stroke
			(width 0.06985)
			(type default)
		)
		(layer "In2.Cu")
	)
	(gr_line
		(start 314.804806 -38.59911)
		(end 314.822586 -38.58768)
		(stroke
			(width 0.06985)
			(type default)
		)
		(layer "In2.Cu")
	)
	(gr_line
		(start 314.893706 -222.294704)
		(end 314.950856 -222.237808)
		(stroke
			(width 0.06985)
			(type default)
		)
		(layer "In2.Cu")
	)
	(gr_line
		(start 314.915042 -28.022296)
		(end 314.950094 -27.997658)
		(stroke
			(width 0.06985)
			(type default)
		)
		(layer "In2.Cu")
	)
	(gr_line
		(start 314.940442 -206.72806)
		(end 314.96 -206.756)
		(stroke
			(width 0.06985)
			(type default)
		)
		(layer "In2.Cu")
	)
	(gr_line
		(start 314.950094 -27.997658)
		(end 314.969652 -27.959558)
		(stroke
			(width 0.06985)
			(type default)
		)
		(layer "In2.Cu")
	)
	(gr_arc
		(start 314.950856 -222.237808)
		(mid 315.087192 -222.033622)
		(end 315.135006 -221.7928)
		(stroke
			(width 0.06985)
			(type default)
		)
		(layer "In2.Cu")
	)
	(gr_line
		(start 314.96 -206.756)
		(end 314.965842 -206.78902)
		(stroke
			(width 0.06985)
			(type default)
		)
		(layer "In2.Cu")
	)
	(gr_line
		(start 315.304932 -215.33993)
		(end 315.310774 -215.37295)
		(stroke
			(width 0.06985)
			(type default)
		)
		(layer "In2.Cu")
	)
	(gr_line
		(start 315.310774 -215.37295)
		(end 315.330332 -215.40089)
		(stroke
			(width 0.06985)
			(type default)
		)
		(layer "In2.Cu")
	)
	(gr_line
		(start 315.322204 -27.272996)
		(end 315.32576 -27.265884)
		(stroke
			(width 0.06985)
			(type default)
		)
		(layer "In2.Cu")
	)
	(gr_line
		(start 315.32576 -27.265884)
		(end 315.327284 -27.257756)
		(stroke
			(width 0.06985)
			(type default)
		)
		(layer "In2.Cu")
	)
	(gr_line
		(start 315.42863 -220.65488)
		(end 315.465206 -220.707204)
		(stroke
			(width 0.06985)
			(type default)
		)
		(layer "In2.Cu")
	)
	(gr_arc
		(start 315.465206 -221.7928)
		(mid 315.513015 -222.033622)
		(end 315.649356 -222.237808)
		(stroke
			(width 0.06985)
			(type default)
		)
		(layer "In2.Cu")
	)
	(gr_line
		(start 315.491114 -209.768694)
		(end 315.494416 -209.78749)
		(stroke
			(width 0.06985)
			(type default)
		)
		(layer "In2.Cu")
	)
	(gr_line
		(start 315.494416 -209.78749)
		(end 315.494416 -209.924396)
		(stroke
			(width 0.06985)
			(type default)
		)
		(layer "In2.Cu")
	)
	(gr_line
		(start 315.60389 -25.716738)
		(end 315.608462 -25.73909)
		(stroke
			(width 0.06985)
			(type default)
		)
		(layer "In2.Cu")
	)
	(gr_line
		(start 315.604398 -25.761696)
		(end 315.608462 -25.73909)
		(stroke
			(width 0.06985)
			(type default)
		)
		(layer "In2.Cu")
	)
	(gr_line
		(start 315.649356 -222.237808)
		(end 315.706506 -222.294704)
		(stroke
			(width 0.06985)
			(type default)
		)
		(layer "In2.Cu")
	)
	(gr_line
		(start 316.26302 -37.652198)
		(end 316.287912 -37.635942)
		(stroke
			(width 0.06985)
			(type default)
		)
		(layer "In2.Cu")
	)
	(gr_line
		(start 316.287912 -37.635942)
		(end 316.304168 -37.61105)
		(stroke
			(width 0.06985)
			(type default)
		)
		(layer "In2.Cu")
	)
	(gr_line
		(start 316.416436 -16.947642)
		(end 316.422278 -16.914622)
		(stroke
			(width 0.06985)
			(type default)
		)
		(layer "In2.Cu")
	)
	(gr_line
		(start 316.422278 -16.914622)
		(end 316.441836 -16.886682)
		(stroke
			(width 0.06985)
			(type default)
		)
		(layer "In2.Cu")
	)
	(gr_line
		(start 316.737238 -28.001722)
		(end 316.815724 -27.946604)
		(stroke
			(width 0.06985)
			(type default)
		)
		(layer "In2.Cu")
	)
	(gr_line
		(start 316.815724 -27.946604)
		(end 316.832488 -27.851862)
		(stroke
			(width 0.06985)
			(type default)
		)
		(layer "In2.Cu")
	)
	(gr_line
		(start 317.049404 -26.622502)
		(end 317.052706 -26.603706)
		(stroke
			(width 0.06985)
			(type default)
		)
		(layer "In2.Cu")
	)
	(gr_line
		(start 317.049404 -26.584656)
		(end 317.052706 -26.603706)
		(stroke
			(width 0.06985)
			(type default)
		)
		(layer "In2.Cu")
	)
	(gr_line
		(start 317.080138 -33.263332)
		(end 317.084456 -33.23844)
		(stroke
			(width 0.06985)
			(type default)
		)
		(layer "In2.Cu")
	)
	(gr_line
		(start 317.080138 -33.263332)
		(end 317.085218 -33.287716)
		(stroke
			(width 0.06985)
			(type default)
		)
		(layer "In2.Cu")
	)
	(gr_line
		(start 317.084456 -33.23844)
		(end 317.084456 -33.238694)
		(stroke
			(width 0.06985)
			(type default)
		)
		(layer "In2.Cu")
	)
	(gr_line
		(start 317.292228 -32.057594)
		(end 317.29807 -32.024574)
		(stroke
			(width 0.06985)
			(type default)
		)
		(layer "In2.Cu")
	)
	(gr_line
		(start 317.29807 -32.024574)
		(end 317.317628 -31.996634)
		(stroke
			(width 0.06985)
			(type default)
		)
		(layer "In2.Cu")
	)
	(gr_line
		(start 317.352934 -15.58544)
		(end 317.379858 -15.546832)
		(stroke
			(width 0.06985)
			(type default)
		)
		(layer "In2.Cu")
	)
	(gr_line
		(start 317.379858 -15.546832)
		(end 317.423038 -15.526004)
		(stroke
			(width 0.06985)
			(type default)
		)
		(layer "In2.Cu")
	)
	(gr_line
		(start 317.542672 -35.704018)
		(end 317.554102 -35.686238)
		(stroke
			(width 0.06985)
			(type default)
		)
		(layer "In2.Cu")
	)
	(gr_line
		(start 317.554102 -35.686238)
		(end 317.558166 -35.666426)
		(stroke
			(width 0.06985)
			(type default)
		)
		(layer "In2.Cu")
	)
	(gr_line
		(start 317.737236 -34.824416)
		(end 317.743586 -34.794952)
		(stroke
			(width 0.06985)
			(type default)
		)
		(layer "In2.Cu")
	)
	(gr_line
		(start 317.737236 -34.764726)
		(end 317.743586 -34.794952)
		(stroke
			(width 0.06985)
			(type default)
		)
		(layer "In2.Cu")
	)
	(gr_line
		(start 318.093598 -222.294704)
		(end 318.150748 -222.237808)
		(stroke
			(width 0.06985)
			(type default)
		)
		(layer "In2.Cu")
	)
	(gr_line
		(start 318.115442 -205.45806)
		(end 318.135 -205.486)
		(stroke
			(width 0.06985)
			(type default)
		)
		(layer "In2.Cu")
	)
	(gr_line
		(start 318.135 -205.486)
		(end 318.140842 -205.51902)
		(stroke
			(width 0.06985)
			(type default)
		)
		(layer "In2.Cu")
	)
	(gr_arc
		(start 318.150748 -222.237808)
		(mid 318.287088 -222.033622)
		(end 318.334898 -221.7928)
		(stroke
			(width 0.06985)
			(type default)
		)
		(layer "In2.Cu")
	)
	(gr_line
		(start 318.157352 -31.373572)
		(end 318.17691 -31.345632)
		(stroke
			(width 0.06985)
			(type default)
		)
		(layer "In2.Cu")
	)
	(gr_line
		(start 318.17691 -31.345632)
		(end 318.182752 -31.312612)
		(stroke
			(width 0.06985)
			(type default)
		)
		(layer "In2.Cu")
	)
	(gr_line
		(start 318.210438 -211.455)
		(end 318.211454 -211.44611)
		(stroke
			(width 0.06985)
			(type default)
		)
		(layer "In2.Cu")
	)
	(gr_line
		(start 318.210438 -211.455)
		(end 318.211962 -211.463636)
		(stroke
			(width 0.06985)
			(type default)
		)
		(layer "In2.Cu")
	)
	(gr_line
		(start 318.361822 -30.250638)
		(end 318.36614 -30.271974)
		(stroke
			(width 0.06985)
			(type default)
		)
		(layer "In2.Cu")
	)
	(gr_line
		(start 318.36233 -30.29331)
		(end 318.36614 -30.271974)
		(stroke
			(width 0.06985)
			(type default)
		)
		(layer "In2.Cu")
	)
	(gr_line
		(start 318.445896 -26.868882)
		(end 318.450976 -26.894028)
		(stroke
			(width 0.06985)
			(type default)
		)
		(layer "In2.Cu")
	)
	(gr_line
		(start 318.44615 -26.918158)
		(end 318.450976 -26.894028)
		(stroke
			(width 0.06985)
			(type default)
		)
		(layer "In2.Cu")
	)
	(gr_line
		(start 318.62903 -219.535756)
		(end 318.665098 -219.587318)
		(stroke
			(width 0.06985)
			(type default)
		)
		(layer "In2.Cu")
	)
	(gr_arc
		(start 318.665098 -221.7928)
		(mid 318.712889 -222.033634)
		(end 318.849248 -222.237808)
		(stroke
			(width 0.06985)
			(type default)
		)
		(layer "In2.Cu")
	)
	(gr_line
		(start 318.795908 -209.234532)
		(end 318.797432 -209.243168)
		(stroke
			(width 0.06985)
			(type default)
		)
		(layer "In2.Cu")
	)
	(gr_line
		(start 318.796416 -209.252058)
		(end 318.797432 -209.243168)
		(stroke
			(width 0.06985)
			(type default)
		)
		(layer "In2.Cu")
	)
	(gr_line
		(start 318.849248 -222.237808)
		(end 318.906398 -222.294704)
		(stroke
			(width 0.06985)
			(type default)
		)
		(layer "In2.Cu")
	)
	(gr_line
		(start 319.01003 -39.755826)
		(end 319.037208 -39.751)
		(stroke
			(width 0.06985)
			(type default)
		)
		(layer "In2.Cu")
	)
	(gr_line
		(start 319.037208 -39.751)
		(end 319.06083 -39.73576)
		(stroke
			(width 0.06985)
			(type default)
		)
		(layer "In2.Cu")
	)
	(gr_line
		(start 319.058798 -216.266268)
		(end 319.06464 -216.299288)
		(stroke
			(width 0.06985)
			(type default)
		)
		(layer "In2.Cu")
	)
	(gr_line
		(start 319.06464 -216.299288)
		(end 319.084198 -216.327228)
		(stroke
			(width 0.06985)
			(type default)
		)
		(layer "In2.Cu")
	)
	(gr_line
		(start 319.261998 -14.645894)
		(end 319.29451 -14.6304)
		(stroke
			(width 0.06985)
			(type default)
		)
		(layer "In2.Cu")
	)
	(gr_line
		(start 320.783458 -38.617398)
		(end 320.80835 -38.601142)
		(stroke
			(width 0.06985)
			(type default)
		)
		(layer "In2.Cu")
	)
	(gr_line
		(start 320.80835 -38.601142)
		(end 320.824606 -38.576758)
		(stroke
			(width 0.06985)
			(type default)
		)
		(layer "In2.Cu")
	)
	(gr_line
		(start 321.293744 -222.294704)
		(end 321.350894 -222.237808)
		(stroke
			(width 0.06985)
			(type default)
		)
		(layer "In2.Cu")
	)
	(gr_line
		(start 321.328796 -13.804138)
		(end 321.384422 -13.930122)
		(stroke
			(width 0.06985)
			(type default)
		)
		(layer "In2.Cu")
	)
	(gr_arc
		(start 321.350894 -222.237808)
		(mid 321.487222 -222.03362)
		(end 321.535044 -221.7928)
		(stroke
			(width 0.06985)
			(type default)
		)
		(layer "In2.Cu")
	)
	(gr_line
		(start 321.352672 -17.644872)
		(end 321.384422 -17.729962)
		(stroke
			(width 0.06985)
			(type default)
		)
		(layer "In2.Cu")
	)
	(gr_line
		(start 321.5005 -37.562028)
		(end 321.512692 -37.544248)
		(stroke
			(width 0.06985)
			(type default)
		)
		(layer "In2.Cu")
	)
	(gr_line
		(start 321.512692 -37.544248)
		(end 321.517518 -37.52215)
		(stroke
			(width 0.06985)
			(type default)
		)
		(layer "In2.Cu")
	)
	(gr_arc
		(start 321.55892 -17.191736)
		(mid 321.361985 -17.375592)
		(end 321.352672 -17.644872)
		(stroke
			(width 0.06985)
			(type default)
		)
		(layer "In2.Cu")
	)
	(gr_line
		(start 321.55892 -17.191736)
		(end 321.559428 -17.191482)
		(stroke
			(width 0.06985)
			(type default)
		)
		(layer "In2.Cu")
	)
	(gr_line
		(start 321.829176 -219.671646)
		(end 321.865244 -219.723208)
		(stroke
			(width 0.06985)
			(type default)
		)
		(layer "In2.Cu")
	)
	(gr_arc
		(start 321.865244 -221.7928)
		(mid 321.913053 -222.033622)
		(end 322.049394 -222.237808)
		(stroke
			(width 0.06985)
			(type default)
		)
		(layer "In2.Cu")
	)
	(gr_line
		(start 321.908932 -207.466438)
		(end 321.945 -207.518)
		(stroke
			(width 0.06985)
			(type default)
		)
		(layer "In2.Cu")
	)
	(gr_arc
		(start 321.968368 -13.521944)
		(mid 321.507484 -13.34337)
		(end 321.328796 -13.804138)
		(stroke
			(width 0.06985)
			(type default)
		)
		(layer "In2.Cu")
	)
	(gr_line
		(start 321.968368 -13.521944)
		(end 322.014596 -13.626592)
		(stroke
			(width 0.06985)
			(type default)
		)
		(layer "In2.Cu")
	)
	(gr_arc
		(start 322.012564 -17.397984)
		(mid 321.828805 -17.200808)
		(end 321.559428 -17.191482)
		(stroke
			(width 0.06985)
			(type default)
		)
		(layer "In2.Cu")
	)
	(gr_line
		(start 322.012564 -17.397984)
		(end 322.012564 -17.398238)
		(stroke
			(width 0.06985)
			(type default)
		)
		(layer "In2.Cu")
	)
	(gr_line
		(start 322.049394 -222.237808)
		(end 322.106544 -222.294704)
		(stroke
			(width 0.06985)
			(type default)
		)
		(layer "In2.Cu")
	)
	(gr_line
		(start 322.051934 -17.499584)
		(end 322.052188 -17.499584)
		(stroke
			(width 0.06985)
			(type default)
		)
		(layer "In2.Cu")
	)
	(gr_line
		(start 322.129912 -216.42197)
		(end 322.135754 -216.45499)
		(stroke
			(width 0.06985)
			(type default)
		)
		(layer "In2.Cu")
	)
	(gr_arc
		(start 322.134484 -12.530074)
		(mid 322.162714 -13.019337)
		(end 322.313554 -13.485622)
		(stroke
			(width 0.06985)
			(type default)
		)
		(layer "In2.Cu")
	)
	(gr_line
		(start 322.135754 -216.45499)
		(end 322.155312 -216.48293)
		(stroke
			(width 0.06985)
			(type default)
		)
		(layer "In2.Cu")
	)
	(gr_line
		(start 322.41998 -31.688786)
		(end 322.424044 -31.668974)
		(stroke
			(width 0.06985)
			(type default)
		)
		(layer "In2.Cu")
	)
	(gr_line
		(start 322.424044 -31.668974)
		(end 322.435474 -31.651194)
		(stroke
			(width 0.06985)
			(type default)
		)
		(layer "In2.Cu")
	)
	(gr_line
		(start 322.903088 -30.931358)
		(end 322.955666 -30.850586)
		(stroke
			(width 0.06985)
			(type default)
		)
		(layer "In2.Cu")
	)
	(gr_line
		(start 322.955666 -30.850586)
		(end 323.0499 -30.83052)
		(stroke
			(width 0.06985)
			(type default)
		)
		(layer "In2.Cu")
	)
	(gr_line
		(start 323.634354 -17.729962)
		(end 323.679566 -17.620996)
		(stroke
			(width 0.06985)
			(type default)
		)
		(layer "In2.Cu")
	)
	(gr_line
		(start 323.634354 -13.930122)
		(end 323.679566 -13.821156)
		(stroke
			(width 0.06985)
			(type default)
		)
		(layer "In2.Cu")
	)
	(gr_arc
		(start 323.786246 -17.490948)
		(mid 323.723252 -17.548055)
		(end 323.679566 -17.620996)
		(stroke
			(width 0.06985)
			(type default)
		)
		(layer "In2.Cu")
	)
	(gr_arc
		(start 323.786246 -13.691108)
		(mid 323.723263 -13.748221)
		(end 323.679566 -13.821156)
		(stroke
			(width 0.06985)
			(type default)
		)
		(layer "In2.Cu")
	)
	(gr_arc
		(start 323.90461 -17.441926)
		(mid 323.840553 -17.454665)
		(end 323.786246 -17.490948)
		(stroke
			(width 0.06985)
			(type default)
		)
		(layer "In2.Cu")
	)
	(gr_line
		(start 323.90461 -17.441926)
		(end 324.015862 -17.441926)
		(stroke
			(width 0.06985)
			(type default)
		)
		(layer "In2.Cu")
	)
	(gr_arc
		(start 323.90461 -13.642086)
		(mid 323.840556 -13.654828)
		(end 323.786246 -13.691108)
		(stroke
			(width 0.06985)
			(type default)
		)
		(layer "In2.Cu")
	)
	(gr_line
		(start 323.90461 -13.642086)
		(end 324.015862 -13.642086)
		(stroke
			(width 0.06985)
			(type default)
		)
		(layer "In2.Cu")
	)
	(gr_arc
		(start 324.074536 -17.4498)
		(mid 324.045463 -17.443895)
		(end 324.015862 -17.441926)
		(stroke
			(width 0.06985)
			(type default)
		)
		(layer "In2.Cu")
	)
	(gr_arc
		(start 324.171564 -17.506442)
		(mid 324.126719 -17.471837)
		(end 324.074536 -17.4498)
		(stroke
			(width 0.06985)
			(type default)
		)
		(layer "In2.Cu")
	)
	(gr_line
		(start 324.171564 -17.506442)
		(end 324.22211 -17.556988)
		(stroke
			(width 0.06985)
			(type default)
		)
		(layer "In2.Cu")
	)
	(gr_arc
		(start 324.171564 -13.706602)
		(mid 324.100131 -13.65886)
		(end 324.015862 -13.642086)
		(stroke
			(width 0.06985)
			(type default)
		)
		(layer "In2.Cu")
	)
	(gr_line
		(start 324.171564 -13.706602)
		(end 324.22211 -13.757148)
		(stroke
			(width 0.06985)
			(type default)
		)
		(layer "In2.Cu")
	)
	(gr_line
		(start 324.3072 -18.45945)
		(end 324.343522 -18.51152)
		(stroke
			(width 0.06985)
			(type default)
		)
		(layer "In2.Cu")
	)
	(gr_line
		(start 324.3072 -15.0876)
		(end 324.375272 -15.155672)
		(stroke
			(width 0.06985)
			(type default)
		)
		(layer "In2.Cu")
	)
	(gr_arc
		(start 324.384416 -17.144746)
		(mid 324.404157 -17.243989)
		(end 324.460362 -17.328134)
		(stroke
			(width 0.06985)
			(type default)
		)
		(layer "In2.Cu")
	)
	(gr_line
		(start 324.384416 -16.330168)
		(end 324.384416 -17.144746)
		(stroke
			(width 0.06985)
			(type default)
		)
		(layer "In2.Cu")
	)
	(gr_arc
		(start 324.384416 -13.344906)
		(mid 324.404157 -13.444149)
		(end 324.460362 -13.528294)
		(stroke
			(width 0.06985)
			(type default)
		)
		(layer "In2.Cu")
	)
	(gr_line
		(start 324.384416 -12.530074)
		(end 324.384416 -13.344906)
		(stroke
			(width 0.06985)
			(type default)
		)
		(layer "In2.Cu")
	)
	(gr_arc
		(start 324.460362 -17.328134)
		(mid 324.462006 -17.329792)
		(end 324.463664 -17.331436)
		(stroke
			(width 0.06985)
			(type default)
		)
		(layer "In2.Cu")
	)
	(gr_arc
		(start 324.460362 -13.528294)
		(mid 324.462006 -13.529952)
		(end 324.463664 -13.531596)
		(stroke
			(width 0.06985)
			(type default)
		)
		(layer "In2.Cu")
	)
	(gr_line
		(start 324.461886 -18.680938)
		(end 324.46214 -18.680938)
		(stroke
			(width 0.06985)
			(type default)
		)
		(layer "In2.Cu")
	)
	(gr_line
		(start 324.461886 -18.680684)
		(end 324.461886 -18.680938)
		(stroke
			(width 0.06985)
			(type default)
		)
		(layer "In2.Cu")
	)
	(gr_line
		(start 324.493636 -222.294704)
		(end 324.550786 -222.237808)
		(stroke
			(width 0.06985)
			(type default)
		)
		(layer "In2.Cu")
	)
	(gr_arc
		(start 324.550786 -222.237808)
		(mid 324.687116 -222.03362)
		(end 324.734936 -221.7928)
		(stroke
			(width 0.06985)
			(type default)
		)
		(layer "In2.Cu")
	)
	(gr_line
		(start 324.588378 -18.861278)
		(end 324.600062 -18.869914)
		(stroke
			(width 0.06985)
			(type default)
		)
		(layer "In2.Cu")
	)
	(gr_line
		(start 324.6374 -18.350484)
		(end 324.6374 -18.35531)
		(stroke
			(width 0.06985)
			(type default)
		)
		(layer "In2.Cu")
	)
	(gr_line
		(start 324.771512 -219.644214)
		(end 324.77964 -219.655898)
		(stroke
			(width 0.06985)
			(type default)
		)
		(layer "In2.Cu")
	)
	(gr_line
		(start 324.77964 -219.655898)
		(end 324.783704 -219.669868)
		(stroke
			(width 0.06985)
			(type default)
		)
		(layer "In2.Cu")
	)
	(gr_line
		(start 325.063612 -220.64599)
		(end 325.065136 -220.651324)
		(stroke
			(width 0.06985)
			(type default)
		)
		(layer "In2.Cu")
	)
	(gr_arc
		(start 325.065136 -221.7928)
		(mid 325.112945 -222.033622)
		(end 325.249286 -222.237808)
		(stroke
			(width 0.06985)
			(type default)
		)
		(layer "In2.Cu")
	)
	(gr_line
		(start 325.083932 -208.754218)
		(end 325.12 -208.80578)
		(stroke
			(width 0.06985)
			(type default)
		)
		(layer "In2.Cu")
	)
	(gr_line
		(start 325.151496 -215.77173)
		(end 325.157338 -215.80475)
		(stroke
			(width 0.06985)
			(type default)
		)
		(layer "In2.Cu")
	)
	(gr_line
		(start 325.157338 -215.80475)
		(end 325.176896 -215.83269)
		(stroke
			(width 0.06985)
			(type default)
		)
		(layer "In2.Cu")
	)
	(gr_line
		(start 325.249286 -222.237808)
		(end 325.306436 -222.294704)
		(stroke
			(width 0.06985)
			(type default)
		)
		(layer "In2.Cu")
	)
	(gr_line
		(start 325.338694 -39.452296)
		(end 325.358506 -39.448232)
		(stroke
			(width 0.06985)
			(type default)
		)
		(layer "In2.Cu")
	)
	(gr_line
		(start 325.358506 -39.448232)
		(end 325.376286 -39.436802)
		(stroke
			(width 0.06985)
			(type default)
		)
		(layer "In2.Cu")
	)
	(gr_line
		(start 326.08393 -30.523434)
		(end 326.103742 -30.51937)
		(stroke
			(width 0.06985)
			(type default)
		)
		(layer "In2.Cu")
	)
	(gr_line
		(start 326.103742 -30.51937)
		(end 326.121522 -30.50794)
		(stroke
			(width 0.06985)
			(type default)
		)
		(layer "In2.Cu")
	)
	(gr_line
		(start 326.302878 -217.440764)
		(end 326.3138 -217.456258)
		(stroke
			(width 0.06985)
			(type default)
		)
		(layer "In2.Cu")
	)
	(gr_line
		(start 326.3138 -217.456258)
		(end 326.329294 -217.46718)
		(stroke
			(width 0.06985)
			(type default)
		)
		(layer "In2.Cu")
	)
	(gr_line
		(start 327.070974 -29.890974)
		(end 327.09739 -29.873702)
		(stroke
			(width 0.06985)
			(type default)
		)
		(layer "In2.Cu")
	)
	(gr_line
		(start 327.09739 -29.873702)
		(end 327.114662 -29.847286)
		(stroke
			(width 0.06985)
			(type default)
		)
		(layer "In2.Cu")
	)
	(gr_line
		(start 327.517506 -217.895678)
		(end 327.533 -217.9066)
		(stroke
			(width 0.06985)
			(type default)
		)
		(layer "In2.Cu")
	)
	(gr_line
		(start 327.533 -217.9066)
		(end 327.543922 -217.922094)
		(stroke
			(width 0.06985)
			(type default)
		)
		(layer "In2.Cu")
	)
	(gr_line
		(start 327.57618 -29.138372)
		(end 327.589134 -29.118306)
		(stroke
			(width 0.06985)
			(type default)
		)
		(layer "In2.Cu")
	)
	(gr_line
		(start 327.589134 -29.118306)
		(end 327.59396 -29.095192)
		(stroke
			(width 0.06985)
			(type default)
		)
		(layer "In2.Cu")
	)
	(gr_line
		(start 327.63968 -20.689062)
		(end 327.708514 -20.739608)
		(stroke
			(width 0.06985)
			(type default)
		)
		(layer "In2.Cu")
	)
	(gr_line
		(start 327.693782 -222.294704)
		(end 327.750932 -222.237808)
		(stroke
			(width 0.06985)
			(type default)
		)
		(layer "In2.Cu")
	)
	(gr_line
		(start 327.708514 -20.739608)
		(end 327.726294 -20.823174)
		(stroke
			(width 0.06985)
			(type default)
		)
		(layer "In2.Cu")
	)
	(gr_arc
		(start 327.750932 -222.237808)
		(mid 327.887272 -222.033622)
		(end 327.935082 -221.7928)
		(stroke
			(width 0.06985)
			(type default)
		)
		(layer "In2.Cu")
	)
	(gr_line
		(start 328.185018 -18.498058)
		(end 328.225658 -18.538698)
		(stroke
			(width 0.06985)
			(type default)
		)
		(layer "In2.Cu")
	)
	(gr_line
		(start 328.225658 -18.538698)
		(end 328.237596 -18.594832)
		(stroke
			(width 0.06985)
			(type default)
		)
		(layer "In2.Cu")
	)
	(gr_line
		(start 328.228452 -218.89974)
		(end 328.265282 -218.952318)
		(stroke
			(width 0.06985)
			(type default)
		)
		(layer "In2.Cu")
	)
	(gr_arc
		(start 328.265282 -221.7928)
		(mid 328.313078 -222.03363)
		(end 328.449432 -222.237808)
		(stroke
			(width 0.06985)
			(type default)
		)
		(layer "In2.Cu")
	)
	(gr_line
		(start 328.449432 -222.237808)
		(end 328.506582 -222.294704)
		(stroke
			(width 0.06985)
			(type default)
		)
		(layer "In2.Cu")
	)
	(gr_line
		(start 328.522584 -24.62784)
		(end 328.52868 -24.599392)
		(stroke
			(width 0.06985)
			(type default)
		)
		(layer "In2.Cu")
	)
	(gr_line
		(start 328.522584 -24.570182)
		(end 328.52868 -24.599392)
		(stroke
			(width 0.06985)
			(type default)
		)
		(layer "In2.Cu")
	)
	(gr_line
		(start 328.522584 -24.569928)
		(end 328.522584 -24.570436)
		(stroke
			(width 0.06985)
			(type default)
		)
		(layer "In2.Cu")
	)
	(gr_line
		(start 328.911966 -27.66822)
		(end 328.918316 -27.697684)
		(stroke
			(width 0.06985)
			(type default)
		)
		(layer "In2.Cu")
	)
	(gr_line
		(start 328.911966 -27.66822)
		(end 328.91857 -27.637486)
		(stroke
			(width 0.06985)
			(type default)
		)
		(layer "In2.Cu")
	)
	(gr_line
		(start 329.392026 -206.128366)
		(end 329.402948 -206.14386)
		(stroke
			(width 0.06985)
			(type default)
		)
		(layer "In2.Cu")
	)
	(gr_line
		(start 329.402948 -206.14386)
		(end 329.418442 -206.154782)
		(stroke
			(width 0.06985)
			(type default)
		)
		(layer "In2.Cu")
	)
	(gr_line
		(start 329.701144 -25.480772)
		(end 329.707748 -25.511506)
		(stroke
			(width 0.06985)
			(type default)
		)
		(layer "In2.Cu")
	)
	(gr_line
		(start 329.701398 -25.54097)
		(end 329.707748 -25.511506)
		(stroke
			(width 0.06985)
			(type default)
		)
		(layer "In2.Cu")
	)
	(gr_line
		(start 329.761342 -210.356196)
		(end 329.7809 -210.384136)
		(stroke
			(width 0.06985)
			(type default)
		)
		(layer "In2.Cu")
	)
	(gr_line
		(start 329.7809 -210.384136)
		(end 329.786742 -210.417156)
		(stroke
			(width 0.06985)
			(type default)
		)
		(layer "In2.Cu")
	)
	(gr_line
		(start 330.264008 -36.261802)
		(end 330.344018 -36.209986)
		(stroke
			(width 0.06985)
			(type default)
		)
		(layer "In2.Cu")
	)
	(gr_line
		(start 330.344018 -36.209986)
		(end 330.364084 -36.115752)
		(stroke
			(width 0.06985)
			(type default)
		)
		(layer "In2.Cu")
	)
	(gr_line
		(start 330.587096 -204.818742)
		(end 330.598018 -204.834236)
		(stroke
			(width 0.06985)
			(type default)
		)
		(layer "In2.Cu")
	)
	(gr_line
		(start 330.598018 -204.834236)
		(end 330.613512 -204.845158)
		(stroke
			(width 0.06985)
			(type default)
		)
		(layer "In2.Cu")
	)
	(gr_line
		(start 330.697586 -34.483548)
		(end 330.70419 -34.514282)
		(stroke
			(width 0.06985)
			(type default)
		)
		(layer "In2.Cu")
	)
	(gr_line
		(start 330.69784 -34.543746)
		(end 330.70419 -34.514282)
		(stroke
			(width 0.06985)
			(type default)
		)
		(layer "In2.Cu")
	)
	(gr_line
		(start 330.893674 -222.294704)
		(end 330.950824 -222.237808)
		(stroke
			(width 0.06985)
			(type default)
		)
		(layer "In2.Cu")
	)
	(gr_arc
		(start 330.950824 -222.237808)
		(mid 331.087164 -222.033622)
		(end 331.134974 -221.7928)
		(stroke
			(width 0.06985)
			(type default)
		)
		(layer "In2.Cu")
	)
	(gr_line
		(start 330.971652 -209.940652)
		(end 330.99121 -209.968592)
		(stroke
			(width 0.06985)
			(type default)
		)
		(layer "In2.Cu")
	)
	(gr_line
		(start 330.99121 -209.968592)
		(end 330.997052 -210.001612)
		(stroke
			(width 0.06985)
			(type default)
		)
		(layer "In2.Cu")
	)
	(gr_line
		(start 331.454252 -214.499444)
		(end 331.460094 -214.532464)
		(stroke
			(width 0.06985)
			(type default)
		)
		(layer "In2.Cu")
	)
	(gr_line
		(start 331.460094 -214.532464)
		(end 331.479652 -214.560404)
		(stroke
			(width 0.06985)
			(type default)
		)
		(layer "In2.Cu")
	)
	(gr_arc
		(start 331.465174 -221.7928)
		(mid 331.51297 -222.03363)
		(end 331.649324 -222.237808)
		(stroke
			(width 0.06985)
			(type default)
		)
		(layer "In2.Cu")
	)
	(gr_line
		(start 331.649324 -222.237808)
		(end 331.706474 -222.294704)
		(stroke
			(width 0.06985)
			(type default)
		)
		(layer "In2.Cu")
	)
	(gr_line
		(start 333.442818 -206.826104)
		(end 333.470758 -206.845662)
		(stroke
			(width 0.06985)
			(type default)
		)
		(layer "In2.Cu")
	)
	(gr_line
		(start 333.470758 -206.845662)
		(end 333.503778 -206.851504)
		(stroke
			(width 0.06985)
			(type default)
		)
		(layer "In2.Cu")
	)
	(gr_line
		(start 334.093566 -222.294704)
		(end 334.150716 -222.237808)
		(stroke
			(width 0.06985)
			(type default)
		)
		(layer "In2.Cu")
	)
	(gr_arc
		(start 334.150716 -222.237808)
		(mid 334.287056 -222.033622)
		(end 334.334866 -221.7928)
		(stroke
			(width 0.06985)
			(type default)
		)
		(layer "In2.Cu")
	)
	(gr_line
		(start 334.453484 -214.67572)
		(end 334.459326 -214.70874)
		(stroke
			(width 0.06985)
			(type default)
		)
		(layer "In2.Cu")
	)
	(gr_line
		(start 334.459326 -214.70874)
		(end 334.478884 -214.73668)
		(stroke
			(width 0.06985)
			(type default)
		)
		(layer "In2.Cu")
	)
	(gr_line
		(start 334.471264 -218.256866)
		(end 334.490822 -218.284806)
		(stroke
			(width 0.06985)
			(type default)
		)
		(layer "In2.Cu")
	)
	(gr_line
		(start 334.490822 -218.284806)
		(end 334.496664 -218.317826)
		(stroke
			(width 0.06985)
			(type default)
		)
		(layer "In2.Cu")
	)
	(gr_arc
		(start 334.665066 -221.7928)
		(mid 334.712861 -222.03363)
		(end 334.849216 -222.237808)
		(stroke
			(width 0.06985)
			(type default)
		)
		(layer "In2.Cu")
	)
	(gr_line
		(start 334.68818 -206.724758)
		(end 334.7212 -206.7306)
		(stroke
			(width 0.06985)
			(type default)
		)
		(layer "In2.Cu")
	)
	(gr_line
		(start 334.7212 -206.7306)
		(end 334.74914 -206.750158)
		(stroke
			(width 0.06985)
			(type default)
		)
		(layer "In2.Cu")
	)
	(gr_line
		(start 334.849216 -222.237808)
		(end 334.906366 -222.294704)
		(stroke
			(width 0.06985)
			(type default)
		)
		(layer "In2.Cu")
	)
	(gr_line
		(start 337.293712 -222.294704)
		(end 337.350862 -222.237808)
		(stroke
			(width 0.06985)
			(type default)
		)
		(layer "In2.Cu")
	)
	(gr_line
		(start 337.34756 -208.569306)
		(end 337.363054 -208.580228)
		(stroke
			(width 0.06985)
			(type default)
		)
		(layer "In2.Cu")
	)
	(gr_arc
		(start 337.350862 -222.237808)
		(mid 337.487202 -222.033622)
		(end 337.535012 -221.7928)
		(stroke
			(width 0.06985)
			(type default)
		)
		(layer "In2.Cu")
	)
	(gr_line
		(start 337.363054 -208.580228)
		(end 337.373976 -208.595722)
		(stroke
			(width 0.06985)
			(type default)
		)
		(layer "In2.Cu")
	)
	(gr_line
		(start 337.828382 -218.943936)
		(end 337.865212 -218.996514)
		(stroke
			(width 0.06985)
			(type default)
		)
		(layer "In2.Cu")
	)
	(gr_line
		(start 337.829144 -209.245708)
		(end 337.865212 -209.29727)
		(stroke
			(width 0.06985)
			(type default)
		)
		(layer "In2.Cu")
	)
	(gr_arc
		(start 337.865212 -221.7928)
		(mid 337.913004 -222.033633)
		(end 338.049362 -222.237808)
		(stroke
			(width 0.06985)
			(type default)
		)
		(layer "In2.Cu")
	)
	(gr_line
		(start 338.049362 -222.237808)
		(end 338.106512 -222.294704)
		(stroke
			(width 0.06985)
			(type default)
		)
		(layer "In2.Cu")
	)
	(gr_line
		(start 338.08162 -216.826592)
		(end 338.087462 -216.859358)
		(stroke
			(width 0.06985)
			(type default)
		)
		(layer "In2.Cu")
	)
	(gr_line
		(start 338.087462 -216.859358)
		(end 338.106258 -216.886282)
		(stroke
			(width 0.06985)
			(type default)
		)
		(layer "In2.Cu")
	)
	(gr_line
		(start 340.493604 -222.294704)
		(end 340.550754 -222.237808)
		(stroke
			(width 0.06985)
			(type default)
		)
		(layer "In2.Cu")
	)
	(gr_arc
		(start 340.550754 -222.237808)
		(mid 340.68709 -222.033622)
		(end 340.734904 -221.7928)
		(stroke
			(width 0.06985)
			(type default)
		)
		(layer "In2.Cu")
	)
	(gr_line
		(start 341.028782 -220.489272)
		(end 341.065104 -220.541342)
		(stroke
			(width 0.06985)
			(type default)
		)
		(layer "In2.Cu")
	)
	(gr_arc
		(start 341.065104 -221.7928)
		(mid 341.112913 -222.033622)
		(end 341.249254 -222.237808)
		(stroke
			(width 0.06985)
			(type default)
		)
		(layer "In2.Cu")
	)
	(gr_line
		(start 341.249254 -222.237808)
		(end 341.306404 -222.294704)
		(stroke
			(width 0.06985)
			(type default)
		)
		(layer "In2.Cu")
	)
	(gr_line
		(start 0 -212.499956)
		(end 0 -28.010104)
		(stroke
			(width 1.524)
			(type default)
		)
		(layer "In3.Cu")
	)
	(gr_arc
		(start 0 -212.499956)
		(mid 0.292895 -213.207058)
		(end 0.999998 -213.499954)
		(stroke
			(width 1.524)
			(type default)
		)
		(layer "In3.Cu")
	)
	(gr_arc
		(start 1.999996 -26.010108)
		(mid 0.585785 -26.595893)
		(end 0 -28.010104)
		(stroke
			(width 1.524)
			(type default)
		)
		(layer "In3.Cu")
	)
	(gr_line
		(start 1.999996 -26.010108)
		(end 49.950116 -26.010108)
		(stroke
			(width 1.524)
			(type default)
		)
		(layer "In3.Cu")
	)
	(gr_line
		(start 2.286 -169.672)
		(end 22.479 -189.865)
		(stroke
			(width 0.381)
			(type default)
		)
		(layer "In3.Cu")
	)
	(gr_line
		(start 2.286 -67.31)
		(end 2.286 -57.658)
		(stroke
			(width 0.381)
			(type default)
		)
		(layer "In3.Cu")
	)
	(gr_line
		(start 2.286 -57.658)
		(end 2.286 -169.672)
		(stroke
			(width 0.381)
			(type default)
		)
		(layer "In3.Cu")
	)
	(gr_line
		(start 6.223 -53.721)
		(end 2.286 -57.658)
		(stroke
			(width 0.381)
			(type default)
		)
		(layer "In3.Cu")
	)
	(gr_circle
		(center 6.852158 -38.509956)
		(end 8.150098 -38.509956)
		(stroke
			(width 0.2)
			(type default)
		)
		(fill no)
		(layer "In3.Cu")
	)
	(gr_line
		(start 9.6647 -55.559452)
		(end 10.477246 -55.559452)
		(stroke
			(width 0.2)
			(type default)
		)
		(layer "In3.Cu")
	)
	(gr_arc
		(start 9.6647 -54.538372)
		(mid 9.15416 -55.048912)
		(end 9.6647 -55.559452)
		(stroke
			(width 0.2)
			(type default)
		)
		(layer "In3.Cu")
	)
	(gr_arc
		(start 10.477246 -55.559452)
		(mid 10.98804 -55.049039)
		(end 10.4775 -54.538372)
		(stroke
			(width 0.2)
			(type default)
		)
		(layer "In3.Cu")
	)
	(gr_line
		(start 10.4775 -54.538372)
		(end 9.6647 -54.538372)
		(stroke
			(width 0.2)
			(type default)
		)
		(layer "In3.Cu")
	)
	(gr_line
		(start 13.5636 -54.340252)
		(end 14.3764 -54.340252)
		(stroke
			(width 0.2)
			(type default)
		)
		(layer "In3.Cu")
	)
	(gr_arc
		(start 13.563854 -53.319172)
		(mid 13.05306 -53.829585)
		(end 13.5636 -54.340252)
		(stroke
			(width 0.2)
			(type default)
		)
		(layer "In3.Cu")
	)
	(gr_arc
		(start 13.66266 -68.451222)
		(mid 14.1732 -68.961762)
		(end 14.68374 -68.451222)
		(stroke
			(width 0.2)
			(type default)
		)
		(layer "In3.Cu")
	)
	(gr_line
		(start 13.66266 -67.638422)
		(end 13.66266 -68.451222)
		(stroke
			(width 0.2)
			(type default)
		)
		(layer "In3.Cu")
	)
	(gr_arc
		(start 14.3764 -54.340252)
		(mid 14.88694 -53.829712)
		(end 14.3764 -53.319172)
		(stroke
			(width 0.2)
			(type default)
		)
		(layer "In3.Cu")
	)
	(gr_line
		(start 14.3764 -53.319172)
		(end 13.563854 -53.319172)
		(stroke
			(width 0.2)
			(type default)
		)
		(layer "In3.Cu")
	)
	(gr_line
		(start 14.68374 -68.451222)
		(end 14.68374 -67.638676)
		(stroke
			(width 0.2)
			(type default)
		)
		(layer "In3.Cu")
	)
	(gr_arc
		(start 14.68374 -67.638676)
		(mid 14.173327 -67.127882)
		(end 13.66266 -67.638422)
		(stroke
			(width 0.2)
			(type default)
		)
		(layer "In3.Cu")
	)
	(gr_arc
		(start 15.66926 -67.03695)
		(mid 16.1798 -67.54749)
		(end 16.69034 -67.03695)
		(stroke
			(width 0.2)
			(type default)
		)
		(layer "In3.Cu")
	)
	(gr_line
		(start 15.66926 -66.22415)
		(end 15.66926 -67.03695)
		(stroke
			(width 0.2)
			(type default)
		)
		(layer "In3.Cu")
	)
	(gr_line
		(start 15.7988 -73.727564)
		(end 16.6116 -73.727564)
		(stroke
			(width 0.2)
			(type default)
		)
		(layer "In3.Cu")
	)
	(gr_arc
		(start 15.799054 -72.706484)
		(mid 15.28826 -73.216897)
		(end 15.7988 -73.727564)
		(stroke
			(width 0.2)
			(type default)
		)
		(layer "In3.Cu")
	)
	(gr_line
		(start 15.8496 -87.65794)
		(end 16.9672 -87.65794)
		(stroke
			(width 0.2)
			(type default)
		)
		(layer "In3.Cu")
	)
	(gr_arc
		(start 15.8496 -86.43366)
		(mid 15.23746 -87.0458)
		(end 15.8496 -87.65794)
		(stroke
			(width 0.2)
			(type default)
		)
		(layer "In3.Cu")
	)
	(gr_arc
		(start 16.6116 -73.727564)
		(mid 17.12214 -73.217024)
		(end 16.6116 -72.706484)
		(stroke
			(width 0.2)
			(type default)
		)
		(layer "In3.Cu")
	)
	(gr_line
		(start 16.6116 -72.706484)
		(end 15.799054 -72.706484)
		(stroke
			(width 0.2)
			(type default)
		)
		(layer "In3.Cu")
	)
	(gr_line
		(start 16.69034 -67.03695)
		(end 16.69034 -66.224404)
		(stroke
			(width 0.2)
			(type default)
		)
		(layer "In3.Cu")
	)
	(gr_arc
		(start 16.69034 -66.224404)
		(mid 16.179927 -65.71361)
		(end 15.66926 -66.22415)
		(stroke
			(width 0.2)
			(type default)
		)
		(layer "In3.Cu")
	)
	(gr_arc
		(start 16.9672 -87.65794)
		(mid 17.57934 -87.0458)
		(end 16.9672 -86.43366)
		(stroke
			(width 0.2)
			(type default)
		)
		(layer "In3.Cu")
	)
	(gr_line
		(start 16.9672 -86.43366)
		(end 15.8496 -86.43366)
		(stroke
			(width 0.2)
			(type default)
		)
		(layer "In3.Cu")
	)
	(gr_line
		(start 18.57375 -73.721214)
		(end 19.38655 -73.721214)
		(stroke
			(width 0.2)
			(type default)
		)
		(layer "In3.Cu")
	)
	(gr_arc
		(start 18.574004 -72.700134)
		(mid 18.06321 -73.210547)
		(end 18.57375 -73.721214)
		(stroke
			(width 0.2)
			(type default)
		)
		(layer "In3.Cu")
	)
	(gr_line
		(start 18.6944 -58.851546)
		(end 19.812 -58.851546)
		(stroke
			(width 0.2)
			(type default)
		)
		(layer "In3.Cu")
	)
	(gr_arc
		(start 18.6944 -57.627266)
		(mid 18.08226 -58.239406)
		(end 18.6944 -58.851546)
		(stroke
			(width 0.2)
			(type default)
		)
		(layer "In3.Cu")
	)
	(gr_line
		(start 18.8468 -55.508652)
		(end 19.659346 -55.508652)
		(stroke
			(width 0.2)
			(type default)
		)
		(layer "In3.Cu")
	)
	(gr_arc
		(start 18.8468 -54.487572)
		(mid 18.33626 -54.998112)
		(end 18.8468 -55.508652)
		(stroke
			(width 0.2)
			(type default)
		)
		(layer "In3.Cu")
	)
	(gr_line
		(start 18.852134 -82.41792)
		(end 19.664934 -82.41792)
		(stroke
			(width 0.2)
			(type default)
		)
		(layer "In3.Cu")
	)
	(gr_arc
		(start 18.852388 -81.39684)
		(mid 18.341594 -81.907253)
		(end 18.852134 -82.41792)
		(stroke
			(width 0.2)
			(type default)
		)
		(layer "In3.Cu")
	)
	(gr_arc
		(start 19.38655 -73.721214)
		(mid 19.89709 -73.210674)
		(end 19.38655 -72.700134)
		(stroke
			(width 0.2)
			(type default)
		)
		(layer "In3.Cu")
	)
	(gr_line
		(start 19.38655 -72.700134)
		(end 18.574004 -72.700134)
		(stroke
			(width 0.2)
			(type default)
		)
		(layer "In3.Cu")
	)
	(gr_arc
		(start 19.659346 -55.508652)
		(mid 20.17014 -54.998239)
		(end 19.6596 -54.487572)
		(stroke
			(width 0.2)
			(type default)
		)
		(layer "In3.Cu")
	)
	(gr_line
		(start 19.6596 -54.487572)
		(end 18.8468 -54.487572)
		(stroke
			(width 0.2)
			(type default)
		)
		(layer "In3.Cu")
	)
	(gr_arc
		(start 19.664934 -82.41792)
		(mid 20.175474 -81.90738)
		(end 19.664934 -81.39684)
		(stroke
			(width 0.2)
			(type default)
		)
		(layer "In3.Cu")
	)
	(gr_line
		(start 19.664934 -81.39684)
		(end 18.852388 -81.39684)
		(stroke
			(width 0.2)
			(type default)
		)
		(layer "In3.Cu")
	)
	(gr_arc
		(start 19.812 -58.851546)
		(mid 20.42414 -58.239406)
		(end 19.812 -57.627266)
		(stroke
			(width 0.2)
			(type default)
		)
		(layer "In3.Cu")
	)
	(gr_line
		(start 19.812 -57.627266)
		(end 18.6944 -57.627266)
		(stroke
			(width 0.2)
			(type default)
		)
		(layer "In3.Cu")
	)
	(gr_line
		(start 20.3962 -87.93734)
		(end 21.209 -87.93734)
		(stroke
			(width 0.2)
			(type default)
		)
		(layer "In3.Cu")
	)
	(gr_arc
		(start 20.396454 -86.91626)
		(mid 19.88566 -87.426673)
		(end 20.3962 -87.93734)
		(stroke
			(width 0.2)
			(type default)
		)
		(layer "In3.Cu")
	)
	(gr_arc
		(start 21.209 -87.93734)
		(mid 21.71954 -87.4268)
		(end 21.209 -86.91626)
		(stroke
			(width 0.2)
			(type default)
		)
		(layer "In3.Cu")
	)
	(gr_line
		(start 21.209 -86.91626)
		(end 20.396454 -86.91626)
		(stroke
			(width 0.2)
			(type default)
		)
		(layer "In3.Cu")
	)
	(gr_line
		(start 22.417786 -57.300876)
		(end 23.535386 -57.300876)
		(stroke
			(width 0.2)
			(type default)
		)
		(layer "In3.Cu")
	)
	(gr_arc
		(start 22.417786 -56.076596)
		(mid 21.805646 -56.688736)
		(end 22.417786 -57.300876)
		(stroke
			(width 0.2)
			(type default)
		)
		(layer "In3.Cu")
	)
	(gr_line
		(start 22.479 -189.865)
		(end 29.845 -189.865)
		(stroke
			(width 0.381)
			(type default)
		)
		(layer "In3.Cu")
	)
	(gr_arc
		(start 22.55266 -115.1128)
		(mid 23.1648 -115.72494)
		(end 23.77694 -115.1128)
		(stroke
			(width 0.2)
			(type default)
		)
		(layer "In3.Cu")
	)
	(gr_line
		(start 22.55266 -113.9952)
		(end 22.55266 -115.1128)
		(stroke
			(width 0.2)
			(type default)
		)
		(layer "In3.Cu")
	)
	(gr_line
		(start 22.5552 -54.066694)
		(end 23.368 -54.066694)
		(stroke
			(width 0.2)
			(type default)
		)
		(layer "In3.Cu")
	)
	(gr_arc
		(start 22.555454 -53.045614)
		(mid 22.04466 -53.556027)
		(end 22.5552 -54.066694)
		(stroke
			(width 0.2)
			(type default)
		)
		(layer "In3.Cu")
	)
	(gr_line
		(start 23.114 -53.721)
		(end 6.223 -53.721)
		(stroke
			(width 0.381)
			(type default)
		)
		(layer "In3.Cu")
	)
	(gr_arc
		(start 23.368 -54.066694)
		(mid 23.87854 -53.556154)
		(end 23.368 -53.045614)
		(stroke
			(width 0.2)
			(type default)
		)
		(layer "In3.Cu")
	)
	(gr_line
		(start 23.368 -53.045614)
		(end 22.555454 -53.045614)
		(stroke
			(width 0.2)
			(type default)
		)
		(layer "In3.Cu")
	)
	(gr_arc
		(start 23.535386 -57.300876)
		(mid 24.147526 -56.688736)
		(end 23.535386 -56.076596)
		(stroke
			(width 0.2)
			(type default)
		)
		(layer "In3.Cu")
	)
	(gr_line
		(start 23.535386 -56.076596)
		(end 22.417786 -56.076596)
		(stroke
			(width 0.2)
			(type default)
		)
		(layer "In3.Cu")
	)
	(gr_line
		(start 23.749 -54.356)
		(end 23.114 -53.721)
		(stroke
			(width 0.381)
			(type default)
		)
		(layer "In3.Cu")
	)
	(gr_line
		(start 23.77694 -115.1128)
		(end 23.77694 -113.995454)
		(stroke
			(width 0.2)
			(type default)
		)
		(layer "In3.Cu")
	)
	(gr_arc
		(start 23.77694 -113.995454)
		(mid 23.164927 -113.38306)
		(end 22.55266 -113.9952)
		(stroke
			(width 0.2)
			(type default)
		)
		(layer "In3.Cu")
	)
	(gr_arc
		(start 23.861014 -112.521746)
		(mid 24.473027 -113.13414)
		(end 25.085294 -112.522)
		(stroke
			(width 0.2)
			(type default)
		)
		(layer "In3.Cu")
	)
	(gr_line
		(start 23.861014 -111.4044)
		(end 23.861014 -112.521746)
		(stroke
			(width 0.2)
			(type default)
		)
		(layer "In3.Cu")
	)
	(gr_circle
		(center 24.432006 -38.509956)
		(end 25.729946 -38.509956)
		(stroke
			(width 0.2)
			(type default)
		)
		(fill no)
		(layer "In3.Cu")
	)
	(gr_line
		(start 25.085294 -112.522)
		(end 25.085294 -111.4044)
		(stroke
			(width 0.2)
			(type default)
		)
		(layer "In3.Cu")
	)
	(gr_arc
		(start 25.085294 -111.4044)
		(mid 24.473154 -110.79226)
		(end 23.861014 -111.4044)
		(stroke
			(width 0.2)
			(type default)
		)
		(layer "In3.Cu")
	)
	(gr_line
		(start 25.273 -209.169)
		(end 25.273 -213.487)
		(stroke
			(width 1.016)
			(type default)
		)
		(layer "In3.Cu")
	)
	(gr_line
		(start 25.4 -213.499954)
		(end 0.999998 -213.499954)
		(stroke
			(width 1.524)
			(type default)
		)
		(layer "In3.Cu")
	)
	(gr_line
		(start 25.50668 -190.25616)
		(end 25.12822 -189.8777)
		(stroke
			(width 0.254)
			(type default)
		)
		(layer "In3.Cu")
	)
	(gr_arc
		(start 25.51684 -143.69796)
		(mid 26.12898 -144.3101)
		(end 26.74112 -143.69796)
		(stroke
			(width 0.2)
			(type default)
		)
		(layer "In3.Cu")
	)
	(gr_line
		(start 25.51684 -142.58036)
		(end 25.51684 -143.69796)
		(stroke
			(width 0.2)
			(type default)
		)
		(layer "In3.Cu")
	)
	(gr_line
		(start 25.527 -200.025)
		(end 26.035 -200.533)
		(stroke
			(width 0.381)
			(type default)
		)
		(layer "In3.Cu")
	)
	(gr_line
		(start 25.527 -189.865)
		(end 25.527 -200.025)
		(stroke
			(width 0.381)
			(type default)
		)
		(layer "In3.Cu")
	)
	(gr_line
		(start 25.654 -208.788)
		(end 25.273 -209.169)
		(stroke
			(width 1.016)
			(type default)
		)
		(layer "In3.Cu")
	)
	(gr_line
		(start 25.89784 -189.865)
		(end 25.50668 -190.25616)
		(stroke
			(width 0.254)
			(type default)
		)
		(layer "In3.Cu")
	)
	(gr_line
		(start 26.035 -200.533)
		(end 55.753 -200.533)
		(stroke
			(width 0.381)
			(type default)
		)
		(layer "In3.Cu")
	)
	(gr_line
		(start 26.699972 -221.400116)
		(end 26.699972 -214.799926)
		(stroke
			(width 1.524)
			(type default)
		)
		(layer "In3.Cu")
	)
	(gr_arc
		(start 26.699972 -221.400116)
		(mid 26.846532 -221.75362)
		(end 27.200098 -221.899988)
		(stroke
			(width 1.524)
			(type default)
		)
		(layer "In3.Cu")
	)
	(gr_arc
		(start 26.699972 -214.799926)
		(mid 26.319219 -213.880707)
		(end 25.4 -213.499954)
		(stroke
			(width 1.524)
			(type default)
		)
		(layer "In3.Cu")
	)
	(gr_line
		(start 26.74112 -143.69796)
		(end 26.74112 -142.580614)
		(stroke
			(width 0.2)
			(type default)
		)
		(layer "In3.Cu")
	)
	(gr_arc
		(start 26.74112 -142.580614)
		(mid 26.129107 -141.96822)
		(end 25.51684 -142.58036)
		(stroke
			(width 0.2)
			(type default)
		)
		(layer "In3.Cu")
	)
	(gr_line
		(start 27.60853 -106.369612)
		(end 28.398978 -107.16006)
		(stroke
			(width 0.2)
			(type default)
		)
		(layer "In3.Cu")
	)
	(gr_line
		(start 27.610308 -106.367834)
		(end 27.60853 -106.369612)
		(stroke
			(width 0.2)
			(type default)
		)
		(layer "In3.Cu")
	)
	(gr_line
		(start 27.999944 -221.899988)
		(end 27.200098 -221.899988)
		(stroke
			(width 1.524)
			(type default)
		)
		(layer "In3.Cu")
	)
	(gr_line
		(start 28.398978 -107.16006)
		(end 28.400756 -107.158282)
		(stroke
			(width 0.2)
			(type default)
		)
		(layer "In3.Cu")
	)
	(gr_arc
		(start 28.400756 -107.158282)
		(mid 29.266388 -107.158282)
		(end 29.266388 -106.29265)
		(stroke
			(width 0.2)
			(type default)
		)
		(layer "In3.Cu")
	)
	(gr_arc
		(start 28.47594 -105.502202)
		(mid 27.610308 -105.502202)
		(end 27.610308 -106.367834)
		(stroke
			(width 0.2)
			(type default)
		)
		(layer "In3.Cu")
	)
	(gr_line
		(start 28.477464 -105.500678)
		(end 28.47594 -105.502202)
		(stroke
			(width 0.2)
			(type default)
		)
		(layer "In3.Cu")
	)
	(gr_line
		(start 28.477972 -105.500678)
		(end 28.477464 -105.500678)
		(stroke
			(width 0.2)
			(type default)
		)
		(layer "In3.Cu")
	)
	(gr_line
		(start 28.50007 -228.000052)
		(end 28.50007 -222.400114)
		(stroke
			(width 1.524)
			(type default)
		)
		(layer "In3.Cu")
	)
	(gr_arc
		(start 28.50007 -222.400114)
		(mid 28.353586 -222.046472)
		(end 27.999944 -221.899988)
		(stroke
			(width 1.524)
			(type default)
		)
		(layer "In3.Cu")
	)
	(gr_line
		(start 29.266388 -106.29265)
		(end 29.268166 -106.290872)
		(stroke
			(width 0.2)
			(type default)
		)
		(layer "In3.Cu")
	)
	(gr_line
		(start 29.268166 -106.290872)
		(end 28.477972 -105.500678)
		(stroke
			(width 0.2)
			(type default)
		)
		(layer "In3.Cu")
	)
	(gr_line
		(start 29.718 -54.356)
		(end 23.749 -54.356)
		(stroke
			(width 0.381)
			(type default)
		)
		(layer "In3.Cu")
	)
	(gr_line
		(start 29.845 -189.865)
		(end 52.07 -167.64)
		(stroke
			(width 0.381)
			(type default)
		)
		(layer "In3.Cu")
	)
	(gr_line
		(start 30.099 -75.819)
		(end 30.099 -70.104)
		(stroke
			(width 0.381)
			(type default)
		)
		(layer "In3.Cu")
	)
	(gr_line
		(start 30.099 -70.104)
		(end 54.102 -46.101)
		(stroke
			(width 0.381)
			(type default)
		)
		(layer "In3.Cu")
	)
	(gr_line
		(start 31.081472 -52.992528)
		(end 29.718 -54.356)
		(stroke
			(width 0.381)
			(type default)
		)
		(layer "In3.Cu")
	)
	(gr_line
		(start 31.081472 -51.372262)
		(end 31.081472 -52.992528)
		(stroke
			(width 0.381)
			(type default)
		)
		(layer "In3.Cu")
	)
	(gr_line
		(start 31.877 -208.788)
		(end 25.654 -208.788)
		(stroke
			(width 1.016)
			(type default)
		)
		(layer "In3.Cu")
	)
	(gr_line
		(start 32.639 -78.359)
		(end 30.099 -75.819)
		(stroke
			(width 0.381)
			(type default)
		)
		(layer "In3.Cu")
	)
	(gr_line
		(start 33.147 -212.725)
		(end 33.147 -210.058)
		(stroke
			(width 1.016)
			(type default)
		)
		(layer "In3.Cu")
	)
	(gr_line
		(start 33.147 -210.058)
		(end 31.877 -208.788)
		(stroke
			(width 1.016)
			(type default)
		)
		(layer "In3.Cu")
	)
	(gr_line
		(start 33.909 -228.219)
		(end 33.909 -224.536)
		(stroke
			(width 0.508)
			(type default)
		)
		(layer "In3.Cu")
	)
	(gr_line
		(start 33.909 -224.536)
		(end 34.163 -224.282)
		(stroke
			(width 0.508)
			(type default)
		)
		(layer "In3.Cu")
	)
	(gr_line
		(start 34.163 -224.282)
		(end 34.163 -213.741)
		(stroke
			(width 1.016)
			(type default)
		)
		(layer "In3.Cu")
	)
	(gr_line
		(start 34.163 -213.741)
		(end 33.147 -212.725)
		(stroke
			(width 1.016)
			(type default)
		)
		(layer "In3.Cu")
	)
	(gr_line
		(start 43.763184 -38.69055)
		(end 31.081472 -51.372262)
		(stroke
			(width 0.381)
			(type default)
		)
		(layer "In3.Cu")
	)
	(gr_line
		(start 45.38345 -38.69055)
		(end 43.763184 -38.69055)
		(stroke
			(width 0.381)
			(type default)
		)
		(layer "In3.Cu")
	)
	(gr_line
		(start 48.49368 -211.406994)
		(end 49.30648 -211.406994)
		(stroke
			(width 0.2)
			(type default)
		)
		(layer "In3.Cu")
	)
	(gr_arc
		(start 48.493934 -210.385914)
		(mid 47.98314 -210.896327)
		(end 48.49368 -211.406994)
		(stroke
			(width 0.2)
			(type default)
		)
		(layer "In3.Cu")
	)
	(gr_arc
		(start 49.30648 -211.406994)
		(mid 49.81702 -210.896454)
		(end 49.30648 -210.385914)
		(stroke
			(width 0.2)
			(type default)
		)
		(layer "In3.Cu")
	)
	(gr_line
		(start 49.30648 -210.385914)
		(end 48.493934 -210.385914)
		(stroke
			(width 0.2)
			(type default)
		)
		(layer "In3.Cu")
	)
	(gr_arc
		(start 49.950116 -26.010108)
		(mid 51.364327 -25.424323)
		(end 51.950112 -24.010112)
		(stroke
			(width 1.524)
			(type default)
		)
		(layer "In3.Cu")
	)
	(gr_line
		(start 50.093372 -221.916244)
		(end 50.905918 -221.916244)
		(stroke
			(width 0.2)
			(type default)
		)
		(layer "In3.Cu")
	)
	(gr_arc
		(start 50.093372 -220.895164)
		(mid 49.582832 -221.405704)
		(end 50.093372 -221.916244)
		(stroke
			(width 0.2)
			(type default)
		)
		(layer "In3.Cu")
	)
	(gr_line
		(start 50.14468 -209.222594)
		(end 50.95748 -209.222594)
		(stroke
			(width 0.2)
			(type default)
		)
		(layer "In3.Cu")
	)
	(gr_arc
		(start 50.144934 -208.201514)
		(mid 49.63414 -208.711927)
		(end 50.14468 -209.222594)
		(stroke
			(width 0.2)
			(type default)
		)
		(layer "In3.Cu")
	)
	(gr_arc
		(start 50.905918 -221.916244)
		(mid 51.416712 -221.405831)
		(end 50.906172 -220.895164)
		(stroke
			(width 0.2)
			(type default)
		)
		(layer "In3.Cu")
	)
	(gr_line
		(start 50.906172 -220.895164)
		(end 50.093372 -220.895164)
		(stroke
			(width 0.2)
			(type default)
		)
		(layer "In3.Cu")
	)
	(gr_arc
		(start 50.95748 -209.222594)
		(mid 51.46802 -208.712054)
		(end 50.95748 -208.201514)
		(stroke
			(width 0.2)
			(type default)
		)
		(layer "In3.Cu")
	)
	(gr_line
		(start 50.95748 -208.201514)
		(end 50.144934 -208.201514)
		(stroke
			(width 0.2)
			(type default)
		)
		(layer "In3.Cu")
	)
	(gr_line
		(start 51.693572 -211.406994)
		(end 52.506372 -211.406994)
		(stroke
			(width 0.2)
			(type default)
		)
		(layer "In3.Cu")
	)
	(gr_arc
		(start 51.693826 -210.385914)
		(mid 51.183032 -210.896327)
		(end 51.693572 -211.406994)
		(stroke
			(width 0.2)
			(type default)
		)
		(layer "In3.Cu")
	)
	(gr_line
		(start 51.950112 -24.010112)
		(end 51.950112 -1.999996)
		(stroke
			(width 1.524)
			(type default)
		)
		(layer "In3.Cu")
	)
	(gr_line
		(start 52.07 -167.64)
		(end 73.406 -167.64)
		(stroke
			(width 0.381)
			(type default)
		)
		(layer "In3.Cu")
	)
	(gr_line
		(start 52.399438 -48.387508)
		(end 53.305964 -48.387508)
		(stroke
			(width 0.2)
			(type default)
		)
		(layer "In3.Cu")
	)
	(gr_arc
		(start 52.399692 -47.366428)
		(mid 51.888898 -47.876841)
		(end 52.399438 -48.387508)
		(stroke
			(width 0.2)
			(type default)
		)
		(layer "In3.Cu")
	)
	(gr_arc
		(start 52.506372 -211.406994)
		(mid 53.016912 -210.896454)
		(end 52.506372 -210.385914)
		(stroke
			(width 0.2)
			(type default)
		)
		(layer "In3.Cu")
	)
	(gr_line
		(start 52.506372 -210.385914)
		(end 51.693826 -210.385914)
		(stroke
			(width 0.2)
			(type default)
		)
		(layer "In3.Cu")
	)
	(gr_line
		(start 53.293518 -222.805244)
		(end 54.106064 -222.805244)
		(stroke
			(width 0.2)
			(type default)
		)
		(layer "In3.Cu")
	)
	(gr_arc
		(start 53.293518 -221.784164)
		(mid 52.782978 -222.294704)
		(end 53.293518 -222.805244)
		(stroke
			(width 0.2)
			(type default)
		)
		(layer "In3.Cu")
	)
	(gr_arc
		(start 53.305964 -48.387508)
		(mid 53.816504 -47.876968)
		(end 53.305964 -47.366428)
		(stroke
			(width 0.2)
			(type default)
		)
		(layer "In3.Cu")
	)
	(gr_line
		(start 53.305964 -47.366428)
		(end 52.399692 -47.366428)
		(stroke
			(width 0.2)
			(type default)
		)
		(layer "In3.Cu")
	)
	(gr_arc
		(start 53.950108 0)
		(mid 52.535891 -0.585782)
		(end 51.950112 -1.999996)
		(stroke
			(width 1.524)
			(type default)
		)
		(layer "In3.Cu")
	)
	(gr_line
		(start 53.950108 0)
		(end 119.637556 0)
		(stroke
			(width 1.524)
			(type default)
		)
		(layer "In3.Cu")
	)
	(gr_line
		(start 54.102 -46.101)
		(end 73.406 -46.101)
		(stroke
			(width 0.381)
			(type default)
		)
		(layer "In3.Cu")
	)
	(gr_arc
		(start 54.106064 -222.805244)
		(mid 54.616858 -222.294831)
		(end 54.106318 -221.784164)
		(stroke
			(width 0.2)
			(type default)
		)
		(layer "In3.Cu")
	)
	(gr_line
		(start 54.106318 -221.784164)
		(end 53.293518 -221.784164)
		(stroke
			(width 0.2)
			(type default)
		)
		(layer "In3.Cu")
	)
	(gr_line
		(start 54.893718 -211.406994)
		(end 55.706264 -211.406994)
		(stroke
			(width 0.2)
			(type default)
		)
		(layer "In3.Cu")
	)
	(gr_arc
		(start 54.893718 -210.385914)
		(mid 54.383178 -210.896454)
		(end 54.893718 -211.406994)
		(stroke
			(width 0.2)
			(type default)
		)
		(layer "In3.Cu")
	)
	(gr_line
		(start 54.94782 -29.12618)
		(end 45.38345 -38.69055)
		(stroke
			(width 0.381)
			(type default)
		)
		(layer "In3.Cu")
	)
	(gr_arc
		(start 55.6387 -86.32825)
		(mid 56.25084 -86.94039)
		(end 56.86298 -86.32825)
		(stroke
			(width 0.2)
			(type default)
		)
		(layer "In3.Cu")
	)
	(gr_line
		(start 55.6387 -85.21065)
		(end 55.6387 -86.32825)
		(stroke
			(width 0.2)
			(type default)
		)
		(layer "In3.Cu")
	)
	(gr_arc
		(start 55.706264 -211.406994)
		(mid 56.217058 -210.896581)
		(end 55.706518 -210.385914)
		(stroke
			(width 0.2)
			(type default)
		)
		(layer "In3.Cu")
	)
	(gr_line
		(start 55.706518 -210.385914)
		(end 54.893718 -210.385914)
		(stroke
			(width 0.2)
			(type default)
		)
		(layer "In3.Cu")
	)
	(gr_line
		(start 55.753 -200.533)
		(end 67.183 -189.103)
		(stroke
			(width 0.381)
			(type default)
		)
		(layer "In3.Cu")
	)
	(gr_line
		(start 56.49341 -222.805244)
		(end 57.305956 -222.805244)
		(stroke
			(width 0.2)
			(type default)
		)
		(layer "In3.Cu")
	)
	(gr_arc
		(start 56.49341 -221.784164)
		(mid 55.98287 -222.294704)
		(end 56.49341 -222.805244)
		(stroke
			(width 0.2)
			(type default)
		)
		(layer "In3.Cu")
	)
	(gr_line
		(start 56.86298 -86.32825)
		(end 56.86298 -85.210904)
		(stroke
			(width 0.2)
			(type default)
		)
		(layer "In3.Cu")
	)
	(gr_arc
		(start 56.86298 -85.210904)
		(mid 56.250967 -84.59851)
		(end 55.6387 -85.21065)
		(stroke
			(width 0.2)
			(type default)
		)
		(layer "In3.Cu")
	)
	(gr_arc
		(start 57.305956 -222.805244)
		(mid 57.81675 -222.294831)
		(end 57.30621 -221.784164)
		(stroke
			(width 0.2)
			(type default)
		)
		(layer "In3.Cu")
	)
	(gr_line
		(start 57.30621 -221.784164)
		(end 56.49341 -221.784164)
		(stroke
			(width 0.2)
			(type default)
		)
		(layer "In3.Cu")
	)
	(gr_line
		(start 58.0517 -196.77634)
		(end 58.8645 -196.77634)
		(stroke
			(width 0.2)
			(type default)
		)
		(layer "In3.Cu")
	)
	(gr_arc
		(start 58.051954 -195.75526)
		(mid 57.54116 -196.265673)
		(end 58.0517 -196.77634)
		(stroke
			(width 0.2)
			(type default)
		)
		(layer "In3.Cu")
	)
	(gr_line
		(start 58.09361 -211.406994)
		(end 58.90641 -211.406994)
		(stroke
			(width 0.2)
			(type default)
		)
		(layer "In3.Cu")
	)
	(gr_arc
		(start 58.093864 -210.385914)
		(mid 57.58307 -210.896327)
		(end 58.09361 -211.406994)
		(stroke
			(width 0.2)
			(type default)
		)
		(layer "In3.Cu")
	)
	(gr_arc
		(start 58.8645 -196.77634)
		(mid 59.37504 -196.2658)
		(end 58.8645 -195.75526)
		(stroke
			(width 0.2)
			(type default)
		)
		(layer "In3.Cu")
	)
	(gr_line
		(start 58.8645 -195.75526)
		(end 58.051954 -195.75526)
		(stroke
			(width 0.2)
			(type default)
		)
		(layer "In3.Cu")
	)
	(gr_arc
		(start 58.90641 -211.406994)
		(mid 59.41695 -210.896454)
		(end 58.90641 -210.385914)
		(stroke
			(width 0.2)
			(type default)
		)
		(layer "In3.Cu")
	)
	(gr_line
		(start 58.90641 -210.385914)
		(end 58.093864 -210.385914)
		(stroke
			(width 0.2)
			(type default)
		)
		(layer "In3.Cu")
	)
	(gr_line
		(start 59.693302 -222.805244)
		(end 60.505848 -222.805244)
		(stroke
			(width 0.2)
			(type default)
		)
		(layer "In3.Cu")
	)
	(gr_arc
		(start 59.693302 -221.784164)
		(mid 59.182762 -222.294704)
		(end 59.693302 -222.805244)
		(stroke
			(width 0.2)
			(type default)
		)
		(layer "In3.Cu")
	)
	(gr_arc
		(start 60.505848 -222.805244)
		(mid 61.016642 -222.294831)
		(end 60.506102 -221.784164)
		(stroke
			(width 0.2)
			(type default)
		)
		(layer "In3.Cu")
	)
	(gr_line
		(start 60.506102 -221.784164)
		(end 59.693302 -221.784164)
		(stroke
			(width 0.2)
			(type default)
		)
		(layer "In3.Cu")
	)
	(gr_line
		(start 63.693548 -211.406994)
		(end 64.506348 -211.406994)
		(stroke
			(width 0.2)
			(type default)
		)
		(layer "In3.Cu")
	)
	(gr_arc
		(start 63.693802 -210.385914)
		(mid 63.183008 -210.896327)
		(end 63.693548 -211.406994)
		(stroke
			(width 0.2)
			(type default)
		)
		(layer "In3.Cu")
	)
	(gr_arc
		(start 64.506348 -211.406994)
		(mid 65.016888 -210.896454)
		(end 64.506348 -210.385914)
		(stroke
			(width 0.2)
			(type default)
		)
		(layer "In3.Cu")
	)
	(gr_line
		(start 64.506348 -210.385914)
		(end 63.693802 -210.385914)
		(stroke
			(width 0.2)
			(type default)
		)
		(layer "In3.Cu")
	)
	(gr_line
		(start 65.293494 -222.805244)
		(end 66.10604 -222.805244)
		(stroke
			(width 0.2)
			(type default)
		)
		(layer "In3.Cu")
	)
	(gr_arc
		(start 65.293494 -221.784164)
		(mid 64.782954 -222.294704)
		(end 65.293494 -222.805244)
		(stroke
			(width 0.2)
			(type default)
		)
		(layer "In3.Cu")
	)
	(gr_line
		(start 65.330578 -128.189736)
		(end 66.143378 -128.189736)
		(stroke
			(width 0.2)
			(type default)
		)
		(layer "In3.Cu")
	)
	(gr_arc
		(start 65.330832 -127.168656)
		(mid 64.820038 -127.679069)
		(end 65.330578 -128.189736)
		(stroke
			(width 0.2)
			(type default)
		)
		(layer "In3.Cu")
	)
	(gr_arc
		(start 66.10604 -222.805244)
		(mid 66.616834 -222.294831)
		(end 66.106294 -221.784164)
		(stroke
			(width 0.2)
			(type default)
		)
		(layer "In3.Cu")
	)
	(gr_line
		(start 66.106294 -221.784164)
		(end 65.293494 -221.784164)
		(stroke
			(width 0.2)
			(type default)
		)
		(layer "In3.Cu")
	)
	(gr_arc
		(start 66.143378 -128.189736)
		(mid 66.653918 -127.679196)
		(end 66.143378 -127.168656)
		(stroke
			(width 0.2)
			(type default)
		)
		(layer "In3.Cu")
	)
	(gr_line
		(start 66.143378 -127.168656)
		(end 65.330832 -127.168656)
		(stroke
			(width 0.2)
			(type default)
		)
		(layer "In3.Cu")
	)
	(gr_line
		(start 66.893694 -211.406994)
		(end 67.706494 -211.406994)
		(stroke
			(width 0.2)
			(type default)
		)
		(layer "In3.Cu")
	)
	(gr_arc
		(start 66.893948 -210.385914)
		(mid 66.383154 -210.896327)
		(end 66.893694 -211.406994)
		(stroke
			(width 0.2)
			(type default)
		)
		(layer "In3.Cu")
	)
	(gr_line
		(start 67.183 -189.103)
		(end 86.487 -189.103)
		(stroke
			(width 0.381)
			(type default)
		)
		(layer "In3.Cu")
	)
	(gr_arc
		(start 67.706494 -211.406994)
		(mid 68.217034 -210.896454)
		(end 67.706494 -210.385914)
		(stroke
			(width 0.2)
			(type default)
		)
		(layer "In3.Cu")
	)
	(gr_line
		(start 67.706494 -210.385914)
		(end 66.893948 -210.385914)
		(stroke
			(width 0.2)
			(type default)
		)
		(layer "In3.Cu")
	)
	(gr_line
		(start 68.493386 -222.805244)
		(end 69.305932 -222.805244)
		(stroke
			(width 0.2)
			(type default)
		)
		(layer "In3.Cu")
	)
	(gr_arc
		(start 68.493386 -221.784164)
		(mid 67.982846 -222.294704)
		(end 68.493386 -222.805244)
		(stroke
			(width 0.2)
			(type default)
		)
		(layer "In3.Cu")
	)
	(gr_arc
		(start 69.305932 -222.805244)
		(mid 69.816726 -222.294831)
		(end 69.306186 -221.784164)
		(stroke
			(width 0.2)
			(type default)
		)
		(layer "In3.Cu")
	)
	(gr_line
		(start 69.306186 -221.784164)
		(end 68.493386 -221.784164)
		(stroke
			(width 0.2)
			(type default)
		)
		(layer "In3.Cu")
	)
	(gr_line
		(start 70.093586 -211.406994)
		(end 70.906386 -211.406994)
		(stroke
			(width 0.2)
			(type default)
		)
		(layer "In3.Cu")
	)
	(gr_arc
		(start 70.09384 -210.385914)
		(mid 69.583046 -210.896327)
		(end 70.093586 -211.406994)
		(stroke
			(width 0.2)
			(type default)
		)
		(layer "In3.Cu")
	)
	(gr_arc
		(start 70.906386 -211.406994)
		(mid 71.416926 -210.896454)
		(end 70.906386 -210.385914)
		(stroke
			(width 0.2)
			(type default)
		)
		(layer "In3.Cu")
	)
	(gr_line
		(start 70.906386 -210.385914)
		(end 70.09384 -210.385914)
		(stroke
			(width 0.2)
			(type default)
		)
		(layer "In3.Cu")
	)
	(gr_line
		(start 71.7042 -220.52534)
		(end 72.516746 -220.52534)
		(stroke
			(width 0.2)
			(type default)
		)
		(layer "In3.Cu")
	)
	(gr_arc
		(start 71.7042 -219.50426)
		(mid 71.19366 -220.0148)
		(end 71.7042 -220.52534)
		(stroke
			(width 0.2)
			(type default)
		)
		(layer "In3.Cu")
	)
	(gr_arc
		(start 72.516746 -220.52534)
		(mid 73.02754 -220.014927)
		(end 72.517 -219.50426)
		(stroke
			(width 0.2)
			(type default)
		)
		(layer "In3.Cu")
	)
	(gr_line
		(start 72.517 -219.50426)
		(end 71.7042 -219.50426)
		(stroke
			(width 0.2)
			(type default)
		)
		(layer "In3.Cu")
	)
	(gr_line
		(start 73.406 -167.64)
		(end 85.979 -155.067)
		(stroke
			(width 0.381)
			(type default)
		)
		(layer "In3.Cu")
	)
	(gr_line
		(start 73.406 -46.101)
		(end 87.884 -60.579)
		(stroke
			(width 0.381)
			(type default)
		)
		(layer "In3.Cu")
	)
	(gr_line
		(start 74.099928 -228.000052)
		(end 28.50007 -228.000052)
		(stroke
			(width 5.08)
			(type default)
		)
		(layer "In3.Cu")
	)
	(gr_line
		(start 74.099928 -222.600012)
		(end 74.099928 -228.000052)
		(stroke
			(width 1.524)
			(type default)
		)
		(layer "In3.Cu")
	)
	(gr_line
		(start 75.57897 -48.27397)
		(end 76.22794 -47.625)
		(stroke
			(width 0.381)
			(type default)
		)
		(layer "In3.Cu")
	)
	(gr_line
		(start 75.92822 -48.56734)
		(end 75.92822 -47.92472)
		(stroke
			(width 0.254)
			(type default)
		)
		(layer "In3.Cu")
	)
	(gr_line
		(start 75.92822 -47.92472)
		(end 75.28052 -47.92472)
		(stroke
			(width 0.254)
			(type default)
		)
		(layer "In3.Cu")
	)
	(gr_line
		(start 75.946 -78.359)
		(end 32.639 -78.359)
		(stroke
			(width 0.381)
			(type default)
		)
		(layer "In3.Cu")
	)
	(gr_line
		(start 76.22794 -47.625)
		(end 108.213144 -47.625)
		(stroke
			(width 0.381)
			(type default)
		)
		(layer "In3.Cu")
	)
	(gr_line
		(start 76.499974 -228.000052)
		(end 76.499974 -222.600012)
		(stroke
			(width 1.524)
			(type default)
		)
		(layer "In3.Cu")
	)
	(gr_arc
		(start 76.499974 -222.600012)
		(mid 75.300078 -221.400116)
		(end 74.099928 -222.600012)
		(stroke
			(width 1.524)
			(type default)
		)
		(layer "In3.Cu")
	)
	(gr_line
		(start 78.16977 -220.392244)
		(end 78.982316 -220.392244)
		(stroke
			(width 0.2)
			(type default)
		)
		(layer "In3.Cu")
	)
	(gr_arc
		(start 78.16977 -219.371164)
		(mid 77.65923 -219.881704)
		(end 78.16977 -220.392244)
		(stroke
			(width 0.2)
			(type default)
		)
		(layer "In3.Cu")
	)
	(gr_arc
		(start 78.982316 -220.392244)
		(mid 79.49311 -219.881831)
		(end 78.98257 -219.371164)
		(stroke
			(width 0.2)
			(type default)
		)
		(layer "In3.Cu")
	)
	(gr_line
		(start 78.98257 -219.371164)
		(end 78.16977 -219.371164)
		(stroke
			(width 0.2)
			(type default)
		)
		(layer "In3.Cu")
	)
	(gr_line
		(start 79.693516 -211.406994)
		(end 80.506316 -211.406994)
		(stroke
			(width 0.2)
			(type default)
		)
		(layer "In3.Cu")
	)
	(gr_arc
		(start 79.69377 -210.385914)
		(mid 79.182976 -210.896327)
		(end 79.693516 -211.406994)
		(stroke
			(width 0.2)
			(type default)
		)
		(layer "In3.Cu")
	)
	(gr_arc
		(start 80.506316 -211.406994)
		(mid 81.016856 -210.896454)
		(end 80.506316 -210.385914)
		(stroke
			(width 0.2)
			(type default)
		)
		(layer "In3.Cu")
	)
	(gr_line
		(start 80.506316 -210.385914)
		(end 79.69377 -210.385914)
		(stroke
			(width 0.2)
			(type default)
		)
		(layer "In3.Cu")
	)
	(gr_line
		(start 81.293462 -222.805244)
		(end 82.106008 -222.805244)
		(stroke
			(width 0.2)
			(type default)
		)
		(layer "In3.Cu")
	)
	(gr_arc
		(start 81.293462 -221.784164)
		(mid 80.782922 -222.294704)
		(end 81.293462 -222.805244)
		(stroke
			(width 0.2)
			(type default)
		)
		(layer "In3.Cu")
	)
	(gr_arc
		(start 82.106008 -222.805244)
		(mid 82.616802 -222.294831)
		(end 82.106262 -221.784164)
		(stroke
			(width 0.2)
			(type default)
		)
		(layer "In3.Cu")
	)
	(gr_line
		(start 82.106262 -221.784164)
		(end 81.293462 -221.784164)
		(stroke
			(width 0.2)
			(type default)
		)
		(layer "In3.Cu")
	)
	(gr_line
		(start 82.893662 -211.406994)
		(end 83.706462 -211.406994)
		(stroke
			(width 0.2)
			(type default)
		)
		(layer "In3.Cu")
	)
	(gr_arc
		(start 82.893916 -210.385914)
		(mid 82.383122 -210.896327)
		(end 82.893662 -211.406994)
		(stroke
			(width 0.2)
			(type default)
		)
		(layer "In3.Cu")
	)
	(gr_arc
		(start 83.706462 -211.406994)
		(mid 84.217002 -210.896454)
		(end 83.706462 -210.385914)
		(stroke
			(width 0.2)
			(type default)
		)
		(layer "In3.Cu")
	)
	(gr_line
		(start 83.706462 -210.385914)
		(end 82.893916 -210.385914)
		(stroke
			(width 0.2)
			(type default)
		)
		(layer "In3.Cu")
	)
	(gr_line
		(start 84.493354 -222.805244)
		(end 85.3059 -222.805244)
		(stroke
			(width 0.2)
			(type default)
		)
		(layer "In3.Cu")
	)
	(gr_arc
		(start 84.493354 -221.784164)
		(mid 83.982814 -222.294704)
		(end 84.493354 -222.805244)
		(stroke
			(width 0.2)
			(type default)
		)
		(layer "In3.Cu")
	)
	(gr_arc
		(start 85.3059 -222.805244)
		(mid 85.816694 -222.294831)
		(end 85.306154 -221.784164)
		(stroke
			(width 0.2)
			(type default)
		)
		(layer "In3.Cu")
	)
	(gr_line
		(start 85.306154 -221.784164)
		(end 84.493354 -221.784164)
		(stroke
			(width 0.2)
			(type default)
		)
		(layer "In3.Cu")
	)
	(gr_line
		(start 85.979 -155.067)
		(end 85.979 -88.392)
		(stroke
			(width 0.381)
			(type default)
		)
		(layer "In3.Cu")
	)
	(gr_line
		(start 85.979 -88.392)
		(end 75.946 -78.359)
		(stroke
			(width 0.381)
			(type default)
		)
		(layer "In3.Cu")
	)
	(gr_line
		(start 86.093554 -211.406994)
		(end 86.906354 -211.406994)
		(stroke
			(width 0.2)
			(type default)
		)
		(layer "In3.Cu")
	)
	(gr_arc
		(start 86.093808 -210.385914)
		(mid 85.583014 -210.896327)
		(end 86.093554 -211.406994)
		(stroke
			(width 0.2)
			(type default)
		)
		(layer "In3.Cu")
	)
	(gr_arc
		(start 86.269068 -77.478382)
		(mid 86.779481 -77.989176)
		(end 87.290148 -77.478636)
		(stroke
			(width 0.2)
			(type default)
		)
		(layer "In3.Cu")
	)
	(gr_line
		(start 86.269068 -76.589636)
		(end 86.269068 -77.478382)
		(stroke
			(width 0.2)
			(type default)
		)
		(layer "In3.Cu")
	)
	(gr_line
		(start 86.487 -189.103)
		(end 132.334 -143.256)
		(stroke
			(width 0.381)
			(type default)
		)
		(layer "In3.Cu")
	)
	(gr_arc
		(start 86.906354 -211.406994)
		(mid 87.416894 -210.896454)
		(end 86.906354 -210.385914)
		(stroke
			(width 0.2)
			(type default)
		)
		(layer "In3.Cu")
	)
	(gr_line
		(start 86.906354 -210.385914)
		(end 86.093808 -210.385914)
		(stroke
			(width 0.2)
			(type default)
		)
		(layer "In3.Cu")
	)
	(gr_line
		(start 87.290148 -77.478636)
		(end 87.290148 -76.589636)
		(stroke
			(width 0.2)
			(type default)
		)
		(layer "In3.Cu")
	)
	(gr_arc
		(start 87.290148 -76.589636)
		(mid 86.779608 -76.079096)
		(end 86.269068 -76.589636)
		(stroke
			(width 0.2)
			(type default)
		)
		(layer "In3.Cu")
	)
	(gr_line
		(start 87.6935 -222.805244)
		(end 88.506046 -222.805244)
		(stroke
			(width 0.2)
			(type default)
		)
		(layer "In3.Cu")
	)
	(gr_arc
		(start 87.6935 -221.784164)
		(mid 87.18296 -222.294704)
		(end 87.6935 -222.805244)
		(stroke
			(width 0.2)
			(type default)
		)
		(layer "In3.Cu")
	)
	(gr_line
		(start 87.884 -60.579)
		(end 96.139 -60.579)
		(stroke
			(width 0.381)
			(type default)
		)
		(layer "In3.Cu")
	)
	(gr_arc
		(start 88.506046 -222.805244)
		(mid 89.01684 -222.294831)
		(end 88.5063 -221.784164)
		(stroke
			(width 0.2)
			(type default)
		)
		(layer "In3.Cu")
	)
	(gr_line
		(start 88.5063 -221.784164)
		(end 87.6935 -221.784164)
		(stroke
			(width 0.2)
			(type default)
		)
		(layer "In3.Cu")
	)
	(gr_line
		(start 89.2937 -211.406994)
		(end 90.1065 -211.406994)
		(stroke
			(width 0.2)
			(type default)
		)
		(layer "In3.Cu")
	)
	(gr_arc
		(start 89.293954 -210.385914)
		(mid 88.78316 -210.896327)
		(end 89.2937 -211.406994)
		(stroke
			(width 0.2)
			(type default)
		)
		(layer "In3.Cu")
	)
	(gr_line
		(start 89.99982 -29.12618)
		(end 54.94782 -29.12618)
		(stroke
			(width 0.381)
			(type default)
		)
		(layer "In3.Cu")
	)
	(gr_arc
		(start 90.1065 -211.406994)
		(mid 90.61704 -210.896454)
		(end 90.1065 -210.385914)
		(stroke
			(width 0.2)
			(type default)
		)
		(layer "In3.Cu")
	)
	(gr_line
		(start 90.1065 -210.385914)
		(end 89.293954 -210.385914)
		(stroke
			(width 0.2)
			(type default)
		)
		(layer "In3.Cu")
	)
	(gr_line
		(start 90.893392 -222.805244)
		(end 91.705938 -222.805244)
		(stroke
			(width 0.2)
			(type default)
		)
		(layer "In3.Cu")
	)
	(gr_arc
		(start 90.893392 -221.784164)
		(mid 90.382852 -222.294704)
		(end 90.893392 -222.805244)
		(stroke
			(width 0.2)
			(type default)
		)
		(layer "In3.Cu")
	)
	(gr_line
		(start 91.608402 -185.665364)
		(end 92.18295 -186.240166)
		(stroke
			(width 0.2)
			(type default)
		)
		(layer "In3.Cu")
	)
	(gr_line
		(start 91.61018 -185.663586)
		(end 91.608402 -185.665364)
		(stroke
			(width 0.2)
			(type default)
		)
		(layer "In3.Cu")
	)
	(gr_arc
		(start 91.705938 -222.805244)
		(mid 92.216732 -222.294831)
		(end 91.706192 -221.784164)
		(stroke
			(width 0.2)
			(type default)
		)
		(layer "In3.Cu")
	)
	(gr_line
		(start 91.706192 -221.784164)
		(end 90.893392 -221.784164)
		(stroke
			(width 0.2)
			(type default)
		)
		(layer "In3.Cu")
	)
	(gr_line
		(start 92.18295 -186.240166)
		(end 92.183204 -186.240166)
		(stroke
			(width 0.2)
			(type default)
		)
		(layer "In3.Cu")
	)
	(gr_line
		(start 92.183204 -186.240166)
		(end 92.184982 -186.238388)
		(stroke
			(width 0.2)
			(type default)
		)
		(layer "In3.Cu")
	)
	(gr_arc
		(start 92.184982 -186.238388)
		(mid 92.90685 -186.238388)
		(end 92.90685 -185.51652)
		(stroke
			(width 0.2)
			(type default)
		)
		(layer "In3.Cu")
	)
	(gr_arc
		(start 92.332048 -184.941718)
		(mid 91.61018 -184.941718)
		(end 91.61018 -185.663586)
		(stroke
			(width 0.2)
			(type default)
		)
		(layer "In3.Cu")
	)
	(gr_line
		(start 92.333826 -184.93994)
		(end 92.332048 -184.941718)
		(stroke
			(width 0.2)
			(type default)
		)
		(layer "In3.Cu")
	)
	(gr_line
		(start 92.493592 -211.406994)
		(end 93.306392 -211.406994)
		(stroke
			(width 0.2)
			(type default)
		)
		(layer "In3.Cu")
	)
	(gr_arc
		(start 92.493846 -210.385914)
		(mid 91.983052 -210.896327)
		(end 92.493592 -211.406994)
		(stroke
			(width 0.2)
			(type default)
		)
		(layer "In3.Cu")
	)
	(gr_line
		(start 92.90685 -185.51652)
		(end 92.908628 -185.514742)
		(stroke
			(width 0.2)
			(type default)
		)
		(layer "In3.Cu")
	)
	(gr_line
		(start 92.908628 -185.514742)
		(end 92.333826 -184.93994)
		(stroke
			(width 0.2)
			(type default)
		)
		(layer "In3.Cu")
	)
	(gr_arc
		(start 93.306392 -211.406994)
		(mid 93.816932 -210.896454)
		(end 93.306392 -210.385914)
		(stroke
			(width 0.2)
			(type default)
		)
		(layer "In3.Cu")
	)
	(gr_line
		(start 93.306392 -210.385914)
		(end 92.493846 -210.385914)
		(stroke
			(width 0.2)
			(type default)
		)
		(layer "In3.Cu")
	)
	(gr_line
		(start 93.38945 -184.15254)
		(end 94.201996 -184.15254)
		(stroke
			(width 0.2)
			(type default)
		)
		(layer "In3.Cu")
	)
	(gr_arc
		(start 93.38945 -183.13146)
		(mid 92.87891 -183.642)
		(end 93.38945 -184.15254)
		(stroke
			(width 0.2)
			(type default)
		)
		(layer "In3.Cu")
	)
	(gr_arc
		(start 94.201996 -184.15254)
		(mid 94.71279 -183.642127)
		(end 94.20225 -183.13146)
		(stroke
			(width 0.2)
			(type default)
		)
		(layer "In3.Cu")
	)
	(gr_line
		(start 94.20225 -183.13146)
		(end 93.38945 -183.13146)
		(stroke
			(width 0.2)
			(type default)
		)
		(layer "In3.Cu")
	)
	(gr_line
		(start 96.139 -60.579)
		(end 112.395 -76.835)
		(stroke
			(width 0.381)
			(type default)
		)
		(layer "In3.Cu")
	)
	(gr_line
		(start 96.493584 -222.805244)
		(end 97.30613 -222.805244)
		(stroke
			(width 0.2)
			(type default)
		)
		(layer "In3.Cu")
	)
	(gr_arc
		(start 96.493584 -221.784164)
		(mid 95.983044 -222.294704)
		(end 96.493584 -222.805244)
		(stroke
			(width 0.2)
			(type default)
		)
		(layer "In3.Cu")
	)
	(gr_line
		(start 97.028 -22.098)
		(end 89.99982 -29.12618)
		(stroke
			(width 0.381)
			(type default)
		)
		(layer "In3.Cu")
	)
	(gr_arc
		(start 97.30613 -222.805244)
		(mid 97.816924 -222.294831)
		(end 97.306384 -221.784164)
		(stroke
			(width 0.2)
			(type default)
		)
		(layer "In3.Cu")
	)
	(gr_line
		(start 97.306384 -221.784164)
		(end 96.493584 -221.784164)
		(stroke
			(width 0.2)
			(type default)
		)
		(layer "In3.Cu")
	)
	(gr_line
		(start 98.093784 -211.406994)
		(end 98.906584 -211.406994)
		(stroke
			(width 0.2)
			(type default)
		)
		(layer "In3.Cu")
	)
	(gr_arc
		(start 98.094038 -210.385914)
		(mid 97.583244 -210.896327)
		(end 98.093784 -211.406994)
		(stroke
			(width 0.2)
			(type default)
		)
		(layer "In3.Cu")
	)
	(gr_arc
		(start 98.906584 -211.406994)
		(mid 99.417124 -210.896454)
		(end 98.906584 -210.385914)
		(stroke
			(width 0.2)
			(type default)
		)
		(layer "In3.Cu")
	)
	(gr_line
		(start 98.906584 -210.385914)
		(end 98.094038 -210.385914)
		(stroke
			(width 0.2)
			(type default)
		)
		(layer "In3.Cu")
	)
	(gr_line
		(start 99.693476 -222.805244)
		(end 100.506022 -222.805244)
		(stroke
			(width 0.2)
			(type default)
		)
		(layer "In3.Cu")
	)
	(gr_arc
		(start 99.693476 -221.784164)
		(mid 99.182936 -222.294704)
		(end 99.693476 -222.805244)
		(stroke
			(width 0.2)
			(type default)
		)
		(layer "In3.Cu")
	)
	(gr_arc
		(start 100.506022 -222.805244)
		(mid 101.016816 -222.294831)
		(end 100.506276 -221.784164)
		(stroke
			(width 0.2)
			(type default)
		)
		(layer "In3.Cu")
	)
	(gr_line
		(start 100.506276 -221.784164)
		(end 99.693476 -221.784164)
		(stroke
			(width 0.2)
			(type default)
		)
		(layer "In3.Cu")
	)
	(gr_line
		(start 101.293676 -211.406994)
		(end 102.106222 -211.406994)
		(stroke
			(width 0.2)
			(type default)
		)
		(layer "In3.Cu")
	)
	(gr_arc
		(start 101.293676 -210.385914)
		(mid 100.783136 -210.896454)
		(end 101.293676 -211.406994)
		(stroke
			(width 0.2)
			(type default)
		)
		(layer "In3.Cu")
	)
	(gr_arc
		(start 101.41966 -39.80561)
		(mid 101.9302 -40.31615)
		(end 102.44074 -39.80561)
		(stroke
			(width 0.2)
			(type default)
		)
		(layer "In3.Cu")
	)
	(gr_line
		(start 101.41966 -38.91661)
		(end 101.41966 -39.80561)
		(stroke
			(width 0.2)
			(type default)
		)
		(layer "In3.Cu")
	)
	(gr_arc
		(start 102.00386 -37.094414)
		(mid 102.514273 -37.605208)
		(end 103.02494 -37.094668)
		(stroke
			(width 0.2)
			(type default)
		)
		(layer "In3.Cu")
	)
	(gr_line
		(start 102.00386 -36.205668)
		(end 102.00386 -37.094414)
		(stroke
			(width 0.2)
			(type default)
		)
		(layer "In3.Cu")
	)
	(gr_arc
		(start 102.01402 -82.1182)
		(mid 102.62616 -82.73034)
		(end 103.2383 -82.1182)
		(stroke
			(width 0.2)
			(type default)
		)
		(layer "In3.Cu")
	)
	(gr_line
		(start 102.01402 -81.0006)
		(end 102.01402 -82.1182)
		(stroke
			(width 0.2)
			(type default)
		)
		(layer "In3.Cu")
	)
	(gr_arc
		(start 102.106222 -211.406994)
		(mid 102.617016 -210.896581)
		(end 102.106476 -210.385914)
		(stroke
			(width 0.2)
			(type default)
		)
		(layer "In3.Cu")
	)
	(gr_line
		(start 102.106476 -210.385914)
		(end 101.293676 -210.385914)
		(stroke
			(width 0.2)
			(type default)
		)
		(layer "In3.Cu")
	)
	(gr_line
		(start 102.44074 -39.80561)
		(end 102.44074 -38.916864)
		(stroke
			(width 0.2)
			(type default)
		)
		(layer "In3.Cu")
	)
	(gr_arc
		(start 102.44074 -38.916864)
		(mid 101.930327 -38.40607)
		(end 101.41966 -38.91661)
		(stroke
			(width 0.2)
			(type default)
		)
		(layer "In3.Cu")
	)
	(gr_line
		(start 102.893368 -222.805244)
		(end 103.705914 -222.805244)
		(stroke
			(width 0.2)
			(type default)
		)
		(layer "In3.Cu")
	)
	(gr_arc
		(start 102.893368 -221.784164)
		(mid 102.382828 -222.294704)
		(end 102.893368 -222.805244)
		(stroke
			(width 0.2)
			(type default)
		)
		(layer "In3.Cu")
	)
	(gr_line
		(start 103.02494 -37.094668)
		(end 103.02494 -36.205668)
		(stroke
			(width 0.2)
			(type default)
		)
		(layer "In3.Cu")
	)
	(gr_arc
		(start 103.02494 -36.205668)
		(mid 102.5144 -35.695128)
		(end 102.00386 -36.205668)
		(stroke
			(width 0.2)
			(type default)
		)
		(layer "In3.Cu")
	)
	(gr_line
		(start 103.2383 -82.1182)
		(end 103.2383 -81.000854)
		(stroke
			(width 0.2)
			(type default)
		)
		(layer "In3.Cu")
	)
	(gr_arc
		(start 103.2383 -81.000854)
		(mid 102.626287 -80.38846)
		(end 102.01402 -81.0006)
		(stroke
			(width 0.2)
			(type default)
		)
		(layer "In3.Cu")
	)
	(gr_arc
		(start 103.705914 -222.805244)
		(mid 104.216708 -222.294831)
		(end 103.706168 -221.784164)
		(stroke
			(width 0.2)
			(type default)
		)
		(layer "In3.Cu")
	)
	(gr_line
		(start 103.706168 -221.784164)
		(end 102.893368 -221.784164)
		(stroke
			(width 0.2)
			(type default)
		)
		(layer "In3.Cu")
	)
	(gr_line
		(start 104.493822 -211.406994)
		(end 105.306622 -211.406994)
		(stroke
			(width 0.2)
			(type default)
		)
		(layer "In3.Cu")
	)
	(gr_arc
		(start 104.494076 -210.385914)
		(mid 103.983282 -210.896327)
		(end 104.493822 -211.406994)
		(stroke
			(width 0.2)
			(type default)
		)
		(layer "In3.Cu")
	)
	(gr_line
		(start 104.775 -22.098)
		(end 97.028 -22.098)
		(stroke
			(width 0.381)
			(type default)
		)
		(layer "In3.Cu")
	)
	(gr_arc
		(start 105.306622 -211.406994)
		(mid 105.817162 -210.896454)
		(end 105.306622 -210.385914)
		(stroke
			(width 0.2)
			(type default)
		)
		(layer "In3.Cu")
	)
	(gr_line
		(start 105.306622 -210.385914)
		(end 104.494076 -210.385914)
		(stroke
			(width 0.2)
			(type default)
		)
		(layer "In3.Cu")
	)
	(gr_line
		(start 106.093514 -222.805244)
		(end 106.90606 -222.805244)
		(stroke
			(width 0.2)
			(type default)
		)
		(layer "In3.Cu")
	)
	(gr_arc
		(start 106.093514 -221.784164)
		(mid 105.582974 -222.294704)
		(end 106.093514 -222.805244)
		(stroke
			(width 0.2)
			(type default)
		)
		(layer "In3.Cu")
	)
	(gr_arc
		(start 106.90606 -222.805244)
		(mid 107.416854 -222.294831)
		(end 106.906314 -221.784164)
		(stroke
			(width 0.2)
			(type default)
		)
		(layer "In3.Cu")
	)
	(gr_line
		(start 106.906314 -221.784164)
		(end 106.093514 -221.784164)
		(stroke
			(width 0.2)
			(type default)
		)
		(layer "In3.Cu")
	)
	(gr_line
		(start 107.693714 -211.406994)
		(end 108.506514 -211.406994)
		(stroke
			(width 0.2)
			(type default)
		)
		(layer "In3.Cu")
	)
	(gr_arc
		(start 107.693968 -210.385914)
		(mid 107.183174 -210.896327)
		(end 107.693714 -211.406994)
		(stroke
			(width 0.2)
			(type default)
		)
		(layer "In3.Cu")
	)
	(gr_line
		(start 108.213144 -47.625)
		(end 121.22658 -34.611564)
		(stroke
			(width 0.381)
			(type default)
		)
		(layer "In3.Cu")
	)
	(gr_arc
		(start 108.506514 -211.406994)
		(mid 109.017054 -210.896454)
		(end 108.506514 -210.385914)
		(stroke
			(width 0.2)
			(type default)
		)
		(layer "In3.Cu")
	)
	(gr_line
		(start 108.506514 -210.385914)
		(end 107.693968 -210.385914)
		(stroke
			(width 0.2)
			(type default)
		)
		(layer "In3.Cu")
	)
	(gr_line
		(start 112.395 -76.835)
		(end 141.9098 -76.835)
		(stroke
			(width 0.381)
			(type default)
		)
		(layer "In3.Cu")
	)
	(gr_line
		(start 112.499902 -228.000052)
		(end 76.499974 -228.000052)
		(stroke
			(width 5.08)
			(type default)
		)
		(layer "In3.Cu")
	)
	(gr_line
		(start 112.499902 -222.400114)
		(end 112.499902 -228.000052)
		(stroke
			(width 1.524)
			(type default)
		)
		(layer "In3.Cu")
	)
	(gr_arc
		(start 113.000028 -221.899988)
		(mid 112.646386 -222.046472)
		(end 112.499902 -222.400114)
		(stroke
			(width 1.524)
			(type default)
		)
		(layer "In3.Cu")
	)
	(gr_line
		(start 113.799874 -221.899988)
		(end 113.000028 -221.899988)
		(stroke
			(width 1.524)
			(type default)
		)
		(layer "In3.Cu")
	)
	(gr_arc
		(start 113.799874 -221.899988)
		(mid 114.153489 -221.75366)
		(end 114.3 -221.400116)
		(stroke
			(width 1.524)
			(type default)
		)
		(layer "In3.Cu")
	)
	(gr_line
		(start 114.3 -214.799926)
		(end 114.3 -221.400116)
		(stroke
			(width 1.524)
			(type default)
		)
		(layer "In3.Cu")
	)
	(gr_arc
		(start 115.599972 -213.499954)
		(mid 114.680753 -213.880707)
		(end 114.3 -214.799926)
		(stroke
			(width 1.524)
			(type default)
		)
		(layer "In3.Cu")
	)
	(gr_arc
		(start 119.637556 0)
		(mid 121.051767 0.585785)
		(end 121.637552 1.999996)
		(stroke
			(width 1.524)
			(type default)
		)
		(layer "In3.Cu")
	)
	(gr_line
		(start 121.22658 -34.611564)
		(end 121.22658 -20.63242)
		(stroke
			(width 0.381)
			(type default)
		)
		(layer "In3.Cu")
	)
	(gr_line
		(start 121.22658 -20.63242)
		(end 136.017 -5.842)
		(stroke
			(width 0.381)
			(type default)
		)
		(layer "In3.Cu")
	)
	(gr_line
		(start 121.637552 1.999996)
		(end 121.637552 2.999994)
		(stroke
			(width 1.524)
			(type default)
		)
		(layer "In3.Cu")
	)
	(gr_arc
		(start 123.637548 4.99999)
		(mid 122.223308 4.414221)
		(end 121.637552 2.999994)
		(stroke
			(width 1.524)
			(type default)
		)
		(layer "In3.Cu")
	)
	(gr_line
		(start 123.637548 4.99999)
		(end 330.74991 4.99999)
		(stroke
			(width 1.524)
			(type default)
		)
		(layer "In3.Cu")
	)
	(gr_circle
		(center 123.80087 -64.83096)
		(end 124.84481 -64.83096)
		(stroke
			(width 0.2)
			(type default)
		)
		(fill no)
		(layer "In3.Cu")
	)
	(gr_line
		(start 129.921 3.048)
		(end 104.775 -22.098)
		(stroke
			(width 0.381)
			(type default)
		)
		(layer "In3.Cu")
	)
	(gr_line
		(start 131.0894 -35.783774)
		(end 131.9022 -35.783774)
		(stroke
			(width 0.2)
			(type default)
		)
		(layer "In3.Cu")
	)
	(gr_arc
		(start 131.089654 -34.762694)
		(mid 130.57886 -35.273107)
		(end 131.0894 -35.783774)
		(stroke
			(width 0.2)
			(type default)
		)
		(layer "In3.Cu")
	)
	(gr_arc
		(start 131.134104 -42.7228)
		(mid 131.746244 -43.33494)
		(end 132.358384 -42.7228)
		(stroke
			(width 0.2)
			(type default)
		)
		(layer "In3.Cu")
	)
	(gr_line
		(start 131.134104 -41.6052)
		(end 131.134104 -42.7228)
		(stroke
			(width 0.2)
			(type default)
		)
		(layer "In3.Cu")
	)
	(gr_line
		(start 131.400042 -213.499954)
		(end 115.599972 -213.499954)
		(stroke
			(width 1.524)
			(type default)
		)
		(layer "In3.Cu")
	)
	(gr_arc
		(start 131.9022 -35.783774)
		(mid 132.41274 -35.273234)
		(end 131.9022 -34.762694)
		(stroke
			(width 0.2)
			(type default)
		)
		(layer "In3.Cu")
	)
	(gr_line
		(start 131.9022 -34.762694)
		(end 131.089654 -34.762694)
		(stroke
			(width 0.2)
			(type default)
		)
		(layer "In3.Cu")
	)
	(gr_line
		(start 132.334 -143.256)
		(end 132.461 -143.256)
		(stroke
			(width 0.381)
			(type default)
		)
		(layer "In3.Cu")
	)
	(gr_line
		(start 132.334 -143.256)
		(end 335.915 -143.256)
		(stroke
			(width 0.381)
			(type default)
		)
		(layer "In3.Cu")
	)
	(gr_line
		(start 132.358384 -42.7228)
		(end 132.358384 -41.605454)
		(stroke
			(width 0.2)
			(type default)
		)
		(layer "In3.Cu")
	)
	(gr_arc
		(start 132.358384 -41.605454)
		(mid 131.746371 -40.99306)
		(end 131.134104 -41.6052)
		(stroke
			(width 0.2)
			(type default)
		)
		(layer "In3.Cu")
	)
	(gr_line
		(start 132.581396 -25.033732)
		(end 132.58165 -25.033986)
		(stroke
			(width 0.2)
			(type default)
		)
		(layer "In3.Cu")
	)
	(gr_line
		(start 132.581396 -13.633958)
		(end 132.583428 -13.635228)
		(stroke
			(width 0.2)
			(type default)
		)
		(layer "In3.Cu")
	)
	(gr_line
		(start 132.58165 -25.033986)
		(end 132.583682 -25.035002)
		(stroke
			(width 0.2)
			(type default)
		)
		(layer "In3.Cu")
	)
	(gr_arc
		(start 132.583428 -13.635228)
		(mid 132.83946 -14.481048)
		(end 133.68528 -14.225016)
		(stroke
			(width 0.2)
			(type default)
		)
		(layer "In3.Cu")
	)
	(gr_arc
		(start 132.583682 -25.035002)
		(mid 132.839358 -25.880903)
		(end 133.68528 -25.625044)
		(stroke
			(width 0.2)
			(type default)
		)
		(layer "In3.Cu")
	)
	(gr_line
		(start 132.700014 -221.400116)
		(end 132.700014 -214.799926)
		(stroke
			(width 1.524)
			(type default)
		)
		(layer "In3.Cu")
	)
	(gr_arc
		(start 132.700014 -221.400116)
		(mid 132.846428 -221.753573)
		(end 133.199886 -221.899988)
		(stroke
			(width 1.524)
			(type default)
		)
		(layer "In3.Cu")
	)
	(gr_arc
		(start 132.700014 -214.799926)
		(mid 132.319261 -213.880707)
		(end 131.400042 -213.499954)
		(stroke
			(width 1.524)
			(type default)
		)
		(layer "In3.Cu")
	)
	(gr_line
		(start 133.331458 -23.633938)
		(end 132.581396 -25.033732)
		(stroke
			(width 0.2)
			(type default)
		)
		(layer "In3.Cu")
	)
	(gr_line
		(start 133.331458 -12.23391)
		(end 132.581396 -13.633958)
		(stroke
			(width 0.2)
			(type default)
		)
		(layer "In3.Cu")
	)
	(gr_line
		(start 133.33349 -23.635208)
		(end 133.331458 -23.633938)
		(stroke
			(width 0.2)
			(type default)
		)
		(layer "In3.Cu")
	)
	(gr_line
		(start 133.33349 -12.23518)
		(end 133.331458 -12.23391)
		(stroke
			(width 0.2)
			(type default)
		)
		(layer "In3.Cu")
	)
	(gr_line
		(start 133.68528 -25.625044)
		(end 133.687312 -25.626314)
		(stroke
			(width 0.2)
			(type default)
		)
		(layer "In3.Cu")
	)
	(gr_line
		(start 133.68528 -14.225016)
		(end 133.687312 -14.226286)
		(stroke
			(width 0.2)
			(type default)
		)
		(layer "In3.Cu")
	)
	(gr_line
		(start 133.687312 -25.626314)
		(end 134.437374 -24.226266)
		(stroke
			(width 0.2)
			(type default)
		)
		(layer "In3.Cu")
	)
	(gr_line
		(start 133.687312 -14.226286)
		(end 134.437374 -12.826492)
		(stroke
			(width 0.2)
			(type default)
		)
		(layer "In3.Cu")
	)
	(gr_line
		(start 133.852158 -36.250372)
		(end 134.664704 -36.250372)
		(stroke
			(width 0.2)
			(type default)
		)
		(layer "In3.Cu")
	)
	(gr_arc
		(start 133.852158 -35.229292)
		(mid 133.341618 -35.739832)
		(end 133.852158 -36.250372)
		(stroke
			(width 0.2)
			(type default)
		)
		(layer "In3.Cu")
	)
	(gr_line
		(start 133.999986 -221.899988)
		(end 133.199886 -221.899988)
		(stroke
			(width 1.524)
			(type default)
		)
		(layer "In3.Cu")
	)
	(gr_arc
		(start 134.435088 -12.825222)
		(mid 134.179412 -11.979321)
		(end 133.33349 -12.23518)
		(stroke
			(width 0.2)
			(type default)
		)
		(layer "In3.Cu")
	)
	(gr_arc
		(start 134.435342 -24.224996)
		(mid 134.17931 -23.379176)
		(end 133.33349 -23.635208)
		(stroke
			(width 0.2)
			(type default)
		)
		(layer "In3.Cu")
	)
	(gr_line
		(start 134.43712 -12.826238)
		(end 134.435088 -12.825222)
		(stroke
			(width 0.2)
			(type default)
		)
		(layer "In3.Cu")
	)
	(gr_line
		(start 134.437374 -24.226266)
		(end 134.435342 -24.224996)
		(stroke
			(width 0.2)
			(type default)
		)
		(layer "In3.Cu")
	)
	(gr_line
		(start 134.437374 -12.826492)
		(end 134.43712 -12.826238)
		(stroke
			(width 0.2)
			(type default)
		)
		(layer "In3.Cu")
	)
	(gr_line
		(start 134.500112 -228.000052)
		(end 134.500112 -222.400114)
		(stroke
			(width 1.524)
			(type default)
		)
		(layer "In3.Cu")
	)
	(gr_arc
		(start 134.500112 -222.400114)
		(mid 134.353628 -222.046472)
		(end 133.999986 -221.899988)
		(stroke
			(width 1.524)
			(type default)
		)
		(layer "In3.Cu")
	)
	(gr_arc
		(start 134.664704 -36.250372)
		(mid 135.175498 -35.739959)
		(end 134.664958 -35.229292)
		(stroke
			(width 0.2)
			(type default)
		)
		(layer "In3.Cu")
	)
	(gr_line
		(start 134.664958 -35.229292)
		(end 133.852158 -35.229292)
		(stroke
			(width 0.2)
			(type default)
		)
		(layer "In3.Cu")
	)
	(gr_line
		(start 134.831582 -17.433544)
		(end 134.831836 -17.433798)
		(stroke
			(width 0.2)
			(type default)
		)
		(layer "In3.Cu")
	)
	(gr_line
		(start 134.831836 -17.433798)
		(end 134.833868 -17.434814)
		(stroke
			(width 0.2)
			(type default)
		)
		(layer "In3.Cu")
	)
	(gr_arc
		(start 134.833614 -13.635228)
		(mid 135.089646 -14.481048)
		(end 135.935466 -14.225016)
		(stroke
			(width 0.2)
			(type default)
		)
		(layer "In3.Cu")
	)
	(gr_arc
		(start 134.833868 -17.434814)
		(mid 135.089544 -18.280715)
		(end 135.935466 -18.024856)
		(stroke
			(width 0.2)
			(type default)
		)
		(layer "In3.Cu")
	)
	(gr_arc
		(start 134.837678 -25.027636)
		(mid 135.085812 -25.879089)
		(end 135.935466 -25.625044)
		(stroke
			(width 0.2)
			(type default)
		)
		(layer "In3.Cu")
	)
	(gr_arc
		(start 134.837678 -21.227542)
		(mid 135.085812 -22.078995)
		(end 135.935466 -21.82495)
		(stroke
			(width 0.2)
			(type default)
		)
		(layer "In3.Cu")
	)
	(gr_line
		(start 135.58139 -16.034004)
		(end 134.831582 -17.433544)
		(stroke
			(width 0.2)
			(type default)
		)
		(layer "In3.Cu")
	)
	(gr_line
		(start 135.583422 -23.635208)
		(end 134.837678 -25.027636)
		(stroke
			(width 0.2)
			(type default)
		)
		(layer "In3.Cu")
	)
	(gr_line
		(start 135.583422 -19.835114)
		(end 134.837678 -21.227542)
		(stroke
			(width 0.2)
			(type default)
		)
		(layer "In3.Cu")
	)
	(gr_line
		(start 135.583422 -16.035274)
		(end 135.58139 -16.034004)
		(stroke
			(width 0.2)
			(type default)
		)
		(layer "In3.Cu")
	)
	(gr_line
		(start 135.583422 -12.23518)
		(end 134.833614 -13.635228)
		(stroke
			(width 0.2)
			(type default)
		)
		(layer "In3.Cu")
	)
	(gr_line
		(start 135.935466 -25.625044)
		(end 136.685274 -24.224996)
		(stroke
			(width 0.2)
			(type default)
		)
		(layer "In3.Cu")
	)
	(gr_line
		(start 135.935466 -21.82495)
		(end 136.685274 -20.424902)
		(stroke
			(width 0.2)
			(type default)
		)
		(layer "In3.Cu")
	)
	(gr_line
		(start 135.935466 -18.024856)
		(end 135.937498 -18.026126)
		(stroke
			(width 0.2)
			(type default)
		)
		(layer "In3.Cu")
	)
	(gr_line
		(start 135.935466 -14.225016)
		(end 136.68121 -12.832588)
		(stroke
			(width 0.2)
			(type default)
		)
		(layer "In3.Cu")
	)
	(gr_line
		(start 135.937498 -18.026126)
		(end 136.687306 -16.626332)
		(stroke
			(width 0.2)
			(type default)
		)
		(layer "In3.Cu")
	)
	(gr_line
		(start 136.017 -5.842)
		(end 174.5234 -5.842)
		(stroke
			(width 0.381)
			(type default)
		)
		(layer "In3.Cu")
	)
	(gr_arc
		(start 136.68121 -12.832588)
		(mid 136.433076 -11.981135)
		(end 135.583422 -12.23518)
		(stroke
			(width 0.2)
			(type default)
		)
		(layer "In3.Cu")
	)
	(gr_arc
		(start 136.685274 -24.224996)
		(mid 136.429242 -23.379176)
		(end 135.583422 -23.635208)
		(stroke
			(width 0.2)
			(type default)
		)
		(layer "In3.Cu")
	)
	(gr_arc
		(start 136.685274 -20.424902)
		(mid 136.429242 -19.579082)
		(end 135.583422 -19.835114)
		(stroke
			(width 0.2)
			(type default)
		)
		(layer "In3.Cu")
	)
	(gr_arc
		(start 136.685274 -16.625062)
		(mid 136.429242 -15.779242)
		(end 135.583422 -16.035274)
		(stroke
			(width 0.2)
			(type default)
		)
		(layer "In3.Cu")
	)
	(gr_line
		(start 136.687306 -16.626332)
		(end 136.685274 -16.625062)
		(stroke
			(width 0.2)
			(type default)
		)
		(layer "In3.Cu")
	)
	(gr_line
		(start 136.893554 -222.805244)
		(end 137.7061 -222.805244)
		(stroke
			(width 0.2)
			(type default)
		)
		(layer "In3.Cu")
	)
	(gr_arc
		(start 136.893554 -221.784164)
		(mid 136.383014 -222.294704)
		(end 136.893554 -222.805244)
		(stroke
			(width 0.2)
			(type default)
		)
		(layer "In3.Cu")
	)
	(gr_line
		(start 137.081514 -25.033732)
		(end 137.081768 -25.033986)
		(stroke
			(width 0.2)
			(type default)
		)
		(layer "In3.Cu")
	)
	(gr_line
		(start 137.081514 -21.233638)
		(end 137.081768 -21.233892)
		(stroke
			(width 0.2)
			(type default)
		)
		(layer "In3.Cu")
	)
	(gr_line
		(start 137.081514 -17.433544)
		(end 137.081768 -17.433798)
		(stroke
			(width 0.2)
			(type default)
		)
		(layer "In3.Cu")
	)
	(gr_line
		(start 137.081514 -13.633958)
		(end 137.083546 -13.635228)
		(stroke
			(width 0.2)
			(type default)
		)
		(layer "In3.Cu")
	)
	(gr_line
		(start 137.081768 -25.033986)
		(end 137.0838 -25.035002)
		(stroke
			(width 0.2)
			(type default)
		)
		(layer "In3.Cu")
	)
	(gr_line
		(start 137.081768 -21.233892)
		(end 137.0838 -21.234908)
		(stroke
			(width 0.2)
			(type default)
		)
		(layer "In3.Cu")
	)
	(gr_line
		(start 137.081768 -17.433798)
		(end 137.0838 -17.434814)
		(stroke
			(width 0.2)
			(type default)
		)
		(layer "In3.Cu")
	)
	(gr_arc
		(start 137.083546 -13.635228)
		(mid 137.339578 -14.481048)
		(end 138.185398 -14.225016)
		(stroke
			(width 0.2)
			(type default)
		)
		(layer "In3.Cu")
	)
	(gr_arc
		(start 137.0838 -25.035002)
		(mid 137.339476 -25.880903)
		(end 138.185398 -25.625044)
		(stroke
			(width 0.2)
			(type default)
		)
		(layer "In3.Cu")
	)
	(gr_arc
		(start 137.0838 -21.234908)
		(mid 137.339476 -22.080809)
		(end 138.185398 -21.82495)
		(stroke
			(width 0.2)
			(type default)
		)
		(layer "In3.Cu")
	)
	(gr_arc
		(start 137.0838 -17.434814)
		(mid 137.339324 -18.280634)
		(end 138.185144 -18.02511)
		(stroke
			(width 0.2)
			(type default)
		)
		(layer "In3.Cu")
	)
	(gr_line
		(start 137.5664 -35.503866)
		(end 138.378946 -35.503866)
		(stroke
			(width 0.2)
			(type default)
		)
		(layer "In3.Cu")
	)
	(gr_arc
		(start 137.5664 -34.482786)
		(mid 137.05586 -34.993326)
		(end 137.5664 -35.503866)
		(stroke
			(width 0.2)
			(type default)
		)
		(layer "In3.Cu")
	)
	(gr_arc
		(start 137.7061 -222.805244)
		(mid 138.216894 -222.294831)
		(end 137.706354 -221.784164)
		(stroke
			(width 0.2)
			(type default)
		)
		(layer "In3.Cu")
	)
	(gr_line
		(start 137.706354 -221.784164)
		(end 136.893554 -221.784164)
		(stroke
			(width 0.2)
			(type default)
		)
		(layer "In3.Cu")
	)
	(gr_line
		(start 137.831576 -23.633938)
		(end 137.081514 -25.033732)
		(stroke
			(width 0.2)
			(type default)
		)
		(layer "In3.Cu")
	)
	(gr_line
		(start 137.831576 -19.833844)
		(end 137.081514 -21.233638)
		(stroke
			(width 0.2)
			(type default)
		)
		(layer "In3.Cu")
	)
	(gr_line
		(start 137.831576 -16.03375)
		(end 137.081514 -17.433544)
		(stroke
			(width 0.2)
			(type default)
		)
		(layer "In3.Cu")
	)
	(gr_line
		(start 137.831576 -12.23391)
		(end 137.081514 -13.633958)
		(stroke
			(width 0.2)
			(type default)
		)
		(layer "In3.Cu")
	)
	(gr_line
		(start 137.833608 -23.635208)
		(end 137.831576 -23.633938)
		(stroke
			(width 0.2)
			(type default)
		)
		(layer "In3.Cu")
	)
	(gr_line
		(start 137.833608 -19.835114)
		(end 137.831576 -19.833844)
		(stroke
			(width 0.2)
			(type default)
		)
		(layer "In3.Cu")
	)
	(gr_line
		(start 137.833608 -12.23518)
		(end 137.831576 -12.23391)
		(stroke
			(width 0.2)
			(type default)
		)
		(layer "In3.Cu")
	)
	(gr_line
		(start 137.833862 -16.03502)
		(end 137.831576 -16.03375)
		(stroke
			(width 0.2)
			(type default)
		)
		(layer "In3.Cu")
	)
	(gr_line
		(start 138.185144 -18.02511)
		(end 138.18743 -18.02638)
		(stroke
			(width 0.2)
			(type default)
		)
		(layer "In3.Cu")
	)
	(gr_line
		(start 138.185398 -25.625044)
		(end 138.18743 -25.626314)
		(stroke
			(width 0.2)
			(type default)
		)
		(layer "In3.Cu")
	)
	(gr_line
		(start 138.185398 -21.82495)
		(end 138.18743 -21.82622)
		(stroke
			(width 0.2)
			(type default)
		)
		(layer "In3.Cu")
	)
	(gr_line
		(start 138.185398 -14.225016)
		(end 138.18743 -14.226286)
		(stroke
			(width 0.2)
			(type default)
		)
		(layer "In3.Cu")
	)
	(gr_line
		(start 138.18743 -25.626314)
		(end 138.937492 -24.226266)
		(stroke
			(width 0.2)
			(type default)
		)
		(layer "In3.Cu")
	)
	(gr_line
		(start 138.18743 -21.82622)
		(end 138.937492 -20.426172)
		(stroke
			(width 0.2)
			(type default)
		)
		(layer "In3.Cu")
	)
	(gr_line
		(start 138.18743 -18.02638)
		(end 138.937492 -16.626586)
		(stroke
			(width 0.2)
			(type default)
		)
		(layer "In3.Cu")
	)
	(gr_line
		(start 138.18743 -14.226286)
		(end 138.937492 -12.826492)
		(stroke
			(width 0.2)
			(type default)
		)
		(layer "In3.Cu")
	)
	(gr_arc
		(start 138.378946 -35.503866)
		(mid 138.88974 -34.993453)
		(end 138.3792 -34.482786)
		(stroke
			(width 0.2)
			(type default)
		)
		(layer "In3.Cu")
	)
	(gr_line
		(start 138.3792 -34.482786)
		(end 137.5664 -34.482786)
		(stroke
			(width 0.2)
			(type default)
		)
		(layer "In3.Cu")
	)
	(gr_line
		(start 138.493754 -211.406994)
		(end 139.306554 -211.406994)
		(stroke
			(width 0.2)
			(type default)
		)
		(layer "In3.Cu")
	)
	(gr_arc
		(start 138.494008 -210.385914)
		(mid 137.983214 -210.896327)
		(end 138.493754 -211.406994)
		(stroke
			(width 0.2)
			(type default)
		)
		(layer "In3.Cu")
	)
	(gr_line
		(start 138.557 -39.16934)
		(end 139.3698 -39.16934)
		(stroke
			(width 0.2)
			(type default)
		)
		(layer "In3.Cu")
	)
	(gr_arc
		(start 138.557254 -38.14826)
		(mid 138.04646 -38.658673)
		(end 138.557 -39.16934)
		(stroke
			(width 0.2)
			(type default)
		)
		(layer "In3.Cu")
	)
	(gr_arc
		(start 138.935206 -16.625316)
		(mid 138.679682 -15.779496)
		(end 137.833862 -16.03502)
		(stroke
			(width 0.2)
			(type default)
		)
		(layer "In3.Cu")
	)
	(gr_arc
		(start 138.935206 -12.825222)
		(mid 138.67953 -11.979321)
		(end 137.833608 -12.23518)
		(stroke
			(width 0.2)
			(type default)
		)
		(layer "In3.Cu")
	)
	(gr_arc
		(start 138.93546 -24.224996)
		(mid 138.679428 -23.379176)
		(end 137.833608 -23.635208)
		(stroke
			(width 0.2)
			(type default)
		)
		(layer "In3.Cu")
	)
	(gr_arc
		(start 138.93546 -20.424902)
		(mid 138.679428 -19.579082)
		(end 137.833608 -19.835114)
		(stroke
			(width 0.2)
			(type default)
		)
		(layer "In3.Cu")
	)
	(gr_line
		(start 138.937238 -12.826238)
		(end 138.935206 -12.825222)
		(stroke
			(width 0.2)
			(type default)
		)
		(layer "In3.Cu")
	)
	(gr_line
		(start 138.937492 -24.226266)
		(end 138.93546 -24.224996)
		(stroke
			(width 0.2)
			(type default)
		)
		(layer "In3.Cu")
	)
	(gr_line
		(start 138.937492 -20.426172)
		(end 138.93546 -20.424902)
		(stroke
			(width 0.2)
			(type default)
		)
		(layer "In3.Cu")
	)
	(gr_line
		(start 138.937492 -16.626586)
		(end 138.935206 -16.625316)
		(stroke
			(width 0.2)
			(type default)
		)
		(layer "In3.Cu")
	)
	(gr_line
		(start 138.937492 -12.826492)
		(end 138.937238 -12.826238)
		(stroke
			(width 0.2)
			(type default)
		)
		(layer "In3.Cu")
	)
	(gr_arc
		(start 139.306554 -211.406994)
		(mid 139.817094 -210.896454)
		(end 139.306554 -210.385914)
		(stroke
			(width 0.2)
			(type default)
		)
		(layer "In3.Cu")
	)
	(gr_line
		(start 139.306554 -210.385914)
		(end 138.494008 -210.385914)
		(stroke
			(width 0.2)
			(type default)
		)
		(layer "In3.Cu")
	)
	(gr_arc
		(start 139.3698 -39.16934)
		(mid 139.88034 -38.6588)
		(end 139.3698 -38.14826)
		(stroke
			(width 0.2)
			(type default)
		)
		(layer "In3.Cu")
	)
	(gr_line
		(start 139.3698 -38.14826)
		(end 138.557254 -38.14826)
		(stroke
			(width 0.2)
			(type default)
		)
		(layer "In3.Cu")
	)
	(gr_line
		(start 140.0937 -222.805244)
		(end 140.906246 -222.805244)
		(stroke
			(width 0.2)
			(type default)
		)
		(layer "In3.Cu")
	)
	(gr_arc
		(start 140.0937 -221.784164)
		(mid 139.58316 -222.294704)
		(end 140.0937 -222.805244)
		(stroke
			(width 0.2)
			(type default)
		)
		(layer "In3.Cu")
	)
	(gr_arc
		(start 140.906246 -222.805244)
		(mid 141.41704 -222.294831)
		(end 140.9065 -221.784164)
		(stroke
			(width 0.2)
			(type default)
		)
		(layer "In3.Cu")
	)
	(gr_line
		(start 140.9065 -221.784164)
		(end 140.0937 -221.784164)
		(stroke
			(width 0.2)
			(type default)
		)
		(layer "In3.Cu")
	)
	(gr_line
		(start 141.478 -133.604)
		(end 142.24 -134.366)
		(stroke
			(width 0.381)
			(type default)
		)
		(layer "In3.Cu")
	)
	(gr_line
		(start 141.478 -84.9884)
		(end 141.478 -133.604)
		(stroke
			(width 0.381)
			(type default)
		)
		(layer "In3.Cu")
	)
	(gr_line
		(start 141.6939 -211.406994)
		(end 142.5067 -211.406994)
		(stroke
			(width 0.2)
			(type default)
		)
		(layer "In3.Cu")
	)
	(gr_arc
		(start 141.694154 -210.385914)
		(mid 141.18336 -210.896327)
		(end 141.6939 -211.406994)
		(stroke
			(width 0.2)
			(type default)
		)
		(layer "In3.Cu")
	)
	(gr_line
		(start 141.9098 -76.835)
		(end 143.4846 -78.4098)
		(stroke
			(width 0.381)
			(type default)
		)
		(layer "In3.Cu")
	)
	(gr_line
		(start 142.24 -134.366)
		(end 330.708 -134.366)
		(stroke
			(width 0.381)
			(type default)
		)
		(layer "In3.Cu")
	)
	(gr_arc
		(start 142.5067 -211.406994)
		(mid 143.01724 -210.896454)
		(end 142.5067 -210.385914)
		(stroke
			(width 0.2)
			(type default)
		)
		(layer "In3.Cu")
	)
	(gr_line
		(start 142.5067 -210.385914)
		(end 141.694154 -210.385914)
		(stroke
			(width 0.2)
			(type default)
		)
		(layer "In3.Cu")
	)
	(gr_line
		(start 143.293592 -222.805244)
		(end 144.106138 -222.805244)
		(stroke
			(width 0.2)
			(type default)
		)
		(layer "In3.Cu")
	)
	(gr_arc
		(start 143.293592 -221.784164)
		(mid 142.783052 -222.294704)
		(end 143.293592 -222.805244)
		(stroke
			(width 0.2)
			(type default)
		)
		(layer "In3.Cu")
	)
	(gr_line
		(start 143.4846 -82.9818)
		(end 141.478 -84.9884)
		(stroke
			(width 0.381)
			(type default)
		)
		(layer "In3.Cu")
	)
	(gr_line
		(start 143.4846 -78.4098)
		(end 143.4846 -82.9818)
		(stroke
			(width 0.381)
			(type default)
		)
		(layer "In3.Cu")
	)
	(gr_line
		(start 143.581374 -25.033986)
		(end 143.583406 -25.035256)
		(stroke
			(width 0.2)
			(type default)
		)
		(layer "In3.Cu")
	)
	(gr_line
		(start 143.581374 -13.633704)
		(end 143.581628 -13.633958)
		(stroke
			(width 0.2)
			(type default)
		)
		(layer "In3.Cu")
	)
	(gr_line
		(start 143.581628 -13.633958)
		(end 143.58366 -13.634974)
		(stroke
			(width 0.2)
			(type default)
		)
		(layer "In3.Cu")
	)
	(gr_arc
		(start 143.583406 -25.035256)
		(mid 143.839438 -25.881076)
		(end 144.685258 -25.625044)
		(stroke
			(width 0.2)
			(type default)
		)
		(layer "In3.Cu")
	)
	(gr_arc
		(start 143.58366 -13.634974)
		(mid 143.839336 -14.480875)
		(end 144.685258 -14.225016)
		(stroke
			(width 0.2)
			(type default)
		)
		(layer "In3.Cu")
	)
	(gr_arc
		(start 144.106138 -222.805244)
		(mid 144.616932 -222.294831)
		(end 144.106392 -221.784164)
		(stroke
			(width 0.2)
			(type default)
		)
		(layer "In3.Cu")
	)
	(gr_line
		(start 144.106392 -221.784164)
		(end 143.293592 -221.784164)
		(stroke
			(width 0.2)
			(type default)
		)
		(layer "In3.Cu")
	)
	(gr_line
		(start 144.331436 -23.633938)
		(end 143.581374 -25.033986)
		(stroke
			(width 0.2)
			(type default)
		)
		(layer "In3.Cu")
	)
	(gr_line
		(start 144.331436 -12.23391)
		(end 143.581374 -13.633704)
		(stroke
			(width 0.2)
			(type default)
		)
		(layer "In3.Cu")
	)
	(gr_line
		(start 144.333468 -23.635208)
		(end 144.331436 -23.633938)
		(stroke
			(width 0.2)
			(type default)
		)
		(layer "In3.Cu")
	)
	(gr_line
		(start 144.333468 -12.23518)
		(end 144.331436 -12.23391)
		(stroke
			(width 0.2)
			(type default)
		)
		(layer "In3.Cu")
	)
	(gr_line
		(start 144.685258 -25.625044)
		(end 144.68729 -25.626314)
		(stroke
			(width 0.2)
			(type default)
		)
		(layer "In3.Cu")
	)
	(gr_line
		(start 144.685258 -14.225016)
		(end 144.68729 -14.226286)
		(stroke
			(width 0.2)
			(type default)
		)
		(layer "In3.Cu")
	)
	(gr_line
		(start 144.68729 -25.626314)
		(end 145.437352 -24.22652)
		(stroke
			(width 0.2)
			(type default)
		)
		(layer "In3.Cu")
	)
	(gr_line
		(start 144.68729 -14.226286)
		(end 145.437352 -12.826238)
		(stroke
			(width 0.2)
			(type default)
		)
		(layer "In3.Cu")
	)
	(gr_line
		(start 144.893792 -211.406994)
		(end 145.706592 -211.406994)
		(stroke
			(width 0.2)
			(type default)
		)
		(layer "In3.Cu")
	)
	(gr_arc
		(start 144.894046 -210.385914)
		(mid 144.383252 -210.896327)
		(end 144.893792 -211.406994)
		(stroke
			(width 0.2)
			(type default)
		)
		(layer "In3.Cu")
	)
	(gr_arc
		(start 145.435066 -24.22525)
		(mid 145.17939 -23.379349)
		(end 144.333468 -23.635208)
		(stroke
			(width 0.2)
			(type default)
		)
		(layer "In3.Cu")
	)
	(gr_arc
		(start 145.43532 -12.824968)
		(mid 145.179288 -11.979148)
		(end 144.333468 -12.23518)
		(stroke
			(width 0.2)
			(type default)
		)
		(layer "In3.Cu")
	)
	(gr_line
		(start 145.437098 -24.226266)
		(end 145.435066 -24.22525)
		(stroke
			(width 0.2)
			(type default)
		)
		(layer "In3.Cu")
	)
	(gr_line
		(start 145.437352 -24.22652)
		(end 145.437098 -24.226266)
		(stroke
			(width 0.2)
			(type default)
		)
		(layer "In3.Cu")
	)
	(gr_line
		(start 145.437352 -12.826238)
		(end 145.43532 -12.824968)
		(stroke
			(width 0.2)
			(type default)
		)
		(layer "In3.Cu")
	)
	(gr_arc
		(start 145.706592 -211.406994)
		(mid 146.217132 -210.896454)
		(end 145.706592 -210.385914)
		(stroke
			(width 0.2)
			(type default)
		)
		(layer "In3.Cu")
	)
	(gr_line
		(start 145.706592 -210.385914)
		(end 144.894046 -210.385914)
		(stroke
			(width 0.2)
			(type default)
		)
		(layer "In3.Cu")
	)
	(gr_line
		(start 145.83156 -17.433544)
		(end 145.831814 -17.433798)
		(stroke
			(width 0.2)
			(type default)
		)
		(layer "In3.Cu")
	)
	(gr_line
		(start 145.831814 -17.433798)
		(end 145.833846 -17.434814)
		(stroke
			(width 0.2)
			(type default)
		)
		(layer "In3.Cu")
	)
	(gr_arc
		(start 145.833592 -21.235162)
		(mid 146.089624 -22.080982)
		(end 146.935444 -21.82495)
		(stroke
			(width 0.2)
			(type default)
		)
		(layer "In3.Cu")
	)
	(gr_arc
		(start 145.833846 -17.434814)
		(mid 146.089522 -18.280715)
		(end 146.935444 -18.024856)
		(stroke
			(width 0.2)
			(type default)
		)
		(layer "In3.Cu")
	)
	(gr_arc
		(start 145.837656 -25.027636)
		(mid 146.08579 -25.879089)
		(end 146.935444 -25.625044)
		(stroke
			(width 0.2)
			(type default)
		)
		(layer "In3.Cu")
	)
	(gr_arc
		(start 145.837656 -13.627608)
		(mid 146.08579 -14.479061)
		(end 146.935444 -14.225016)
		(stroke
			(width 0.2)
			(type default)
		)
		(layer "In3.Cu")
	)
	(gr_line
		(start 145.9103 -35.50666)
		(end 146.7231 -35.50666)
		(stroke
			(width 0.2)
			(type default)
		)
		(layer "In3.Cu")
	)
	(gr_arc
		(start 145.910554 -34.48558)
		(mid 145.39976 -34.995993)
		(end 145.9103 -35.50666)
		(stroke
			(width 0.2)
			(type default)
		)
		(layer "In3.Cu")
	)
	(gr_line
		(start 146.493738 -222.805244)
		(end 147.306284 -222.805244)
		(stroke
			(width 0.2)
			(type default)
		)
		(layer "In3.Cu")
	)
	(gr_arc
		(start 146.493738 -221.784164)
		(mid 145.983198 -222.294704)
		(end 146.493738 -222.805244)
		(stroke
			(width 0.2)
			(type default)
		)
		(layer "In3.Cu")
	)
	(gr_line
		(start 146.581368 -16.034004)
		(end 145.83156 -17.433544)
		(stroke
			(width 0.2)
			(type default)
		)
		(layer "In3.Cu")
	)
	(gr_line
		(start 146.5834 -23.635208)
		(end 145.837656 -25.027636)
		(stroke
			(width 0.2)
			(type default)
		)
		(layer "In3.Cu")
	)
	(gr_line
		(start 146.5834 -19.835114)
		(end 145.833592 -21.235162)
		(stroke
			(width 0.2)
			(type default)
		)
		(layer "In3.Cu")
	)
	(gr_line
		(start 146.5834 -16.035274)
		(end 146.581368 -16.034004)
		(stroke
			(width 0.2)
			(type default)
		)
		(layer "In3.Cu")
	)
	(gr_line
		(start 146.5834 -12.23518)
		(end 145.837656 -13.627608)
		(stroke
			(width 0.2)
			(type default)
		)
		(layer "In3.Cu")
	)
	(gr_arc
		(start 146.7231 -35.50666)
		(mid 147.23364 -34.99612)
		(end 146.7231 -34.48558)
		(stroke
			(width 0.2)
			(type default)
		)
		(layer "In3.Cu")
	)
	(gr_line
		(start 146.7231 -34.48558)
		(end 145.910554 -34.48558)
		(stroke
			(width 0.2)
			(type default)
		)
		(layer "In3.Cu")
	)
	(gr_line
		(start 146.935444 -25.625044)
		(end 147.685252 -24.224996)
		(stroke
			(width 0.2)
			(type default)
		)
		(layer "In3.Cu")
	)
	(gr_line
		(start 146.935444 -21.82495)
		(end 147.681188 -20.432522)
		(stroke
			(width 0.2)
			(type default)
		)
		(layer "In3.Cu")
	)
	(gr_line
		(start 146.935444 -18.024856)
		(end 146.937476 -18.026126)
		(stroke
			(width 0.2)
			(type default)
		)
		(layer "In3.Cu")
	)
	(gr_line
		(start 146.935444 -14.225016)
		(end 147.685252 -12.824968)
		(stroke
			(width 0.2)
			(type default)
		)
		(layer "In3.Cu")
	)
	(gr_line
		(start 146.937476 -18.026126)
		(end 147.687284 -16.626332)
		(stroke
			(width 0.2)
			(type default)
		)
		(layer "In3.Cu")
	)
	(gr_arc
		(start 147.306284 -222.805244)
		(mid 147.817078 -222.294831)
		(end 147.306538 -221.784164)
		(stroke
			(width 0.2)
			(type default)
		)
		(layer "In3.Cu")
	)
	(gr_line
		(start 147.306538 -221.784164)
		(end 146.493738 -221.784164)
		(stroke
			(width 0.2)
			(type default)
		)
		(layer "In3.Cu")
	)
	(gr_arc
		(start 147.681188 -20.432522)
		(mid 147.433054 -19.581069)
		(end 146.5834 -19.835114)
		(stroke
			(width 0.2)
			(type default)
		)
		(layer "In3.Cu")
	)
	(gr_arc
		(start 147.685252 -24.224996)
		(mid 147.42922 -23.379176)
		(end 146.5834 -23.635208)
		(stroke
			(width 0.2)
			(type default)
		)
		(layer "In3.Cu")
	)
	(gr_arc
		(start 147.685252 -16.625062)
		(mid 147.42922 -15.779242)
		(end 146.5834 -16.035274)
		(stroke
			(width 0.2)
			(type default)
		)
		(layer "In3.Cu")
	)
	(gr_arc
		(start 147.685252 -12.824968)
		(mid 147.42922 -11.979148)
		(end 146.5834 -12.23518)
		(stroke
			(width 0.2)
			(type default)
		)
		(layer "In3.Cu")
	)
	(gr_line
		(start 147.687284 -16.626332)
		(end 147.685252 -16.625062)
		(stroke
			(width 0.2)
			(type default)
		)
		(layer "In3.Cu")
	)
	(gr_line
		(start 148.081492 -25.033732)
		(end 148.081746 -25.033986)
		(stroke
			(width 0.2)
			(type default)
		)
		(layer "In3.Cu")
	)
	(gr_line
		(start 148.081492 -21.233892)
		(end 148.083524 -21.235162)
		(stroke
			(width 0.2)
			(type default)
		)
		(layer "In3.Cu")
	)
	(gr_line
		(start 148.081492 -17.433544)
		(end 148.081746 -17.433798)
		(stroke
			(width 0.2)
			(type default)
		)
		(layer "In3.Cu")
	)
	(gr_line
		(start 148.081492 -13.633704)
		(end 148.081746 -13.633958)
		(stroke
			(width 0.2)
			(type default)
		)
		(layer "In3.Cu")
	)
	(gr_line
		(start 148.081746 -25.033986)
		(end 148.083778 -25.035002)
		(stroke
			(width 0.2)
			(type default)
		)
		(layer "In3.Cu")
	)
	(gr_line
		(start 148.081746 -17.433798)
		(end 148.083778 -17.434814)
		(stroke
			(width 0.2)
			(type default)
		)
		(layer "In3.Cu")
	)
	(gr_line
		(start 148.081746 -13.633958)
		(end 148.083778 -13.634974)
		(stroke
			(width 0.2)
			(type default)
		)
		(layer "In3.Cu")
	)
	(gr_arc
		(start 148.083524 -21.235162)
		(mid 148.339556 -22.080982)
		(end 149.185376 -21.82495)
		(stroke
			(width 0.2)
			(type default)
		)
		(layer "In3.Cu")
	)
	(gr_arc
		(start 148.083778 -25.035002)
		(mid 148.339454 -25.880903)
		(end 149.185376 -25.625044)
		(stroke
			(width 0.2)
			(type default)
		)
		(layer "In3.Cu")
	)
	(gr_arc
		(start 148.083778 -17.434814)
		(mid 148.339302 -18.280634)
		(end 149.185122 -18.02511)
		(stroke
			(width 0.2)
			(type default)
		)
		(layer "In3.Cu")
	)
	(gr_arc
		(start 148.083778 -13.634974)
		(mid 148.339454 -14.480875)
		(end 149.185376 -14.225016)
		(stroke
			(width 0.2)
			(type default)
		)
		(layer "In3.Cu")
	)
	(gr_line
		(start 148.093684 -211.406994)
		(end 148.906484 -211.406994)
		(stroke
			(width 0.2)
			(type default)
		)
		(layer "In3.Cu")
	)
	(gr_arc
		(start 148.093938 -210.385914)
		(mid 147.583144 -210.896327)
		(end 148.093684 -211.406994)
		(stroke
			(width 0.2)
			(type default)
		)
		(layer "In3.Cu")
	)
	(gr_line
		(start 148.5011 -35.51174)
		(end 149.313646 -35.51174)
		(stroke
			(width 0.2)
			(type default)
		)
		(layer "In3.Cu")
	)
	(gr_arc
		(start 148.5011 -34.49066)
		(mid 147.99056 -35.0012)
		(end 148.5011 -35.51174)
		(stroke
			(width 0.2)
			(type default)
		)
		(layer "In3.Cu")
	)
	(gr_line
		(start 148.831554 -23.633938)
		(end 148.081492 -25.033732)
		(stroke
			(width 0.2)
			(type default)
		)
		(layer "In3.Cu")
	)
	(gr_line
		(start 148.831554 -19.833844)
		(end 148.081492 -21.233892)
		(stroke
			(width 0.2)
			(type default)
		)
		(layer "In3.Cu")
	)
	(gr_line
		(start 148.831554 -16.03375)
		(end 148.081492 -17.433544)
		(stroke
			(width 0.2)
			(type default)
		)
		(layer "In3.Cu")
	)
	(gr_line
		(start 148.831554 -12.23391)
		(end 148.081492 -13.633704)
		(stroke
			(width 0.2)
			(type default)
		)
		(layer "In3.Cu")
	)
	(gr_line
		(start 148.833586 -23.635208)
		(end 148.831554 -23.633938)
		(stroke
			(width 0.2)
			(type default)
		)
		(layer "In3.Cu")
	)
	(gr_line
		(start 148.833586 -19.835114)
		(end 148.831554 -19.833844)
		(stroke
			(width 0.2)
			(type default)
		)
		(layer "In3.Cu")
	)
	(gr_line
		(start 148.833586 -12.23518)
		(end 148.831554 -12.23391)
		(stroke
			(width 0.2)
			(type default)
		)
		(layer "In3.Cu")
	)
	(gr_line
		(start 148.83384 -16.03502)
		(end 148.831554 -16.03375)
		(stroke
			(width 0.2)
			(type default)
		)
		(layer "In3.Cu")
	)
	(gr_arc
		(start 148.906484 -211.406994)
		(mid 149.417024 -210.896454)
		(end 148.906484 -210.385914)
		(stroke
			(width 0.2)
			(type default)
		)
		(layer "In3.Cu")
	)
	(gr_line
		(start 148.906484 -210.385914)
		(end 148.093938 -210.385914)
		(stroke
			(width 0.2)
			(type default)
		)
		(layer "In3.Cu")
	)
	(gr_line
		(start 149.185122 -18.02511)
		(end 149.187408 -18.02638)
		(stroke
			(width 0.2)
			(type default)
		)
		(layer "In3.Cu")
	)
	(gr_line
		(start 149.185376 -25.625044)
		(end 149.187408 -25.626314)
		(stroke
			(width 0.2)
			(type default)
		)
		(layer "In3.Cu")
	)
	(gr_line
		(start 149.185376 -21.82495)
		(end 149.187408 -21.82622)
		(stroke
			(width 0.2)
			(type default)
		)
		(layer "In3.Cu")
	)
	(gr_line
		(start 149.185376 -14.225016)
		(end 149.187408 -14.226286)
		(stroke
			(width 0.2)
			(type default)
		)
		(layer "In3.Cu")
	)
	(gr_line
		(start 149.187408 -25.626314)
		(end 149.93747 -24.226266)
		(stroke
			(width 0.2)
			(type default)
		)
		(layer "In3.Cu")
	)
	(gr_line
		(start 149.187408 -21.82622)
		(end 149.93747 -20.426426)
		(stroke
			(width 0.2)
			(type default)
		)
		(layer "In3.Cu")
	)
	(gr_line
		(start 149.187408 -18.02638)
		(end 149.93747 -16.626586)
		(stroke
			(width 0.2)
			(type default)
		)
		(layer "In3.Cu")
	)
	(gr_line
		(start 149.187408 -14.226286)
		(end 149.93747 -12.826238)
		(stroke
			(width 0.2)
			(type default)
		)
		(layer "In3.Cu")
	)
	(gr_arc
		(start 149.313646 -35.51174)
		(mid 149.82444 -35.001327)
		(end 149.3139 -34.49066)
		(stroke
			(width 0.2)
			(type default)
		)
		(layer "In3.Cu")
	)
	(gr_line
		(start 149.3139 -34.49066)
		(end 148.5011 -34.49066)
		(stroke
			(width 0.2)
			(type default)
		)
		(layer "In3.Cu")
	)
	(gr_line
		(start 149.69363 -222.805244)
		(end 150.506176 -222.805244)
		(stroke
			(width 0.2)
			(type default)
		)
		(layer "In3.Cu")
	)
	(gr_arc
		(start 149.69363 -221.784164)
		(mid 149.18309 -222.294704)
		(end 149.69363 -222.805244)
		(stroke
			(width 0.2)
			(type default)
		)
		(layer "In3.Cu")
	)
	(gr_arc
		(start 149.935184 -20.425156)
		(mid 149.679508 -19.579255)
		(end 148.833586 -19.835114)
		(stroke
			(width 0.2)
			(type default)
		)
		(layer "In3.Cu")
	)
	(gr_arc
		(start 149.935184 -16.625316)
		(mid 149.67966 -15.779496)
		(end 148.83384 -16.03502)
		(stroke
			(width 0.2)
			(type default)
		)
		(layer "In3.Cu")
	)
	(gr_arc
		(start 149.935438 -24.224996)
		(mid 149.679406 -23.379176)
		(end 148.833586 -23.635208)
		(stroke
			(width 0.2)
			(type default)
		)
		(layer "In3.Cu")
	)
	(gr_arc
		(start 149.935438 -12.824968)
		(mid 149.679406 -11.979148)
		(end 148.833586 -12.23518)
		(stroke
			(width 0.2)
			(type default)
		)
		(layer "In3.Cu")
	)
	(gr_line
		(start 149.937216 -20.426172)
		(end 149.935184 -20.425156)
		(stroke
			(width 0.2)
			(type default)
		)
		(layer "In3.Cu")
	)
	(gr_line
		(start 149.93747 -24.226266)
		(end 149.935438 -24.224996)
		(stroke
			(width 0.2)
			(type default)
		)
		(layer "In3.Cu")
	)
	(gr_line
		(start 149.93747 -20.426426)
		(end 149.937216 -20.426172)
		(stroke
			(width 0.2)
			(type default)
		)
		(layer "In3.Cu")
	)
	(gr_line
		(start 149.93747 -16.626586)
		(end 149.935184 -16.625316)
		(stroke
			(width 0.2)
			(type default)
		)
		(layer "In3.Cu")
	)
	(gr_line
		(start 149.93747 -12.826238)
		(end 149.935438 -12.824968)
		(stroke
			(width 0.2)
			(type default)
		)
		(layer "In3.Cu")
	)
	(gr_arc
		(start 150.506176 -222.805244)
		(mid 151.01697 -222.294831)
		(end 150.50643 -221.784164)
		(stroke
			(width 0.2)
			(type default)
		)
		(layer "In3.Cu")
	)
	(gr_line
		(start 150.50643 -221.784164)
		(end 149.69363 -221.784164)
		(stroke
			(width 0.2)
			(type default)
		)
		(layer "In3.Cu")
	)
	(gr_line
		(start 150.9141 -38.59784)
		(end 151.726646 -38.59784)
		(stroke
			(width 0.2)
			(type default)
		)
		(layer "In3.Cu")
	)
	(gr_arc
		(start 150.9141 -37.57676)
		(mid 150.40356 -38.0873)
		(end 150.9141 -38.59784)
		(stroke
			(width 0.2)
			(type default)
		)
		(layer "In3.Cu")
	)
	(gr_line
		(start 151.29383 -211.406994)
		(end 152.10663 -211.406994)
		(stroke
			(width 0.2)
			(type default)
		)
		(layer "In3.Cu")
	)
	(gr_arc
		(start 151.294084 -210.385914)
		(mid 150.78329 -210.896327)
		(end 151.29383 -211.406994)
		(stroke
			(width 0.2)
			(type default)
		)
		(layer "In3.Cu")
	)
	(gr_arc
		(start 151.726646 -38.59784)
		(mid 152.23744 -38.087427)
		(end 151.7269 -37.57676)
		(stroke
			(width 0.2)
			(type default)
		)
		(layer "In3.Cu")
	)
	(gr_line
		(start 151.7269 -37.57676)
		(end 150.9141 -37.57676)
		(stroke
			(width 0.2)
			(type default)
		)
		(layer "In3.Cu")
	)
	(gr_arc
		(start 152.10663 -211.406994)
		(mid 152.61717 -210.896454)
		(end 152.10663 -210.385914)
		(stroke
			(width 0.2)
			(type default)
		)
		(layer "In3.Cu")
	)
	(gr_line
		(start 152.10663 -210.385914)
		(end 151.294084 -210.385914)
		(stroke
			(width 0.2)
			(type default)
		)
		(layer "In3.Cu")
	)
	(gr_line
		(start 152.7175 -35.50666)
		(end 153.530046 -35.50666)
		(stroke
			(width 0.2)
			(type default)
		)
		(layer "In3.Cu")
	)
	(gr_arc
		(start 152.7175 -34.48558)
		(mid 152.20696 -34.99612)
		(end 152.7175 -35.50666)
		(stroke
			(width 0.2)
			(type default)
		)
		(layer "In3.Cu")
	)
	(gr_line
		(start 152.893776 -222.805244)
		(end 153.706322 -222.805244)
		(stroke
			(width 0.2)
			(type default)
		)
		(layer "In3.Cu")
	)
	(gr_arc
		(start 152.893776 -221.784164)
		(mid 152.383236 -222.294704)
		(end 152.893776 -222.805244)
		(stroke
			(width 0.2)
			(type default)
		)
		(layer "In3.Cu")
	)
	(gr_arc
		(start 153.530046 -35.50666)
		(mid 154.04084 -34.996247)
		(end 153.5303 -34.48558)
		(stroke
			(width 0.2)
			(type default)
		)
		(layer "In3.Cu")
	)
	(gr_line
		(start 153.5303 -34.48558)
		(end 152.7175 -34.48558)
		(stroke
			(width 0.2)
			(type default)
		)
		(layer "In3.Cu")
	)
	(gr_arc
		(start 153.706322 -222.805244)
		(mid 154.217116 -222.294831)
		(end 153.706576 -221.784164)
		(stroke
			(width 0.2)
			(type default)
		)
		(layer "In3.Cu")
	)
	(gr_line
		(start 153.706576 -221.784164)
		(end 152.893776 -221.784164)
		(stroke
			(width 0.2)
			(type default)
		)
		(layer "In3.Cu")
	)
	(gr_line
		(start 154.493722 -211.406994)
		(end 155.306522 -211.406994)
		(stroke
			(width 0.2)
			(type default)
		)
		(layer "In3.Cu")
	)
	(gr_arc
		(start 154.493976 -210.385914)
		(mid 153.983182 -210.896327)
		(end 154.493722 -211.406994)
		(stroke
			(width 0.2)
			(type default)
		)
		(layer "In3.Cu")
	)
	(gr_arc
		(start 154.583638 -25.035256)
		(mid 154.83967 -25.881076)
		(end 155.68549 -25.625044)
		(stroke
			(width 0.2)
			(type default)
		)
		(layer "In3.Cu")
	)
	(gr_arc
		(start 154.587702 -13.627608)
		(mid 154.835836 -14.479061)
		(end 155.68549 -14.225016)
		(stroke
			(width 0.2)
			(type default)
		)
		(layer "In3.Cu")
	)
	(gr_arc
		(start 155.306522 -211.406994)
		(mid 155.817062 -210.896454)
		(end 155.306522 -210.385914)
		(stroke
			(width 0.2)
			(type default)
		)
		(layer "In3.Cu")
	)
	(gr_line
		(start 155.306522 -210.385914)
		(end 154.493976 -210.385914)
		(stroke
			(width 0.2)
			(type default)
		)
		(layer "In3.Cu")
	)
	(gr_line
		(start 155.333446 -23.635208)
		(end 154.583638 -25.035256)
		(stroke
			(width 0.2)
			(type default)
		)
		(layer "In3.Cu")
	)
	(gr_line
		(start 155.333446 -12.23518)
		(end 154.587702 -13.627608)
		(stroke
			(width 0.2)
			(type default)
		)
		(layer "In3.Cu")
	)
	(gr_line
		(start 155.68549 -25.625044)
		(end 156.431234 -24.232616)
		(stroke
			(width 0.2)
			(type default)
		)
		(layer "In3.Cu")
	)
	(gr_line
		(start 155.68549 -14.225016)
		(end 156.435298 -12.824968)
		(stroke
			(width 0.2)
			(type default)
		)
		(layer "In3.Cu")
	)
	(gr_line
		(start 156.093668 -222.805244)
		(end 156.906214 -222.805244)
		(stroke
			(width 0.2)
			(type default)
		)
		(layer "In3.Cu")
	)
	(gr_arc
		(start 156.093668 -221.784164)
		(mid 155.583128 -222.294704)
		(end 156.093668 -222.805244)
		(stroke
			(width 0.2)
			(type default)
		)
		(layer "In3.Cu")
	)
	(gr_arc
		(start 156.431234 -24.232616)
		(mid 156.1831 -23.381163)
		(end 155.333446 -23.635208)
		(stroke
			(width 0.2)
			(type default)
		)
		(layer "In3.Cu")
	)
	(gr_arc
		(start 156.435298 -12.824968)
		(mid 156.179266 -11.979148)
		(end 155.333446 -12.23518)
		(stroke
			(width 0.2)
			(type default)
		)
		(layer "In3.Cu")
	)
	(gr_line
		(start 156.831538 -25.033732)
		(end 156.831792 -25.033986)
		(stroke
			(width 0.2)
			(type default)
		)
		(layer "In3.Cu")
	)
	(gr_line
		(start 156.831538 -21.233892)
		(end 156.83357 -21.235162)
		(stroke
			(width 0.2)
			(type default)
		)
		(layer "In3.Cu")
	)
	(gr_line
		(start 156.831538 -17.433544)
		(end 156.831792 -17.433798)
		(stroke
			(width 0.2)
			(type default)
		)
		(layer "In3.Cu")
	)
	(gr_line
		(start 156.831538 -13.633704)
		(end 156.831792 -13.633958)
		(stroke
			(width 0.2)
			(type default)
		)
		(layer "In3.Cu")
	)
	(gr_line
		(start 156.831792 -25.033986)
		(end 156.833824 -25.035002)
		(stroke
			(width 0.2)
			(type default)
		)
		(layer "In3.Cu")
	)
	(gr_line
		(start 156.831792 -17.433798)
		(end 156.833824 -17.434814)
		(stroke
			(width 0.2)
			(type default)
		)
		(layer "In3.Cu")
	)
	(gr_line
		(start 156.831792 -13.633958)
		(end 156.833824 -13.634974)
		(stroke
			(width 0.2)
			(type default)
		)
		(layer "In3.Cu")
	)
	(gr_arc
		(start 156.83357 -21.235162)
		(mid 157.089602 -22.080982)
		(end 157.935422 -21.82495)
		(stroke
			(width 0.2)
			(type default)
		)
		(layer "In3.Cu")
	)
	(gr_arc
		(start 156.833824 -25.035002)
		(mid 157.0895 -25.880903)
		(end 157.935422 -25.625044)
		(stroke
			(width 0.2)
			(type default)
		)
		(layer "In3.Cu")
	)
	(gr_arc
		(start 156.833824 -17.434814)
		(mid 157.089348 -18.280634)
		(end 157.935168 -18.02511)
		(stroke
			(width 0.2)
			(type default)
		)
		(layer "In3.Cu")
	)
	(gr_arc
		(start 156.833824 -13.634974)
		(mid 157.0895 -14.480875)
		(end 157.935422 -14.225016)
		(stroke
			(width 0.2)
			(type default)
		)
		(layer "In3.Cu")
	)
	(gr_arc
		(start 156.906214 -222.805244)
		(mid 157.417008 -222.294831)
		(end 156.906468 -221.784164)
		(stroke
			(width 0.2)
			(type default)
		)
		(layer "In3.Cu")
	)
	(gr_line
		(start 156.906468 -221.784164)
		(end 156.093668 -221.784164)
		(stroke
			(width 0.2)
			(type default)
		)
		(layer "In3.Cu")
	)
	(gr_line
		(start 157.5816 -23.633938)
		(end 156.831538 -25.033732)
		(stroke
			(width 0.2)
			(type default)
		)
		(layer "In3.Cu")
	)
	(gr_line
		(start 157.5816 -19.833844)
		(end 156.831538 -21.233892)
		(stroke
			(width 0.2)
			(type default)
		)
		(layer "In3.Cu")
	)
	(gr_line
		(start 157.5816 -16.03375)
		(end 156.831538 -17.433544)
		(stroke
			(width 0.2)
			(type default)
		)
		(layer "In3.Cu")
	)
	(gr_line
		(start 157.5816 -12.23391)
		(end 156.831538 -13.633704)
		(stroke
			(width 0.2)
			(type default)
		)
		(layer "In3.Cu")
	)
	(gr_line
		(start 157.583632 -23.635208)
		(end 157.5816 -23.633938)
		(stroke
			(width 0.2)
			(type default)
		)
		(layer "In3.Cu")
	)
	(gr_line
		(start 157.583632 -19.835114)
		(end 157.5816 -19.833844)
		(stroke
			(width 0.2)
			(type default)
		)
		(layer "In3.Cu")
	)
	(gr_line
		(start 157.583632 -12.23518)
		(end 157.5816 -12.23391)
		(stroke
			(width 0.2)
			(type default)
		)
		(layer "In3.Cu")
	)
	(gr_line
		(start 157.583886 -16.03502)
		(end 157.5816 -16.03375)
		(stroke
			(width 0.2)
			(type default)
		)
		(layer "In3.Cu")
	)
	(gr_line
		(start 157.693868 -211.406994)
		(end 158.506668 -211.406994)
		(stroke
			(width 0.2)
			(type default)
		)
		(layer "In3.Cu")
	)
	(gr_arc
		(start 157.694122 -210.385914)
		(mid 157.183328 -210.896327)
		(end 157.693868 -211.406994)
		(stroke
			(width 0.2)
			(type default)
		)
		(layer "In3.Cu")
	)
	(gr_line
		(start 157.935168 -18.02511)
		(end 157.937454 -18.02638)
		(stroke
			(width 0.2)
			(type default)
		)
		(layer "In3.Cu")
	)
	(gr_line
		(start 157.935422 -25.625044)
		(end 157.937454 -25.626314)
		(stroke
			(width 0.2)
			(type default)
		)
		(layer "In3.Cu")
	)
	(gr_line
		(start 157.935422 -21.82495)
		(end 157.937454 -21.82622)
		(stroke
			(width 0.2)
			(type default)
		)
		(layer "In3.Cu")
	)
	(gr_line
		(start 157.935422 -14.225016)
		(end 157.937454 -14.226286)
		(stroke
			(width 0.2)
			(type default)
		)
		(layer "In3.Cu")
	)
	(gr_line
		(start 157.937454 -25.626314)
		(end 158.687516 -24.226266)
		(stroke
			(width 0.2)
			(type default)
		)
		(layer "In3.Cu")
	)
	(gr_line
		(start 157.937454 -21.82622)
		(end 158.687516 -20.426426)
		(stroke
			(width 0.2)
			(type default)
		)
		(layer "In3.Cu")
	)
	(gr_line
		(start 157.937454 -18.02638)
		(end 158.687516 -16.626586)
		(stroke
			(width 0.2)
			(type default)
		)
		(layer "In3.Cu")
	)
	(gr_line
		(start 157.937454 -14.226286)
		(end 158.687516 -12.826238)
		(stroke
			(width 0.2)
			(type default)
		)
		(layer "In3.Cu")
	)
	(gr_arc
		(start 158.506668 -211.406994)
		(mid 159.017208 -210.896454)
		(end 158.506668 -210.385914)
		(stroke
			(width 0.2)
			(type default)
		)
		(layer "In3.Cu")
	)
	(gr_line
		(start 158.506668 -210.385914)
		(end 157.694122 -210.385914)
		(stroke
			(width 0.2)
			(type default)
		)
		(layer "In3.Cu")
	)
	(gr_line
		(start 158.655004 -35.53206)
		(end 159.467804 -35.53206)
		(stroke
			(width 0.2)
			(type default)
		)
		(layer "In3.Cu")
	)
	(gr_arc
		(start 158.655258 -34.51098)
		(mid 158.144464 -35.021393)
		(end 158.655004 -35.53206)
		(stroke
			(width 0.2)
			(type default)
		)
		(layer "In3.Cu")
	)
	(gr_arc
		(start 158.68523 -20.425156)
		(mid 158.429554 -19.579255)
		(end 157.583632 -19.835114)
		(stroke
			(width 0.2)
			(type default)
		)
		(layer "In3.Cu")
	)
	(gr_arc
		(start 158.68523 -16.625316)
		(mid 158.429706 -15.779496)
		(end 157.583886 -16.03502)
		(stroke
			(width 0.2)
			(type default)
		)
		(layer "In3.Cu")
	)
	(gr_arc
		(start 158.685484 -24.224996)
		(mid 158.429452 -23.379176)
		(end 157.583632 -23.635208)
		(stroke
			(width 0.2)
			(type default)
		)
		(layer "In3.Cu")
	)
	(gr_arc
		(start 158.685484 -12.824968)
		(mid 158.429452 -11.979148)
		(end 157.583632 -12.23518)
		(stroke
			(width 0.2)
			(type default)
		)
		(layer "In3.Cu")
	)
	(gr_line
		(start 158.687262 -20.426172)
		(end 158.68523 -20.425156)
		(stroke
			(width 0.2)
			(type default)
		)
		(layer "In3.Cu")
	)
	(gr_line
		(start 158.687516 -24.226266)
		(end 158.685484 -24.224996)
		(stroke
			(width 0.2)
			(type default)
		)
		(layer "In3.Cu")
	)
	(gr_line
		(start 158.687516 -20.426426)
		(end 158.687262 -20.426172)
		(stroke
			(width 0.2)
			(type default)
		)
		(layer "In3.Cu")
	)
	(gr_line
		(start 158.687516 -16.626586)
		(end 158.68523 -16.625316)
		(stroke
			(width 0.2)
			(type default)
		)
		(layer "In3.Cu")
	)
	(gr_line
		(start 158.687516 -12.826238)
		(end 158.685484 -12.824968)
		(stroke
			(width 0.2)
			(type default)
		)
		(layer "In3.Cu")
	)
	(gr_line
		(start 159.08147 -25.033732)
		(end 159.081724 -25.033986)
		(stroke
			(width 0.2)
			(type default)
		)
		(layer "In3.Cu")
	)
	(gr_line
		(start 159.08147 -21.233892)
		(end 159.083502 -21.235162)
		(stroke
			(width 0.2)
			(type default)
		)
		(layer "In3.Cu")
	)
	(gr_line
		(start 159.08147 -17.433544)
		(end 159.081724 -17.433798)
		(stroke
			(width 0.2)
			(type default)
		)
		(layer "In3.Cu")
	)
	(gr_line
		(start 159.08147 -13.633704)
		(end 159.081724 -13.633958)
		(stroke
			(width 0.2)
			(type default)
		)
		(layer "In3.Cu")
	)
	(gr_line
		(start 159.081724 -25.033986)
		(end 159.083756 -25.035002)
		(stroke
			(width 0.2)
			(type default)
		)
		(layer "In3.Cu")
	)
	(gr_line
		(start 159.081724 -17.433798)
		(end 159.083756 -17.434814)
		(stroke
			(width 0.2)
			(type default)
		)
		(layer "In3.Cu")
	)
	(gr_line
		(start 159.081724 -13.633958)
		(end 159.083756 -13.634974)
		(stroke
			(width 0.2)
			(type default)
		)
		(layer "In3.Cu")
	)
	(gr_arc
		(start 159.083502 -21.235162)
		(mid 159.339534 -22.080982)
		(end 160.185354 -21.82495)
		(stroke
			(width 0.2)
			(type default)
		)
		(layer "In3.Cu")
	)
	(gr_arc
		(start 159.083756 -25.035002)
		(mid 159.339432 -25.880903)
		(end 160.185354 -25.625044)
		(stroke
			(width 0.2)
			(type default)
		)
		(layer "In3.Cu")
	)
	(gr_arc
		(start 159.083756 -17.434814)
		(mid 159.33928 -18.280634)
		(end 160.1851 -18.02511)
		(stroke
			(width 0.2)
			(type default)
		)
		(layer "In3.Cu")
	)
	(gr_arc
		(start 159.083756 -13.634974)
		(mid 159.339432 -14.480875)
		(end 160.185354 -14.225016)
		(stroke
			(width 0.2)
			(type default)
		)
		(layer "In3.Cu")
	)
	(gr_line
		(start 159.29356 -222.805244)
		(end 160.106106 -222.805244)
		(stroke
			(width 0.2)
			(type default)
		)
		(layer "In3.Cu")
	)
	(gr_arc
		(start 159.29356 -221.784164)
		(mid 158.78302 -222.294704)
		(end 159.29356 -222.805244)
		(stroke
			(width 0.2)
			(type default)
		)
		(layer "In3.Cu")
	)
	(gr_arc
		(start 159.467804 -35.53206)
		(mid 159.978344 -35.02152)
		(end 159.467804 -34.51098)
		(stroke
			(width 0.2)
			(type default)
		)
		(layer "In3.Cu")
	)
	(gr_line
		(start 159.467804 -34.51098)
		(end 158.655258 -34.51098)
		(stroke
			(width 0.2)
			(type default)
		)
		(layer "In3.Cu")
	)
	(gr_line
		(start 159.831532 -23.633938)
		(end 159.08147 -25.033732)
		(stroke
			(width 0.2)
			(type default)
		)
		(layer "In3.Cu")
	)
	(gr_line
		(start 159.831532 -19.833844)
		(end 159.08147 -21.233892)
		(stroke
			(width 0.2)
			(type default)
		)
		(layer "In3.Cu")
	)
	(gr_line
		(start 159.831532 -16.03375)
		(end 159.08147 -17.433544)
		(stroke
			(width 0.2)
			(type default)
		)
		(layer "In3.Cu")
	)
	(gr_line
		(start 159.831532 -12.23391)
		(end 159.08147 -13.633704)
		(stroke
			(width 0.2)
			(type default)
		)
		(layer "In3.Cu")
	)
	(gr_line
		(start 159.833564 -23.635208)
		(end 159.831532 -23.633938)
		(stroke
			(width 0.2)
			(type default)
		)
		(layer "In3.Cu")
	)
	(gr_line
		(start 159.833564 -19.835114)
		(end 159.831532 -19.833844)
		(stroke
			(width 0.2)
			(type default)
		)
		(layer "In3.Cu")
	)
	(gr_line
		(start 159.833564 -12.23518)
		(end 159.831532 -12.23391)
		(stroke
			(width 0.2)
			(type default)
		)
		(layer "In3.Cu")
	)
	(gr_line
		(start 159.833818 -16.03502)
		(end 159.831532 -16.03375)
		(stroke
			(width 0.2)
			(type default)
		)
		(layer "In3.Cu")
	)
	(gr_arc
		(start 160.106106 -222.805244)
		(mid 160.6169 -222.294831)
		(end 160.10636 -221.784164)
		(stroke
			(width 0.2)
			(type default)
		)
		(layer "In3.Cu")
	)
	(gr_line
		(start 160.10636 -221.784164)
		(end 159.29356 -221.784164)
		(stroke
			(width 0.2)
			(type default)
		)
		(layer "In3.Cu")
	)
	(gr_line
		(start 160.1851 -18.02511)
		(end 160.187386 -18.02638)
		(stroke
			(width 0.2)
			(type default)
		)
		(layer "In3.Cu")
	)
	(gr_line
		(start 160.185354 -25.625044)
		(end 160.187386 -25.626314)
		(stroke
			(width 0.2)
			(type default)
		)
		(layer "In3.Cu")
	)
	(gr_line
		(start 160.185354 -21.82495)
		(end 160.187386 -21.82622)
		(stroke
			(width 0.2)
			(type default)
		)
		(layer "In3.Cu")
	)
	(gr_line
		(start 160.185354 -14.225016)
		(end 160.187386 -14.226286)
		(stroke
			(width 0.2)
			(type default)
		)
		(layer "In3.Cu")
	)
	(gr_line
		(start 160.187386 -25.626314)
		(end 160.937448 -24.226266)
		(stroke
			(width 0.2)
			(type default)
		)
		(layer "In3.Cu")
	)
	(gr_line
		(start 160.187386 -21.82622)
		(end 160.937448 -20.426426)
		(stroke
			(width 0.2)
			(type default)
		)
		(layer "In3.Cu")
	)
	(gr_line
		(start 160.187386 -18.02638)
		(end 160.937448 -16.626586)
		(stroke
			(width 0.2)
			(type default)
		)
		(layer "In3.Cu")
	)
	(gr_line
		(start 160.187386 -14.226286)
		(end 160.937448 -12.826238)
		(stroke
			(width 0.2)
			(type default)
		)
		(layer "In3.Cu")
	)
	(gr_line
		(start 160.89376 -211.406994)
		(end 161.70656 -211.406994)
		(stroke
			(width 0.2)
			(type default)
		)
		(layer "In3.Cu")
	)
	(gr_arc
		(start 160.894014 -210.385914)
		(mid 160.38322 -210.896327)
		(end 160.89376 -211.406994)
		(stroke
			(width 0.2)
			(type default)
		)
		(layer "In3.Cu")
	)
	(gr_arc
		(start 160.935162 -20.425156)
		(mid 160.679486 -19.579255)
		(end 159.833564 -19.835114)
		(stroke
			(width 0.2)
			(type default)
		)
		(layer "In3.Cu")
	)
	(gr_arc
		(start 160.935162 -16.625316)
		(mid 160.679638 -15.779496)
		(end 159.833818 -16.03502)
		(stroke
			(width 0.2)
			(type default)
		)
		(layer "In3.Cu")
	)
	(gr_arc
		(start 160.935416 -24.224996)
		(mid 160.679384 -23.379176)
		(end 159.833564 -23.635208)
		(stroke
			(width 0.2)
			(type default)
		)
		(layer "In3.Cu")
	)
	(gr_arc
		(start 160.935416 -12.824968)
		(mid 160.679384 -11.979148)
		(end 159.833564 -12.23518)
		(stroke
			(width 0.2)
			(type default)
		)
		(layer "In3.Cu")
	)
	(gr_line
		(start 160.937194 -20.426172)
		(end 160.935162 -20.425156)
		(stroke
			(width 0.2)
			(type default)
		)
		(layer "In3.Cu")
	)
	(gr_line
		(start 160.937448 -24.226266)
		(end 160.935416 -24.224996)
		(stroke
			(width 0.2)
			(type default)
		)
		(layer "In3.Cu")
	)
	(gr_line
		(start 160.937448 -20.426426)
		(end 160.937194 -20.426172)
		(stroke
			(width 0.2)
			(type default)
		)
		(layer "In3.Cu")
	)
	(gr_line
		(start 160.937448 -16.626586)
		(end 160.935162 -16.625316)
		(stroke
			(width 0.2)
			(type default)
		)
		(layer "In3.Cu")
	)
	(gr_line
		(start 160.937448 -12.826238)
		(end 160.935416 -12.824968)
		(stroke
			(width 0.2)
			(type default)
		)
		(layer "In3.Cu")
	)
	(gr_line
		(start 161.2773 -35.53206)
		(end 162.0901 -35.53206)
		(stroke
			(width 0.2)
			(type default)
		)
		(layer "In3.Cu")
	)
	(gr_arc
		(start 161.277554 -34.51098)
		(mid 160.76676 -35.021393)
		(end 161.2773 -35.53206)
		(stroke
			(width 0.2)
			(type default)
		)
		(layer "In3.Cu")
	)
	(gr_arc
		(start 161.70656 -211.406994)
		(mid 162.2171 -210.896454)
		(end 161.70656 -210.385914)
		(stroke
			(width 0.2)
			(type default)
		)
		(layer "In3.Cu")
	)
	(gr_line
		(start 161.70656 -210.385914)
		(end 160.894014 -210.385914)
		(stroke
			(width 0.2)
			(type default)
		)
		(layer "In3.Cu")
	)
	(gr_line
		(start 161.7853 -38.52164)
		(end 162.597846 -38.52164)
		(stroke
			(width 0.2)
			(type default)
		)
		(layer "In3.Cu")
	)
	(gr_arc
		(start 161.7853 -37.50056)
		(mid 161.27476 -38.0111)
		(end 161.7853 -38.52164)
		(stroke
			(width 0.2)
			(type default)
		)
		(layer "In3.Cu")
	)
	(gr_arc
		(start 162.0901 -35.53206)
		(mid 162.60064 -35.02152)
		(end 162.0901 -34.51098)
		(stroke
			(width 0.2)
			(type default)
		)
		(layer "In3.Cu")
	)
	(gr_line
		(start 162.0901 -34.51098)
		(end 161.277554 -34.51098)
		(stroke
			(width 0.2)
			(type default)
		)
		(layer "In3.Cu")
	)
	(gr_arc
		(start 162.597846 -38.52164)
		(mid 163.10864 -38.011227)
		(end 162.5981 -37.50056)
		(stroke
			(width 0.2)
			(type default)
		)
		(layer "In3.Cu")
	)
	(gr_line
		(start 162.5981 -37.50056)
		(end 161.7853 -37.50056)
		(stroke
			(width 0.2)
			(type default)
		)
		(layer "In3.Cu")
	)
	(gr_line
		(start 162.6997 -82.17154)
		(end 163.512246 -82.17154)
		(stroke
			(width 0.2)
			(type default)
		)
		(layer "In3.Cu")
	)
	(gr_arc
		(start 162.6997 -81.15046)
		(mid 162.18916 -81.661)
		(end 162.6997 -82.17154)
		(stroke
			(width 0.2)
			(type default)
		)
		(layer "In3.Cu")
	)
	(gr_line
		(start 162.941 -70.612)
		(end 163.322 -70.993)
		(stroke
			(width 0.381)
			(type default)
		)
		(layer "In3.Cu")
	)
	(gr_line
		(start 162.941 -62.738)
		(end 162.941 -70.612)
		(stroke
			(width 0.381)
			(type default)
		)
		(layer "In3.Cu")
	)
	(gr_arc
		(start 163.512246 -82.17154)
		(mid 164.02304 -81.661127)
		(end 163.5125 -81.15046)
		(stroke
			(width 0.2)
			(type default)
		)
		(layer "In3.Cu")
	)
	(gr_line
		(start 163.5125 -81.15046)
		(end 162.6997 -81.15046)
		(stroke
			(width 0.2)
			(type default)
		)
		(layer "In3.Cu")
	)
	(gr_line
		(start 163.957 -61.722)
		(end 162.941 -62.738)
		(stroke
			(width 0.381)
			(type default)
		)
		(layer "In3.Cu")
	)
	(gr_line
		(start 164.893752 -222.805244)
		(end 165.706298 -222.805244)
		(stroke
			(width 0.2)
			(type default)
		)
		(layer "In3.Cu")
	)
	(gr_arc
		(start 164.893752 -221.784164)
		(mid 164.383212 -222.294704)
		(end 164.893752 -222.805244)
		(stroke
			(width 0.2)
			(type default)
		)
		(layer "In3.Cu")
	)
	(gr_arc
		(start 165.583616 -25.035256)
		(mid 165.839648 -25.881076)
		(end 166.685468 -25.625044)
		(stroke
			(width 0.2)
			(type default)
		)
		(layer "In3.Cu")
	)
	(gr_arc
		(start 165.58768 -13.627608)
		(mid 165.835814 -14.479061)
		(end 166.685468 -14.225016)
		(stroke
			(width 0.2)
			(type default)
		)
		(layer "In3.Cu")
	)
	(gr_arc
		(start 165.706298 -222.805244)
		(mid 166.217092 -222.294831)
		(end 165.706552 -221.784164)
		(stroke
			(width 0.2)
			(type default)
		)
		(layer "In3.Cu")
	)
	(gr_line
		(start 165.706552 -221.784164)
		(end 164.893752 -221.784164)
		(stroke
			(width 0.2)
			(type default)
		)
		(layer "In3.Cu")
	)
	(gr_line
		(start 166.333424 -23.635208)
		(end 165.583616 -25.035256)
		(stroke
			(width 0.2)
			(type default)
		)
		(layer "In3.Cu")
	)
	(gr_line
		(start 166.333424 -12.23518)
		(end 165.58768 -13.627608)
		(stroke
			(width 0.2)
			(type default)
		)
		(layer "In3.Cu")
	)
	(gr_line
		(start 166.493698 -211.406994)
		(end 167.306498 -211.406994)
		(stroke
			(width 0.2)
			(type default)
		)
		(layer "In3.Cu")
	)
	(gr_arc
		(start 166.493952 -210.385914)
		(mid 165.983158 -210.896327)
		(end 166.493698 -211.406994)
		(stroke
			(width 0.2)
			(type default)
		)
		(layer "In3.Cu")
	)
	(gr_line
		(start 166.685468 -25.625044)
		(end 167.431212 -24.232616)
		(stroke
			(width 0.2)
			(type default)
		)
		(layer "In3.Cu")
	)
	(gr_line
		(start 166.685468 -14.225016)
		(end 167.435276 -12.824968)
		(stroke
			(width 0.2)
			(type default)
		)
		(layer "In3.Cu")
	)
	(gr_arc
		(start 167.191436 -89.4588)
		(mid 167.701976 -89.96934)
		(end 168.212516 -89.4588)
		(stroke
			(width 0.2)
			(type default)
		)
		(layer "In3.Cu")
	)
	(gr_line
		(start 167.191436 -88.646)
		(end 167.191436 -89.4588)
		(stroke
			(width 0.2)
			(type default)
		)
		(layer "In3.Cu")
	)
	(gr_arc
		(start 167.306498 -211.406994)
		(mid 167.817038 -210.896454)
		(end 167.306498 -210.385914)
		(stroke
			(width 0.2)
			(type default)
		)
		(layer "In3.Cu")
	)
	(gr_line
		(start 167.306498 -210.385914)
		(end 166.493952 -210.385914)
		(stroke
			(width 0.2)
			(type default)
		)
		(layer "In3.Cu")
	)
	(gr_arc
		(start 167.431212 -24.232616)
		(mid 167.183078 -23.381163)
		(end 166.333424 -23.635208)
		(stroke
			(width 0.2)
			(type default)
		)
		(layer "In3.Cu")
	)
	(gr_arc
		(start 167.435276 -12.824968)
		(mid 167.179244 -11.979148)
		(end 166.333424 -12.23518)
		(stroke
			(width 0.2)
			(type default)
		)
		(layer "In3.Cu")
	)
	(gr_line
		(start 167.831516 -25.033732)
		(end 167.83177 -25.033986)
		(stroke
			(width 0.2)
			(type default)
		)
		(layer "In3.Cu")
	)
	(gr_line
		(start 167.831516 -21.233892)
		(end 167.833548 -21.235162)
		(stroke
			(width 0.2)
			(type default)
		)
		(layer "In3.Cu")
	)
	(gr_line
		(start 167.831516 -17.433544)
		(end 167.83177 -17.433798)
		(stroke
			(width 0.2)
			(type default)
		)
		(layer "In3.Cu")
	)
	(gr_line
		(start 167.831516 -13.633704)
		(end 167.83177 -13.633958)
		(stroke
			(width 0.2)
			(type default)
		)
		(layer "In3.Cu")
	)
	(gr_line
		(start 167.83177 -25.033986)
		(end 167.833802 -25.035002)
		(stroke
			(width 0.2)
			(type default)
		)
		(layer "In3.Cu")
	)
	(gr_line
		(start 167.83177 -17.433798)
		(end 167.833802 -17.434814)
		(stroke
			(width 0.2)
			(type default)
		)
		(layer "In3.Cu")
	)
	(gr_line
		(start 167.83177 -13.633958)
		(end 167.833802 -13.634974)
		(stroke
			(width 0.2)
			(type default)
		)
		(layer "In3.Cu")
	)
	(gr_arc
		(start 167.833548 -21.235162)
		(mid 168.08958 -22.080982)
		(end 168.9354 -21.82495)
		(stroke
			(width 0.2)
			(type default)
		)
		(layer "In3.Cu")
	)
	(gr_arc
		(start 167.833802 -25.035002)
		(mid 168.089478 -25.880903)
		(end 168.9354 -25.625044)
		(stroke
			(width 0.2)
			(type default)
		)
		(layer "In3.Cu")
	)
	(gr_arc
		(start 167.833802 -17.434814)
		(mid 168.089326 -18.280634)
		(end 168.935146 -18.02511)
		(stroke
			(width 0.2)
			(type default)
		)
		(layer "In3.Cu")
	)
	(gr_arc
		(start 167.833802 -13.634974)
		(mid 168.089478 -14.480875)
		(end 168.9354 -14.225016)
		(stroke
			(width 0.2)
			(type default)
		)
		(layer "In3.Cu")
	)
	(gr_line
		(start 168.093644 -222.805244)
		(end 168.90619 -222.805244)
		(stroke
			(width 0.2)
			(type default)
		)
		(layer "In3.Cu")
	)
	(gr_arc
		(start 168.093644 -221.784164)
		(mid 167.583104 -222.294704)
		(end 168.093644 -222.805244)
		(stroke
			(width 0.2)
			(type default)
		)
		(layer "In3.Cu")
	)
	(gr_line
		(start 168.212516 -89.4588)
		(end 168.212516 -88.646254)
		(stroke
			(width 0.2)
			(type default)
		)
		(layer "In3.Cu")
	)
	(gr_arc
		(start 168.212516 -88.646254)
		(mid 167.702103 -88.13546)
		(end 167.191436 -88.646)
		(stroke
			(width 0.2)
			(type default)
		)
		(layer "In3.Cu")
	)
	(gr_line
		(start 168.581578 -23.633938)
		(end 167.831516 -25.033732)
		(stroke
			(width 0.2)
			(type default)
		)
		(layer "In3.Cu")
	)
	(gr_line
		(start 168.581578 -19.833844)
		(end 167.831516 -21.233892)
		(stroke
			(width 0.2)
			(type default)
		)
		(layer "In3.Cu")
	)
	(gr_line
		(start 168.581578 -16.03375)
		(end 167.831516 -17.433544)
		(stroke
			(width 0.2)
			(type default)
		)
		(layer "In3.Cu")
	)
	(gr_line
		(start 168.581578 -12.23391)
		(end 167.831516 -13.633704)
		(stroke
			(width 0.2)
			(type default)
		)
		(layer "In3.Cu")
	)
	(gr_line
		(start 168.58361 -23.635208)
		(end 168.581578 -23.633938)
		(stroke
			(width 0.2)
			(type default)
		)
		(layer "In3.Cu")
	)
	(gr_line
		(start 168.58361 -19.835114)
		(end 168.581578 -19.833844)
		(stroke
			(width 0.2)
			(type default)
		)
		(layer "In3.Cu")
	)
	(gr_line
		(start 168.58361 -12.23518)
		(end 168.581578 -12.23391)
		(stroke
			(width 0.2)
			(type default)
		)
		(layer "In3.Cu")
	)
	(gr_line
		(start 168.583864 -16.03502)
		(end 168.581578 -16.03375)
		(stroke
			(width 0.2)
			(type default)
		)
		(layer "In3.Cu")
	)
	(gr_arc
		(start 168.90619 -222.805244)
		(mid 169.416984 -222.294831)
		(end 168.906444 -221.784164)
		(stroke
			(width 0.2)
			(type default)
		)
		(layer "In3.Cu")
	)
	(gr_line
		(start 168.906444 -221.784164)
		(end 168.093644 -221.784164)
		(stroke
			(width 0.2)
			(type default)
		)
		(layer "In3.Cu")
	)
	(gr_line
		(start 168.935146 -18.02511)
		(end 168.937432 -18.02638)
		(stroke
			(width 0.2)
			(type default)
		)
		(layer "In3.Cu")
	)
	(gr_line
		(start 168.9354 -25.625044)
		(end 168.937432 -25.626314)
		(stroke
			(width 0.2)
			(type default)
		)
		(layer "In3.Cu")
	)
	(gr_line
		(start 168.9354 -21.82495)
		(end 168.937432 -21.82622)
		(stroke
			(width 0.2)
			(type default)
		)
		(layer "In3.Cu")
	)
	(gr_line
		(start 168.9354 -14.225016)
		(end 168.937432 -14.226286)
		(stroke
			(width 0.2)
			(type default)
		)
		(layer "In3.Cu")
	)
	(gr_line
		(start 168.937432 -25.626314)
		(end 169.687494 -24.226266)
		(stroke
			(width 0.2)
			(type default)
		)
		(layer "In3.Cu")
	)
	(gr_line
		(start 168.937432 -21.82622)
		(end 169.687494 -20.426426)
		(stroke
			(width 0.2)
			(type default)
		)
		(layer "In3.Cu")
	)
	(gr_line
		(start 168.937432 -18.02638)
		(end 169.687494 -16.626586)
		(stroke
			(width 0.2)
			(type default)
		)
		(layer "In3.Cu")
	)
	(gr_line
		(start 168.937432 -14.226286)
		(end 169.687494 -12.826238)
		(stroke
			(width 0.2)
			(type default)
		)
		(layer "In3.Cu")
	)
	(gr_arc
		(start 169.685208 -20.425156)
		(mid 169.429532 -19.579255)
		(end 168.58361 -19.835114)
		(stroke
			(width 0.2)
			(type default)
		)
		(layer "In3.Cu")
	)
	(gr_arc
		(start 169.685208 -16.625316)
		(mid 169.429684 -15.779496)
		(end 168.583864 -16.03502)
		(stroke
			(width 0.2)
			(type default)
		)
		(layer "In3.Cu")
	)
	(gr_arc
		(start 169.685462 -24.224996)
		(mid 169.42943 -23.379176)
		(end 168.58361 -23.635208)
		(stroke
			(width 0.2)
			(type default)
		)
		(layer "In3.Cu")
	)
	(gr_arc
		(start 169.685462 -12.824968)
		(mid 169.42943 -11.979148)
		(end 168.58361 -12.23518)
		(stroke
			(width 0.2)
			(type default)
		)
		(layer "In3.Cu")
	)
	(gr_line
		(start 169.68724 -20.426172)
		(end 169.685208 -20.425156)
		(stroke
			(width 0.2)
			(type default)
		)
		(layer "In3.Cu")
	)
	(gr_line
		(start 169.687494 -24.226266)
		(end 169.685462 -24.224996)
		(stroke
			(width 0.2)
			(type default)
		)
		(layer "In3.Cu")
	)
	(gr_line
		(start 169.687494 -20.426426)
		(end 169.68724 -20.426172)
		(stroke
			(width 0.2)
			(type default)
		)
		(layer "In3.Cu")
	)
	(gr_line
		(start 169.687494 -16.626586)
		(end 169.685208 -16.625316)
		(stroke
			(width 0.2)
			(type default)
		)
		(layer "In3.Cu")
	)
	(gr_line
		(start 169.687494 -12.826238)
		(end 169.685462 -12.824968)
		(stroke
			(width 0.2)
			(type default)
		)
		(layer "In3.Cu")
	)
	(gr_line
		(start 169.69359 -211.406994)
		(end 170.50639 -211.406994)
		(stroke
			(width 0.2)
			(type default)
		)
		(layer "In3.Cu")
	)
	(gr_arc
		(start 169.693844 -210.385914)
		(mid 169.18305 -210.896327)
		(end 169.69359 -211.406994)
		(stroke
			(width 0.2)
			(type default)
		)
		(layer "In3.Cu")
	)
	(gr_line
		(start 170.081448 -25.033732)
		(end 170.081702 -25.033986)
		(stroke
			(width 0.2)
			(type default)
		)
		(layer "In3.Cu")
	)
	(gr_line
		(start 170.081448 -21.233892)
		(end 170.08348 -21.235162)
		(stroke
			(width 0.2)
			(type default)
		)
		(layer "In3.Cu")
	)
	(gr_line
		(start 170.081448 -17.433544)
		(end 170.081702 -17.433798)
		(stroke
			(width 0.2)
			(type default)
		)
		(layer "In3.Cu")
	)
	(gr_line
		(start 170.081448 -13.633704)
		(end 170.081702 -13.633958)
		(stroke
			(width 0.2)
			(type default)
		)
		(layer "In3.Cu")
	)
	(gr_line
		(start 170.081702 -25.033986)
		(end 170.083734 -25.035002)
		(stroke
			(width 0.2)
			(type default)
		)
		(layer "In3.Cu")
	)
	(gr_line
		(start 170.081702 -17.433798)
		(end 170.083734 -17.434814)
		(stroke
			(width 0.2)
			(type default)
		)
		(layer "In3.Cu")
	)
	(gr_line
		(start 170.081702 -13.633958)
		(end 170.083734 -13.634974)
		(stroke
			(width 0.2)
			(type default)
		)
		(layer "In3.Cu")
	)
	(gr_arc
		(start 170.08348 -21.235162)
		(mid 170.339512 -22.080982)
		(end 171.185332 -21.82495)
		(stroke
			(width 0.2)
			(type default)
		)
		(layer "In3.Cu")
	)
	(gr_arc
		(start 170.083734 -25.035002)
		(mid 170.33941 -25.880903)
		(end 171.185332 -25.625044)
		(stroke
			(width 0.2)
			(type default)
		)
		(layer "In3.Cu")
	)
	(gr_arc
		(start 170.083734 -17.434814)
		(mid 170.339258 -18.280634)
		(end 171.185078 -18.02511)
		(stroke
			(width 0.2)
			(type default)
		)
		(layer "In3.Cu")
	)
	(gr_arc
		(start 170.083734 -13.634974)
		(mid 170.33941 -14.480875)
		(end 171.185332 -14.225016)
		(stroke
			(width 0.2)
			(type default)
		)
		(layer "In3.Cu")
	)
	(gr_arc
		(start 170.50639 -211.406994)
		(mid 171.01693 -210.896454)
		(end 170.50639 -210.385914)
		(stroke
			(width 0.2)
			(type default)
		)
		(layer "In3.Cu")
	)
	(gr_line
		(start 170.50639 -210.385914)
		(end 169.693844 -210.385914)
		(stroke
			(width 0.2)
			(type default)
		)
		(layer "In3.Cu")
	)
	(gr_line
		(start 170.83151 -23.633938)
		(end 170.081448 -25.033732)
		(stroke
			(width 0.2)
			(type default)
		)
		(layer "In3.Cu")
	)
	(gr_line
		(start 170.83151 -19.833844)
		(end 170.081448 -21.233892)
		(stroke
			(width 0.2)
			(type default)
		)
		(layer "In3.Cu")
	)
	(gr_line
		(start 170.83151 -16.03375)
		(end 170.081448 -17.433544)
		(stroke
			(width 0.2)
			(type default)
		)
		(layer "In3.Cu")
	)
	(gr_line
		(start 170.83151 -12.23391)
		(end 170.081448 -13.633704)
		(stroke
			(width 0.2)
			(type default)
		)
		(layer "In3.Cu")
	)
	(gr_line
		(start 170.833542 -23.635208)
		(end 170.83151 -23.633938)
		(stroke
			(width 0.2)
			(type default)
		)
		(layer "In3.Cu")
	)
	(gr_line
		(start 170.833542 -19.835114)
		(end 170.83151 -19.833844)
		(stroke
			(width 0.2)
			(type default)
		)
		(layer "In3.Cu")
	)
	(gr_line
		(start 170.833542 -12.23518)
		(end 170.83151 -12.23391)
		(stroke
			(width 0.2)
			(type default)
		)
		(layer "In3.Cu")
	)
	(gr_line
		(start 170.833796 -16.03502)
		(end 170.83151 -16.03375)
		(stroke
			(width 0.2)
			(type default)
		)
		(layer "In3.Cu")
	)
	(gr_line
		(start 171.185078 -18.02511)
		(end 171.187364 -18.02638)
		(stroke
			(width 0.2)
			(type default)
		)
		(layer "In3.Cu")
	)
	(gr_line
		(start 171.185332 -25.625044)
		(end 171.187364 -25.626314)
		(stroke
			(width 0.2)
			(type default)
		)
		(layer "In3.Cu")
	)
	(gr_line
		(start 171.185332 -21.82495)
		(end 171.187364 -21.82622)
		(stroke
			(width 0.2)
			(type default)
		)
		(layer "In3.Cu")
	)
	(gr_line
		(start 171.185332 -14.225016)
		(end 171.187364 -14.226286)
		(stroke
			(width 0.2)
			(type default)
		)
		(layer "In3.Cu")
	)
	(gr_line
		(start 171.187364 -25.626314)
		(end 171.937426 -24.226266)
		(stroke
			(width 0.2)
			(type default)
		)
		(layer "In3.Cu")
	)
	(gr_line
		(start 171.187364 -21.82622)
		(end 171.937426 -20.426426)
		(stroke
			(width 0.2)
			(type default)
		)
		(layer "In3.Cu")
	)
	(gr_line
		(start 171.187364 -18.02638)
		(end 171.937426 -16.626586)
		(stroke
			(width 0.2)
			(type default)
		)
		(layer "In3.Cu")
	)
	(gr_line
		(start 171.187364 -14.226286)
		(end 171.937426 -12.826238)
		(stroke
			(width 0.2)
			(type default)
		)
		(layer "In3.Cu")
	)
	(gr_line
		(start 171.29379 -222.805244)
		(end 172.106336 -222.805244)
		(stroke
			(width 0.2)
			(type default)
		)
		(layer "In3.Cu")
	)
	(gr_arc
		(start 171.29379 -221.784164)
		(mid 170.78325 -222.294704)
		(end 171.29379 -222.805244)
		(stroke
			(width 0.2)
			(type default)
		)
		(layer "In3.Cu")
	)
	(gr_arc
		(start 171.93514 -20.425156)
		(mid 171.679464 -19.579255)
		(end 170.833542 -19.835114)
		(stroke
			(width 0.2)
			(type default)
		)
		(layer "In3.Cu")
	)
	(gr_arc
		(start 171.93514 -16.625316)
		(mid 171.679616 -15.779496)
		(end 170.833796 -16.03502)
		(stroke
			(width 0.2)
			(type default)
		)
		(layer "In3.Cu")
	)
	(gr_arc
		(start 171.935394 -24.224996)
		(mid 171.679362 -23.379176)
		(end 170.833542 -23.635208)
		(stroke
			(width 0.2)
			(type default)
		)
		(layer "In3.Cu")
	)
	(gr_arc
		(start 171.935394 -12.824968)
		(mid 171.679362 -11.979148)
		(end 170.833542 -12.23518)
		(stroke
			(width 0.2)
			(type default)
		)
		(layer "In3.Cu")
	)
	(gr_line
		(start 171.937172 -20.426172)
		(end 171.93514 -20.425156)
		(stroke
			(width 0.2)
			(type default)
		)
		(layer "In3.Cu")
	)
	(gr_line
		(start 171.937426 -24.226266)
		(end 171.935394 -24.224996)
		(stroke
			(width 0.2)
			(type default)
		)
		(layer "In3.Cu")
	)
	(gr_line
		(start 171.937426 -20.426426)
		(end 171.937172 -20.426172)
		(stroke
			(width 0.2)
			(type default)
		)
		(layer "In3.Cu")
	)
	(gr_line
		(start 171.937426 -16.626586)
		(end 171.93514 -16.625316)
		(stroke
			(width 0.2)
			(type default)
		)
		(layer "In3.Cu")
	)
	(gr_line
		(start 171.937426 -12.826238)
		(end 171.935394 -12.824968)
		(stroke
			(width 0.2)
			(type default)
		)
		(layer "In3.Cu")
	)
	(gr_arc
		(start 172.106336 -222.805244)
		(mid 172.61713 -222.294831)
		(end 172.10659 -221.784164)
		(stroke
			(width 0.2)
			(type default)
		)
		(layer "In3.Cu")
	)
	(gr_line
		(start 172.10659 -221.784164)
		(end 171.29379 -221.784164)
		(stroke
			(width 0.2)
			(type default)
		)
		(layer "In3.Cu")
	)
	(gr_line
		(start 172.7454 -96.704912)
		(end 173.6344 -96.704912)
		(stroke
			(width 0.2)
			(type default)
		)
		(layer "In3.Cu")
	)
	(gr_arc
		(start 172.745654 -95.683832)
		(mid 172.23486 -96.194245)
		(end 172.7454 -96.704912)
		(stroke
			(width 0.2)
			(type default)
		)
		(layer "In3.Cu")
	)
	(gr_line
		(start 172.893736 -211.406994)
		(end 173.706536 -211.406994)
		(stroke
			(width 0.2)
			(type default)
		)
		(layer "In3.Cu")
	)
	(gr_arc
		(start 172.89399 -210.385914)
		(mid 172.383196 -210.896327)
		(end 172.893736 -211.406994)
		(stroke
			(width 0.2)
			(type default)
		)
		(layer "In3.Cu")
	)
	(gr_arc
		(start 173.6344 -96.704912)
		(mid 174.14494 -96.194372)
		(end 173.6344 -95.683832)
		(stroke
			(width 0.2)
			(type default)
		)
		(layer "In3.Cu")
	)
	(gr_line
		(start 173.6344 -95.683832)
		(end 172.745654 -95.683832)
		(stroke
			(width 0.2)
			(type default)
		)
		(layer "In3.Cu")
	)
	(gr_arc
		(start 173.706536 -211.406994)
		(mid 174.217076 -210.896454)
		(end 173.706536 -210.385914)
		(stroke
			(width 0.2)
			(type default)
		)
		(layer "In3.Cu")
	)
	(gr_line
		(start 173.706536 -210.385914)
		(end 172.89399 -210.385914)
		(stroke
			(width 0.2)
			(type default)
		)
		(layer "In3.Cu")
	)
	(gr_line
		(start 174.493682 -222.805244)
		(end 175.306228 -222.805244)
		(stroke
			(width 0.2)
			(type default)
		)
		(layer "In3.Cu")
	)
	(gr_arc
		(start 174.493682 -221.784164)
		(mid 173.983142 -222.294704)
		(end 174.493682 -222.805244)
		(stroke
			(width 0.2)
			(type default)
		)
		(layer "In3.Cu")
	)
	(gr_line
		(start 174.5234 -5.842)
		(end 186.86526 -18.18386)
		(stroke
			(width 0.381)
			(type default)
		)
		(layer "In3.Cu")
	)
	(gr_arc
		(start 175.306228 -222.805244)
		(mid 175.817022 -222.294831)
		(end 175.306482 -221.784164)
		(stroke
			(width 0.2)
			(type default)
		)
		(layer "In3.Cu")
	)
	(gr_line
		(start 175.306482 -221.784164)
		(end 174.493682 -221.784164)
		(stroke
			(width 0.2)
			(type default)
		)
		(layer "In3.Cu")
	)
	(gr_line
		(start 176.093628 -211.406994)
		(end 176.906428 -211.406994)
		(stroke
			(width 0.2)
			(type default)
		)
		(layer "In3.Cu")
	)
	(gr_arc
		(start 176.093882 -210.385914)
		(mid 175.583088 -210.896327)
		(end 176.093628 -211.406994)
		(stroke
			(width 0.2)
			(type default)
		)
		(layer "In3.Cu")
	)
	(gr_arc
		(start 176.906428 -211.406994)
		(mid 177.416968 -210.896454)
		(end 176.906428 -210.385914)
		(stroke
			(width 0.2)
			(type default)
		)
		(layer "In3.Cu")
	)
	(gr_line
		(start 176.906428 -210.385914)
		(end 176.093882 -210.385914)
		(stroke
			(width 0.2)
			(type default)
		)
		(layer "In3.Cu")
	)
	(gr_line
		(start 177.5968 -221.18574)
		(end 178.409346 -221.18574)
		(stroke
			(width 0.2)
			(type default)
		)
		(layer "In3.Cu")
	)
	(gr_arc
		(start 177.5968 -220.16466)
		(mid 177.08626 -220.6752)
		(end 177.5968 -221.18574)
		(stroke
			(width 0.2)
			(type default)
		)
		(layer "In3.Cu")
	)
	(gr_line
		(start 177.66665 -71.02094)
		(end 178.19243 -71.54672)
		(stroke
			(width 0.3048)
			(type default)
		)
		(layer "In3.Cu")
	)
	(gr_line
		(start 177.66665 -71.00824)
		(end 177.66665 -71.02094)
		(stroke
			(width 0.3048)
			(type default)
		)
		(layer "In3.Cu")
	)
	(gr_line
		(start 177.68443 -61.77534)
		(end 178.21021 -62.30112)
		(stroke
			(width 0.3048)
			(type default)
		)
		(layer "In3.Cu")
	)
	(gr_line
		(start 177.68443 -61.76264)
		(end 177.68443 -61.77534)
		(stroke
			(width 0.3048)
			(type default)
		)
		(layer "In3.Cu")
	)
	(gr_line
		(start 178.13401 -70.54088)
		(end 177.66665 -71.00824)
		(stroke
			(width 0.3048)
			(type default)
		)
		(layer "In3.Cu")
	)
	(gr_line
		(start 178.15179 -61.29528)
		(end 177.68443 -61.76264)
		(stroke
			(width 0.3048)
			(type default)
		)
		(layer "In3.Cu")
	)
	(gr_line
		(start 178.181 -72.644)
		(end 178.181 -70.993)
		(stroke
			(width 0.381)
			(type default)
		)
		(layer "In3.Cu")
	)
	(gr_line
		(start 178.181 -70.993)
		(end 163.322 -70.993)
		(stroke
			(width 0.381)
			(type default)
		)
		(layer "In3.Cu")
	)
	(gr_line
		(start 178.181 -61.722)
		(end 163.957 -61.722)
		(stroke
			(width 0.381)
			(type default)
		)
		(layer "In3.Cu")
	)
	(gr_line
		(start 178.181 -61.722)
		(end 178.181 -70.993)
		(stroke
			(width 0.381)
			(type default)
		)
		(layer "In3.Cu")
	)
	(gr_line
		(start 178.181 -46.482)
		(end 178.181 -61.722)
		(stroke
			(width 0.381)
			(type default)
		)
		(layer "In3.Cu")
	)
	(gr_arc
		(start 178.409346 -221.18574)
		(mid 178.92014 -220.675327)
		(end 178.4096 -220.16466)
		(stroke
			(width 0.2)
			(type default)
		)
		(layer "In3.Cu")
	)
	(gr_line
		(start 178.4096 -220.16466)
		(end 177.5968 -220.16466)
		(stroke
			(width 0.2)
			(type default)
		)
		(layer "In3.Cu")
	)
	(gr_line
		(start 179.832 -74.295)
		(end 178.181 -72.644)
		(stroke
			(width 0.381)
			(type default)
		)
		(layer "In3.Cu")
	)
	(gr_line
		(start 180.09997 -228.000052)
		(end 134.500112 -228.000052)
		(stroke
			(width 5.08)
			(type default)
		)
		(layer "In3.Cu")
	)
	(gr_line
		(start 180.09997 -222.600012)
		(end 180.09997 -228.000052)
		(stroke
			(width 1.524)
			(type default)
		)
		(layer "In3.Cu")
	)
	(gr_line
		(start 181.864 -42.799)
		(end 178.181 -46.482)
		(stroke
			(width 0.381)
			(type default)
		)
		(layer "In3.Cu")
	)
	(gr_line
		(start 182.500016 -228.000052)
		(end 182.500016 -222.600012)
		(stroke
			(width 1.524)
			(type default)
		)
		(layer "In3.Cu")
	)
	(gr_arc
		(start 182.500016 -222.600012)
		(mid 181.30012 -221.400116)
		(end 180.09997 -222.600012)
		(stroke
			(width 1.524)
			(type default)
		)
		(layer "In3.Cu")
	)
	(gr_arc
		(start 182.57266 -29.8069)
		(mid 183.0832 -30.31744)
		(end 183.59374 -29.8069)
		(stroke
			(width 0.2)
			(type default)
		)
		(layer "In3.Cu")
	)
	(gr_line
		(start 182.57266 -28.9941)
		(end 182.57266 -29.8069)
		(stroke
			(width 0.2)
			(type default)
		)
		(layer "In3.Cu")
	)
	(gr_arc
		(start 182.57266 -26.7589)
		(mid 183.0832 -27.26944)
		(end 183.59374 -26.7589)
		(stroke
			(width 0.2)
			(type default)
		)
		(layer "In3.Cu")
	)
	(gr_line
		(start 182.57266 -25.9461)
		(end 182.57266 -26.7589)
		(stroke
			(width 0.2)
			(type default)
		)
		(layer "In3.Cu")
	)
	(gr_arc
		(start 182.57266 -24.472646)
		(mid 183.083073 -24.98344)
		(end 183.59374 -24.4729)
		(stroke
			(width 0.2)
			(type default)
		)
		(layer "In3.Cu")
	)
	(gr_line
		(start 182.57266 -23.6601)
		(end 182.57266 -24.472646)
		(stroke
			(width 0.2)
			(type default)
		)
		(layer "In3.Cu")
	)
	(gr_arc
		(start 182.57266 -20.6629)
		(mid 183.0832 -21.17344)
		(end 183.59374 -20.6629)
		(stroke
			(width 0.2)
			(type default)
		)
		(layer "In3.Cu")
	)
	(gr_line
		(start 182.57266 -19.8501)
		(end 182.57266 -20.6629)
		(stroke
			(width 0.2)
			(type default)
		)
		(layer "In3.Cu")
	)
	(gr_line
		(start 183.59374 -29.8069)
		(end 183.59374 -28.994354)
		(stroke
			(width 0.2)
			(type default)
		)
		(layer "In3.Cu")
	)
	(gr_arc
		(start 183.59374 -28.994354)
		(mid 183.083327 -28.48356)
		(end 182.57266 -28.9941)
		(stroke
			(width 0.2)
			(type default)
		)
		(layer "In3.Cu")
	)
	(gr_line
		(start 183.59374 -26.7589)
		(end 183.59374 -25.946354)
		(stroke
			(width 0.2)
			(type default)
		)
		(layer "In3.Cu")
	)
	(gr_arc
		(start 183.59374 -25.946354)
		(mid 183.083327 -25.43556)
		(end 182.57266 -25.9461)
		(stroke
			(width 0.2)
			(type default)
		)
		(layer "In3.Cu")
	)
	(gr_line
		(start 183.59374 -24.4729)
		(end 183.59374 -23.6601)
		(stroke
			(width 0.2)
			(type default)
		)
		(layer "In3.Cu")
	)
	(gr_arc
		(start 183.59374 -23.6601)
		(mid 183.0832 -23.14956)
		(end 182.57266 -23.6601)
		(stroke
			(width 0.2)
			(type default)
		)
		(layer "In3.Cu")
	)
	(gr_line
		(start 183.59374 -20.6629)
		(end 183.59374 -19.850354)
		(stroke
			(width 0.2)
			(type default)
		)
		(layer "In3.Cu")
	)
	(gr_arc
		(start 183.59374 -19.850354)
		(mid 183.083327 -19.33956)
		(end 182.57266 -19.8501)
		(stroke
			(width 0.2)
			(type default)
		)
		(layer "In3.Cu")
	)
	(gr_line
		(start 183.63057 -8.91667)
		(end 184.443116 -8.91667)
		(stroke
			(width 0.2)
			(type default)
		)
		(layer "In3.Cu")
	)
	(gr_arc
		(start 183.63057 -7.89559)
		(mid 183.12003 -8.40613)
		(end 183.63057 -8.91667)
		(stroke
			(width 0.2)
			(type default)
		)
		(layer "In3.Cu")
	)
	(gr_arc
		(start 184.048146 -12.509754)
		(mid 184.558686 -13.020294)
		(end 185.069226 -12.509754)
		(stroke
			(width 0.2)
			(type default)
		)
		(layer "In3.Cu")
	)
	(gr_line
		(start 184.048146 -11.696954)
		(end 184.048146 -12.509754)
		(stroke
			(width 0.2)
			(type default)
		)
		(layer "In3.Cu")
	)
	(gr_line
		(start 184.093612 -211.406994)
		(end 184.906412 -211.406994)
		(stroke
			(width 0.2)
			(type default)
		)
		(layer "In3.Cu")
	)
	(gr_arc
		(start 184.093866 -210.385914)
		(mid 183.583072 -210.896327)
		(end 184.093612 -211.406994)
		(stroke
			(width 0.2)
			(type default)
		)
		(layer "In3.Cu")
	)
	(gr_arc
		(start 184.443116 -8.91667)
		(mid 184.95391 -8.406257)
		(end 184.44337 -7.89559)
		(stroke
			(width 0.2)
			(type default)
		)
		(layer "In3.Cu")
	)
	(gr_line
		(start 184.44337 -7.89559)
		(end 183.63057 -7.89559)
		(stroke
			(width 0.2)
			(type default)
		)
		(layer "In3.Cu")
	)
	(gr_arc
		(start 184.906412 -211.406994)
		(mid 185.416952 -210.896454)
		(end 184.906412 -210.385914)
		(stroke
			(width 0.2)
			(type default)
		)
		(layer "In3.Cu")
	)
	(gr_line
		(start 184.906412 -210.385914)
		(end 184.093866 -210.385914)
		(stroke
			(width 0.2)
			(type default)
		)
		(layer "In3.Cu")
	)
	(gr_line
		(start 185.069226 -12.509754)
		(end 185.069226 -11.697208)
		(stroke
			(width 0.2)
			(type default)
		)
		(layer "In3.Cu")
	)
	(gr_arc
		(start 185.069226 -11.697208)
		(mid 184.558813 -11.186414)
		(end 184.048146 -11.696954)
		(stroke
			(width 0.2)
			(type default)
		)
		(layer "In3.Cu")
	)
	(gr_arc
		(start 185.54446 -25.811734)
		(mid 186.055 -26.322274)
		(end 186.56554 -25.811734)
		(stroke
			(width 0.2)
			(type default)
		)
		(layer "In3.Cu")
	)
	(gr_line
		(start 185.54446 -24.998934)
		(end 185.54446 -25.811734)
		(stroke
			(width 0.2)
			(type default)
		)
		(layer "In3.Cu")
	)
	(gr_line
		(start 185.693558 -222.805244)
		(end 186.506358 -222.805244)
		(stroke
			(width 0.2)
			(type default)
		)
		(layer "In3.Cu")
	)
	(gr_arc
		(start 185.693812 -221.784164)
		(mid 185.183018 -222.294577)
		(end 185.693558 -222.805244)
		(stroke
			(width 0.2)
			(type default)
		)
		(layer "In3.Cu")
	)
	(gr_arc
		(start 186.506358 -222.805244)
		(mid 187.016898 -222.294704)
		(end 186.506358 -221.784164)
		(stroke
			(width 0.2)
			(type default)
		)
		(layer "In3.Cu")
	)
	(gr_line
		(start 186.506358 -221.784164)
		(end 185.693812 -221.784164)
		(stroke
			(width 0.2)
			(type default)
		)
		(layer "In3.Cu")
	)
	(gr_line
		(start 186.56554 -25.811734)
		(end 186.56554 -24.999188)
		(stroke
			(width 0.2)
			(type default)
		)
		(layer "In3.Cu")
	)
	(gr_arc
		(start 186.56554 -24.999188)
		(mid 186.055127 -24.488394)
		(end 185.54446 -24.998934)
		(stroke
			(width 0.2)
			(type default)
		)
		(layer "In3.Cu")
	)
	(gr_line
		(start 186.86526 -18.18386)
		(end 201.70394 -18.18386)
		(stroke
			(width 0.381)
			(type default)
		)
		(layer "In3.Cu")
	)
	(gr_line
		(start 187.293758 -211.406994)
		(end 188.106558 -211.406994)
		(stroke
			(width 0.2)
			(type default)
		)
		(layer "In3.Cu")
	)
	(gr_arc
		(start 187.294012 -210.385914)
		(mid 186.783218 -210.896327)
		(end 187.293758 -211.406994)
		(stroke
			(width 0.2)
			(type default)
		)
		(layer "In3.Cu")
	)
	(gr_arc
		(start 188.106558 -211.406994)
		(mid 188.617098 -210.896454)
		(end 188.106558 -210.385914)
		(stroke
			(width 0.2)
			(type default)
		)
		(layer "In3.Cu")
	)
	(gr_line
		(start 188.106558 -210.385914)
		(end 187.294012 -210.385914)
		(stroke
			(width 0.2)
			(type default)
		)
		(layer "In3.Cu")
	)
	(gr_line
		(start 188.893704 -222.805244)
		(end 189.70625 -222.805244)
		(stroke
			(width 0.2)
			(type default)
		)
		(layer "In3.Cu")
	)
	(gr_arc
		(start 188.893704 -221.784164)
		(mid 188.383164 -222.294704)
		(end 188.893704 -222.805244)
		(stroke
			(width 0.2)
			(type default)
		)
		(layer "In3.Cu")
	)
	(gr_arc
		(start 189.70625 -222.805244)
		(mid 190.217044 -222.294831)
		(end 189.706504 -221.784164)
		(stroke
			(width 0.2)
			(type default)
		)
		(layer "In3.Cu")
	)
	(gr_line
		(start 189.706504 -221.784164)
		(end 188.893704 -221.784164)
		(stroke
			(width 0.2)
			(type default)
		)
		(layer "In3.Cu")
	)
	(gr_line
		(start 190.49365 -211.406994)
		(end 191.30645 -211.406994)
		(stroke
			(width 0.2)
			(type default)
		)
		(layer "In3.Cu")
	)
	(gr_arc
		(start 190.493904 -210.385914)
		(mid 189.98311 -210.896327)
		(end 190.49365 -211.406994)
		(stroke
			(width 0.2)
			(type default)
		)
		(layer "In3.Cu")
	)
	(gr_arc
		(start 191.30645 -211.406994)
		(mid 191.81699 -210.896454)
		(end 191.30645 -210.385914)
		(stroke
			(width 0.2)
			(type default)
		)
		(layer "In3.Cu")
	)
	(gr_line
		(start 191.30645 -210.385914)
		(end 190.493904 -210.385914)
		(stroke
			(width 0.2)
			(type default)
		)
		(layer "In3.Cu")
	)
	(gr_line
		(start 192.093596 -222.805244)
		(end 192.906142 -222.805244)
		(stroke
			(width 0.2)
			(type default)
		)
		(layer "In3.Cu")
	)
	(gr_arc
		(start 192.093596 -221.784164)
		(mid 191.583056 -222.294704)
		(end 192.093596 -222.805244)
		(stroke
			(width 0.2)
			(type default)
		)
		(layer "In3.Cu")
	)
	(gr_arc
		(start 192.906142 -222.805244)
		(mid 193.416936 -222.294831)
		(end 192.906396 -221.784164)
		(stroke
			(width 0.2)
			(type default)
		)
		(layer "In3.Cu")
	)
	(gr_line
		(start 192.906396 -221.784164)
		(end 192.093596 -221.784164)
		(stroke
			(width 0.2)
			(type default)
		)
		(layer "In3.Cu")
	)
	(gr_line
		(start 193.693796 -211.406994)
		(end 194.506596 -211.406994)
		(stroke
			(width 0.2)
			(type default)
		)
		(layer "In3.Cu")
	)
	(gr_arc
		(start 193.69405 -210.385914)
		(mid 193.183256 -210.896327)
		(end 193.693796 -211.406994)
		(stroke
			(width 0.2)
			(type default)
		)
		(layer "In3.Cu")
	)
	(gr_arc
		(start 194.506596 -211.406994)
		(mid 195.017136 -210.896454)
		(end 194.506596 -210.385914)
		(stroke
			(width 0.2)
			(type default)
		)
		(layer "In3.Cu")
	)
	(gr_line
		(start 194.506596 -210.385914)
		(end 193.69405 -210.385914)
		(stroke
			(width 0.2)
			(type default)
		)
		(layer "In3.Cu")
	)
	(gr_line
		(start 195.293742 -222.805244)
		(end 196.106288 -222.805244)
		(stroke
			(width 0.2)
			(type default)
		)
		(layer "In3.Cu")
	)
	(gr_arc
		(start 195.293742 -221.784164)
		(mid 194.783202 -222.294704)
		(end 195.293742 -222.805244)
		(stroke
			(width 0.2)
			(type default)
		)
		(layer "In3.Cu")
	)
	(gr_arc
		(start 196.106288 -222.805244)
		(mid 196.617082 -222.294831)
		(end 196.106542 -221.784164)
		(stroke
			(width 0.2)
			(type default)
		)
		(layer "In3.Cu")
	)
	(gr_line
		(start 196.106542 -221.784164)
		(end 195.293742 -221.784164)
		(stroke
			(width 0.2)
			(type default)
		)
		(layer "In3.Cu")
	)
	(gr_line
		(start 196.893688 -211.406994)
		(end 197.706488 -211.406994)
		(stroke
			(width 0.2)
			(type default)
		)
		(layer "In3.Cu")
	)
	(gr_arc
		(start 196.893942 -210.385914)
		(mid 196.383148 -210.896327)
		(end 196.893688 -211.406994)
		(stroke
			(width 0.2)
			(type default)
		)
		(layer "In3.Cu")
	)
	(gr_arc
		(start 197.204838 -46.70806)
		(mid 197.816978 -47.3202)
		(end 198.429118 -46.70806)
		(stroke
			(width 0.2)
			(type default)
		)
		(layer "In3.Cu")
	)
	(gr_line
		(start 197.204838 -45.59046)
		(end 197.204838 -46.70806)
		(stroke
			(width 0.2)
			(type default)
		)
		(layer "In3.Cu")
	)
	(gr_arc
		(start 197.706488 -211.406994)
		(mid 198.217028 -210.896454)
		(end 197.706488 -210.385914)
		(stroke
			(width 0.2)
			(type default)
		)
		(layer "In3.Cu")
	)
	(gr_line
		(start 197.706488 -210.385914)
		(end 196.893942 -210.385914)
		(stroke
			(width 0.2)
			(type default)
		)
		(layer "In3.Cu")
	)
	(gr_line
		(start 198.429118 -46.70806)
		(end 198.429118 -45.590714)
		(stroke
			(width 0.2)
			(type default)
		)
		(layer "In3.Cu")
	)
	(gr_arc
		(start 198.429118 -45.590714)
		(mid 197.817105 -44.97832)
		(end 197.204838 -45.59046)
		(stroke
			(width 0.2)
			(type default)
		)
		(layer "In3.Cu")
	)
	(gr_line
		(start 198.493634 -222.805244)
		(end 199.30618 -222.805244)
		(stroke
			(width 0.2)
			(type default)
		)
		(layer "In3.Cu")
	)
	(gr_arc
		(start 198.493634 -221.784164)
		(mid 197.983094 -222.294704)
		(end 198.493634 -222.805244)
		(stroke
			(width 0.2)
			(type default)
		)
		(layer "In3.Cu")
	)
	(gr_arc
		(start 199.30618 -222.805244)
		(mid 199.816974 -222.294831)
		(end 199.306434 -221.784164)
		(stroke
			(width 0.2)
			(type default)
		)
		(layer "In3.Cu")
	)
	(gr_line
		(start 199.306434 -221.784164)
		(end 198.493634 -221.784164)
		(stroke
			(width 0.2)
			(type default)
		)
		(layer "In3.Cu")
	)
	(gr_arc
		(start 200.046844 -49.122076)
		(mid 199.43826 -49.737772)
		(end 200.053956 -50.346356)
		(stroke
			(width 0.2)
			(type default)
		)
		(layer "In3.Cu")
	)
	(gr_line
		(start 200.053956 -50.346356)
		(end 201.171302 -50.339752)
		(stroke
			(width 0.2)
			(type default)
		)
		(layer "In3.Cu")
	)
	(gr_line
		(start 200.09358 -211.406994)
		(end 200.90638 -211.406994)
		(stroke
			(width 0.2)
			(type default)
		)
		(layer "In3.Cu")
	)
	(gr_arc
		(start 200.093834 -210.385914)
		(mid 199.58304 -210.896327)
		(end 200.09358 -211.406994)
		(stroke
			(width 0.2)
			(type default)
		)
		(layer "In3.Cu")
	)
	(gr_arc
		(start 200.7489 -45.832268)
		(mid 201.360913 -46.444662)
		(end 201.97318 -45.832522)
		(stroke
			(width 0.2)
			(type default)
		)
		(layer "In3.Cu")
	)
	(gr_line
		(start 200.7489 -44.714922)
		(end 200.7489 -45.832268)
		(stroke
			(width 0.2)
			(type default)
		)
		(layer "In3.Cu")
	)
	(gr_arc
		(start 200.90638 -211.406994)
		(mid 201.41692 -210.896454)
		(end 200.90638 -210.385914)
		(stroke
			(width 0.2)
			(type default)
		)
		(layer "In3.Cu")
	)
	(gr_line
		(start 200.90638 -210.385914)
		(end 200.093834 -210.385914)
		(stroke
			(width 0.2)
			(type default)
		)
		(layer "In3.Cu")
	)
	(gr_line
		(start 201.164444 -49.115472)
		(end 200.046844 -49.122076)
		(stroke
			(width 0.2)
			(type default)
		)
		(layer "In3.Cu")
	)
	(gr_arc
		(start 201.171302 -50.339752)
		(mid 201.780139 -49.724183)
		(end 201.164444 -49.115472)
		(stroke
			(width 0.2)
			(type default)
		)
		(layer "In3.Cu")
	)
	(gr_line
		(start 201.69378 -222.805244)
		(end 202.506326 -222.805244)
		(stroke
			(width 0.2)
			(type default)
		)
		(layer "In3.Cu")
	)
	(gr_arc
		(start 201.69378 -221.784164)
		(mid 201.18324 -222.294704)
		(end 201.69378 -222.805244)
		(stroke
			(width 0.2)
			(type default)
		)
		(layer "In3.Cu")
	)
	(gr_line
		(start 201.70394 -18.18386)
		(end 205.0034 -14.8844)
		(stroke
			(width 0.381)
			(type default)
		)
		(layer "In3.Cu")
	)
	(gr_line
		(start 201.97318 -45.832522)
		(end 201.97318 -44.714922)
		(stroke
			(width 0.2)
			(type default)
		)
		(layer "In3.Cu")
	)
	(gr_arc
		(start 201.97318 -44.714922)
		(mid 201.36104 -44.102782)
		(end 200.7489 -44.714922)
		(stroke
			(width 0.2)
			(type default)
		)
		(layer "In3.Cu")
	)
	(gr_arc
		(start 202.506326 -222.805244)
		(mid 203.01712 -222.294831)
		(end 202.50658 -221.784164)
		(stroke
			(width 0.2)
			(type default)
		)
		(layer "In3.Cu")
	)
	(gr_line
		(start 202.50658 -221.784164)
		(end 201.69378 -221.784164)
		(stroke
			(width 0.2)
			(type default)
		)
		(layer "In3.Cu")
	)
	(gr_line
		(start 202.946 -50.29454)
		(end 203.7588 -50.29454)
		(stroke
			(width 0.2)
			(type default)
		)
		(layer "In3.Cu")
	)
	(gr_arc
		(start 202.946254 -49.27346)
		(mid 202.43546 -49.783873)
		(end 202.946 -50.29454)
		(stroke
			(width 0.2)
			(type default)
		)
		(layer "In3.Cu")
	)
	(gr_line
		(start 203.293726 -211.406994)
		(end 204.106526 -211.406994)
		(stroke
			(width 0.2)
			(type default)
		)
		(layer "In3.Cu")
	)
	(gr_arc
		(start 203.29398 -210.385914)
		(mid 202.783186 -210.896327)
		(end 203.293726 -211.406994)
		(stroke
			(width 0.2)
			(type default)
		)
		(layer "In3.Cu")
	)
	(gr_arc
		(start 203.7588 -50.29454)
		(mid 204.26934 -49.784)
		(end 203.7588 -49.27346)
		(stroke
			(width 0.2)
			(type default)
		)
		(layer "In3.Cu")
	)
	(gr_line
		(start 203.7588 -49.27346)
		(end 202.946254 -49.27346)
		(stroke
			(width 0.2)
			(type default)
		)
		(layer "In3.Cu")
	)
	(gr_arc
		(start 204.106526 -211.406994)
		(mid 204.617066 -210.896454)
		(end 204.106526 -210.385914)
		(stroke
			(width 0.2)
			(type default)
		)
		(layer "In3.Cu")
	)
	(gr_line
		(start 204.106526 -210.385914)
		(end 203.29398 -210.385914)
		(stroke
			(width 0.2)
			(type default)
		)
		(layer "In3.Cu")
	)
	(gr_line
		(start 204.893672 -222.805244)
		(end 205.706218 -222.805244)
		(stroke
			(width 0.2)
			(type default)
		)
		(layer "In3.Cu")
	)
	(gr_arc
		(start 204.893672 -221.784164)
		(mid 204.383132 -222.294704)
		(end 204.893672 -222.805244)
		(stroke
			(width 0.2)
			(type default)
		)
		(layer "In3.Cu")
	)
	(gr_line
		(start 205.0034 -14.8844)
		(end 222.7072 -14.8844)
		(stroke
			(width 0.381)
			(type default)
		)
		(layer "In3.Cu")
	)
	(gr_arc
		(start 205.706218 -222.805244)
		(mid 206.217012 -222.294831)
		(end 205.706472 -221.784164)
		(stroke
			(width 0.2)
			(type default)
		)
		(layer "In3.Cu")
	)
	(gr_line
		(start 205.706472 -221.784164)
		(end 204.893672 -221.784164)
		(stroke
			(width 0.2)
			(type default)
		)
		(layer "In3.Cu")
	)
	(gr_line
		(start 206.493618 -211.406994)
		(end 207.306418 -211.406994)
		(stroke
			(width 0.2)
			(type default)
		)
		(layer "In3.Cu")
	)
	(gr_arc
		(start 206.493872 -210.385914)
		(mid 205.983078 -210.896327)
		(end 206.493618 -211.406994)
		(stroke
			(width 0.2)
			(type default)
		)
		(layer "In3.Cu")
	)
	(gr_arc
		(start 207.306418 -211.406994)
		(mid 207.816958 -210.896454)
		(end 207.306418 -210.385914)
		(stroke
			(width 0.2)
			(type default)
		)
		(layer "In3.Cu")
	)
	(gr_line
		(start 207.306418 -210.385914)
		(end 206.493872 -210.385914)
		(stroke
			(width 0.2)
			(type default)
		)
		(layer "In3.Cu")
	)
	(gr_line
		(start 211.074 -42.799)
		(end 181.864 -42.799)
		(stroke
			(width 0.381)
			(type default)
		)
		(layer "In3.Cu")
	)
	(gr_line
		(start 211.29371 -222.805244)
		(end 212.106256 -222.805244)
		(stroke
			(width 0.2)
			(type default)
		)
		(layer "In3.Cu")
	)
	(gr_arc
		(start 211.29371 -221.784164)
		(mid 210.78317 -222.294704)
		(end 211.29371 -222.805244)
		(stroke
			(width 0.2)
			(type default)
		)
		(layer "In3.Cu")
	)
	(gr_arc
		(start 212.106256 -222.805244)
		(mid 212.61705 -222.294831)
		(end 212.10651 -221.784164)
		(stroke
			(width 0.2)
			(type default)
		)
		(layer "In3.Cu")
	)
	(gr_line
		(start 212.10651 -221.784164)
		(end 211.29371 -221.784164)
		(stroke
			(width 0.2)
			(type default)
		)
		(layer "In3.Cu")
	)
	(gr_line
		(start 212.598 -41.275)
		(end 211.074 -42.799)
		(stroke
			(width 0.381)
			(type default)
		)
		(layer "In3.Cu")
	)
	(gr_line
		(start 212.598 -34.798)
		(end 212.598 -41.275)
		(stroke
			(width 0.381)
			(type default)
		)
		(layer "In3.Cu")
	)
	(gr_line
		(start 212.893656 -211.406994)
		(end 213.706456 -211.406994)
		(stroke
			(width 0.2)
			(type default)
		)
		(layer "In3.Cu")
	)
	(gr_arc
		(start 212.89391 -210.385914)
		(mid 212.383116 -210.896327)
		(end 212.893656 -211.406994)
		(stroke
			(width 0.2)
			(type default)
		)
		(layer "In3.Cu")
	)
	(gr_arc
		(start 213.706456 -211.406994)
		(mid 214.216996 -210.896454)
		(end 213.706456 -210.385914)
		(stroke
			(width 0.2)
			(type default)
		)
		(layer "In3.Cu")
	)
	(gr_line
		(start 213.706456 -210.385914)
		(end 212.89391 -210.385914)
		(stroke
			(width 0.2)
			(type default)
		)
		(layer "In3.Cu")
	)
	(gr_line
		(start 214.493602 -222.805244)
		(end 215.306148 -222.805244)
		(stroke
			(width 0.2)
			(type default)
		)
		(layer "In3.Cu")
	)
	(gr_arc
		(start 214.493602 -221.784164)
		(mid 213.983062 -222.294704)
		(end 214.493602 -222.805244)
		(stroke
			(width 0.2)
			(type default)
		)
		(layer "In3.Cu")
	)
	(gr_arc
		(start 215.306148 -222.805244)
		(mid 215.816942 -222.294831)
		(end 215.306402 -221.784164)
		(stroke
			(width 0.2)
			(type default)
		)
		(layer "In3.Cu")
	)
	(gr_line
		(start 215.306402 -221.784164)
		(end 214.493602 -221.784164)
		(stroke
			(width 0.2)
			(type default)
		)
		(layer "In3.Cu")
	)
	(gr_line
		(start 215.392 -32.004)
		(end 212.598 -34.798)
		(stroke
			(width 0.381)
			(type default)
		)
		(layer "In3.Cu")
	)
	(gr_line
		(start 216.093548 -211.406994)
		(end 216.906348 -211.406994)
		(stroke
			(width 0.2)
			(type default)
		)
		(layer "In3.Cu")
	)
	(gr_arc
		(start 216.093802 -210.385914)
		(mid 215.583008 -210.896327)
		(end 216.093548 -211.406994)
		(stroke
			(width 0.2)
			(type default)
		)
		(layer "In3.Cu")
	)
	(gr_arc
		(start 216.906348 -211.406994)
		(mid 217.416888 -210.896454)
		(end 216.906348 -210.385914)
		(stroke
			(width 0.2)
			(type default)
		)
		(layer "In3.Cu")
	)
	(gr_line
		(start 216.906348 -210.385914)
		(end 216.093802 -210.385914)
		(stroke
			(width 0.2)
			(type default)
		)
		(layer "In3.Cu")
	)
	(gr_line
		(start 218.499944 -228.000052)
		(end 182.500016 -228.000052)
		(stroke
			(width 5.08)
			(type default)
		)
		(layer "In3.Cu")
	)
	(gr_line
		(start 218.499944 -222.400114)
		(end 218.499944 -228.000052)
		(stroke
			(width 1.524)
			(type default)
		)
		(layer "In3.Cu")
	)
	(gr_arc
		(start 219.00007 -221.899988)
		(mid 218.646428 -222.046472)
		(end 218.499944 -222.400114)
		(stroke
			(width 1.524)
			(type default)
		)
		(layer "In3.Cu")
	)
	(gr_line
		(start 219.799916 -221.899988)
		(end 219.00007 -221.899988)
		(stroke
			(width 1.524)
			(type default)
		)
		(layer "In3.Cu")
	)
	(gr_arc
		(start 219.799916 -221.899988)
		(mid 220.153445 -221.753586)
		(end 220.300042 -221.400116)
		(stroke
			(width 1.524)
			(type default)
		)
		(layer "In3.Cu")
	)
	(gr_line
		(start 220.300042 -214.799926)
		(end 220.300042 -221.400116)
		(stroke
			(width 1.524)
			(type default)
		)
		(layer "In3.Cu")
	)
	(gr_arc
		(start 221.600014 -213.499954)
		(mid 220.680795 -213.880707)
		(end 220.300042 -214.799926)
		(stroke
			(width 1.524)
			(type default)
		)
		(layer "In3.Cu")
	)
	(gr_line
		(start 222.7072 -14.8844)
		(end 222.885 -14.7066)
		(stroke
			(width 0.381)
			(type default)
		)
		(layer "In3.Cu")
	)
	(gr_line
		(start 222.885 -14.7066)
		(end 235.5596 -14.7066)
		(stroke
			(width 0.381)
			(type default)
		)
		(layer "In3.Cu")
	)
	(gr_line
		(start 229.142036 -213.499954)
		(end 221.600014 -213.499954)
		(stroke
			(width 1.524)
			(type default)
		)
		(layer "In3.Cu")
	)
	(gr_arc
		(start 229.142036 -213.499954)
		(mid 232.677527 -212.035476)
		(end 234.142026 -208.499964)
		(stroke
			(width 1.524)
			(type default)
		)
		(layer "In3.Cu")
	)
	(gr_line
		(start 231.902 -32.004)
		(end 215.392 -32.004)
		(stroke
			(width 0.381)
			(type default)
		)
		(layer "In3.Cu")
	)
	(gr_line
		(start 231.902 -32.004)
		(end 231.902 -25.908)
		(stroke
			(width 0.381)
			(type default)
		)
		(layer "In3.Cu")
	)
	(gr_line
		(start 231.902 -25.908)
		(end 232.791 -25.019)
		(stroke
			(width 0.381)
			(type default)
		)
		(layer "In3.Cu")
	)
	(gr_line
		(start 232.537 -52.959)
		(end 234.569 -54.991)
		(stroke
			(width 0.381)
			(type default)
		)
		(layer "In3.Cu")
	)
	(gr_line
		(start 232.537 -41.148)
		(end 232.537 -52.959)
		(stroke
			(width 0.381)
			(type default)
		)
		(layer "In3.Cu")
	)
	(gr_line
		(start 232.791 -25.019)
		(end 284.353 -25.019)
		(stroke
			(width 0.381)
			(type default)
		)
		(layer "In3.Cu")
	)
	(gr_line
		(start 233.807 -39.878)
		(end 232.537 -41.148)
		(stroke
			(width 0.381)
			(type default)
		)
		(layer "In3.Cu")
	)
	(gr_line
		(start 233.807 -39.878)
		(end 233.807 -33.909)
		(stroke
			(width 0.381)
			(type default)
		)
		(layer "In3.Cu")
	)
	(gr_line
		(start 233.807 -33.909)
		(end 231.902 -32.004)
		(stroke
			(width 0.381)
			(type default)
		)
		(layer "In3.Cu")
	)
	(gr_line
		(start 234.142026 -165.269926)
		(end 234.142026 -208.499964)
		(stroke
			(width 1.524)
			(type default)
		)
		(layer "In3.Cu")
	)
	(gr_line
		(start 234.569 -54.991)
		(end 255.0668 -54.991)
		(stroke
			(width 0.381)
			(type default)
		)
		(layer "In3.Cu")
	)
	(gr_arc
		(start 235.412026 -163.999926)
		(mid 234.514 -164.3719)
		(end 234.142026 -165.269926)
		(stroke
			(width 1.524)
			(type default)
		)
		(layer "In3.Cu")
	)
	(gr_line
		(start 235.5596 -14.7066)
		(end 238.633 -17.78)
		(stroke
			(width 0.381)
			(type default)
		)
		(layer "In3.Cu")
	)
	(gr_line
		(start 238.633 -17.78)
		(end 264.5918 -17.78)
		(stroke
			(width 0.381)
			(type default)
		)
		(layer "In3.Cu")
	)
	(gr_line
		(start 246.1768 3.048)
		(end 129.921 3.048)
		(stroke
			(width 0.381)
			(type default)
		)
		(layer "In3.Cu")
	)
	(gr_line
		(start 247.1928 2.032)
		(end 246.1768 3.048)
		(stroke
			(width 0.381)
			(type default)
		)
		(layer "In3.Cu")
	)
	(gr_line
		(start 248.666 -74.295)
		(end 179.832 -74.295)
		(stroke
			(width 0.381)
			(type default)
		)
		(layer "In3.Cu")
	)
	(gr_line
		(start 249.301 -73.66)
		(end 248.666 -74.295)
		(stroke
			(width 0.381)
			(type default)
		)
		(layer "In3.Cu")
	)
	(gr_line
		(start 249.871992 -163.999926)
		(end 235.412026 -163.999926)
		(stroke
			(width 1.524)
			(type default)
		)
		(layer "In3.Cu")
	)
	(gr_line
		(start 251.141992 -208.499964)
		(end 251.141992 -165.269926)
		(stroke
			(width 1.524)
			(type default)
		)
		(layer "In3.Cu")
	)
	(gr_arc
		(start 251.141992 -208.499964)
		(mid 252.606441 -212.03552)
		(end 256.141982 -213.499954)
		(stroke
			(width 1.524)
			(type default)
		)
		(layer "In3.Cu")
	)
	(gr_arc
		(start 251.141992 -165.269926)
		(mid 250.770018 -164.3719)
		(end 249.871992 -163.999926)
		(stroke
			(width 1.524)
			(type default)
		)
		(layer "In3.Cu")
	)
	(gr_line
		(start 255.0668 -54.991)
		(end 255.524 -55.4482)
		(stroke
			(width 0.381)
			(type default)
		)
		(layer "In3.Cu")
	)
	(gr_line
		(start 255.27 2.032)
		(end 247.1928 2.032)
		(stroke
			(width 0.381)
			(type default)
		)
		(layer "In3.Cu")
	)
	(gr_line
		(start 255.51892 -73.12787)
		(end 254.99314 -73.65365)
		(stroke
			(width 0.3048)
			(type default)
		)
		(layer "In3.Cu")
	)
	(gr_line
		(start 255.524 -73.66)
		(end 249.301 -73.66)
		(stroke
			(width 0.381)
			(type default)
		)
		(layer "In3.Cu")
	)
	(gr_line
		(start 255.524 -73.66)
		(end 285.496 -73.66)
		(stroke
			(width 0.381)
			(type default)
		)
		(layer "In3.Cu")
	)
	(gr_line
		(start 255.524 -55.4482)
		(end 255.524 -73.66)
		(stroke
			(width 0.381)
			(type default)
		)
		(layer "In3.Cu")
	)
	(gr_line
		(start 255.53162 -73.12787)
		(end 255.51892 -73.12787)
		(stroke
			(width 0.3048)
			(type default)
		)
		(layer "In3.Cu")
	)
	(gr_line
		(start 255.99898 -73.59523)
		(end 255.53162 -73.12787)
		(stroke
			(width 0.3048)
			(type default)
		)
		(layer "In3.Cu")
	)
	(gr_line
		(start 256.286 3.048)
		(end 255.27 2.032)
		(stroke
			(width 0.381)
			(type default)
		)
		(layer "In3.Cu")
	)
	(gr_line
		(start 257.400044 -213.499954)
		(end 256.141982 -213.499954)
		(stroke
			(width 1.524)
			(type default)
		)
		(layer "In3.Cu")
	)
	(gr_line
		(start 258.700016 -221.400116)
		(end 258.700016 -214.799926)
		(stroke
			(width 1.524)
			(type default)
		)
		(layer "In3.Cu")
	)
	(gr_arc
		(start 258.700016 -221.400116)
		(mid 258.84643 -221.753573)
		(end 259.199888 -221.899988)
		(stroke
			(width 1.524)
			(type default)
		)
		(layer "In3.Cu")
	)
	(gr_arc
		(start 258.700016 -214.799926)
		(mid 258.319263 -213.880707)
		(end 257.400044 -213.499954)
		(stroke
			(width 1.524)
			(type default)
		)
		(layer "In3.Cu")
	)
	(gr_line
		(start 259.999988 -221.899988)
		(end 259.199888 -221.899988)
		(stroke
			(width 1.524)
			(type default)
		)
		(layer "In3.Cu")
	)
	(gr_line
		(start 260.500114 -228.000052)
		(end 260.500114 -222.400114)
		(stroke
			(width 1.524)
			(type default)
		)
		(layer "In3.Cu")
	)
	(gr_arc
		(start 260.500114 -222.400114)
		(mid 260.35363 -222.046472)
		(end 259.999988 -221.899988)
		(stroke
			(width 1.524)
			(type default)
		)
		(layer "In3.Cu")
	)
	(gr_line
		(start 262.893556 -222.805244)
		(end 263.706102 -222.805244)
		(stroke
			(width 0.2)
			(type default)
		)
		(layer "In3.Cu")
	)
	(gr_arc
		(start 262.893556 -221.784164)
		(mid 262.383016 -222.294704)
		(end 262.893556 -222.805244)
		(stroke
			(width 0.2)
			(type default)
		)
		(layer "In3.Cu")
	)
	(gr_arc
		(start 263.706102 -222.805244)
		(mid 264.216896 -222.294831)
		(end 263.706356 -221.784164)
		(stroke
			(width 0.2)
			(type default)
		)
		(layer "In3.Cu")
	)
	(gr_line
		(start 263.706356 -221.784164)
		(end 262.893556 -221.784164)
		(stroke
			(width 0.2)
			(type default)
		)
		(layer "In3.Cu")
	)
	(gr_line
		(start 264.493756 -211.406994)
		(end 265.306556 -211.406994)
		(stroke
			(width 0.2)
			(type default)
		)
		(layer "In3.Cu")
	)
	(gr_arc
		(start 264.49401 -210.385914)
		(mid 263.983216 -210.896327)
		(end 264.493756 -211.406994)
		(stroke
			(width 0.2)
			(type default)
		)
		(layer "In3.Cu")
	)
	(gr_line
		(start 264.5918 -17.78)
		(end 266.8778 -20.066)
		(stroke
			(width 0.381)
			(type default)
		)
		(layer "In3.Cu")
	)
	(gr_arc
		(start 265.306556 -211.406994)
		(mid 265.817096 -210.896454)
		(end 265.306556 -210.385914)
		(stroke
			(width 0.2)
			(type default)
		)
		(layer "In3.Cu")
	)
	(gr_line
		(start 265.306556 -210.385914)
		(end 264.49401 -210.385914)
		(stroke
			(width 0.2)
			(type default)
		)
		(layer "In3.Cu")
	)
	(gr_line
		(start 266.093702 -222.805244)
		(end 266.906248 -222.805244)
		(stroke
			(width 0.2)
			(type default)
		)
		(layer "In3.Cu")
	)
	(gr_arc
		(start 266.093702 -221.784164)
		(mid 265.583162 -222.294704)
		(end 266.093702 -222.805244)
		(stroke
			(width 0.2)
			(type default)
		)
		(layer "In3.Cu")
	)
	(gr_line
		(start 266.8778 -20.066)
		(end 272.7452 -20.066)
		(stroke
			(width 0.381)
			(type default)
		)
		(layer "In3.Cu")
	)
	(gr_arc
		(start 266.906248 -222.805244)
		(mid 267.417042 -222.294831)
		(end 266.906502 -221.784164)
		(stroke
			(width 0.2)
			(type default)
		)
		(layer "In3.Cu")
	)
	(gr_line
		(start 266.906502 -221.784164)
		(end 266.093702 -221.784164)
		(stroke
			(width 0.2)
			(type default)
		)
		(layer "In3.Cu")
	)
	(gr_line
		(start 267.693648 -211.406994)
		(end 268.506448 -211.406994)
		(stroke
			(width 0.2)
			(type default)
		)
		(layer "In3.Cu")
	)
	(gr_arc
		(start 267.693902 -210.385914)
		(mid 267.183108 -210.896327)
		(end 267.693648 -211.406994)
		(stroke
			(width 0.2)
			(type default)
		)
		(layer "In3.Cu")
	)
	(gr_arc
		(start 267.96746 -14.6558)
		(mid 268.478 -15.16634)
		(end 268.98854 -14.6558)
		(stroke
			(width 0.2)
			(type default)
		)
		(layer "In3.Cu")
	)
	(gr_line
		(start 267.96746 -13.843)
		(end 267.96746 -14.6558)
		(stroke
			(width 0.2)
			(type default)
		)
		(layer "In3.Cu")
	)
	(gr_arc
		(start 268.506448 -211.406994)
		(mid 269.016988 -210.896454)
		(end 268.506448 -210.385914)
		(stroke
			(width 0.2)
			(type default)
		)
		(layer "In3.Cu")
	)
	(gr_line
		(start 268.506448 -210.385914)
		(end 267.693902 -210.385914)
		(stroke
			(width 0.2)
			(type default)
		)
		(layer "In3.Cu")
	)
	(gr_line
		(start 268.98854 -14.6558)
		(end 268.98854 -13.843254)
		(stroke
			(width 0.2)
			(type default)
		)
		(layer "In3.Cu")
	)
	(gr_arc
		(start 268.98854 -13.843254)
		(mid 268.478127 -13.33246)
		(end 267.96746 -13.843)
		(stroke
			(width 0.2)
			(type default)
		)
		(layer "In3.Cu")
	)
	(gr_arc
		(start 269.03426 -6.118352)
		(mid 269.5448 -6.628892)
		(end 270.05534 -6.118352)
		(stroke
			(width 0.2)
			(type default)
		)
		(layer "In3.Cu")
	)
	(gr_line
		(start 269.03426 -5.305552)
		(end 269.03426 -6.118352)
		(stroke
			(width 0.2)
			(type default)
		)
		(layer "In3.Cu")
	)
	(gr_line
		(start 270.05534 -6.118352)
		(end 270.05534 -5.305806)
		(stroke
			(width 0.2)
			(type default)
		)
		(layer "In3.Cu")
	)
	(gr_arc
		(start 270.05534 -5.305806)
		(mid 269.544927 -4.795012)
		(end 269.03426 -5.305552)
		(stroke
			(width 0.2)
			(type default)
		)
		(layer "In3.Cu")
	)
	(gr_arc
		(start 270.17726 -9.166352)
		(mid 270.6878 -9.676892)
		(end 271.19834 -9.166352)
		(stroke
			(width 0.2)
			(type default)
		)
		(layer "In3.Cu")
	)
	(gr_line
		(start 270.17726 -8.353552)
		(end 270.17726 -9.166352)
		(stroke
			(width 0.2)
			(type default)
		)
		(layer "In3.Cu")
	)
	(gr_line
		(start 270.893794 -211.406994)
		(end 271.706594 -211.406994)
		(stroke
			(width 0.2)
			(type default)
		)
		(layer "In3.Cu")
	)
	(gr_arc
		(start 270.894048 -210.385914)
		(mid 270.383254 -210.896327)
		(end 270.893794 -211.406994)
		(stroke
			(width 0.2)
			(type default)
		)
		(layer "In3.Cu")
	)
	(gr_line
		(start 271.19834 -9.166352)
		(end 271.19834 -8.353806)
		(stroke
			(width 0.2)
			(type default)
		)
		(layer "In3.Cu")
	)
	(gr_arc
		(start 271.19834 -8.353806)
		(mid 270.687927 -7.843012)
		(end 270.17726 -8.353552)
		(stroke
			(width 0.2)
			(type default)
		)
		(layer "In3.Cu")
	)
	(gr_arc
		(start 271.55775 -15.334996)
		(mid 272.068163 -15.84579)
		(end 272.57883 -15.33525)
		(stroke
			(width 0.2)
			(type default)
		)
		(layer "In3.Cu")
	)
	(gr_line
		(start 271.55775 -14.52245)
		(end 271.55775 -15.334996)
		(stroke
			(width 0.2)
			(type default)
		)
		(layer "In3.Cu")
	)
	(gr_arc
		(start 271.706594 -211.406994)
		(mid 272.217134 -210.896454)
		(end 271.706594 -210.385914)
		(stroke
			(width 0.2)
			(type default)
		)
		(layer "In3.Cu")
	)
	(gr_line
		(start 271.706594 -210.385914)
		(end 270.894048 -210.385914)
		(stroke
			(width 0.2)
			(type default)
		)
		(layer "In3.Cu")
	)
	(gr_line
		(start 272.49374 -222.805244)
		(end 273.306286 -222.805244)
		(stroke
			(width 0.2)
			(type default)
		)
		(layer "In3.Cu")
	)
	(gr_arc
		(start 272.49374 -221.784164)
		(mid 271.9832 -222.294704)
		(end 272.49374 -222.805244)
		(stroke
			(width 0.2)
			(type default)
		)
		(layer "In3.Cu")
	)
	(gr_line
		(start 272.57883 -15.33525)
		(end 272.57883 -14.52245)
		(stroke
			(width 0.2)
			(type default)
		)
		(layer "In3.Cu")
	)
	(gr_arc
		(start 272.57883 -14.52245)
		(mid 272.06829 -14.01191)
		(end 271.55775 -14.52245)
		(stroke
			(width 0.2)
			(type default)
		)
		(layer "In3.Cu")
	)
	(gr_line
		(start 272.7452 -20.066)
		(end 274.3708 -18.4404)
		(stroke
			(width 0.381)
			(type default)
		)
		(layer "In3.Cu")
	)
	(gr_line
		(start 273.0246 -10.8458)
		(end 273.0246 -7.0104)
		(stroke
			(width 0.381)
			(type default)
		)
		(layer "In3.Cu")
	)
	(gr_line
		(start 273.0246 -7.0104)
		(end 273.812 -6.223)
		(stroke
			(width 0.381)
			(type default)
		)
		(layer "In3.Cu")
	)
	(gr_circle
		(center 273.100038 -23.400004)
		(end 274.118578 -23.400004)
		(stroke
			(width 0.2)
			(type default)
		)
		(fill no)
		(layer "In3.Cu")
	)
	(gr_arc
		(start 273.306286 -222.805244)
		(mid 273.81708 -222.294831)
		(end 273.30654 -221.784164)
		(stroke
			(width 0.2)
			(type default)
		)
		(layer "In3.Cu")
	)
	(gr_line
		(start 273.30654 -221.784164)
		(end 272.49374 -221.784164)
		(stroke
			(width 0.2)
			(type default)
		)
		(layer "In3.Cu")
	)
	(gr_line
		(start 273.3548 3.048)
		(end 256.286 3.048)
		(stroke
			(width 0.381)
			(type default)
		)
		(layer "In3.Cu")
	)
	(gr_line
		(start 273.812 -6.223)
		(end 273.812 2.5908)
		(stroke
			(width 0.381)
			(type default)
		)
		(layer "In3.Cu")
	)
	(gr_line
		(start 273.812 2.5908)
		(end 273.3548 3.048)
		(stroke
			(width 0.381)
			(type default)
		)
		(layer "In3.Cu")
	)
	(gr_line
		(start 274.093686 -211.406994)
		(end 274.906486 -211.406994)
		(stroke
			(width 0.2)
			(type default)
		)
		(layer "In3.Cu")
	)
	(gr_arc
		(start 274.09394 -210.385914)
		(mid 273.583146 -210.896327)
		(end 274.093686 -211.406994)
		(stroke
			(width 0.2)
			(type default)
		)
		(layer "In3.Cu")
	)
	(gr_line
		(start 274.3708 -18.4404)
		(end 274.3708 -12.192)
		(stroke
			(width 0.381)
			(type default)
		)
		(layer "In3.Cu")
	)
	(gr_line
		(start 274.3708 -12.192)
		(end 273.0246 -10.8458)
		(stroke
			(width 0.381)
			(type default)
		)
		(layer "In3.Cu")
	)
	(gr_arc
		(start 274.906486 -211.406994)
		(mid 275.417026 -210.896454)
		(end 274.906486 -210.385914)
		(stroke
			(width 0.2)
			(type default)
		)
		(layer "In3.Cu")
	)
	(gr_line
		(start 274.906486 -210.385914)
		(end 274.09394 -210.385914)
		(stroke
			(width 0.2)
			(type default)
		)
		(layer "In3.Cu")
	)
	(gr_line
		(start 275.693632 -222.805244)
		(end 276.506178 -222.805244)
		(stroke
			(width 0.2)
			(type default)
		)
		(layer "In3.Cu")
	)
	(gr_arc
		(start 275.693632 -221.784164)
		(mid 275.183092 -222.294704)
		(end 275.693632 -222.805244)
		(stroke
			(width 0.2)
			(type default)
		)
		(layer "In3.Cu")
	)
	(gr_arc
		(start 276.506178 -222.805244)
		(mid 277.016972 -222.294831)
		(end 276.506432 -221.784164)
		(stroke
			(width 0.2)
			(type default)
		)
		(layer "In3.Cu")
	)
	(gr_line
		(start 276.506432 -221.784164)
		(end 275.693632 -221.784164)
		(stroke
			(width 0.2)
			(type default)
		)
		(layer "In3.Cu")
	)
	(gr_line
		(start 277.293578 -211.406994)
		(end 278.106378 -211.406994)
		(stroke
			(width 0.2)
			(type default)
		)
		(layer "In3.Cu")
	)
	(gr_arc
		(start 277.293832 -210.385914)
		(mid 276.783038 -210.896327)
		(end 277.293578 -211.406994)
		(stroke
			(width 0.2)
			(type default)
		)
		(layer "In3.Cu")
	)
	(gr_arc
		(start 278.106378 -211.406994)
		(mid 278.616918 -210.896454)
		(end 278.106378 -210.385914)
		(stroke
			(width 0.2)
			(type default)
		)
		(layer "In3.Cu")
	)
	(gr_line
		(start 278.106378 -210.385914)
		(end 277.293832 -210.385914)
		(stroke
			(width 0.2)
			(type default)
		)
		(layer "In3.Cu")
	)
	(gr_line
		(start 278.893778 -222.805244)
		(end 279.706324 -222.805244)
		(stroke
			(width 0.2)
			(type default)
		)
		(layer "In3.Cu")
	)
	(gr_arc
		(start 278.893778 -221.784164)
		(mid 278.383238 -222.294704)
		(end 278.893778 -222.805244)
		(stroke
			(width 0.2)
			(type default)
		)
		(layer "In3.Cu")
	)
	(gr_arc
		(start 279.706324 -222.805244)
		(mid 280.217118 -222.294831)
		(end 279.706578 -221.784164)
		(stroke
			(width 0.2)
			(type default)
		)
		(layer "In3.Cu")
	)
	(gr_line
		(start 279.706578 -221.784164)
		(end 278.893778 -221.784164)
		(stroke
			(width 0.2)
			(type default)
		)
		(layer "In3.Cu")
	)
	(gr_arc
		(start 279.72766 -18.762726)
		(mid 280.230326 -19.28114)
		(end 280.74874 -18.778474)
		(stroke
			(width 0.2)
			(type default)
		)
		(layer "In3.Cu")
	)
	(gr_line
		(start 279.740106 -17.949926)
		(end 279.72766 -18.762726)
		(stroke
			(width 0.2)
			(type default)
		)
		(layer "In3.Cu")
	)
	(gr_line
		(start 280.493724 -211.406994)
		(end 281.306524 -211.406994)
		(stroke
			(width 0.2)
			(type default)
		)
		(layer "In3.Cu")
	)
	(gr_arc
		(start 280.493978 -210.385914)
		(mid 279.983184 -210.896327)
		(end 280.493724 -211.406994)
		(stroke
			(width 0.2)
			(type default)
		)
		(layer "In3.Cu")
	)
	(gr_line
		(start 280.74874 -18.778474)
		(end 280.761186 -17.965928)
		(stroke
			(width 0.2)
			(type default)
		)
		(layer "In3.Cu")
	)
	(gr_arc
		(start 280.761186 -17.965928)
		(mid 280.258647 -17.447516)
		(end 279.740106 -17.949926)
		(stroke
			(width 0.2)
			(type default)
		)
		(layer "In3.Cu")
	)
	(gr_arc
		(start 281.306524 -211.406994)
		(mid 281.817064 -210.896454)
		(end 281.306524 -210.385914)
		(stroke
			(width 0.2)
			(type default)
		)
		(layer "In3.Cu")
	)
	(gr_line
		(start 281.306524 -210.385914)
		(end 280.493978 -210.385914)
		(stroke
			(width 0.2)
			(type default)
		)
		(layer "In3.Cu")
	)
	(gr_line
		(start 282.09367 -222.805244)
		(end 282.906216 -222.805244)
		(stroke
			(width 0.2)
			(type default)
		)
		(layer "In3.Cu")
	)
	(gr_arc
		(start 282.09367 -221.784164)
		(mid 281.58313 -222.294704)
		(end 282.09367 -222.805244)
		(stroke
			(width 0.2)
			(type default)
		)
		(layer "In3.Cu")
	)
	(gr_line
		(start 282.244546 -20.841208)
		(end 282.788614 -21.44522)
		(stroke
			(width 0.2)
			(type default)
		)
		(layer "In3.Cu")
	)
	(gr_line
		(start 282.246578 -20.83943)
		(end 282.244546 -20.841208)
		(stroke
			(width 0.2)
			(type default)
		)
		(layer "In3.Cu")
	)
	(gr_line
		(start 282.788614 -21.44522)
		(end 282.790646 -21.443442)
		(stroke
			(width 0.2)
			(type default)
		)
		(layer "In3.Cu")
	)
	(gr_arc
		(start 282.790646 -21.443442)
		(mid 283.511498 -21.481034)
		(end 283.54909 -20.760182)
		(stroke
			(width 0.2)
			(type default)
		)
		(layer "In3.Cu")
	)
	(gr_arc
		(start 282.906216 -222.805244)
		(mid 283.41701 -222.294831)
		(end 282.90647 -221.784164)
		(stroke
			(width 0.2)
			(type default)
		)
		(layer "In3.Cu")
	)
	(gr_line
		(start 282.90647 -221.784164)
		(end 282.09367 -221.784164)
		(stroke
			(width 0.2)
			(type default)
		)
		(layer "In3.Cu")
	)
	(gr_arc
		(start 283.005276 -20.15617)
		(mid 282.284107 -20.118381)
		(end 282.246578 -20.83943)
		(stroke
			(width 0.2)
			(type default)
		)
		(layer "In3.Cu")
	)
	(gr_line
		(start 283.0068 -20.154646)
		(end 283.005276 -20.15617)
		(stroke
			(width 0.2)
			(type default)
		)
		(layer "In3.Cu")
	)
	(gr_line
		(start 283.007308 -20.154646)
		(end 283.0068 -20.154646)
		(stroke
			(width 0.2)
			(type default)
		)
		(layer "In3.Cu")
	)
	(gr_line
		(start 283.54909 -20.760182)
		(end 283.551122 -20.758404)
		(stroke
			(width 0.2)
			(type default)
		)
		(layer "In3.Cu")
	)
	(gr_line
		(start 283.551122 -20.758404)
		(end 283.007308 -20.154646)
		(stroke
			(width 0.2)
			(type default)
		)
		(layer "In3.Cu")
	)
	(gr_line
		(start 283.693616 -211.406994)
		(end 284.506416 -211.406994)
		(stroke
			(width 0.2)
			(type default)
		)
		(layer "In3.Cu")
	)
	(gr_arc
		(start 283.69387 -210.385914)
		(mid 283.183076 -210.896327)
		(end 283.693616 -211.406994)
		(stroke
			(width 0.2)
			(type default)
		)
		(layer "In3.Cu")
	)
	(gr_line
		(start 284.353 -25.019)
		(end 310.134 -50.8)
		(stroke
			(width 0.381)
			(type default)
		)
		(layer "In3.Cu")
	)
	(gr_arc
		(start 284.477714 -33.864042)
		(mid 284.988127 -34.374836)
		(end 285.498794 -33.864296)
		(stroke
			(width 0.2)
			(type default)
		)
		(layer "In3.Cu")
	)
	(gr_line
		(start 284.477714 -33.051496)
		(end 284.477714 -33.864042)
		(stroke
			(width 0.2)
			(type default)
		)
		(layer "In3.Cu")
	)
	(gr_arc
		(start 284.506416 -211.406994)
		(mid 285.016956 -210.896454)
		(end 284.506416 -210.385914)
		(stroke
			(width 0.2)
			(type default)
		)
		(layer "In3.Cu")
	)
	(gr_line
		(start 284.506416 -210.385914)
		(end 283.69387 -210.385914)
		(stroke
			(width 0.2)
			(type default)
		)
		(layer "In3.Cu")
	)
	(gr_line
		(start 285.293562 -222.805244)
		(end 286.106108 -222.805244)
		(stroke
			(width 0.2)
			(type default)
		)
		(layer "In3.Cu")
	)
	(gr_arc
		(start 285.293562 -221.784164)
		(mid 284.783022 -222.294704)
		(end 285.293562 -222.805244)
		(stroke
			(width 0.2)
			(type default)
		)
		(layer "In3.Cu")
	)
	(gr_line
		(start 285.498794 -33.864296)
		(end 285.498794 -33.051496)
		(stroke
			(width 0.2)
			(type default)
		)
		(layer "In3.Cu")
	)
	(gr_arc
		(start 285.498794 -33.051496)
		(mid 284.988254 -32.540956)
		(end 284.477714 -33.051496)
		(stroke
			(width 0.2)
			(type default)
		)
		(layer "In3.Cu")
	)
	(gr_line
		(start 285.581344 -25.033732)
		(end 285.581598 -25.033986)
		(stroke
			(width 0.2)
			(type default)
		)
		(layer "In3.Cu")
	)
	(gr_line
		(start 285.581344 -13.633958)
		(end 285.583376 -13.635228)
		(stroke
			(width 0.2)
			(type default)
		)
		(layer "In3.Cu")
	)
	(gr_line
		(start 285.581598 -25.033986)
		(end 285.58363 -25.035002)
		(stroke
			(width 0.2)
			(type default)
		)
		(layer "In3.Cu")
	)
	(gr_arc
		(start 285.583376 -13.635228)
		(mid 285.839408 -14.481048)
		(end 286.685228 -14.225016)
		(stroke
			(width 0.2)
			(type default)
		)
		(layer "In3.Cu")
	)
	(gr_arc
		(start 285.58363 -25.035002)
		(mid 285.839306 -25.880903)
		(end 286.685228 -25.625044)
		(stroke
			(width 0.2)
			(type default)
		)
		(layer "In3.Cu")
	)
	(gr_arc
		(start 286.106108 -222.805244)
		(mid 286.616902 -222.294831)
		(end 286.106362 -221.784164)
		(stroke
			(width 0.2)
			(type default)
		)
		(layer "In3.Cu")
	)
	(gr_line
		(start 286.106362 -221.784164)
		(end 285.293562 -221.784164)
		(stroke
			(width 0.2)
			(type default)
		)
		(layer "In3.Cu")
	)
	(gr_line
		(start 286.331406 -23.633938)
		(end 285.581344 -25.033732)
		(stroke
			(width 0.2)
			(type default)
		)
		(layer "In3.Cu")
	)
	(gr_line
		(start 286.331406 -12.23391)
		(end 285.581344 -13.633958)
		(stroke
			(width 0.2)
			(type default)
		)
		(layer "In3.Cu")
	)
	(gr_line
		(start 286.333438 -23.635208)
		(end 286.331406 -23.633938)
		(stroke
			(width 0.2)
			(type default)
		)
		(layer "In3.Cu")
	)
	(gr_line
		(start 286.333438 -12.23518)
		(end 286.331406 -12.23391)
		(stroke
			(width 0.2)
			(type default)
		)
		(layer "In3.Cu")
	)
	(gr_line
		(start 286.685228 -25.625044)
		(end 286.68726 -25.626314)
		(stroke
			(width 0.2)
			(type default)
		)
		(layer "In3.Cu")
	)
	(gr_line
		(start 286.685228 -14.225016)
		(end 286.68726 -14.226286)
		(stroke
			(width 0.2)
			(type default)
		)
		(layer "In3.Cu")
	)
	(gr_line
		(start 286.68726 -25.626314)
		(end 287.437322 -24.226266)
		(stroke
			(width 0.2)
			(type default)
		)
		(layer "In3.Cu")
	)
	(gr_line
		(start 286.68726 -14.226286)
		(end 287.437322 -12.826492)
		(stroke
			(width 0.2)
			(type default)
		)
		(layer "In3.Cu")
	)
	(gr_line
		(start 286.893762 -211.406994)
		(end 287.706308 -211.406994)
		(stroke
			(width 0.2)
			(type default)
		)
		(layer "In3.Cu")
	)
	(gr_arc
		(start 286.893762 -210.385914)
		(mid 286.383222 -210.896454)
		(end 286.893762 -211.406994)
		(stroke
			(width 0.2)
			(type default)
		)
		(layer "In3.Cu")
	)
	(gr_arc
		(start 287.435036 -12.825222)
		(mid 287.17936 -11.979321)
		(end 286.333438 -12.23518)
		(stroke
			(width 0.2)
			(type default)
		)
		(layer "In3.Cu")
	)
	(gr_arc
		(start 287.43529 -24.224996)
		(mid 287.179258 -23.379176)
		(end 286.333438 -23.635208)
		(stroke
			(width 0.2)
			(type default)
		)
		(layer "In3.Cu")
	)
	(gr_line
		(start 287.437068 -12.826238)
		(end 287.435036 -12.825222)
		(stroke
			(width 0.2)
			(type default)
		)
		(layer "In3.Cu")
	)
	(gr_line
		(start 287.437322 -24.226266)
		(end 287.43529 -24.224996)
		(stroke
			(width 0.2)
			(type default)
		)
		(layer "In3.Cu")
	)
	(gr_line
		(start 287.437322 -12.826492)
		(end 287.437068 -12.826238)
		(stroke
			(width 0.2)
			(type default)
		)
		(layer "In3.Cu")
	)
	(gr_arc
		(start 287.706308 -211.406994)
		(mid 288.217102 -210.896581)
		(end 287.706562 -210.385914)
		(stroke
			(width 0.2)
			(type default)
		)
		(layer "In3.Cu")
	)
	(gr_line
		(start 287.706562 -210.385914)
		(end 286.893762 -210.385914)
		(stroke
			(width 0.2)
			(type default)
		)
		(layer "In3.Cu")
	)
	(gr_line
		(start 287.83153 -17.433544)
		(end 287.831784 -17.433798)
		(stroke
			(width 0.2)
			(type default)
		)
		(layer "In3.Cu")
	)
	(gr_line
		(start 287.831784 -17.433798)
		(end 287.833816 -17.434814)
		(stroke
			(width 0.2)
			(type default)
		)
		(layer "In3.Cu")
	)
	(gr_arc
		(start 287.833562 -13.635228)
		(mid 288.089594 -14.481048)
		(end 288.935414 -14.225016)
		(stroke
			(width 0.2)
			(type default)
		)
		(layer "In3.Cu")
	)
	(gr_arc
		(start 287.833816 -17.434814)
		(mid 288.089492 -18.280715)
		(end 288.935414 -18.024856)
		(stroke
			(width 0.2)
			(type default)
		)
		(layer "In3.Cu")
	)
	(gr_arc
		(start 287.837626 -25.027636)
		(mid 288.08576 -25.879089)
		(end 288.935414 -25.625044)
		(stroke
			(width 0.2)
			(type default)
		)
		(layer "In3.Cu")
	)
	(gr_arc
		(start 287.837626 -21.227542)
		(mid 288.08576 -22.078995)
		(end 288.935414 -21.82495)
		(stroke
			(width 0.2)
			(type default)
		)
		(layer "In3.Cu")
	)
	(gr_line
		(start 288.493708 -222.805244)
		(end 289.306254 -222.805244)
		(stroke
			(width 0.2)
			(type default)
		)
		(layer "In3.Cu")
	)
	(gr_arc
		(start 288.493708 -221.784164)
		(mid 287.983168 -222.294704)
		(end 288.493708 -222.805244)
		(stroke
			(width 0.2)
			(type default)
		)
		(layer "In3.Cu")
	)
	(gr_line
		(start 288.581338 -16.034004)
		(end 287.83153 -17.433544)
		(stroke
			(width 0.2)
			(type default)
		)
		(layer "In3.Cu")
	)
	(gr_line
		(start 288.58337 -23.635208)
		(end 287.837626 -25.027636)
		(stroke
			(width 0.2)
			(type default)
		)
		(layer "In3.Cu")
	)
	(gr_line
		(start 288.58337 -19.835114)
		(end 287.837626 -21.227542)
		(stroke
			(width 0.2)
			(type default)
		)
		(layer "In3.Cu")
	)
	(gr_line
		(start 288.58337 -16.035274)
		(end 288.581338 -16.034004)
		(stroke
			(width 0.2)
			(type default)
		)
		(layer "In3.Cu")
	)
	(gr_line
		(start 288.58337 -12.23518)
		(end 287.833562 -13.635228)
		(stroke
			(width 0.2)
			(type default)
		)
		(layer "In3.Cu")
	)
	(gr_line
		(start 288.935414 -25.625044)
		(end 289.685222 -24.224996)
		(stroke
			(width 0.2)
			(type default)
		)
		(layer "In3.Cu")
	)
	(gr_line
		(start 288.935414 -21.82495)
		(end 289.685222 -20.424902)
		(stroke
			(width 0.2)
			(type default)
		)
		(layer "In3.Cu")
	)
	(gr_line
		(start 288.935414 -18.024856)
		(end 288.937446 -18.026126)
		(stroke
			(width 0.2)
			(type default)
		)
		(layer "In3.Cu")
	)
	(gr_line
		(start 288.935414 -14.225016)
		(end 289.681158 -12.832588)
		(stroke
			(width 0.2)
			(type default)
		)
		(layer "In3.Cu")
	)
	(gr_line
		(start 288.937446 -18.026126)
		(end 289.687254 -16.626332)
		(stroke
			(width 0.2)
			(type default)
		)
		(layer "In3.Cu")
	)
	(gr_line
		(start 289.2298 -35.524694)
		(end 290.042346 -35.524694)
		(stroke
			(width 0.2)
			(type default)
		)
		(layer "In3.Cu")
	)
	(gr_arc
		(start 289.2298 -34.503614)
		(mid 288.71926 -35.014154)
		(end 289.2298 -35.524694)
		(stroke
			(width 0.2)
			(type default)
		)
		(layer "In3.Cu")
	)
	(gr_arc
		(start 289.306254 -222.805244)
		(mid 289.817048 -222.294831)
		(end 289.306508 -221.784164)
		(stroke
			(width 0.2)
			(type default)
		)
		(layer "In3.Cu")
	)
	(gr_line
		(start 289.306508 -221.784164)
		(end 288.493708 -221.784164)
		(stroke
			(width 0.2)
			(type default)
		)
		(layer "In3.Cu")
	)
	(gr_arc
		(start 289.681158 -12.832588)
		(mid 289.433024 -11.981135)
		(end 288.58337 -12.23518)
		(stroke
			(width 0.2)
			(type default)
		)
		(layer "In3.Cu")
	)
	(gr_arc
		(start 289.685222 -24.224996)
		(mid 289.42919 -23.379176)
		(end 288.58337 -23.635208)
		(stroke
			(width 0.2)
			(type default)
		)
		(layer "In3.Cu")
	)
	(gr_arc
		(start 289.685222 -20.424902)
		(mid 289.42919 -19.579082)
		(end 288.58337 -19.835114)
		(stroke
			(width 0.2)
			(type default)
		)
		(layer "In3.Cu")
	)
	(gr_arc
		(start 289.685222 -16.625062)
		(mid 289.42919 -15.779242)
		(end 288.58337 -16.035274)
		(stroke
			(width 0.2)
			(type default)
		)
		(layer "In3.Cu")
	)
	(gr_line
		(start 289.687254 -16.626332)
		(end 289.685222 -16.625062)
		(stroke
			(width 0.2)
			(type default)
		)
		(layer "In3.Cu")
	)
	(gr_arc
		(start 290.042346 -35.524694)
		(mid 290.55314 -35.014281)
		(end 290.0426 -34.503614)
		(stroke
			(width 0.2)
			(type default)
		)
		(layer "In3.Cu")
	)
	(gr_line
		(start 290.0426 -34.503614)
		(end 289.2298 -34.503614)
		(stroke
			(width 0.2)
			(type default)
		)
		(layer "In3.Cu")
	)
	(gr_line
		(start 290.081462 -25.033732)
		(end 290.081716 -25.033986)
		(stroke
			(width 0.2)
			(type default)
		)
		(layer "In3.Cu")
	)
	(gr_line
		(start 290.081462 -21.233638)
		(end 290.081716 -21.233892)
		(stroke
			(width 0.2)
			(type default)
		)
		(layer "In3.Cu")
	)
	(gr_line
		(start 290.081462 -17.433544)
		(end 290.081716 -17.433798)
		(stroke
			(width 0.2)
			(type default)
		)
		(layer "In3.Cu")
	)
	(gr_line
		(start 290.081462 -13.633958)
		(end 290.083494 -13.635228)
		(stroke
			(width 0.2)
			(type default)
		)
		(layer "In3.Cu")
	)
	(gr_line
		(start 290.081716 -25.033986)
		(end 290.083748 -25.035002)
		(stroke
			(width 0.2)
			(type default)
		)
		(layer "In3.Cu")
	)
	(gr_line
		(start 290.081716 -21.233892)
		(end 290.083748 -21.234908)
		(stroke
			(width 0.2)
			(type default)
		)
		(layer "In3.Cu")
	)
	(gr_line
		(start 290.081716 -17.433798)
		(end 290.083748 -17.434814)
		(stroke
			(width 0.2)
			(type default)
		)
		(layer "In3.Cu")
	)
	(gr_arc
		(start 290.083494 -13.635228)
		(mid 290.339526 -14.481048)
		(end 291.185346 -14.225016)
		(stroke
			(width 0.2)
			(type default)
		)
		(layer "In3.Cu")
	)
	(gr_arc
		(start 290.083748 -25.035002)
		(mid 290.339424 -25.880903)
		(end 291.185346 -25.625044)
		(stroke
			(width 0.2)
			(type default)
		)
		(layer "In3.Cu")
	)
	(gr_arc
		(start 290.083748 -21.234908)
		(mid 290.339424 -22.080809)
		(end 291.185346 -21.82495)
		(stroke
			(width 0.2)
			(type default)
		)
		(layer "In3.Cu")
	)
	(gr_arc
		(start 290.083748 -17.434814)
		(mid 290.339272 -18.280634)
		(end 291.185092 -18.02511)
		(stroke
			(width 0.2)
			(type default)
		)
		(layer "In3.Cu")
	)
	(gr_line
		(start 290.093654 -211.406994)
		(end 290.906454 -211.406994)
		(stroke
			(width 0.2)
			(type default)
		)
		(layer "In3.Cu")
	)
	(gr_arc
		(start 290.093908 -210.385914)
		(mid 289.583114 -210.896327)
		(end 290.093654 -211.406994)
		(stroke
			(width 0.2)
			(type default)
		)
		(layer "In3.Cu")
	)
	(gr_line
		(start 290.831524 -23.633938)
		(end 290.081462 -25.033732)
		(stroke
			(width 0.2)
			(type default)
		)
		(layer "In3.Cu")
	)
	(gr_line
		(start 290.831524 -19.833844)
		(end 290.081462 -21.233638)
		(stroke
			(width 0.2)
			(type default)
		)
		(layer "In3.Cu")
	)
	(gr_line
		(start 290.831524 -16.03375)
		(end 290.081462 -17.433544)
		(stroke
			(width 0.2)
			(type default)
		)
		(layer "In3.Cu")
	)
	(gr_line
		(start 290.831524 -12.23391)
		(end 290.081462 -13.633958)
		(stroke
			(width 0.2)
			(type default)
		)
		(layer "In3.Cu")
	)
	(gr_line
		(start 290.833556 -23.635208)
		(end 290.831524 -23.633938)
		(stroke
			(width 0.2)
			(type default)
		)
		(layer "In3.Cu")
	)
	(gr_line
		(start 290.833556 -19.835114)
		(end 290.831524 -19.833844)
		(stroke
			(width 0.2)
			(type default)
		)
		(layer "In3.Cu")
	)
	(gr_line
		(start 290.833556 -12.23518)
		(end 290.831524 -12.23391)
		(stroke
			(width 0.2)
			(type default)
		)
		(layer "In3.Cu")
	)
	(gr_line
		(start 290.83381 -16.03502)
		(end 290.831524 -16.03375)
		(stroke
			(width 0.2)
			(type default)
		)
		(layer "In3.Cu")
	)
	(gr_arc
		(start 290.906454 -211.406994)
		(mid 291.416994 -210.896454)
		(end 290.906454 -210.385914)
		(stroke
			(width 0.2)
			(type default)
		)
		(layer "In3.Cu")
	)
	(gr_line
		(start 290.906454 -210.385914)
		(end 290.093908 -210.385914)
		(stroke
			(width 0.2)
			(type default)
		)
		(layer "In3.Cu")
	)
	(gr_line
		(start 291.185092 -18.02511)
		(end 291.187378 -18.02638)
		(stroke
			(width 0.2)
			(type default)
		)
		(layer "In3.Cu")
	)
	(gr_line
		(start 291.185346 -25.625044)
		(end 291.187378 -25.626314)
		(stroke
			(width 0.2)
			(type default)
		)
		(layer "In3.Cu")
	)
	(gr_line
		(start 291.185346 -21.82495)
		(end 291.187378 -21.82622)
		(stroke
			(width 0.2)
			(type default)
		)
		(layer "In3.Cu")
	)
	(gr_line
		(start 291.185346 -14.225016)
		(end 291.187378 -14.226286)
		(stroke
			(width 0.2)
			(type default)
		)
		(layer "In3.Cu")
	)
	(gr_line
		(start 291.187378 -25.626314)
		(end 291.93744 -24.226266)
		(stroke
			(width 0.2)
			(type default)
		)
		(layer "In3.Cu")
	)
	(gr_line
		(start 291.187378 -21.82622)
		(end 291.93744 -20.426172)
		(stroke
			(width 0.2)
			(type default)
		)
		(layer "In3.Cu")
	)
	(gr_line
		(start 291.187378 -18.02638)
		(end 291.93744 -16.626586)
		(stroke
			(width 0.2)
			(type default)
		)
		(layer "In3.Cu")
	)
	(gr_line
		(start 291.187378 -14.226286)
		(end 291.93744 -12.826492)
		(stroke
			(width 0.2)
			(type default)
		)
		(layer "In3.Cu")
	)
	(gr_line
		(start 291.6936 -222.805244)
		(end 292.506146 -222.805244)
		(stroke
			(width 0.2)
			(type default)
		)
		(layer "In3.Cu")
	)
	(gr_arc
		(start 291.6936 -221.784164)
		(mid 291.18306 -222.294704)
		(end 291.6936 -222.805244)
		(stroke
			(width 0.2)
			(type default)
		)
		(layer "In3.Cu")
	)
	(gr_arc
		(start 291.935154 -16.625316)
		(mid 291.67963 -15.779496)
		(end 290.83381 -16.03502)
		(stroke
			(width 0.2)
			(type default)
		)
		(layer "In3.Cu")
	)
	(gr_arc
		(start 291.935154 -12.825222)
		(mid 291.679478 -11.979321)
		(end 290.833556 -12.23518)
		(stroke
			(width 0.2)
			(type default)
		)
		(layer "In3.Cu")
	)
	(gr_arc
		(start 291.935408 -24.224996)
		(mid 291.679376 -23.379176)
		(end 290.833556 -23.635208)
		(stroke
			(width 0.2)
			(type default)
		)
		(layer "In3.Cu")
	)
	(gr_arc
		(start 291.935408 -20.424902)
		(mid 291.679376 -19.579082)
		(end 290.833556 -19.835114)
		(stroke
			(width 0.2)
			(type default)
		)
		(layer "In3.Cu")
	)
	(gr_line
		(start 291.937186 -12.826238)
		(end 291.935154 -12.825222)
		(stroke
			(width 0.2)
			(type default)
		)
		(layer "In3.Cu")
	)
	(gr_line
		(start 291.93744 -24.226266)
		(end 291.935408 -24.224996)
		(stroke
			(width 0.2)
			(type default)
		)
		(layer "In3.Cu")
	)
	(gr_line
		(start 291.93744 -20.426172)
		(end 291.935408 -20.424902)
		(stroke
			(width 0.2)
			(type default)
		)
		(layer "In3.Cu")
	)
	(gr_line
		(start 291.93744 -16.626586)
		(end 291.935154 -16.625316)
		(stroke
			(width 0.2)
			(type default)
		)
		(layer "In3.Cu")
	)
	(gr_line
		(start 291.93744 -12.826492)
		(end 291.937186 -12.826238)
		(stroke
			(width 0.2)
			(type default)
		)
		(layer "In3.Cu")
	)
	(gr_arc
		(start 292.506146 -222.805244)
		(mid 293.01694 -222.294831)
		(end 292.5064 -221.784164)
		(stroke
			(width 0.2)
			(type default)
		)
		(layer "In3.Cu")
	)
	(gr_line
		(start 292.5064 -221.784164)
		(end 291.6936 -221.784164)
		(stroke
			(width 0.2)
			(type default)
		)
		(layer "In3.Cu")
	)
	(gr_line
		(start 293.293546 -211.406994)
		(end 294.106346 -211.406994)
		(stroke
			(width 0.2)
			(type default)
		)
		(layer "In3.Cu")
	)
	(gr_arc
		(start 293.2938 -210.385914)
		(mid 292.783006 -210.896327)
		(end 293.293546 -211.406994)
		(stroke
			(width 0.2)
			(type default)
		)
		(layer "In3.Cu")
	)
	(gr_arc
		(start 294.106346 -211.406994)
		(mid 294.616886 -210.896454)
		(end 294.106346 -210.385914)
		(stroke
			(width 0.2)
			(type default)
		)
		(layer "In3.Cu")
	)
	(gr_line
		(start 294.106346 -210.385914)
		(end 293.2938 -210.385914)
		(stroke
			(width 0.2)
			(type default)
		)
		(layer "In3.Cu")
	)
	(gr_line
		(start 294.159178 -35.69081)
		(end 294.971978 -35.69081)
		(stroke
			(width 0.2)
			(type default)
		)
		(layer "In3.Cu")
	)
	(gr_arc
		(start 294.159432 -34.66973)
		(mid 293.648638 -35.180143)
		(end 294.159178 -35.69081)
		(stroke
			(width 0.2)
			(type default)
		)
		(layer "In3.Cu")
	)
	(gr_line
		(start 294.893746 -222.805244)
		(end 295.706292 -222.805244)
		(stroke
			(width 0.2)
			(type default)
		)
		(layer "In3.Cu")
	)
	(gr_arc
		(start 294.893746 -221.784164)
		(mid 294.383206 -222.294704)
		(end 294.893746 -222.805244)
		(stroke
			(width 0.2)
			(type default)
		)
		(layer "In3.Cu")
	)
	(gr_arc
		(start 294.971978 -35.69081)
		(mid 295.482518 -35.18027)
		(end 294.971978 -34.66973)
		(stroke
			(width 0.2)
			(type default)
		)
		(layer "In3.Cu")
	)
	(gr_line
		(start 294.971978 -34.66973)
		(end 294.159432 -34.66973)
		(stroke
			(width 0.2)
			(type default)
		)
		(layer "In3.Cu")
	)
	(gr_arc
		(start 295.706292 -222.805244)
		(mid 296.217086 -222.294831)
		(end 295.706546 -221.784164)
		(stroke
			(width 0.2)
			(type default)
		)
		(layer "In3.Cu")
	)
	(gr_line
		(start 295.706546 -221.784164)
		(end 294.893746 -221.784164)
		(stroke
			(width 0.2)
			(type default)
		)
		(layer "In3.Cu")
	)
	(gr_line
		(start 296.581322 -25.033986)
		(end 296.583354 -25.035256)
		(stroke
			(width 0.2)
			(type default)
		)
		(layer "In3.Cu")
	)
	(gr_line
		(start 296.581322 -13.633704)
		(end 296.581576 -13.633958)
		(stroke
			(width 0.2)
			(type default)
		)
		(layer "In3.Cu")
	)
	(gr_line
		(start 296.581576 -13.633958)
		(end 296.583608 -13.634974)
		(stroke
			(width 0.2)
			(type default)
		)
		(layer "In3.Cu")
	)
	(gr_arc
		(start 296.583354 -25.035256)
		(mid 296.839386 -25.881076)
		(end 297.685206 -25.625044)
		(stroke
			(width 0.2)
			(type default)
		)
		(layer "In3.Cu")
	)
	(gr_arc
		(start 296.583608 -13.634974)
		(mid 296.839284 -14.480875)
		(end 297.685206 -14.225016)
		(stroke
			(width 0.2)
			(type default)
		)
		(layer "In3.Cu")
	)
	(gr_line
		(start 297.331384 -23.633938)
		(end 296.581322 -25.033986)
		(stroke
			(width 0.2)
			(type default)
		)
		(layer "In3.Cu")
	)
	(gr_line
		(start 297.331384 -12.23391)
		(end 296.581322 -13.633704)
		(stroke
			(width 0.2)
			(type default)
		)
		(layer "In3.Cu")
	)
	(gr_line
		(start 297.333416 -23.635208)
		(end 297.331384 -23.633938)
		(stroke
			(width 0.2)
			(type default)
		)
		(layer "In3.Cu")
	)
	(gr_line
		(start 297.333416 -12.23518)
		(end 297.331384 -12.23391)
		(stroke
			(width 0.2)
			(type default)
		)
		(layer "In3.Cu")
	)
	(gr_line
		(start 297.685206 -25.625044)
		(end 297.687238 -25.626314)
		(stroke
			(width 0.2)
			(type default)
		)
		(layer "In3.Cu")
	)
	(gr_line
		(start 297.685206 -14.225016)
		(end 297.687238 -14.226286)
		(stroke
			(width 0.2)
			(type default)
		)
		(layer "In3.Cu")
	)
	(gr_line
		(start 297.687238 -25.626314)
		(end 298.4373 -24.22652)
		(stroke
			(width 0.2)
			(type default)
		)
		(layer "In3.Cu")
	)
	(gr_line
		(start 297.687238 -14.226286)
		(end 298.4373 -12.826238)
		(stroke
			(width 0.2)
			(type default)
		)
		(layer "In3.Cu")
	)
	(gr_arc
		(start 298.435014 -24.22525)
		(mid 298.179338 -23.379349)
		(end 297.333416 -23.635208)
		(stroke
			(width 0.2)
			(type default)
		)
		(layer "In3.Cu")
	)
	(gr_arc
		(start 298.435268 -12.824968)
		(mid 298.179236 -11.979148)
		(end 297.333416 -12.23518)
		(stroke
			(width 0.2)
			(type default)
		)
		(layer "In3.Cu")
	)
	(gr_line
		(start 298.437046 -24.226266)
		(end 298.435014 -24.22525)
		(stroke
			(width 0.2)
			(type default)
		)
		(layer "In3.Cu")
	)
	(gr_line
		(start 298.4373 -24.22652)
		(end 298.437046 -24.226266)
		(stroke
			(width 0.2)
			(type default)
		)
		(layer "In3.Cu")
	)
	(gr_line
		(start 298.4373 -12.826238)
		(end 298.435268 -12.824968)
		(stroke
			(width 0.2)
			(type default)
		)
		(layer "In3.Cu")
	)
	(gr_line
		(start 298.831508 -17.433544)
		(end 298.831762 -17.433798)
		(stroke
			(width 0.2)
			(type default)
		)
		(layer "In3.Cu")
	)
	(gr_line
		(start 298.831762 -17.433798)
		(end 298.833794 -17.434814)
		(stroke
			(width 0.2)
			(type default)
		)
		(layer "In3.Cu")
	)
	(gr_arc
		(start 298.83354 -21.235162)
		(mid 299.089572 -22.080982)
		(end 299.935392 -21.82495)
		(stroke
			(width 0.2)
			(type default)
		)
		(layer "In3.Cu")
	)
	(gr_arc
		(start 298.833794 -17.434814)
		(mid 299.08947 -18.280715)
		(end 299.935392 -18.024856)
		(stroke
			(width 0.2)
			(type default)
		)
		(layer "In3.Cu")
	)
	(gr_arc
		(start 298.837604 -25.027636)
		(mid 299.085738 -25.879089)
		(end 299.935392 -25.625044)
		(stroke
			(width 0.2)
			(type default)
		)
		(layer "In3.Cu")
	)
	(gr_arc
		(start 298.837604 -13.627608)
		(mid 299.085738 -14.479061)
		(end 299.935392 -14.225016)
		(stroke
			(width 0.2)
			(type default)
		)
		(layer "In3.Cu")
	)
	(gr_line
		(start 298.893738 -211.406994)
		(end 299.706538 -211.406994)
		(stroke
			(width 0.2)
			(type default)
		)
		(layer "In3.Cu")
	)
	(gr_arc
		(start 298.893992 -210.385914)
		(mid 298.383198 -210.896327)
		(end 298.893738 -211.406994)
		(stroke
			(width 0.2)
			(type default)
		)
		(layer "In3.Cu")
	)
	(gr_line
		(start 299.430694 -36.699952)
		(end 300.243494 -36.699952)
		(stroke
			(width 0.2)
			(type default)
		)
		(layer "In3.Cu")
	)
	(gr_arc
		(start 299.430948 -35.678872)
		(mid 298.920154 -36.189285)
		(end 299.430694 -36.699952)
		(stroke
			(width 0.2)
			(type default)
		)
		(layer "In3.Cu")
	)
	(gr_line
		(start 299.581316 -16.034004)
		(end 298.831508 -17.433544)
		(stroke
			(width 0.2)
			(type default)
		)
		(layer "In3.Cu")
	)
	(gr_line
		(start 299.583348 -23.635208)
		(end 298.837604 -25.027636)
		(stroke
			(width 0.2)
			(type default)
		)
		(layer "In3.Cu")
	)
	(gr_line
		(start 299.583348 -19.835114)
		(end 298.83354 -21.235162)
		(stroke
			(width 0.2)
			(type default)
		)
		(layer "In3.Cu")
	)
	(gr_line
		(start 299.583348 -16.035274)
		(end 299.581316 -16.034004)
		(stroke
			(width 0.2)
			(type default)
		)
		(layer "In3.Cu")
	)
	(gr_line
		(start 299.583348 -12.23518)
		(end 298.837604 -13.627608)
		(stroke
			(width 0.2)
			(type default)
		)
		(layer "In3.Cu")
	)
	(gr_arc
		(start 299.706538 -211.406994)
		(mid 300.217078 -210.896454)
		(end 299.706538 -210.385914)
		(stroke
			(width 0.2)
			(type default)
		)
		(layer "In3.Cu")
	)
	(gr_line
		(start 299.706538 -210.385914)
		(end 298.893992 -210.385914)
		(stroke
			(width 0.2)
			(type default)
		)
		(layer "In3.Cu")
	)
	(gr_line
		(start 299.935392 -25.625044)
		(end 300.6852 -24.224996)
		(stroke
			(width 0.2)
			(type default)
		)
		(layer "In3.Cu")
	)
	(gr_line
		(start 299.935392 -21.82495)
		(end 300.681136 -20.432522)
		(stroke
			(width 0.2)
			(type default)
		)
		(layer "In3.Cu")
	)
	(gr_line
		(start 299.935392 -18.024856)
		(end 299.937424 -18.026126)
		(stroke
			(width 0.2)
			(type default)
		)
		(layer "In3.Cu")
	)
	(gr_line
		(start 299.935392 -14.225016)
		(end 300.6852 -12.824968)
		(stroke
			(width 0.2)
			(type default)
		)
		(layer "In3.Cu")
	)
	(gr_line
		(start 299.937424 -18.026126)
		(end 300.687232 -16.626332)
		(stroke
			(width 0.2)
			(type default)
		)
		(layer "In3.Cu")
	)
	(gr_arc
		(start 300.243494 -36.699952)
		(mid 300.754034 -36.189412)
		(end 300.243494 -35.678872)
		(stroke
			(width 0.2)
			(type default)
		)
		(layer "In3.Cu")
	)
	(gr_line
		(start 300.243494 -35.678872)
		(end 299.430948 -35.678872)
		(stroke
			(width 0.2)
			(type default)
		)
		(layer "In3.Cu")
	)
	(gr_line
		(start 300.493684 -222.805244)
		(end 301.30623 -222.805244)
		(stroke
			(width 0.2)
			(type default)
		)
		(layer "In3.Cu")
	)
	(gr_arc
		(start 300.493684 -221.784164)
		(mid 299.983144 -222.294704)
		(end 300.493684 -222.805244)
		(stroke
			(width 0.2)
			(type default)
		)
		(layer "In3.Cu")
	)
	(gr_arc
		(start 300.681136 -20.432522)
		(mid 300.433002 -19.581069)
		(end 299.583348 -19.835114)
		(stroke
			(width 0.2)
			(type default)
		)
		(layer "In3.Cu")
	)
	(gr_arc
		(start 300.6852 -24.224996)
		(mid 300.429168 -23.379176)
		(end 299.583348 -23.635208)
		(stroke
			(width 0.2)
			(type default)
		)
		(layer "In3.Cu")
	)
	(gr_arc
		(start 300.6852 -16.625062)
		(mid 300.429168 -15.779242)
		(end 299.583348 -16.035274)
		(stroke
			(width 0.2)
			(type default)
		)
		(layer "In3.Cu")
	)
	(gr_arc
		(start 300.6852 -12.824968)
		(mid 300.429168 -11.979148)
		(end 299.583348 -12.23518)
		(stroke
			(width 0.2)
			(type default)
		)
		(layer "In3.Cu")
	)
	(gr_line
		(start 300.687232 -16.626332)
		(end 300.6852 -16.625062)
		(stroke
			(width 0.2)
			(type default)
		)
		(layer "In3.Cu")
	)
	(gr_line
		(start 301.08144 -25.033732)
		(end 301.081694 -25.033986)
		(stroke
			(width 0.2)
			(type default)
		)
		(layer "In3.Cu")
	)
	(gr_line
		(start 301.08144 -21.233892)
		(end 301.083472 -21.235162)
		(stroke
			(width 0.2)
			(type default)
		)
		(layer "In3.Cu")
	)
	(gr_line
		(start 301.08144 -17.433544)
		(end 301.081694 -17.433798)
		(stroke
			(width 0.2)
			(type default)
		)
		(layer "In3.Cu")
	)
	(gr_line
		(start 301.08144 -13.633704)
		(end 301.081694 -13.633958)
		(stroke
			(width 0.2)
			(type default)
		)
		(layer "In3.Cu")
	)
	(gr_line
		(start 301.081694 -25.033986)
		(end 301.083726 -25.035002)
		(stroke
			(width 0.2)
			(type default)
		)
		(layer "In3.Cu")
	)
	(gr_line
		(start 301.081694 -17.433798)
		(end 301.083726 -17.434814)
		(stroke
			(width 0.2)
			(type default)
		)
		(layer "In3.Cu")
	)
	(gr_line
		(start 301.081694 -13.633958)
		(end 301.083726 -13.634974)
		(stroke
			(width 0.2)
			(type default)
		)
		(layer "In3.Cu")
	)
	(gr_arc
		(start 301.083472 -21.235162)
		(mid 301.339504 -22.080982)
		(end 302.185324 -21.82495)
		(stroke
			(width 0.2)
			(type default)
		)
		(layer "In3.Cu")
	)
	(gr_arc
		(start 301.083726 -25.035002)
		(mid 301.339402 -25.880903)
		(end 302.185324 -25.625044)
		(stroke
			(width 0.2)
			(type default)
		)
		(layer "In3.Cu")
	)
	(gr_arc
		(start 301.083726 -17.434814)
		(mid 301.33925 -18.280634)
		(end 302.18507 -18.02511)
		(stroke
			(width 0.2)
			(type default)
		)
		(layer "In3.Cu")
	)
	(gr_arc
		(start 301.083726 -13.634974)
		(mid 301.339402 -14.480875)
		(end 302.185324 -14.225016)
		(stroke
			(width 0.2)
			(type default)
		)
		(layer "In3.Cu")
	)
	(gr_arc
		(start 301.30623 -222.805244)
		(mid 301.817024 -222.294831)
		(end 301.306484 -221.784164)
		(stroke
			(width 0.2)
			(type default)
		)
		(layer "In3.Cu")
	)
	(gr_line
		(start 301.306484 -221.784164)
		(end 300.493684 -221.784164)
		(stroke
			(width 0.2)
			(type default)
		)
		(layer "In3.Cu")
	)
	(gr_line
		(start 301.65929 -35.536886)
		(end 302.471836 -35.536886)
		(stroke
			(width 0.2)
			(type default)
		)
		(layer "In3.Cu")
	)
	(gr_arc
		(start 301.65929 -34.515806)
		(mid 301.14875 -35.026346)
		(end 301.65929 -35.536886)
		(stroke
			(width 0.2)
			(type default)
		)
		(layer "In3.Cu")
	)
	(gr_line
		(start 301.831502 -23.633938)
		(end 301.08144 -25.033732)
		(stroke
			(width 0.2)
			(type default)
		)
		(layer "In3.Cu")
	)
	(gr_line
		(start 301.831502 -19.833844)
		(end 301.08144 -21.233892)
		(stroke
			(width 0.2)
			(type default)
		)
		(layer "In3.Cu")
	)
	(gr_line
		(start 301.831502 -16.03375)
		(end 301.08144 -17.433544)
		(stroke
			(width 0.2)
			(type default)
		)
		(layer "In3.Cu")
	)
	(gr_line
		(start 301.831502 -12.23391)
		(end 301.08144 -13.633704)
		(stroke
			(width 0.2)
			(type default)
		)
		(layer "In3.Cu")
	)
	(gr_line
		(start 301.833534 -23.635208)
		(end 301.831502 -23.633938)
		(stroke
			(width 0.2)
			(type default)
		)
		(layer "In3.Cu")
	)
	(gr_line
		(start 301.833534 -19.835114)
		(end 301.831502 -19.833844)
		(stroke
			(width 0.2)
			(type default)
		)
		(layer "In3.Cu")
	)
	(gr_line
		(start 301.833534 -12.23518)
		(end 301.831502 -12.23391)
		(stroke
			(width 0.2)
			(type default)
		)
		(layer "In3.Cu")
	)
	(gr_line
		(start 301.833788 -16.03502)
		(end 301.831502 -16.03375)
		(stroke
			(width 0.2)
			(type default)
		)
		(layer "In3.Cu")
	)
	(gr_line
		(start 302.09363 -211.406994)
		(end 302.90643 -211.406994)
		(stroke
			(width 0.2)
			(type default)
		)
		(layer "In3.Cu")
	)
	(gr_arc
		(start 302.093884 -210.385914)
		(mid 301.58309 -210.896327)
		(end 302.09363 -211.406994)
		(stroke
			(width 0.2)
			(type default)
		)
		(layer "In3.Cu")
	)
	(gr_line
		(start 302.18507 -18.02511)
		(end 302.187356 -18.02638)
		(stroke
			(width 0.2)
			(type default)
		)
		(layer "In3.Cu")
	)
	(gr_line
		(start 302.185324 -25.625044)
		(end 302.187356 -25.626314)
		(stroke
			(width 0.2)
			(type default)
		)
		(layer "In3.Cu")
	)
	(gr_line
		(start 302.185324 -21.82495)
		(end 302.187356 -21.82622)
		(stroke
			(width 0.2)
			(type default)
		)
		(layer "In3.Cu")
	)
	(gr_line
		(start 302.185324 -14.225016)
		(end 302.187356 -14.226286)
		(stroke
			(width 0.2)
			(type default)
		)
		(layer "In3.Cu")
	)
	(gr_line
		(start 302.187356 -25.626314)
		(end 302.937418 -24.226266)
		(stroke
			(width 0.2)
			(type default)
		)
		(layer "In3.Cu")
	)
	(gr_line
		(start 302.187356 -21.82622)
		(end 302.937418 -20.426426)
		(stroke
			(width 0.2)
			(type default)
		)
		(layer "In3.Cu")
	)
	(gr_line
		(start 302.187356 -18.02638)
		(end 302.937418 -16.626586)
		(stroke
			(width 0.2)
			(type default)
		)
		(layer "In3.Cu")
	)
	(gr_line
		(start 302.187356 -14.226286)
		(end 302.937418 -12.826238)
		(stroke
			(width 0.2)
			(type default)
		)
		(layer "In3.Cu")
	)
	(gr_arc
		(start 302.471836 -35.536886)
		(mid 302.98263 -35.026473)
		(end 302.47209 -34.515806)
		(stroke
			(width 0.2)
			(type default)
		)
		(layer "In3.Cu")
	)
	(gr_line
		(start 302.47209 -34.515806)
		(end 301.65929 -34.515806)
		(stroke
			(width 0.2)
			(type default)
		)
		(layer "In3.Cu")
	)
	(gr_arc
		(start 302.90643 -211.406994)
		(mid 303.41697 -210.896454)
		(end 302.90643 -210.385914)
		(stroke
			(width 0.2)
			(type default)
		)
		(layer "In3.Cu")
	)
	(gr_line
		(start 302.90643 -210.385914)
		(end 302.093884 -210.385914)
		(stroke
			(width 0.2)
			(type default)
		)
		(layer "In3.Cu")
	)
	(gr_arc
		(start 302.935132 -20.425156)
		(mid 302.679456 -19.579255)
		(end 301.833534 -19.835114)
		(stroke
			(width 0.2)
			(type default)
		)
		(layer "In3.Cu")
	)
	(gr_arc
		(start 302.935132 -16.625316)
		(mid 302.679608 -15.779496)
		(end 301.833788 -16.03502)
		(stroke
			(width 0.2)
			(type default)
		)
		(layer "In3.Cu")
	)
	(gr_arc
		(start 302.935386 -24.224996)
		(mid 302.679354 -23.379176)
		(end 301.833534 -23.635208)
		(stroke
			(width 0.2)
			(type default)
		)
		(layer "In3.Cu")
	)
	(gr_arc
		(start 302.935386 -12.824968)
		(mid 302.679354 -11.979148)
		(end 301.833534 -12.23518)
		(stroke
			(width 0.2)
			(type default)
		)
		(layer "In3.Cu")
	)
	(gr_line
		(start 302.937164 -20.426172)
		(end 302.935132 -20.425156)
		(stroke
			(width 0.2)
			(type default)
		)
		(layer "In3.Cu")
	)
	(gr_line
		(start 302.937418 -24.226266)
		(end 302.935386 -24.224996)
		(stroke
			(width 0.2)
			(type default)
		)
		(layer "In3.Cu")
	)
	(gr_line
		(start 302.937418 -20.426426)
		(end 302.937164 -20.426172)
		(stroke
			(width 0.2)
			(type default)
		)
		(layer "In3.Cu")
	)
	(gr_line
		(start 302.937418 -16.626586)
		(end 302.935132 -16.625316)
		(stroke
			(width 0.2)
			(type default)
		)
		(layer "In3.Cu")
	)
	(gr_line
		(start 302.937418 -12.826238)
		(end 302.935386 -12.824968)
		(stroke
			(width 0.2)
			(type default)
		)
		(layer "In3.Cu")
	)
	(gr_arc
		(start 303.717198 -219.783914)
		(mid 303.222914 -220.310202)
		(end 303.749202 -220.804486)
		(stroke
			(width 0.2)
			(type default)
		)
		(layer "In3.Cu")
	)
	(gr_line
		(start 303.717198 -219.781374)
		(end 303.717198 -219.783914)
		(stroke
			(width 0.2)
			(type default)
		)
		(layer "In3.Cu")
	)
	(gr_line
		(start 303.749202 -220.807026)
		(end 304.561748 -220.781626)
		(stroke
			(width 0.2)
			(type default)
		)
		(layer "In3.Cu")
	)
	(gr_line
		(start 303.749202 -220.804486)
		(end 303.749202 -220.807026)
		(stroke
			(width 0.2)
			(type default)
		)
		(layer "In3.Cu")
	)
	(gr_line
		(start 303.8348 -36.794694)
		(end 304.647346 -36.794694)
		(stroke
			(width 0.2)
			(type default)
		)
		(layer "In3.Cu")
	)
	(gr_arc
		(start 303.8348 -35.773614)
		(mid 303.32426 -36.284154)
		(end 303.8348 -36.794694)
		(stroke
			(width 0.2)
			(type default)
		)
		(layer "In3.Cu")
	)
	(gr_line
		(start 304.529998 -219.758514)
		(end 304.529998 -219.755974)
		(stroke
			(width 0.2)
			(type default)
		)
		(layer "In3.Cu")
	)
	(gr_line
		(start 304.529998 -219.755974)
		(end 303.717198 -219.781374)
		(stroke
			(width 0.2)
			(type default)
		)
		(layer "In3.Cu")
	)
	(gr_line
		(start 304.561748 -220.781626)
		(end 304.562002 -220.781372)
		(stroke
			(width 0.2)
			(type default)
		)
		(layer "In3.Cu")
	)
	(gr_line
		(start 304.562002 -220.781372)
		(end 304.562002 -220.779086)
		(stroke
			(width 0.2)
			(type default)
		)
		(layer "In3.Cu")
	)
	(gr_arc
		(start 304.562002 -220.779086)
		(mid 305.056286 -220.252798)
		(end 304.529998 -219.758514)
		(stroke
			(width 0.2)
			(type default)
		)
		(layer "In3.Cu")
	)
	(gr_arc
		(start 304.647346 -36.794694)
		(mid 305.15814 -36.284281)
		(end 304.6476 -35.773614)
		(stroke
			(width 0.2)
			(type default)
		)
		(layer "In3.Cu")
	)
	(gr_line
		(start 304.6476 -35.773614)
		(end 303.8348 -35.773614)
		(stroke
			(width 0.2)
			(type default)
		)
		(layer "In3.Cu")
	)
	(gr_line
		(start 305.762914 -40.31996)
		(end 306.57546 -40.31996)
		(stroke
			(width 0.2)
			(type default)
		)
		(layer "In3.Cu")
	)
	(gr_arc
		(start 305.762914 -39.29888)
		(mid 305.252374 -39.80942)
		(end 305.762914 -40.31996)
		(stroke
			(width 0.2)
			(type default)
		)
		(layer "In3.Cu")
	)
	(gr_line
		(start 306.099972 -228.000052)
		(end 260.500114 -228.000052)
		(stroke
			(width 5.08)
			(type default)
		)
		(layer "In3.Cu")
	)
	(gr_line
		(start 306.099972 -222.600012)
		(end 306.099972 -228.000052)
		(stroke
			(width 1.524)
			(type default)
		)
		(layer "In3.Cu")
	)
	(gr_arc
		(start 306.57546 -40.31996)
		(mid 307.086254 -39.809547)
		(end 306.575714 -39.29888)
		(stroke
			(width 0.2)
			(type default)
		)
		(layer "In3.Cu")
	)
	(gr_line
		(start 306.575714 -39.29888)
		(end 305.762914 -39.29888)
		(stroke
			(width 0.2)
			(type default)
		)
		(layer "In3.Cu")
	)
	(gr_arc
		(start 307.583586 -25.035256)
		(mid 307.839618 -25.881076)
		(end 308.685438 -25.625044)
		(stroke
			(width 0.2)
			(type default)
		)
		(layer "In3.Cu")
	)
	(gr_arc
		(start 307.58765 -13.627608)
		(mid 307.835784 -14.479061)
		(end 308.685438 -14.225016)
		(stroke
			(width 0.2)
			(type default)
		)
		(layer "In3.Cu")
	)
	(gr_line
		(start 308.333394 -23.635208)
		(end 307.583586 -25.035256)
		(stroke
			(width 0.2)
			(type default)
		)
		(layer "In3.Cu")
	)
	(gr_line
		(start 308.333394 -12.23518)
		(end 307.58765 -13.627608)
		(stroke
			(width 0.2)
			(type default)
		)
		(layer "In3.Cu")
	)
	(gr_line
		(start 308.500018 -228.000052)
		(end 308.500018 -222.600012)
		(stroke
			(width 1.524)
			(type default)
		)
		(layer "In3.Cu")
	)
	(gr_arc
		(start 308.500018 -222.600012)
		(mid 307.300122 -221.400116)
		(end 306.099972 -222.600012)
		(stroke
			(width 1.524)
			(type default)
		)
		(layer "In3.Cu")
	)
	(gr_line
		(start 308.685438 -25.625044)
		(end 309.431182 -24.232616)
		(stroke
			(width 0.2)
			(type default)
		)
		(layer "In3.Cu")
	)
	(gr_line
		(start 308.685438 -14.225016)
		(end 309.435246 -12.824968)
		(stroke
			(width 0.2)
			(type default)
		)
		(layer "In3.Cu")
	)
	(gr_line
		(start 309.245 -73.66)
		(end 285.496 -73.66)
		(stroke
			(width 0.381)
			(type default)
		)
		(layer "In3.Cu")
	)
	(gr_arc
		(start 309.431182 -24.232616)
		(mid 309.183048 -23.381163)
		(end 308.333394 -23.635208)
		(stroke
			(width 0.2)
			(type default)
		)
		(layer "In3.Cu")
	)
	(gr_arc
		(start 309.435246 -12.824968)
		(mid 309.179214 -11.979148)
		(end 308.333394 -12.23518)
		(stroke
			(width 0.2)
			(type default)
		)
		(layer "In3.Cu")
	)
	(gr_line
		(start 309.831486 -25.033732)
		(end 309.83174 -25.033986)
		(stroke
			(width 0.2)
			(type default)
		)
		(layer "In3.Cu")
	)
	(gr_line
		(start 309.831486 -21.233892)
		(end 309.833518 -21.235162)
		(stroke
			(width 0.2)
			(type default)
		)
		(layer "In3.Cu")
	)
	(gr_line
		(start 309.831486 -17.433544)
		(end 309.83174 -17.433798)
		(stroke
			(width 0.2)
			(type default)
		)
		(layer "In3.Cu")
	)
	(gr_line
		(start 309.831486 -13.633704)
		(end 309.83174 -13.633958)
		(stroke
			(width 0.2)
			(type default)
		)
		(layer "In3.Cu")
	)
	(gr_line
		(start 309.83174 -25.033986)
		(end 309.833772 -25.035002)
		(stroke
			(width 0.2)
			(type default)
		)
		(layer "In3.Cu")
	)
	(gr_line
		(start 309.83174 -17.433798)
		(end 309.833772 -17.434814)
		(stroke
			(width 0.2)
			(type default)
		)
		(layer "In3.Cu")
	)
	(gr_line
		(start 309.83174 -13.633958)
		(end 309.833772 -13.634974)
		(stroke
			(width 0.2)
			(type default)
		)
		(layer "In3.Cu")
	)
	(gr_arc
		(start 309.833518 -21.235162)
		(mid 310.08955 -22.080982)
		(end 310.93537 -21.82495)
		(stroke
			(width 0.2)
			(type default)
		)
		(layer "In3.Cu")
	)
	(gr_arc
		(start 309.833772 -25.035002)
		(mid 310.089448 -25.880903)
		(end 310.93537 -25.625044)
		(stroke
			(width 0.2)
			(type default)
		)
		(layer "In3.Cu")
	)
	(gr_arc
		(start 309.833772 -17.434814)
		(mid 310.089296 -18.280634)
		(end 310.935116 -18.02511)
		(stroke
			(width 0.2)
			(type default)
		)
		(layer "In3.Cu")
	)
	(gr_arc
		(start 309.833772 -13.634974)
		(mid 310.089448 -14.480875)
		(end 310.93537 -14.225016)
		(stroke
			(width 0.2)
			(type default)
		)
		(layer "In3.Cu")
	)
	(gr_line
		(start 310.093868 -211.406994)
		(end 310.906414 -211.406994)
		(stroke
			(width 0.2)
			(type default)
		)
		(layer "In3.Cu")
	)
	(gr_arc
		(start 310.093868 -210.385914)
		(mid 309.583328 -210.896454)
		(end 310.093868 -211.406994)
		(stroke
			(width 0.2)
			(type default)
		)
		(layer "In3.Cu")
	)
	(gr_line
		(start 310.134 -72.771)
		(end 309.245 -73.66)
		(stroke
			(width 0.381)
			(type default)
		)
		(layer "In3.Cu")
	)
	(gr_line
		(start 310.134 -68.453)
		(end 310.134 -72.771)
		(stroke
			(width 0.381)
			(type default)
		)
		(layer "In3.Cu")
	)
	(gr_line
		(start 310.134 -68.453)
		(end 310.134 -54.991)
		(stroke
			(width 0.381)
			(type default)
		)
		(layer "In3.Cu")
	)
	(gr_line
		(start 310.134 -54.991)
		(end 324.866 -54.991)
		(stroke
			(width 0.381)
			(type default)
		)
		(layer "In3.Cu")
	)
	(gr_line
		(start 310.134 -50.8)
		(end 310.134 -54.991)
		(stroke
			(width 0.381)
			(type default)
		)
		(layer "In3.Cu")
	)
	(gr_line
		(start 310.20766 -68.93052)
		(end 310.67502 -68.46316)
		(stroke
			(width 0.3048)
			(type default)
		)
		(layer "In3.Cu")
	)
	(gr_line
		(start 310.21401 -55.50662)
		(end 310.68137 -55.03926)
		(stroke
			(width 0.3048)
			(type default)
		)
		(layer "In3.Cu")
	)
	(gr_line
		(start 310.425592 -35.55238)
		(end 311.238138 -35.55238)
		(stroke
			(width 0.2)
			(type default)
		)
		(layer "In3.Cu")
	)
	(gr_arc
		(start 310.425592 -34.5313)
		(mid 309.915052 -35.04184)
		(end 310.425592 -35.55238)
		(stroke
			(width 0.2)
			(type default)
		)
		(layer "In3.Cu")
	)
	(gr_line
		(start 310.581548 -23.633938)
		(end 309.831486 -25.033732)
		(stroke
			(width 0.2)
			(type default)
		)
		(layer "In3.Cu")
	)
	(gr_line
		(start 310.581548 -19.833844)
		(end 309.831486 -21.233892)
		(stroke
			(width 0.2)
			(type default)
		)
		(layer "In3.Cu")
	)
	(gr_line
		(start 310.581548 -16.03375)
		(end 309.831486 -17.433544)
		(stroke
			(width 0.2)
			(type default)
		)
		(layer "In3.Cu")
	)
	(gr_line
		(start 310.581548 -12.23391)
		(end 309.831486 -13.633704)
		(stroke
			(width 0.2)
			(type default)
		)
		(layer "In3.Cu")
	)
	(gr_line
		(start 310.58358 -23.635208)
		(end 310.581548 -23.633938)
		(stroke
			(width 0.2)
			(type default)
		)
		(layer "In3.Cu")
	)
	(gr_line
		(start 310.58358 -19.835114)
		(end 310.581548 -19.833844)
		(stroke
			(width 0.2)
			(type default)
		)
		(layer "In3.Cu")
	)
	(gr_line
		(start 310.58358 -12.23518)
		(end 310.581548 -12.23391)
		(stroke
			(width 0.2)
			(type default)
		)
		(layer "In3.Cu")
	)
	(gr_line
		(start 310.583834 -16.03502)
		(end 310.581548 -16.03375)
		(stroke
			(width 0.2)
			(type default)
		)
		(layer "In3.Cu")
	)
	(gr_line
		(start 310.67502 -68.46316)
		(end 310.67502 -68.45046)
		(stroke
			(width 0.3048)
			(type default)
		)
		(layer "In3.Cu")
	)
	(gr_line
		(start 310.67502 -68.45046)
		(end 310.14924 -67.92468)
		(stroke
			(width 0.3048)
			(type default)
		)
		(layer "In3.Cu")
	)
	(gr_line
		(start 310.68137 -55.03926)
		(end 310.68137 -55.02656)
		(stroke
			(width 0.3048)
			(type default)
		)
		(layer "In3.Cu")
	)
	(gr_line
		(start 310.68137 -55.02656)
		(end 310.15559 -54.50078)
		(stroke
			(width 0.3048)
			(type default)
		)
		(layer "In3.Cu")
	)
	(gr_arc
		(start 310.906414 -211.406994)
		(mid 311.417208 -210.896581)
		(end 310.906668 -210.385914)
		(stroke
			(width 0.2)
			(type default)
		)
		(layer "In3.Cu")
	)
	(gr_line
		(start 310.906668 -210.385914)
		(end 310.093868 -210.385914)
		(stroke
			(width 0.2)
			(type default)
		)
		(layer "In3.Cu")
	)
	(gr_line
		(start 310.935116 -18.02511)
		(end 310.937402 -18.02638)
		(stroke
			(width 0.2)
			(type default)
		)
		(layer "In3.Cu")
	)
	(gr_line
		(start 310.93537 -25.625044)
		(end 310.937402 -25.626314)
		(stroke
			(width 0.2)
			(type default)
		)
		(layer "In3.Cu")
	)
	(gr_line
		(start 310.93537 -21.82495)
		(end 310.937402 -21.82622)
		(stroke
			(width 0.2)
			(type default)
		)
		(layer "In3.Cu")
	)
	(gr_line
		(start 310.93537 -14.225016)
		(end 310.937402 -14.226286)
		(stroke
			(width 0.2)
			(type default)
		)
		(layer "In3.Cu")
	)
	(gr_line
		(start 310.937402 -25.626314)
		(end 311.687464 -24.226266)
		(stroke
			(width 0.2)
			(type default)
		)
		(layer "In3.Cu")
	)
	(gr_line
		(start 310.937402 -21.82622)
		(end 311.687464 -20.426426)
		(stroke
			(width 0.2)
			(type default)
		)
		(layer "In3.Cu")
	)
	(gr_line
		(start 310.937402 -18.02638)
		(end 311.687464 -16.626586)
		(stroke
			(width 0.2)
			(type default)
		)
		(layer "In3.Cu")
	)
	(gr_line
		(start 310.937402 -14.226286)
		(end 311.687464 -12.826238)
		(stroke
			(width 0.2)
			(type default)
		)
		(layer "In3.Cu")
	)
	(gr_arc
		(start 311.238138 -35.55238)
		(mid 311.748932 -35.041967)
		(end 311.238392 -34.5313)
		(stroke
			(width 0.2)
			(type default)
		)
		(layer "In3.Cu")
	)
	(gr_line
		(start 311.238392 -34.5313)
		(end 310.425592 -34.5313)
		(stroke
			(width 0.2)
			(type default)
		)
		(layer "In3.Cu")
	)
	(gr_arc
		(start 311.685178 -20.425156)
		(mid 311.429502 -19.579255)
		(end 310.58358 -19.835114)
		(stroke
			(width 0.2)
			(type default)
		)
		(layer "In3.Cu")
	)
	(gr_arc
		(start 311.685178 -16.625316)
		(mid 311.429654 -15.779496)
		(end 310.583834 -16.03502)
		(stroke
			(width 0.2)
			(type default)
		)
		(layer "In3.Cu")
	)
	(gr_arc
		(start 311.685432 -24.224996)
		(mid 311.4294 -23.379176)
		(end 310.58358 -23.635208)
		(stroke
			(width 0.2)
			(type default)
		)
		(layer "In3.Cu")
	)
	(gr_arc
		(start 311.685432 -12.824968)
		(mid 311.4294 -11.979148)
		(end 310.58358 -12.23518)
		(stroke
			(width 0.2)
			(type default)
		)
		(layer "In3.Cu")
	)
	(gr_line
		(start 311.68721 -20.426172)
		(end 311.685178 -20.425156)
		(stroke
			(width 0.2)
			(type default)
		)
		(layer "In3.Cu")
	)
	(gr_line
		(start 311.687464 -24.226266)
		(end 311.685432 -24.224996)
		(stroke
			(width 0.2)
			(type default)
		)
		(layer "In3.Cu")
	)
	(gr_line
		(start 311.687464 -20.426426)
		(end 311.68721 -20.426172)
		(stroke
			(width 0.2)
			(type default)
		)
		(layer "In3.Cu")
	)
	(gr_line
		(start 311.687464 -16.626586)
		(end 311.685178 -16.625316)
		(stroke
			(width 0.2)
			(type default)
		)
		(layer "In3.Cu")
	)
	(gr_line
		(start 311.687464 -12.826238)
		(end 311.685432 -12.824968)
		(stroke
			(width 0.2)
			(type default)
		)
		(layer "In3.Cu")
	)
	(gr_line
		(start 311.69356 -222.805244)
		(end 312.506106 -222.805244)
		(stroke
			(width 0.2)
			(type default)
		)
		(layer "In3.Cu")
	)
	(gr_arc
		(start 311.69356 -221.784164)
		(mid 311.18302 -222.294704)
		(end 311.69356 -222.805244)
		(stroke
			(width 0.2)
			(type default)
		)
		(layer "In3.Cu")
	)
	(gr_line
		(start 312.081418 -25.033732)
		(end 312.081672 -25.033986)
		(stroke
			(width 0.2)
			(type default)
		)
		(layer "In3.Cu")
	)
	(gr_line
		(start 312.081418 -21.233892)
		(end 312.08345 -21.235162)
		(stroke
			(width 0.2)
			(type default)
		)
		(layer "In3.Cu")
	)
	(gr_line
		(start 312.081418 -17.433544)
		(end 312.081672 -17.433798)
		(stroke
			(width 0.2)
			(type default)
		)
		(layer "In3.Cu")
	)
	(gr_line
		(start 312.081418 -13.633704)
		(end 312.081672 -13.633958)
		(stroke
			(width 0.2)
			(type default)
		)
		(layer "In3.Cu")
	)
	(gr_line
		(start 312.081672 -25.033986)
		(end 312.083704 -25.035002)
		(stroke
			(width 0.2)
			(type default)
		)
		(layer "In3.Cu")
	)
	(gr_line
		(start 312.081672 -17.433798)
		(end 312.083704 -17.434814)
		(stroke
			(width 0.2)
			(type default)
		)
		(layer "In3.Cu")
	)
	(gr_line
		(start 312.081672 -13.633958)
		(end 312.083704 -13.634974)
		(stroke
			(width 0.2)
			(type default)
		)
		(layer "In3.Cu")
	)
	(gr_arc
		(start 312.08345 -21.235162)
		(mid 312.339482 -22.080982)
		(end 313.185302 -21.82495)
		(stroke
			(width 0.2)
			(type default)
		)
		(layer "In3.Cu")
	)
	(gr_arc
		(start 312.083704 -25.035002)
		(mid 312.33938 -25.880903)
		(end 313.185302 -25.625044)
		(stroke
			(width 0.2)
			(type default)
		)
		(layer "In3.Cu")
	)
	(gr_arc
		(start 312.083704 -17.434814)
		(mid 312.339228 -18.280634)
		(end 313.185048 -18.02511)
		(stroke
			(width 0.2)
			(type default)
		)
		(layer "In3.Cu")
	)
	(gr_arc
		(start 312.083704 -13.634974)
		(mid 312.33938 -14.480875)
		(end 313.185302 -14.225016)
		(stroke
			(width 0.2)
			(type default)
		)
		(layer "In3.Cu")
	)
	(gr_arc
		(start 312.506106 -222.805244)
		(mid 313.0169 -222.294831)
		(end 312.50636 -221.784164)
		(stroke
			(width 0.2)
			(type default)
		)
		(layer "In3.Cu")
	)
	(gr_line
		(start 312.50636 -221.784164)
		(end 311.69356 -221.784164)
		(stroke
			(width 0.2)
			(type default)
		)
		(layer "In3.Cu")
	)
	(gr_line
		(start 312.676286 -36.696142)
		(end 313.489086 -36.696142)
		(stroke
			(width 0.2)
			(type default)
		)
		(layer "In3.Cu")
	)
	(gr_arc
		(start 312.67654 -35.675062)
		(mid 312.165746 -36.185475)
		(end 312.676286 -36.696142)
		(stroke
			(width 0.2)
			(type default)
		)
		(layer "In3.Cu")
	)
	(gr_line
		(start 312.83148 -23.633938)
		(end 312.081418 -25.033732)
		(stroke
			(width 0.2)
			(type default)
		)
		(layer "In3.Cu")
	)
	(gr_line
		(start 312.83148 -19.833844)
		(end 312.081418 -21.233892)
		(stroke
			(width 0.2)
			(type default)
		)
		(layer "In3.Cu")
	)
	(gr_line
		(start 312.83148 -16.03375)
		(end 312.081418 -17.433544)
		(stroke
			(width 0.2)
			(type default)
		)
		(layer "In3.Cu")
	)
	(gr_line
		(start 312.83148 -12.23391)
		(end 312.081418 -13.633704)
		(stroke
			(width 0.2)
			(type default)
		)
		(layer "In3.Cu")
	)
	(gr_line
		(start 312.833512 -23.635208)
		(end 312.83148 -23.633938)
		(stroke
			(width 0.2)
			(type default)
		)
		(layer "In3.Cu")
	)
	(gr_line
		(start 312.833512 -19.835114)
		(end 312.83148 -19.833844)
		(stroke
			(width 0.2)
			(type default)
		)
		(layer "In3.Cu")
	)
	(gr_line
		(start 312.833512 -12.23518)
		(end 312.83148 -12.23391)
		(stroke
			(width 0.2)
			(type default)
		)
		(layer "In3.Cu")
	)
	(gr_line
		(start 312.833766 -16.03502)
		(end 312.83148 -16.03375)
		(stroke
			(width 0.2)
			(type default)
		)
		(layer "In3.Cu")
	)
	(gr_line
		(start 313.185048 -18.02511)
		(end 313.187334 -18.02638)
		(stroke
			(width 0.2)
			(type default)
		)
		(layer "In3.Cu")
	)
	(gr_line
		(start 313.185302 -25.625044)
		(end 313.187334 -25.626314)
		(stroke
			(width 0.2)
			(type default)
		)
		(layer "In3.Cu")
	)
	(gr_line
		(start 313.185302 -21.82495)
		(end 313.187334 -21.82622)
		(stroke
			(width 0.2)
			(type default)
		)
		(layer "In3.Cu")
	)
	(gr_line
		(start 313.185302 -14.225016)
		(end 313.187334 -14.226286)
		(stroke
			(width 0.2)
			(type default)
		)
		(layer "In3.Cu")
	)
	(gr_line
		(start 313.187334 -25.626314)
		(end 313.937396 -24.226266)
		(stroke
			(width 0.2)
			(type default)
		)
		(layer "In3.Cu")
	)
	(gr_line
		(start 313.187334 -21.82622)
		(end 313.937396 -20.426426)
		(stroke
			(width 0.2)
			(type default)
		)
		(layer "In3.Cu")
	)
	(gr_line
		(start 313.187334 -18.02638)
		(end 313.937396 -16.626586)
		(stroke
			(width 0.2)
			(type default)
		)
		(layer "In3.Cu")
	)
	(gr_line
		(start 313.187334 -14.226286)
		(end 313.937396 -12.826238)
		(stroke
			(width 0.2)
			(type default)
		)
		(layer "In3.Cu")
	)
	(gr_line
		(start 313.29376 -211.406994)
		(end 314.10656 -211.406994)
		(stroke
			(width 0.2)
			(type default)
		)
		(layer "In3.Cu")
	)
	(gr_arc
		(start 313.294014 -210.385914)
		(mid 312.78322 -210.896327)
		(end 313.29376 -211.406994)
		(stroke
			(width 0.2)
			(type default)
		)
		(layer "In3.Cu")
	)
	(gr_arc
		(start 313.489086 -36.696142)
		(mid 313.999626 -36.185602)
		(end 313.489086 -35.675062)
		(stroke
			(width 0.2)
			(type default)
		)
		(layer "In3.Cu")
	)
	(gr_line
		(start 313.489086 -35.675062)
		(end 312.67654 -35.675062)
		(stroke
			(width 0.2)
			(type default)
		)
		(layer "In3.Cu")
	)
	(gr_arc
		(start 313.93511 -20.425156)
		(mid 313.679434 -19.579255)
		(end 312.833512 -19.835114)
		(stroke
			(width 0.2)
			(type default)
		)
		(layer "In3.Cu")
	)
	(gr_arc
		(start 313.93511 -16.625316)
		(mid 313.679586 -15.779496)
		(end 312.833766 -16.03502)
		(stroke
			(width 0.2)
			(type default)
		)
		(layer "In3.Cu")
	)
	(gr_arc
		(start 313.935364 -24.224996)
		(mid 313.679332 -23.379176)
		(end 312.833512 -23.635208)
		(stroke
			(width 0.2)
			(type default)
		)
		(layer "In3.Cu")
	)
	(gr_arc
		(start 313.935364 -12.824968)
		(mid 313.679332 -11.979148)
		(end 312.833512 -12.23518)
		(stroke
			(width 0.2)
			(type default)
		)
		(layer "In3.Cu")
	)
	(gr_line
		(start 313.937142 -20.426172)
		(end 313.93511 -20.425156)
		(stroke
			(width 0.2)
			(type default)
		)
		(layer "In3.Cu")
	)
	(gr_line
		(start 313.937396 -24.226266)
		(end 313.935364 -24.224996)
		(stroke
			(width 0.2)
			(type default)
		)
		(layer "In3.Cu")
	)
	(gr_line
		(start 313.937396 -20.426426)
		(end 313.937142 -20.426172)
		(stroke
			(width 0.2)
			(type default)
		)
		(layer "In3.Cu")
	)
	(gr_line
		(start 313.937396 -16.626586)
		(end 313.93511 -16.625316)
		(stroke
			(width 0.2)
			(type default)
		)
		(layer "In3.Cu")
	)
	(gr_line
		(start 313.937396 -12.826238)
		(end 313.935364 -12.824968)
		(stroke
			(width 0.2)
			(type default)
		)
		(layer "In3.Cu")
	)
	(gr_arc
		(start 314.10656 -211.406994)
		(mid 314.6171 -210.896454)
		(end 314.10656 -210.385914)
		(stroke
			(width 0.2)
			(type default)
		)
		(layer "In3.Cu")
	)
	(gr_line
		(start 314.10656 -210.385914)
		(end 313.294014 -210.385914)
		(stroke
			(width 0.2)
			(type default)
		)
		(layer "In3.Cu")
	)
	(gr_line
		(start 314.8838 -35.524694)
		(end 315.696346 -35.524694)
		(stroke
			(width 0.2)
			(type default)
		)
		(layer "In3.Cu")
	)
	(gr_arc
		(start 314.8838 -34.503614)
		(mid 314.37326 -35.014154)
		(end 314.8838 -35.524694)
		(stroke
			(width 0.2)
			(type default)
		)
		(layer "In3.Cu")
	)
	(gr_line
		(start 314.893706 -222.805244)
		(end 315.706252 -222.805244)
		(stroke
			(width 0.2)
			(type default)
		)
		(layer "In3.Cu")
	)
	(gr_arc
		(start 314.893706 -221.784164)
		(mid 314.383166 -222.294704)
		(end 314.893706 -222.805244)
		(stroke
			(width 0.2)
			(type default)
		)
		(layer "In3.Cu")
	)
	(gr_arc
		(start 315.696346 -35.524694)
		(mid 316.20714 -35.014281)
		(end 315.6966 -34.503614)
		(stroke
			(width 0.2)
			(type default)
		)
		(layer "In3.Cu")
	)
	(gr_line
		(start 315.6966 -34.503614)
		(end 314.8838 -34.503614)
		(stroke
			(width 0.2)
			(type default)
		)
		(layer "In3.Cu")
	)
	(gr_arc
		(start 315.706252 -222.805244)
		(mid 316.217046 -222.294831)
		(end 315.706506 -221.784164)
		(stroke
			(width 0.2)
			(type default)
		)
		(layer "In3.Cu")
	)
	(gr_line
		(start 315.706506 -221.784164)
		(end 314.893706 -221.784164)
		(stroke
			(width 0.2)
			(type default)
		)
		(layer "In3.Cu")
	)
	(gr_line
		(start 316.493906 -211.406994)
		(end 317.306706 -211.406994)
		(stroke
			(width 0.2)
			(type default)
		)
		(layer "In3.Cu")
	)
	(gr_arc
		(start 316.49416 -210.385914)
		(mid 315.983366 -210.896327)
		(end 316.493906 -211.406994)
		(stroke
			(width 0.2)
			(type default)
		)
		(layer "In3.Cu")
	)
	(gr_arc
		(start 317.306706 -211.406994)
		(mid 317.817246 -210.896454)
		(end 317.306706 -210.385914)
		(stroke
			(width 0.2)
			(type default)
		)
		(layer "In3.Cu")
	)
	(gr_line
		(start 317.306706 -210.385914)
		(end 316.49416 -210.385914)
		(stroke
			(width 0.2)
			(type default)
		)
		(layer "In3.Cu")
	)
	(gr_line
		(start 318.093598 -222.805244)
		(end 318.906144 -222.805244)
		(stroke
			(width 0.2)
			(type default)
		)
		(layer "In3.Cu")
	)
	(gr_arc
		(start 318.093598 -221.784164)
		(mid 317.583058 -222.294704)
		(end 318.093598 -222.805244)
		(stroke
			(width 0.2)
			(type default)
		)
		(layer "In3.Cu")
	)
	(gr_arc
		(start 318.583564 -25.035256)
		(mid 318.839596 -25.881076)
		(end 319.685416 -25.625044)
		(stroke
			(width 0.2)
			(type default)
		)
		(layer "In3.Cu")
	)
	(gr_arc
		(start 318.587628 -13.627608)
		(mid 318.835762 -14.479061)
		(end 319.685416 -14.225016)
		(stroke
			(width 0.2)
			(type default)
		)
		(layer "In3.Cu")
	)
	(gr_arc
		(start 318.906144 -222.805244)
		(mid 319.416938 -222.294831)
		(end 318.906398 -221.784164)
		(stroke
			(width 0.2)
			(type default)
		)
		(layer "In3.Cu")
	)
	(gr_line
		(start 318.906398 -221.784164)
		(end 318.093598 -221.784164)
		(stroke
			(width 0.2)
			(type default)
		)
		(layer "In3.Cu")
	)
	(gr_line
		(start 319.333372 -23.635208)
		(end 318.583564 -25.035256)
		(stroke
			(width 0.2)
			(type default)
		)
		(layer "In3.Cu")
	)
	(gr_line
		(start 319.333372 -12.23518)
		(end 318.587628 -13.627608)
		(stroke
			(width 0.2)
			(type default)
		)
		(layer "In3.Cu")
	)
	(gr_line
		(start 319.685416 -25.625044)
		(end 320.43116 -24.232616)
		(stroke
			(width 0.2)
			(type default)
		)
		(layer "In3.Cu")
	)
	(gr_line
		(start 319.685416 -14.225016)
		(end 320.435224 -12.824968)
		(stroke
			(width 0.2)
			(type default)
		)
		(layer "In3.Cu")
	)
	(gr_line
		(start 319.693798 -211.406994)
		(end 320.506598 -211.406994)
		(stroke
			(width 0.2)
			(type default)
		)
		(layer "In3.Cu")
	)
	(gr_arc
		(start 319.694052 -210.385914)
		(mid 319.183258 -210.896327)
		(end 319.693798 -211.406994)
		(stroke
			(width 0.2)
			(type default)
		)
		(layer "In3.Cu")
	)
	(gr_line
		(start 319.720976 -37.53612)
		(end 320.533522 -37.53612)
		(stroke
			(width 0.2)
			(type default)
		)
		(layer "In3.Cu")
	)
	(gr_line
		(start 319.720976 -37.53612)
		(end 320.533776 -37.53612)
		(stroke
			(width 0.2)
			(type default)
		)
		(layer "In3.Cu")
	)
	(gr_arc
		(start 319.720976 -36.51504)
		(mid 319.210436 -37.02558)
		(end 319.720976 -37.53612)
		(stroke
			(width 0.2)
			(type default)
		)
		(layer "In3.Cu")
	)
	(gr_arc
		(start 319.72123 -36.51504)
		(mid 319.210436 -37.025453)
		(end 319.720976 -37.53612)
		(stroke
			(width 0.2)
			(type default)
		)
		(layer "In3.Cu")
	)
	(gr_arc
		(start 320.43116 -24.232616)
		(mid 320.183026 -23.381163)
		(end 319.333372 -23.635208)
		(stroke
			(width 0.2)
			(type default)
		)
		(layer "In3.Cu")
	)
	(gr_arc
		(start 320.435224 -12.824968)
		(mid 320.179192 -11.979148)
		(end 319.333372 -12.23518)
		(stroke
			(width 0.2)
			(type default)
		)
		(layer "In3.Cu")
	)
	(gr_arc
		(start 320.506598 -211.406994)
		(mid 321.017138 -210.896454)
		(end 320.506598 -210.385914)
		(stroke
			(width 0.2)
			(type default)
		)
		(layer "In3.Cu")
	)
	(gr_line
		(start 320.506598 -210.385914)
		(end 319.694052 -210.385914)
		(stroke
			(width 0.2)
			(type default)
		)
		(layer "In3.Cu")
	)
	(gr_arc
		(start 320.533522 -37.53612)
		(mid 321.044316 -37.025707)
		(end 320.533776 -36.51504)
		(stroke
			(width 0.2)
			(type default)
		)
		(layer "In3.Cu")
	)
	(gr_arc
		(start 320.533776 -37.53612)
		(mid 321.044316 -37.02558)
		(end 320.533776 -36.51504)
		(stroke
			(width 0.2)
			(type default)
		)
		(layer "In3.Cu")
	)
	(gr_line
		(start 320.533776 -36.51504)
		(end 319.720976 -36.51504)
		(stroke
			(width 0.2)
			(type default)
		)
		(layer "In3.Cu")
	)
	(gr_line
		(start 320.533776 -36.51504)
		(end 319.72123 -36.51504)
		(stroke
			(width 0.2)
			(type default)
		)
		(layer "In3.Cu")
	)
	(gr_line
		(start 320.831464 -25.033732)
		(end 320.831718 -25.033986)
		(stroke
			(width 0.2)
			(type default)
		)
		(layer "In3.Cu")
	)
	(gr_line
		(start 320.831464 -21.233892)
		(end 320.833496 -21.235162)
		(stroke
			(width 0.2)
			(type default)
		)
		(layer "In3.Cu")
	)
	(gr_line
		(start 320.831464 -17.433544)
		(end 320.831718 -17.433798)
		(stroke
			(width 0.2)
			(type default)
		)
		(layer "In3.Cu")
	)
	(gr_line
		(start 320.831464 -13.633704)
		(end 320.831718 -13.633958)
		(stroke
			(width 0.2)
			(type default)
		)
		(layer "In3.Cu")
	)
	(gr_line
		(start 320.831718 -25.033986)
		(end 320.83375 -25.035002)
		(stroke
			(width 0.2)
			(type default)
		)
		(layer "In3.Cu")
	)
	(gr_line
		(start 320.831718 -17.433798)
		(end 320.83375 -17.434814)
		(stroke
			(width 0.2)
			(type default)
		)
		(layer "In3.Cu")
	)
	(gr_line
		(start 320.831718 -13.633958)
		(end 320.83375 -13.634974)
		(stroke
			(width 0.2)
			(type default)
		)
		(layer "In3.Cu")
	)
	(gr_arc
		(start 320.833496 -21.235162)
		(mid 321.089528 -22.080982)
		(end 321.935348 -21.82495)
		(stroke
			(width 0.2)
			(type default)
		)
		(layer "In3.Cu")
	)
	(gr_arc
		(start 320.83375 -25.035002)
		(mid 321.089426 -25.880903)
		(end 321.935348 -25.625044)
		(stroke
			(width 0.2)
			(type default)
		)
		(layer "In3.Cu")
	)
	(gr_arc
		(start 320.83375 -17.434814)
		(mid 321.089274 -18.280634)
		(end 321.935094 -18.02511)
		(stroke
			(width 0.2)
			(type default)
		)
		(layer "In3.Cu")
	)
	(gr_arc
		(start 320.83375 -13.634974)
		(mid 321.089426 -14.480875)
		(end 321.935348 -14.225016)
		(stroke
			(width 0.2)
			(type default)
		)
		(layer "In3.Cu")
	)
	(gr_line
		(start 321.293744 -222.805244)
		(end 322.10629 -222.805244)
		(stroke
			(width 0.2)
			(type default)
		)
		(layer "In3.Cu")
	)
	(gr_arc
		(start 321.293744 -221.784164)
		(mid 320.783204 -222.294704)
		(end 321.293744 -222.805244)
		(stroke
			(width 0.2)
			(type default)
		)
		(layer "In3.Cu")
	)
	(gr_line
		(start 321.581526 -23.633938)
		(end 320.831464 -25.033732)
		(stroke
			(width 0.2)
			(type default)
		)
		(layer "In3.Cu")
	)
	(gr_line
		(start 321.581526 -19.833844)
		(end 320.831464 -21.233892)
		(stroke
			(width 0.2)
			(type default)
		)
		(layer "In3.Cu")
	)
	(gr_line
		(start 321.581526 -16.03375)
		(end 320.831464 -17.433544)
		(stroke
			(width 0.2)
			(type default)
		)
		(layer "In3.Cu")
	)
	(gr_line
		(start 321.581526 -12.23391)
		(end 320.831464 -13.633704)
		(stroke
			(width 0.2)
			(type default)
		)
		(layer "In3.Cu")
	)
	(gr_line
		(start 321.583558 -23.635208)
		(end 321.581526 -23.633938)
		(stroke
			(width 0.2)
			(type default)
		)
		(layer "In3.Cu")
	)
	(gr_line
		(start 321.583558 -19.835114)
		(end 321.581526 -19.833844)
		(stroke
			(width 0.2)
			(type default)
		)
		(layer "In3.Cu")
	)
	(gr_line
		(start 321.583558 -12.23518)
		(end 321.581526 -12.23391)
		(stroke
			(width 0.2)
			(type default)
		)
		(layer "In3.Cu")
	)
	(gr_line
		(start 321.583812 -16.03502)
		(end 321.581526 -16.03375)
		(stroke
			(width 0.2)
			(type default)
		)
		(layer "In3.Cu")
	)
	(gr_line
		(start 321.935094 -18.02511)
		(end 321.93738 -18.02638)
		(stroke
			(width 0.2)
			(type default)
		)
		(layer "In3.Cu")
	)
	(gr_line
		(start 321.935348 -25.625044)
		(end 321.93738 -25.626314)
		(stroke
			(width 0.2)
			(type default)
		)
		(layer "In3.Cu")
	)
	(gr_line
		(start 321.935348 -21.82495)
		(end 321.93738 -21.82622)
		(stroke
			(width 0.2)
			(type default)
		)
		(layer "In3.Cu")
	)
	(gr_line
		(start 321.935348 -14.225016)
		(end 321.93738 -14.226286)
		(stroke
			(width 0.2)
			(type default)
		)
		(layer "In3.Cu")
	)
	(gr_line
		(start 321.93738 -25.626314)
		(end 322.687442 -24.226266)
		(stroke
			(width 0.2)
			(type default)
		)
		(layer "In3.Cu")
	)
	(gr_line
		(start 321.93738 -21.82622)
		(end 322.687442 -20.426426)
		(stroke
			(width 0.2)
			(type default)
		)
		(layer "In3.Cu")
	)
	(gr_line
		(start 321.93738 -18.02638)
		(end 322.687442 -16.626586)
		(stroke
			(width 0.2)
			(type default)
		)
		(layer "In3.Cu")
	)
	(gr_line
		(start 321.93738 -14.226286)
		(end 322.687442 -12.826238)
		(stroke
			(width 0.2)
			(type default)
		)
		(layer "In3.Cu")
	)
	(gr_arc
		(start 322.10629 -222.805244)
		(mid 322.617084 -222.294831)
		(end 322.106544 -221.784164)
		(stroke
			(width 0.2)
			(type default)
		)
		(layer "In3.Cu")
	)
	(gr_line
		(start 322.106544 -221.784164)
		(end 321.293744 -221.784164)
		(stroke
			(width 0.2)
			(type default)
		)
		(layer "In3.Cu")
	)
	(gr_arc
		(start 322.685156 -20.425156)
		(mid 322.42948 -19.579255)
		(end 321.583558 -19.835114)
		(stroke
			(width 0.2)
			(type default)
		)
		(layer "In3.Cu")
	)
	(gr_arc
		(start 322.685156 -16.625316)
		(mid 322.429632 -15.779496)
		(end 321.583812 -16.03502)
		(stroke
			(width 0.2)
			(type default)
		)
		(layer "In3.Cu")
	)
	(gr_arc
		(start 322.68541 -24.224996)
		(mid 322.429378 -23.379176)
		(end 321.583558 -23.635208)
		(stroke
			(width 0.2)
			(type default)
		)
		(layer "In3.Cu")
	)
	(gr_arc
		(start 322.68541 -12.824968)
		(mid 322.429378 -11.979148)
		(end 321.583558 -12.23518)
		(stroke
			(width 0.2)
			(type default)
		)
		(layer "In3.Cu")
	)
	(gr_line
		(start 322.687188 -20.426172)
		(end 322.685156 -20.425156)
		(stroke
			(width 0.2)
			(type default)
		)
		(layer "In3.Cu")
	)
	(gr_line
		(start 322.687442 -24.226266)
		(end 322.68541 -24.224996)
		(stroke
			(width 0.2)
			(type default)
		)
		(layer "In3.Cu")
	)
	(gr_line
		(start 322.687442 -20.426426)
		(end 322.687188 -20.426172)
		(stroke
			(width 0.2)
			(type default)
		)
		(layer "In3.Cu")
	)
	(gr_line
		(start 322.687442 -16.626586)
		(end 322.685156 -16.625316)
		(stroke
			(width 0.2)
			(type default)
		)
		(layer "In3.Cu")
	)
	(gr_line
		(start 322.687442 -12.826238)
		(end 322.68541 -12.824968)
		(stroke
			(width 0.2)
			(type default)
		)
		(layer "In3.Cu")
	)
	(gr_line
		(start 322.89369 -211.406994)
		(end 323.70649 -211.406994)
		(stroke
			(width 0.2)
			(type default)
		)
		(layer "In3.Cu")
	)
	(gr_arc
		(start 322.893944 -210.385914)
		(mid 322.38315 -210.896327)
		(end 322.89369 -211.406994)
		(stroke
			(width 0.2)
			(type default)
		)
		(layer "In3.Cu")
	)
	(gr_line
		(start 323.081396 -25.033732)
		(end 323.08165 -25.033986)
		(stroke
			(width 0.2)
			(type default)
		)
		(layer "In3.Cu")
	)
	(gr_line
		(start 323.081396 -21.233892)
		(end 323.083428 -21.235162)
		(stroke
			(width 0.2)
			(type default)
		)
		(layer "In3.Cu")
	)
	(gr_line
		(start 323.081396 -17.433544)
		(end 323.08165 -17.433798)
		(stroke
			(width 0.2)
			(type default)
		)
		(layer "In3.Cu")
	)
	(gr_line
		(start 323.081396 -13.633704)
		(end 323.08165 -13.633958)
		(stroke
			(width 0.2)
			(type default)
		)
		(layer "In3.Cu")
	)
	(gr_line
		(start 323.08165 -25.033986)
		(end 323.083682 -25.035002)
		(stroke
			(width 0.2)
			(type default)
		)
		(layer "In3.Cu")
	)
	(gr_line
		(start 323.08165 -17.433798)
		(end 323.083682 -17.434814)
		(stroke
			(width 0.2)
			(type default)
		)
		(layer "In3.Cu")
	)
	(gr_line
		(start 323.08165 -13.633958)
		(end 323.083682 -13.634974)
		(stroke
			(width 0.2)
			(type default)
		)
		(layer "In3.Cu")
	)
	(gr_arc
		(start 323.083428 -21.235162)
		(mid 323.33946 -22.080982)
		(end 324.18528 -21.82495)
		(stroke
			(width 0.2)
			(type default)
		)
		(layer "In3.Cu")
	)
	(gr_arc
		(start 323.083682 -25.035002)
		(mid 323.339358 -25.880903)
		(end 324.18528 -25.625044)
		(stroke
			(width 0.2)
			(type default)
		)
		(layer "In3.Cu")
	)
	(gr_arc
		(start 323.083682 -17.434814)
		(mid 323.339206 -18.280634)
		(end 324.185026 -18.02511)
		(stroke
			(width 0.2)
			(type default)
		)
		(layer "In3.Cu")
	)
	(gr_arc
		(start 323.083682 -13.634974)
		(mid 323.339358 -14.480875)
		(end 324.18528 -14.225016)
		(stroke
			(width 0.2)
			(type default)
		)
		(layer "In3.Cu")
	)
	(gr_line
		(start 323.61251 -35.479482)
		(end 324.425056 -35.479482)
		(stroke
			(width 0.2)
			(type default)
		)
		(layer "In3.Cu")
	)
	(gr_line
		(start 323.61251 -35.479482)
		(end 324.42531 -35.479482)
		(stroke
			(width 0.2)
			(type default)
		)
		(layer "In3.Cu")
	)
	(gr_arc
		(start 323.61251 -34.458402)
		(mid 323.10197 -34.968942)
		(end 323.61251 -35.479482)
		(stroke
			(width 0.2)
			(type default)
		)
		(layer "In3.Cu")
	)
	(gr_arc
		(start 323.612764 -34.458402)
		(mid 323.10197 -34.968815)
		(end 323.61251 -35.479482)
		(stroke
			(width 0.2)
			(type default)
		)
		(layer "In3.Cu")
	)
	(gr_arc
		(start 323.70649 -211.406994)
		(mid 324.21703 -210.896454)
		(end 323.70649 -210.385914)
		(stroke
			(width 0.2)
			(type default)
		)
		(layer "In3.Cu")
	)
	(gr_line
		(start 323.70649 -210.385914)
		(end 322.893944 -210.385914)
		(stroke
			(width 0.2)
			(type default)
		)
		(layer "In3.Cu")
	)
	(gr_line
		(start 323.831458 -23.633938)
		(end 323.081396 -25.033732)
		(stroke
			(width 0.2)
			(type default)
		)
		(layer "In3.Cu")
	)
	(gr_line
		(start 323.831458 -19.833844)
		(end 323.081396 -21.233892)
		(stroke
			(width 0.2)
			(type default)
		)
		(layer "In3.Cu")
	)
	(gr_line
		(start 323.831458 -16.03375)
		(end 323.081396 -17.433544)
		(stroke
			(width 0.2)
			(type default)
		)
		(layer "In3.Cu")
	)
	(gr_line
		(start 323.831458 -12.23391)
		(end 323.081396 -13.633704)
		(stroke
			(width 0.2)
			(type default)
		)
		(layer "In3.Cu")
	)
	(gr_line
		(start 323.83349 -23.635208)
		(end 323.831458 -23.633938)
		(stroke
			(width 0.2)
			(type default)
		)
		(layer "In3.Cu")
	)
	(gr_line
		(start 323.83349 -19.835114)
		(end 323.831458 -19.833844)
		(stroke
			(width 0.2)
			(type default)
		)
		(layer "In3.Cu")
	)
	(gr_line
		(start 323.83349 -12.23518)
		(end 323.831458 -12.23391)
		(stroke
			(width 0.2)
			(type default)
		)
		(layer "In3.Cu")
	)
	(gr_line
		(start 323.833744 -16.03502)
		(end 323.831458 -16.03375)
		(stroke
			(width 0.2)
			(type default)
		)
		(layer "In3.Cu")
	)
	(gr_line
		(start 324.185026 -18.02511)
		(end 324.187312 -18.02638)
		(stroke
			(width 0.2)
			(type default)
		)
		(layer "In3.Cu")
	)
	(gr_line
		(start 324.18528 -25.625044)
		(end 324.187312 -25.626314)
		(stroke
			(width 0.2)
			(type default)
		)
		(layer "In3.Cu")
	)
	(gr_line
		(start 324.18528 -21.82495)
		(end 324.187312 -21.82622)
		(stroke
			(width 0.2)
			(type default)
		)
		(layer "In3.Cu")
	)
	(gr_line
		(start 324.18528 -14.225016)
		(end 324.187312 -14.226286)
		(stroke
			(width 0.2)
			(type default)
		)
		(layer "In3.Cu")
	)
	(gr_line
		(start 324.187312 -25.626314)
		(end 324.937374 -24.226266)
		(stroke
			(width 0.2)
			(type default)
		)
		(layer "In3.Cu")
	)
	(gr_line
		(start 324.187312 -21.82622)
		(end 324.937374 -20.426426)
		(stroke
			(width 0.2)
			(type default)
		)
		(layer "In3.Cu")
	)
	(gr_line
		(start 324.187312 -18.02638)
		(end 324.937374 -16.626586)
		(stroke
			(width 0.2)
			(type default)
		)
		(layer "In3.Cu")
	)
	(gr_line
		(start 324.187312 -14.226286)
		(end 324.937374 -12.826238)
		(stroke
			(width 0.2)
			(type default)
		)
		(layer "In3.Cu")
	)
	(gr_arc
		(start 324.425056 -35.479482)
		(mid 324.93585 -34.969069)
		(end 324.42531 -34.458402)
		(stroke
			(width 0.2)
			(type default)
		)
		(layer "In3.Cu")
	)
	(gr_arc
		(start 324.42531 -35.479482)
		(mid 324.93585 -34.968942)
		(end 324.42531 -34.458402)
		(stroke
			(width 0.2)
			(type default)
		)
		(layer "In3.Cu")
	)
	(gr_line
		(start 324.42531 -34.458402)
		(end 323.61251 -34.458402)
		(stroke
			(width 0.2)
			(type default)
		)
		(layer "In3.Cu")
	)
	(gr_line
		(start 324.42531 -34.458402)
		(end 323.612764 -34.458402)
		(stroke
			(width 0.2)
			(type default)
		)
		(layer "In3.Cu")
	)
	(gr_line
		(start 324.493636 -222.805244)
		(end 325.306182 -222.805244)
		(stroke
			(width 0.2)
			(type default)
		)
		(layer "In3.Cu")
	)
	(gr_arc
		(start 324.493636 -221.784164)
		(mid 323.983096 -222.294704)
		(end 324.493636 -222.805244)
		(stroke
			(width 0.2)
			(type default)
		)
		(layer "In3.Cu")
	)
	(gr_line
		(start 324.866 -54.991)
		(end 325.755 -55.88)
		(stroke
			(width 0.381)
			(type default)
		)
		(layer "In3.Cu")
	)
	(gr_arc
		(start 324.935088 -20.425156)
		(mid 324.679412 -19.579255)
		(end 323.83349 -19.835114)
		(stroke
			(width 0.2)
			(type default)
		)
		(layer "In3.Cu")
	)
	(gr_arc
		(start 324.935088 -16.625316)
		(mid 324.679564 -15.779496)
		(end 323.833744 -16.03502)
		(stroke
			(width 0.2)
			(type default)
		)
		(layer "In3.Cu")
	)
	(gr_arc
		(start 324.935342 -24.224996)
		(mid 324.67931 -23.379176)
		(end 323.83349 -23.635208)
		(stroke
			(width 0.2)
			(type default)
		)
		(layer "In3.Cu")
	)
	(gr_arc
		(start 324.935342 -12.824968)
		(mid 324.67931 -11.979148)
		(end 323.83349 -12.23518)
		(stroke
			(width 0.2)
			(type default)
		)
		(layer "In3.Cu")
	)
	(gr_line
		(start 324.93712 -20.426172)
		(end 324.935088 -20.425156)
		(stroke
			(width 0.2)
			(type default)
		)
		(layer "In3.Cu")
	)
	(gr_line
		(start 324.937374 -24.226266)
		(end 324.935342 -24.224996)
		(stroke
			(width 0.2)
			(type default)
		)
		(layer "In3.Cu")
	)
	(gr_line
		(start 324.937374 -20.426426)
		(end 324.93712 -20.426172)
		(stroke
			(width 0.2)
			(type default)
		)
		(layer "In3.Cu")
	)
	(gr_line
		(start 324.937374 -16.626586)
		(end 324.935088 -16.625316)
		(stroke
			(width 0.2)
			(type default)
		)
		(layer "In3.Cu")
	)
	(gr_line
		(start 324.937374 -12.826238)
		(end 324.935342 -12.824968)
		(stroke
			(width 0.2)
			(type default)
		)
		(layer "In3.Cu")
	)
	(gr_line
		(start 325.247 -68.453)
		(end 310.134 -68.453)
		(stroke
			(width 0.381)
			(type default)
		)
		(layer "In3.Cu")
	)
	(gr_arc
		(start 325.306182 -222.805244)
		(mid 325.816976 -222.294831)
		(end 325.306436 -221.784164)
		(stroke
			(width 0.2)
			(type default)
		)
		(layer "In3.Cu")
	)
	(gr_line
		(start 325.306436 -221.784164)
		(end 324.493636 -221.784164)
		(stroke
			(width 0.2)
			(type default)
		)
		(layer "In3.Cu")
	)
	(gr_line
		(start 325.755 -67.945)
		(end 325.247 -68.453)
		(stroke
			(width 0.381)
			(type default)
		)
		(layer "In3.Cu")
	)
	(gr_line
		(start 325.755 -55.88)
		(end 325.755 -67.945)
		(stroke
			(width 0.381)
			(type default)
		)
		(layer "In3.Cu")
	)
	(gr_line
		(start 325.969122 -36.472114)
		(end 326.781668 -36.472114)
		(stroke
			(width 0.2)
			(type default)
		)
		(layer "In3.Cu")
	)
	(gr_arc
		(start 325.969122 -35.451034)
		(mid 325.458582 -35.961574)
		(end 325.969122 -36.472114)
		(stroke
			(width 0.2)
			(type default)
		)
		(layer "In3.Cu")
	)
	(gr_line
		(start 326.093582 -211.406994)
		(end 326.906382 -211.406994)
		(stroke
			(width 0.2)
			(type default)
		)
		(layer "In3.Cu")
	)
	(gr_arc
		(start 326.093836 -210.385914)
		(mid 325.583042 -210.896327)
		(end 326.093582 -211.406994)
		(stroke
			(width 0.2)
			(type default)
		)
		(layer "In3.Cu")
	)
	(gr_arc
		(start 326.781668 -36.472114)
		(mid 327.292462 -35.961701)
		(end 326.781922 -35.451034)
		(stroke
			(width 0.2)
			(type default)
		)
		(layer "In3.Cu")
	)
	(gr_line
		(start 326.781922 -35.451034)
		(end 325.969122 -35.451034)
		(stroke
			(width 0.2)
			(type default)
		)
		(layer "In3.Cu")
	)
	(gr_arc
		(start 326.906382 -211.406994)
		(mid 327.416922 -210.896454)
		(end 326.906382 -210.385914)
		(stroke
			(width 0.2)
			(type default)
		)
		(layer "In3.Cu")
	)
	(gr_line
		(start 326.906382 -210.385914)
		(end 326.093836 -210.385914)
		(stroke
			(width 0.2)
			(type default)
		)
		(layer "In3.Cu")
	)
	(gr_line
		(start 327.693782 -222.805244)
		(end 328.506328 -222.805244)
		(stroke
			(width 0.2)
			(type default)
		)
		(layer "In3.Cu")
	)
	(gr_arc
		(start 327.693782 -221.784164)
		(mid 327.183242 -222.294704)
		(end 327.693782 -222.805244)
		(stroke
			(width 0.2)
			(type default)
		)
		(layer "In3.Cu")
	)
	(gr_line
		(start 328.375518 -35.429952)
		(end 329.188064 -35.429952)
		(stroke
			(width 0.2)
			(type default)
		)
		(layer "In3.Cu")
	)
	(gr_arc
		(start 328.375518 -34.408872)
		(mid 327.864978 -34.919412)
		(end 328.375518 -35.429952)
		(stroke
			(width 0.2)
			(type default)
		)
		(layer "In3.Cu")
	)
	(gr_arc
		(start 328.506328 -222.805244)
		(mid 329.017122 -222.294831)
		(end 328.506582 -221.784164)
		(stroke
			(width 0.2)
			(type default)
		)
		(layer "In3.Cu")
	)
	(gr_line
		(start 328.506582 -221.784164)
		(end 327.693782 -221.784164)
		(stroke
			(width 0.2)
			(type default)
		)
		(layer "In3.Cu")
	)
	(gr_arc
		(start 329.188064 -35.429952)
		(mid 329.698858 -34.919539)
		(end 329.188318 -34.408872)
		(stroke
			(width 0.2)
			(type default)
		)
		(layer "In3.Cu")
	)
	(gr_line
		(start 329.188318 -34.408872)
		(end 328.375518 -34.408872)
		(stroke
			(width 0.2)
			(type default)
		)
		(layer "In3.Cu")
	)
	(gr_line
		(start 330.708 -134.366)
		(end 345.059 -120.015)
		(stroke
			(width 0.381)
			(type default)
		)
		(layer "In3.Cu")
	)
	(gr_line
		(start 330.893674 -222.805244)
		(end 331.70622 -222.805244)
		(stroke
			(width 0.2)
			(type default)
		)
		(layer "In3.Cu")
	)
	(gr_arc
		(start 330.893674 -221.784164)
		(mid 330.383134 -222.294704)
		(end 330.893674 -222.805244)
		(stroke
			(width 0.2)
			(type default)
		)
		(layer "In3.Cu")
	)
	(gr_arc
		(start 331.70622 -222.805244)
		(mid 332.217014 -222.294831)
		(end 331.706474 -221.784164)
		(stroke
			(width 0.2)
			(type default)
		)
		(layer "In3.Cu")
	)
	(gr_line
		(start 331.706474 -221.784164)
		(end 330.893674 -221.784164)
		(stroke
			(width 0.2)
			(type default)
		)
		(layer "In3.Cu")
	)
	(gr_arc
		(start 331.749908 0.999998)
		(mid 332.042801 0.292893)
		(end 332.749906 0)
		(stroke
			(width 1.524)
			(type default)
		)
		(layer "In3.Cu")
	)
	(gr_arc
		(start 331.749908 3.999992)
		(mid 331.457019 4.707106)
		(end 330.74991 4.99999)
		(stroke
			(width 1.524)
			(type default)
		)
		(layer "In3.Cu")
	)
	(gr_line
		(start 331.749908 3.999992)
		(end 331.749908 0.999998)
		(stroke
			(width 1.524)
			(type default)
		)
		(layer "In3.Cu")
	)
	(gr_line
		(start 332.493874 -211.406994)
		(end 333.306674 -211.406994)
		(stroke
			(width 0.2)
			(type default)
		)
		(layer "In3.Cu")
	)
	(gr_arc
		(start 332.494128 -210.385914)
		(mid 331.983334 -210.896327)
		(end 332.493874 -211.406994)
		(stroke
			(width 0.2)
			(type default)
		)
		(layer "In3.Cu")
	)
	(gr_line
		(start 332.749906 0)
		(end 354.600002 0)
		(stroke
			(width 1.524)
			(type default)
		)
		(layer "In3.Cu")
	)
	(gr_arc
		(start 333.306674 -211.406994)
		(mid 333.817214 -210.896454)
		(end 333.306674 -210.385914)
		(stroke
			(width 0.2)
			(type default)
		)
		(layer "In3.Cu")
	)
	(gr_line
		(start 333.306674 -210.385914)
		(end 332.494128 -210.385914)
		(stroke
			(width 0.2)
			(type default)
		)
		(layer "In3.Cu")
	)
	(gr_line
		(start 334.093566 -222.805244)
		(end 334.906112 -222.805244)
		(stroke
			(width 0.2)
			(type default)
		)
		(layer "In3.Cu")
	)
	(gr_arc
		(start 334.093566 -221.784164)
		(mid 333.583026 -222.294704)
		(end 334.093566 -222.805244)
		(stroke
			(width 0.2)
			(type default)
		)
		(layer "In3.Cu")
	)
	(gr_arc
		(start 334.906112 -222.805244)
		(mid 335.416906 -222.294831)
		(end 334.906366 -221.784164)
		(stroke
			(width 0.2)
			(type default)
		)
		(layer "In3.Cu")
	)
	(gr_line
		(start 334.906366 -221.784164)
		(end 334.093566 -221.784164)
		(stroke
			(width 0.2)
			(type default)
		)
		(layer "In3.Cu")
	)
	(gr_line
		(start 335.693766 -211.406994)
		(end 336.506566 -211.406994)
		(stroke
			(width 0.2)
			(type default)
		)
		(layer "In3.Cu")
	)
	(gr_arc
		(start 335.69402 -210.385914)
		(mid 335.183226 -210.896327)
		(end 335.693766 -211.406994)
		(stroke
			(width 0.2)
			(type default)
		)
		(layer "In3.Cu")
	)
	(gr_line
		(start 335.915 -143.256)
		(end 353.314 -125.857)
		(stroke
			(width 0.381)
			(type default)
		)
		(layer "In3.Cu")
	)
	(gr_arc
		(start 336.506566 -211.406994)
		(mid 337.017106 -210.896454)
		(end 336.506566 -210.385914)
		(stroke
			(width 0.2)
			(type default)
		)
		(layer "In3.Cu")
	)
	(gr_line
		(start 336.506566 -210.385914)
		(end 335.69402 -210.385914)
		(stroke
			(width 0.2)
			(type default)
		)
		(layer "In3.Cu")
	)
	(gr_line
		(start 337.293712 -222.805244)
		(end 338.106258 -222.805244)
		(stroke
			(width 0.2)
			(type default)
		)
		(layer "In3.Cu")
	)
	(gr_arc
		(start 337.293712 -221.784164)
		(mid 336.783172 -222.294704)
		(end 337.293712 -222.805244)
		(stroke
			(width 0.2)
			(type default)
		)
		(layer "In3.Cu")
	)
	(gr_arc
		(start 338.106258 -222.805244)
		(mid 338.617052 -222.294831)
		(end 338.106512 -221.784164)
		(stroke
			(width 0.2)
			(type default)
		)
		(layer "In3.Cu")
	)
	(gr_line
		(start 338.106512 -221.784164)
		(end 337.293712 -221.784164)
		(stroke
			(width 0.2)
			(type default)
		)
		(layer "In3.Cu")
	)
	(gr_line
		(start 338.893658 -211.406994)
		(end 339.706204 -211.406994)
		(stroke
			(width 0.2)
			(type default)
		)
		(layer "In3.Cu")
	)
	(gr_arc
		(start 338.893658 -210.385914)
		(mid 338.383118 -210.896454)
		(end 338.893658 -211.406994)
		(stroke
			(width 0.2)
			(type default)
		)
		(layer "In3.Cu")
	)
	(gr_arc
		(start 339.706204 -211.406994)
		(mid 340.216998 -210.896581)
		(end 339.706458 -210.385914)
		(stroke
			(width 0.2)
			(type default)
		)
		(layer "In3.Cu")
	)
	(gr_line
		(start 339.706458 -210.385914)
		(end 338.893658 -210.385914)
		(stroke
			(width 0.2)
			(type default)
		)
		(layer "In3.Cu")
	)
	(gr_line
		(start 340.493604 -222.805244)
		(end 341.306404 -222.805244)
		(stroke
			(width 0.2)
			(type default)
		)
		(layer "In3.Cu")
	)
	(gr_arc
		(start 340.493858 -221.784164)
		(mid 339.983064 -222.294577)
		(end 340.493604 -222.805244)
		(stroke
			(width 0.2)
			(type default)
		)
		(layer "In3.Cu")
	)
	(gr_arc
		(start 341.306404 -222.805244)
		(mid 341.816944 -222.294704)
		(end 341.306404 -221.784164)
		(stroke
			(width 0.2)
			(type default)
		)
		(layer "In3.Cu")
	)
	(gr_line
		(start 341.306404 -221.784164)
		(end 340.493858 -221.784164)
		(stroke
			(width 0.2)
			(type default)
		)
		(layer "In3.Cu")
	)
	(gr_line
		(start 342.09355 -211.406994)
		(end 342.906096 -211.406994)
		(stroke
			(width 0.2)
			(type default)
		)
		(layer "In3.Cu")
	)
	(gr_arc
		(start 342.09355 -210.385914)
		(mid 341.58301 -210.896454)
		(end 342.09355 -211.406994)
		(stroke
			(width 0.2)
			(type default)
		)
		(layer "In3.Cu")
	)
	(gr_arc
		(start 342.906096 -211.406994)
		(mid 343.41689 -210.896581)
		(end 342.90635 -210.385914)
		(stroke
			(width 0.2)
			(type default)
		)
		(layer "In3.Cu")
	)
	(gr_line
		(start 342.90635 -210.385914)
		(end 342.09355 -210.385914)
		(stroke
			(width 0.2)
			(type default)
		)
		(layer "In3.Cu")
	)
	(gr_line
		(start 344.499946 -228.000052)
		(end 308.500018 -228.000052)
		(stroke
			(width 5.08)
			(type default)
		)
		(layer "In3.Cu")
	)
	(gr_line
		(start 344.499946 -222.400114)
		(end 344.499946 -228.000052)
		(stroke
			(width 1.524)
			(type default)
		)
		(layer "In3.Cu")
	)
	(gr_arc
		(start 345.000072 -221.899988)
		(mid 344.64643 -222.046472)
		(end 344.499946 -222.400114)
		(stroke
			(width 1.524)
			(type default)
		)
		(layer "In3.Cu")
	)
	(gr_line
		(start 345.059 -120.015)
		(end 345.059 -48.006)
		(stroke
			(width 0.381)
			(type default)
		)
		(layer "In3.Cu")
	)
	(gr_line
		(start 345.059 -48.006)
		(end 346.075 -46.99)
		(stroke
			(width 0.381)
			(type default)
		)
		(layer "In3.Cu")
	)
	(gr_line
		(start 345.799918 -221.899988)
		(end 345.000072 -221.899988)
		(stroke
			(width 1.524)
			(type default)
		)
		(layer "In3.Cu")
	)
	(gr_arc
		(start 345.799918 -221.899988)
		(mid 346.153446 -221.753586)
		(end 346.300044 -221.400116)
		(stroke
			(width 1.524)
			(type default)
		)
		(layer "In3.Cu")
	)
	(gr_line
		(start 346.075 -46.99)
		(end 351.155 -46.99)
		(stroke
			(width 0.381)
			(type default)
		)
		(layer "In3.Cu")
	)
	(gr_line
		(start 346.300044 -214.799926)
		(end 346.300044 -221.400116)
		(stroke
			(width 1.524)
			(type default)
		)
		(layer "In3.Cu")
	)
	(gr_arc
		(start 347.600016 -213.499954)
		(mid 346.680797 -213.880707)
		(end 346.300044 -214.799926)
		(stroke
			(width 1.524)
			(type default)
		)
		(layer "In3.Cu")
	)
	(gr_line
		(start 352.298 -46.99)
		(end 351.155 -46.99)
		(stroke
			(width 0.381)
			(type default)
		)
		(layer "In3.Cu")
	)
	(gr_line
		(start 353.314 -125.857)
		(end 353.314 -48.006)
		(stroke
			(width 0.381)
			(type default)
		)
		(layer "In3.Cu")
	)
	(gr_line
		(start 353.314 -48.006)
		(end 352.298 -46.99)
		(stroke
			(width 0.381)
			(type default)
		)
		(layer "In3.Cu")
	)
	(gr_arc
		(start 354.24999 -18.200116)
		(mid 354.396563 -18.553594)
		(end 354.750116 -18.699988)
		(stroke
			(width 1.524)
			(type default)
		)
		(layer "In3.Cu")
	)
	(gr_line
		(start 354.24999 -10.199878)
		(end 354.24999 -18.200116)
		(stroke
			(width 1.524)
			(type default)
		)
		(layer "In3.Cu")
	)
	(gr_line
		(start 354.600002 -213.499954)
		(end 347.600016 -213.499954)
		(stroke
			(width 1.524)
			(type default)
		)
		(layer "In3.Cu")
	)
	(gr_arc
		(start 354.600002 -213.499954)
		(mid 355.307091 -213.207058)
		(end 355.6 -212.499956)
		(stroke
			(width 1.524)
			(type default)
		)
		(layer "In3.Cu")
	)
	(gr_line
		(start 354.750116 -18.699988)
		(end 355.099874 -18.699988)
		(stroke
			(width 1.524)
			(type default)
		)
		(layer "In3.Cu")
	)
	(gr_arc
		(start 354.750116 -9.700006)
		(mid 354.396563 -9.8464)
		(end 354.24999 -10.199878)
		(stroke
			(width 1.524)
			(type default)
		)
		(layer "In3.Cu")
	)
	(gr_line
		(start 355.099874 -9.700006)
		(end 354.750116 -9.700006)
		(stroke
			(width 1.524)
			(type default)
		)
		(layer "In3.Cu")
	)
	(gr_arc
		(start 355.099874 -9.700006)
		(mid 355.453526 -9.55353)
		(end 355.6 -9.19988)
		(stroke
			(width 1.524)
			(type default)
		)
		(layer "In3.Cu")
	)
	(gr_arc
		(start 355.6 -19.200114)
		(mid 355.45352 -18.846472)
		(end 355.099874 -18.699988)
		(stroke
			(width 1.524)
			(type default)
		)
		(layer "In3.Cu")
	)
	(gr_line
		(start 355.6 -19.200114)
		(end 355.6 -212.499956)
		(stroke
			(width 1.524)
			(type default)
		)
		(layer "In3.Cu")
	)
	(gr_arc
		(start 355.6 -0.999998)
		(mid 355.307107 -0.292893)
		(end 354.600002 0)
		(stroke
			(width 1.524)
			(type default)
		)
		(layer "In3.Cu")
	)
	(gr_line
		(start 355.6 -0.999998)
		(end 355.6 -9.19988)
		(stroke
			(width 1.524)
			(type default)
		)
		(layer "In3.Cu")
	)
	(gr_line
		(start 0 -212.499956)
		(end 0 -28.010104)
		(stroke
			(width 1.524)
			(type default)
		)
		(layer "In4.Cu")
	)
	(gr_arc
		(start 0 -212.499956)
		(mid 0.292895 -213.207058)
		(end 0.999998 -213.499954)
		(stroke
			(width 1.524)
			(type default)
		)
		(layer "In4.Cu")
	)
	(gr_arc
		(start 1.999996 -26.010108)
		(mid 0.585785 -26.595893)
		(end 0 -28.010104)
		(stroke
			(width 1.524)
			(type default)
		)
		(layer "In4.Cu")
	)
	(gr_line
		(start 1.999996 -26.010108)
		(end 49.950116 -26.010108)
		(stroke
			(width 1.524)
			(type default)
		)
		(layer "In4.Cu")
	)
	(gr_circle
		(center 6.852158 -38.509956)
		(end 8.150098 -38.509956)
		(stroke
			(width 0.2)
			(type default)
		)
		(fill no)
		(layer "In4.Cu")
	)
	(gr_line
		(start 9.6647 -55.559452)
		(end 10.477246 -55.559452)
		(stroke
			(width 0.2)
			(type default)
		)
		(layer "In4.Cu")
	)
	(gr_arc
		(start 9.6647 -54.538372)
		(mid 9.15416 -55.048912)
		(end 9.6647 -55.559452)
		(stroke
			(width 0.2)
			(type default)
		)
		(layer "In4.Cu")
	)
	(gr_arc
		(start 10.477246 -55.559452)
		(mid 10.98804 -55.049039)
		(end 10.4775 -54.538372)
		(stroke
			(width 0.2)
			(type default)
		)
		(layer "In4.Cu")
	)
	(gr_line
		(start 10.4775 -54.538372)
		(end 9.6647 -54.538372)
		(stroke
			(width 0.2)
			(type default)
		)
		(layer "In4.Cu")
	)
	(gr_line
		(start 13.5636 -54.340252)
		(end 14.3764 -54.340252)
		(stroke
			(width 0.2)
			(type default)
		)
		(layer "In4.Cu")
	)
	(gr_arc
		(start 13.563854 -53.319172)
		(mid 13.05306 -53.829585)
		(end 13.5636 -54.340252)
		(stroke
			(width 0.2)
			(type default)
		)
		(layer "In4.Cu")
	)
	(gr_arc
		(start 13.66266 -68.451222)
		(mid 14.1732 -68.961762)
		(end 14.68374 -68.451222)
		(stroke
			(width 0.2)
			(type default)
		)
		(layer "In4.Cu")
	)
	(gr_line
		(start 13.66266 -67.638422)
		(end 13.66266 -68.451222)
		(stroke
			(width 0.2)
			(type default)
		)
		(layer "In4.Cu")
	)
	(gr_arc
		(start 14.3764 -54.340252)
		(mid 14.88694 -53.829712)
		(end 14.3764 -53.319172)
		(stroke
			(width 0.2)
			(type default)
		)
		(layer "In4.Cu")
	)
	(gr_line
		(start 14.3764 -53.319172)
		(end 13.563854 -53.319172)
		(stroke
			(width 0.2)
			(type default)
		)
		(layer "In4.Cu")
	)
	(gr_line
		(start 14.68374 -68.451222)
		(end 14.68374 -67.638676)
		(stroke
			(width 0.2)
			(type default)
		)
		(layer "In4.Cu")
	)
	(gr_arc
		(start 14.68374 -67.638676)
		(mid 14.173327 -67.127882)
		(end 13.66266 -67.638422)
		(stroke
			(width 0.2)
			(type default)
		)
		(layer "In4.Cu")
	)
	(gr_arc
		(start 15.66926 -67.03695)
		(mid 16.1798 -67.54749)
		(end 16.69034 -67.03695)
		(stroke
			(width 0.2)
			(type default)
		)
		(layer "In4.Cu")
	)
	(gr_line
		(start 15.66926 -66.22415)
		(end 15.66926 -67.03695)
		(stroke
			(width 0.2)
			(type default)
		)
		(layer "In4.Cu")
	)
	(gr_line
		(start 15.7988 -73.727564)
		(end 16.6116 -73.727564)
		(stroke
			(width 0.2)
			(type default)
		)
		(layer "In4.Cu")
	)
	(gr_arc
		(start 15.799054 -72.706484)
		(mid 15.28826 -73.216897)
		(end 15.7988 -73.727564)
		(stroke
			(width 0.2)
			(type default)
		)
		(layer "In4.Cu")
	)
	(gr_line
		(start 15.8496 -87.65794)
		(end 16.9672 -87.65794)
		(stroke
			(width 0.2)
			(type default)
		)
		(layer "In4.Cu")
	)
	(gr_arc
		(start 15.8496 -86.43366)
		(mid 15.23746 -87.0458)
		(end 15.8496 -87.65794)
		(stroke
			(width 0.2)
			(type default)
		)
		(layer "In4.Cu")
	)
	(gr_arc
		(start 16.6116 -73.727564)
		(mid 17.12214 -73.217024)
		(end 16.6116 -72.706484)
		(stroke
			(width 0.2)
			(type default)
		)
		(layer "In4.Cu")
	)
	(gr_line
		(start 16.6116 -72.706484)
		(end 15.799054 -72.706484)
		(stroke
			(width 0.2)
			(type default)
		)
		(layer "In4.Cu")
	)
	(gr_line
		(start 16.69034 -67.03695)
		(end 16.69034 -66.224404)
		(stroke
			(width 0.2)
			(type default)
		)
		(layer "In4.Cu")
	)
	(gr_arc
		(start 16.69034 -66.224404)
		(mid 16.179927 -65.71361)
		(end 15.66926 -66.22415)
		(stroke
			(width 0.2)
			(type default)
		)
		(layer "In4.Cu")
	)
	(gr_arc
		(start 16.9672 -87.65794)
		(mid 17.57934 -87.0458)
		(end 16.9672 -86.43366)
		(stroke
			(width 0.2)
			(type default)
		)
		(layer "In4.Cu")
	)
	(gr_line
		(start 16.9672 -86.43366)
		(end 15.8496 -86.43366)
		(stroke
			(width 0.2)
			(type default)
		)
		(layer "In4.Cu")
	)
	(gr_line
		(start 18.57375 -73.721214)
		(end 19.38655 -73.721214)
		(stroke
			(width 0.2)
			(type default)
		)
		(layer "In4.Cu")
	)
	(gr_arc
		(start 18.574004 -72.700134)
		(mid 18.06321 -73.210547)
		(end 18.57375 -73.721214)
		(stroke
			(width 0.2)
			(type default)
		)
		(layer "In4.Cu")
	)
	(gr_line
		(start 18.6944 -58.851546)
		(end 19.812 -58.851546)
		(stroke
			(width 0.2)
			(type default)
		)
		(layer "In4.Cu")
	)
	(gr_arc
		(start 18.6944 -57.627266)
		(mid 18.08226 -58.239406)
		(end 18.6944 -58.851546)
		(stroke
			(width 0.2)
			(type default)
		)
		(layer "In4.Cu")
	)
	(gr_line
		(start 18.8468 -55.508652)
		(end 19.659346 -55.508652)
		(stroke
			(width 0.2)
			(type default)
		)
		(layer "In4.Cu")
	)
	(gr_arc
		(start 18.8468 -54.487572)
		(mid 18.33626 -54.998112)
		(end 18.8468 -55.508652)
		(stroke
			(width 0.2)
			(type default)
		)
		(layer "In4.Cu")
	)
	(gr_line
		(start 18.852134 -82.41792)
		(end 19.664934 -82.41792)
		(stroke
			(width 0.2)
			(type default)
		)
		(layer "In4.Cu")
	)
	(gr_arc
		(start 18.852388 -81.39684)
		(mid 18.341594 -81.907253)
		(end 18.852134 -82.41792)
		(stroke
			(width 0.2)
			(type default)
		)
		(layer "In4.Cu")
	)
	(gr_arc
		(start 19.38655 -73.721214)
		(mid 19.89709 -73.210674)
		(end 19.38655 -72.700134)
		(stroke
			(width 0.2)
			(type default)
		)
		(layer "In4.Cu")
	)
	(gr_line
		(start 19.38655 -72.700134)
		(end 18.574004 -72.700134)
		(stroke
			(width 0.2)
			(type default)
		)
		(layer "In4.Cu")
	)
	(gr_arc
		(start 19.659346 -55.508652)
		(mid 20.17014 -54.998239)
		(end 19.6596 -54.487572)
		(stroke
			(width 0.2)
			(type default)
		)
		(layer "In4.Cu")
	)
	(gr_line
		(start 19.6596 -54.487572)
		(end 18.8468 -54.487572)
		(stroke
			(width 0.2)
			(type default)
		)
		(layer "In4.Cu")
	)
	(gr_arc
		(start 19.664934 -82.41792)
		(mid 20.175474 -81.90738)
		(end 19.664934 -81.39684)
		(stroke
			(width 0.2)
			(type default)
		)
		(layer "In4.Cu")
	)
	(gr_line
		(start 19.664934 -81.39684)
		(end 18.852388 -81.39684)
		(stroke
			(width 0.2)
			(type default)
		)
		(layer "In4.Cu")
	)
	(gr_arc
		(start 19.812 -58.851546)
		(mid 20.42414 -58.239406)
		(end 19.812 -57.627266)
		(stroke
			(width 0.2)
			(type default)
		)
		(layer "In4.Cu")
	)
	(gr_line
		(start 19.812 -57.627266)
		(end 18.6944 -57.627266)
		(stroke
			(width 0.2)
			(type default)
		)
		(layer "In4.Cu")
	)
	(gr_line
		(start 20.3962 -87.93734)
		(end 21.209 -87.93734)
		(stroke
			(width 0.2)
			(type default)
		)
		(layer "In4.Cu")
	)
	(gr_arc
		(start 20.396454 -86.91626)
		(mid 19.88566 -87.426673)
		(end 20.3962 -87.93734)
		(stroke
			(width 0.2)
			(type default)
		)
		(layer "In4.Cu")
	)
	(gr_arc
		(start 21.209 -87.93734)
		(mid 21.71954 -87.4268)
		(end 21.209 -86.91626)
		(stroke
			(width 0.2)
			(type default)
		)
		(layer "In4.Cu")
	)
	(gr_line
		(start 21.209 -86.91626)
		(end 20.396454 -86.91626)
		(stroke
			(width 0.2)
			(type default)
		)
		(layer "In4.Cu")
	)
	(gr_line
		(start 22.417786 -57.300876)
		(end 23.535386 -57.300876)
		(stroke
			(width 0.2)
			(type default)
		)
		(layer "In4.Cu")
	)
	(gr_arc
		(start 22.417786 -56.076596)
		(mid 21.805646 -56.688736)
		(end 22.417786 -57.300876)
		(stroke
			(width 0.2)
			(type default)
		)
		(layer "In4.Cu")
	)
	(gr_arc
		(start 22.55266 -115.1128)
		(mid 23.1648 -115.72494)
		(end 23.77694 -115.1128)
		(stroke
			(width 0.2)
			(type default)
		)
		(layer "In4.Cu")
	)
	(gr_line
		(start 22.55266 -113.9952)
		(end 22.55266 -115.1128)
		(stroke
			(width 0.2)
			(type default)
		)
		(layer "In4.Cu")
	)
	(gr_line
		(start 22.5552 -54.066694)
		(end 23.368 -54.066694)
		(stroke
			(width 0.2)
			(type default)
		)
		(layer "In4.Cu")
	)
	(gr_arc
		(start 22.555454 -53.045614)
		(mid 22.04466 -53.556027)
		(end 22.5552 -54.066694)
		(stroke
			(width 0.2)
			(type default)
		)
		(layer "In4.Cu")
	)
	(gr_arc
		(start 23.368 -54.066694)
		(mid 23.87854 -53.556154)
		(end 23.368 -53.045614)
		(stroke
			(width 0.2)
			(type default)
		)
		(layer "In4.Cu")
	)
	(gr_line
		(start 23.368 -53.045614)
		(end 22.555454 -53.045614)
		(stroke
			(width 0.2)
			(type default)
		)
		(layer "In4.Cu")
	)
	(gr_arc
		(start 23.535386 -57.300876)
		(mid 24.147526 -56.688736)
		(end 23.535386 -56.076596)
		(stroke
			(width 0.2)
			(type default)
		)
		(layer "In4.Cu")
	)
	(gr_line
		(start 23.535386 -56.076596)
		(end 22.417786 -56.076596)
		(stroke
			(width 0.2)
			(type default)
		)
		(layer "In4.Cu")
	)
	(gr_line
		(start 23.77694 -115.1128)
		(end 23.77694 -113.995454)
		(stroke
			(width 0.2)
			(type default)
		)
		(layer "In4.Cu")
	)
	(gr_arc
		(start 23.77694 -113.995454)
		(mid 23.164927 -113.38306)
		(end 22.55266 -113.9952)
		(stroke
			(width 0.2)
			(type default)
		)
		(layer "In4.Cu")
	)
	(gr_arc
		(start 23.861014 -112.521746)
		(mid 24.473027 -113.13414)
		(end 25.085294 -112.522)
		(stroke
			(width 0.2)
			(type default)
		)
		(layer "In4.Cu")
	)
	(gr_line
		(start 23.861014 -111.4044)
		(end 23.861014 -112.521746)
		(stroke
			(width 0.2)
			(type default)
		)
		(layer "In4.Cu")
	)
	(gr_circle
		(center 24.432006 -38.509956)
		(end 25.729946 -38.509956)
		(stroke
			(width 0.2)
			(type default)
		)
		(fill no)
		(layer "In4.Cu")
	)
	(gr_line
		(start 25.085294 -112.522)
		(end 25.085294 -111.4044)
		(stroke
			(width 0.2)
			(type default)
		)
		(layer "In4.Cu")
	)
	(gr_arc
		(start 25.085294 -111.4044)
		(mid 24.473154 -110.79226)
		(end 23.861014 -111.4044)
		(stroke
			(width 0.2)
			(type default)
		)
		(layer "In4.Cu")
	)
	(gr_line
		(start 25.4 -213.499954)
		(end 0.999998 -213.499954)
		(stroke
			(width 1.524)
			(type default)
		)
		(layer "In4.Cu")
	)
	(gr_arc
		(start 25.51684 -143.69796)
		(mid 26.12898 -144.3101)
		(end 26.74112 -143.69796)
		(stroke
			(width 0.2)
			(type default)
		)
		(layer "In4.Cu")
	)
	(gr_line
		(start 25.51684 -142.58036)
		(end 25.51684 -143.69796)
		(stroke
			(width 0.2)
			(type default)
		)
		(layer "In4.Cu")
	)
	(gr_line
		(start 26.699972 -221.400116)
		(end 26.699972 -214.799926)
		(stroke
			(width 1.524)
			(type default)
		)
		(layer "In4.Cu")
	)
	(gr_arc
		(start 26.699972 -221.400116)
		(mid 26.846532 -221.75362)
		(end 27.200098 -221.899988)
		(stroke
			(width 1.524)
			(type default)
		)
		(layer "In4.Cu")
	)
	(gr_arc
		(start 26.699972 -214.799926)
		(mid 26.319219 -213.880707)
		(end 25.4 -213.499954)
		(stroke
			(width 1.524)
			(type default)
		)
		(layer "In4.Cu")
	)
	(gr_line
		(start 26.74112 -143.69796)
		(end 26.74112 -142.580614)
		(stroke
			(width 0.2)
			(type default)
		)
		(layer "In4.Cu")
	)
	(gr_arc
		(start 26.74112 -142.580614)
		(mid 26.129107 -141.96822)
		(end 25.51684 -142.58036)
		(stroke
			(width 0.2)
			(type default)
		)
		(layer "In4.Cu")
	)
	(gr_line
		(start 27.60853 -106.369612)
		(end 28.398978 -107.16006)
		(stroke
			(width 0.2)
			(type default)
		)
		(layer "In4.Cu")
	)
	(gr_line
		(start 27.610308 -106.367834)
		(end 27.60853 -106.369612)
		(stroke
			(width 0.2)
			(type default)
		)
		(layer "In4.Cu")
	)
	(gr_line
		(start 27.999944 -221.899988)
		(end 27.200098 -221.899988)
		(stroke
			(width 1.524)
			(type default)
		)
		(layer "In4.Cu")
	)
	(gr_line
		(start 28.398978 -107.16006)
		(end 28.400756 -107.158282)
		(stroke
			(width 0.2)
			(type default)
		)
		(layer "In4.Cu")
	)
	(gr_arc
		(start 28.400756 -107.158282)
		(mid 29.266388 -107.158282)
		(end 29.266388 -106.29265)
		(stroke
			(width 0.2)
			(type default)
		)
		(layer "In4.Cu")
	)
	(gr_arc
		(start 28.47594 -105.502202)
		(mid 27.610308 -105.502202)
		(end 27.610308 -106.367834)
		(stroke
			(width 0.2)
			(type default)
		)
		(layer "In4.Cu")
	)
	(gr_line
		(start 28.477464 -105.500678)
		(end 28.47594 -105.502202)
		(stroke
			(width 0.2)
			(type default)
		)
		(layer "In4.Cu")
	)
	(gr_line
		(start 28.477972 -105.500678)
		(end 28.477464 -105.500678)
		(stroke
			(width 0.2)
			(type default)
		)
		(layer "In4.Cu")
	)
	(gr_line
		(start 28.50007 -228.000052)
		(end 28.50007 -222.400114)
		(stroke
			(width 1.524)
			(type default)
		)
		(layer "In4.Cu")
	)
	(gr_arc
		(start 28.50007 -222.400114)
		(mid 28.353586 -222.046472)
		(end 27.999944 -221.899988)
		(stroke
			(width 1.524)
			(type default)
		)
		(layer "In4.Cu")
	)
	(gr_line
		(start 29.266388 -106.29265)
		(end 29.268166 -106.290872)
		(stroke
			(width 0.2)
			(type default)
		)
		(layer "In4.Cu")
	)
	(gr_line
		(start 29.268166 -106.290872)
		(end 28.477972 -105.500678)
		(stroke
			(width 0.2)
			(type default)
		)
		(layer "In4.Cu")
	)
	(gr_line
		(start 48.49368 -211.406994)
		(end 49.30648 -211.406994)
		(stroke
			(width 0.2)
			(type default)
		)
		(layer "In4.Cu")
	)
	(gr_arc
		(start 48.493934 -210.385914)
		(mid 47.98314 -210.896327)
		(end 48.49368 -211.406994)
		(stroke
			(width 0.2)
			(type default)
		)
		(layer "In4.Cu")
	)
	(gr_arc
		(start 49.30648 -211.406994)
		(mid 49.81702 -210.896454)
		(end 49.30648 -210.385914)
		(stroke
			(width 0.2)
			(type default)
		)
		(layer "In4.Cu")
	)
	(gr_line
		(start 49.30648 -210.385914)
		(end 48.493934 -210.385914)
		(stroke
			(width 0.2)
			(type default)
		)
		(layer "In4.Cu")
	)
	(gr_arc
		(start 49.950116 -26.010108)
		(mid 51.364327 -25.424323)
		(end 51.950112 -24.010112)
		(stroke
			(width 1.524)
			(type default)
		)
		(layer "In4.Cu")
	)
	(gr_line
		(start 50.093372 -221.916244)
		(end 50.905918 -221.916244)
		(stroke
			(width 0.2)
			(type default)
		)
		(layer "In4.Cu")
	)
	(gr_arc
		(start 50.093372 -220.895164)
		(mid 49.582832 -221.405704)
		(end 50.093372 -221.916244)
		(stroke
			(width 0.2)
			(type default)
		)
		(layer "In4.Cu")
	)
	(gr_line
		(start 50.14468 -209.222594)
		(end 50.95748 -209.222594)
		(stroke
			(width 0.2)
			(type default)
		)
		(layer "In4.Cu")
	)
	(gr_arc
		(start 50.144934 -208.201514)
		(mid 49.63414 -208.711927)
		(end 50.14468 -209.222594)
		(stroke
			(width 0.2)
			(type default)
		)
		(layer "In4.Cu")
	)
	(gr_arc
		(start 50.905918 -221.916244)
		(mid 51.416712 -221.405831)
		(end 50.906172 -220.895164)
		(stroke
			(width 0.2)
			(type default)
		)
		(layer "In4.Cu")
	)
	(gr_line
		(start 50.906172 -220.895164)
		(end 50.093372 -220.895164)
		(stroke
			(width 0.2)
			(type default)
		)
		(layer "In4.Cu")
	)
	(gr_arc
		(start 50.95748 -209.222594)
		(mid 51.46802 -208.712054)
		(end 50.95748 -208.201514)
		(stroke
			(width 0.2)
			(type default)
		)
		(layer "In4.Cu")
	)
	(gr_line
		(start 50.95748 -208.201514)
		(end 50.144934 -208.201514)
		(stroke
			(width 0.2)
			(type default)
		)
		(layer "In4.Cu")
	)
	(gr_line
		(start 51.693572 -211.406994)
		(end 52.506372 -211.406994)
		(stroke
			(width 0.2)
			(type default)
		)
		(layer "In4.Cu")
	)
	(gr_arc
		(start 51.693826 -210.385914)
		(mid 51.183032 -210.896327)
		(end 51.693572 -211.406994)
		(stroke
			(width 0.2)
			(type default)
		)
		(layer "In4.Cu")
	)
	(gr_line
		(start 51.950112 -24.010112)
		(end 51.950112 -1.999996)
		(stroke
			(width 1.524)
			(type default)
		)
		(layer "In4.Cu")
	)
	(gr_line
		(start 52.399438 -48.387508)
		(end 53.305964 -48.387508)
		(stroke
			(width 0.2)
			(type default)
		)
		(layer "In4.Cu")
	)
	(gr_arc
		(start 52.399692 -47.366428)
		(mid 51.888898 -47.876841)
		(end 52.399438 -48.387508)
		(stroke
			(width 0.2)
			(type default)
		)
		(layer "In4.Cu")
	)
	(gr_arc
		(start 52.506372 -211.406994)
		(mid 53.016912 -210.896454)
		(end 52.506372 -210.385914)
		(stroke
			(width 0.2)
			(type default)
		)
		(layer "In4.Cu")
	)
	(gr_line
		(start 52.506372 -210.385914)
		(end 51.693826 -210.385914)
		(stroke
			(width 0.2)
			(type default)
		)
		(layer "In4.Cu")
	)
	(gr_line
		(start 53.293518 -222.805244)
		(end 54.106064 -222.805244)
		(stroke
			(width 0.2)
			(type default)
		)
		(layer "In4.Cu")
	)
	(gr_arc
		(start 53.293518 -221.784164)
		(mid 52.782978 -222.294704)
		(end 53.293518 -222.805244)
		(stroke
			(width 0.2)
			(type default)
		)
		(layer "In4.Cu")
	)
	(gr_arc
		(start 53.305964 -48.387508)
		(mid 53.816504 -47.876968)
		(end 53.305964 -47.366428)
		(stroke
			(width 0.2)
			(type default)
		)
		(layer "In4.Cu")
	)
	(gr_line
		(start 53.305964 -47.366428)
		(end 52.399692 -47.366428)
		(stroke
			(width 0.2)
			(type default)
		)
		(layer "In4.Cu")
	)
	(gr_arc
		(start 53.950108 0)
		(mid 52.535891 -0.585782)
		(end 51.950112 -1.999996)
		(stroke
			(width 1.524)
			(type default)
		)
		(layer "In4.Cu")
	)
	(gr_line
		(start 53.950108 0)
		(end 119.637556 0)
		(stroke
			(width 1.524)
			(type default)
		)
		(layer "In4.Cu")
	)
	(gr_arc
		(start 54.106064 -222.805244)
		(mid 54.616858 -222.294831)
		(end 54.106318 -221.784164)
		(stroke
			(width 0.2)
			(type default)
		)
		(layer "In4.Cu")
	)
	(gr_line
		(start 54.106318 -221.784164)
		(end 53.293518 -221.784164)
		(stroke
			(width 0.2)
			(type default)
		)
		(layer "In4.Cu")
	)
	(gr_line
		(start 54.893718 -211.406994)
		(end 55.706264 -211.406994)
		(stroke
			(width 0.2)
			(type default)
		)
		(layer "In4.Cu")
	)
	(gr_arc
		(start 54.893718 -210.385914)
		(mid 54.383178 -210.896454)
		(end 54.893718 -211.406994)
		(stroke
			(width 0.2)
			(type default)
		)
		(layer "In4.Cu")
	)
	(gr_arc
		(start 55.6387 -86.32825)
		(mid 56.25084 -86.94039)
		(end 56.86298 -86.32825)
		(stroke
			(width 0.2)
			(type default)
		)
		(layer "In4.Cu")
	)
	(gr_line
		(start 55.6387 -85.21065)
		(end 55.6387 -86.32825)
		(stroke
			(width 0.2)
			(type default)
		)
		(layer "In4.Cu")
	)
	(gr_arc
		(start 55.706264 -211.406994)
		(mid 56.217058 -210.896581)
		(end 55.706518 -210.385914)
		(stroke
			(width 0.2)
			(type default)
		)
		(layer "In4.Cu")
	)
	(gr_line
		(start 55.706518 -210.385914)
		(end 54.893718 -210.385914)
		(stroke
			(width 0.2)
			(type default)
		)
		(layer "In4.Cu")
	)
	(gr_line
		(start 56.49341 -222.805244)
		(end 57.305956 -222.805244)
		(stroke
			(width 0.2)
			(type default)
		)
		(layer "In4.Cu")
	)
	(gr_arc
		(start 56.49341 -221.784164)
		(mid 55.98287 -222.294704)
		(end 56.49341 -222.805244)
		(stroke
			(width 0.2)
			(type default)
		)
		(layer "In4.Cu")
	)
	(gr_line
		(start 56.86298 -86.32825)
		(end 56.86298 -85.210904)
		(stroke
			(width 0.2)
			(type default)
		)
		(layer "In4.Cu")
	)
	(gr_arc
		(start 56.86298 -85.210904)
		(mid 56.250967 -84.59851)
		(end 55.6387 -85.21065)
		(stroke
			(width 0.2)
			(type default)
		)
		(layer "In4.Cu")
	)
	(gr_arc
		(start 57.305956 -222.805244)
		(mid 57.81675 -222.294831)
		(end 57.30621 -221.784164)
		(stroke
			(width 0.2)
			(type default)
		)
		(layer "In4.Cu")
	)
	(gr_line
		(start 57.30621 -221.784164)
		(end 56.49341 -221.784164)
		(stroke
			(width 0.2)
			(type default)
		)
		(layer "In4.Cu")
	)
	(gr_line
		(start 58.0517 -196.77634)
		(end 58.8645 -196.77634)
		(stroke
			(width 0.2)
			(type default)
		)
		(layer "In4.Cu")
	)
	(gr_arc
		(start 58.051954 -195.75526)
		(mid 57.54116 -196.265673)
		(end 58.0517 -196.77634)
		(stroke
			(width 0.2)
			(type default)
		)
		(layer "In4.Cu")
	)
	(gr_line
		(start 58.09361 -211.406994)
		(end 58.90641 -211.406994)
		(stroke
			(width 0.2)
			(type default)
		)
		(layer "In4.Cu")
	)
	(gr_arc
		(start 58.093864 -210.385914)
		(mid 57.58307 -210.896327)
		(end 58.09361 -211.406994)
		(stroke
			(width 0.2)
			(type default)
		)
		(layer "In4.Cu")
	)
	(gr_arc
		(start 58.8645 -196.77634)
		(mid 59.37504 -196.2658)
		(end 58.8645 -195.75526)
		(stroke
			(width 0.2)
			(type default)
		)
		(layer "In4.Cu")
	)
	(gr_line
		(start 58.8645 -195.75526)
		(end 58.051954 -195.75526)
		(stroke
			(width 0.2)
			(type default)
		)
		(layer "In4.Cu")
	)
	(gr_arc
		(start 58.90641 -211.406994)
		(mid 59.41695 -210.896454)
		(end 58.90641 -210.385914)
		(stroke
			(width 0.2)
			(type default)
		)
		(layer "In4.Cu")
	)
	(gr_line
		(start 58.90641 -210.385914)
		(end 58.093864 -210.385914)
		(stroke
			(width 0.2)
			(type default)
		)
		(layer "In4.Cu")
	)
	(gr_line
		(start 59.693302 -222.805244)
		(end 60.505848 -222.805244)
		(stroke
			(width 0.2)
			(type default)
		)
		(layer "In4.Cu")
	)
	(gr_arc
		(start 59.693302 -221.784164)
		(mid 59.182762 -222.294704)
		(end 59.693302 -222.805244)
		(stroke
			(width 0.2)
			(type default)
		)
		(layer "In4.Cu")
	)
	(gr_arc
		(start 60.505848 -222.805244)
		(mid 61.016642 -222.294831)
		(end 60.506102 -221.784164)
		(stroke
			(width 0.2)
			(type default)
		)
		(layer "In4.Cu")
	)
	(gr_line
		(start 60.506102 -221.784164)
		(end 59.693302 -221.784164)
		(stroke
			(width 0.2)
			(type default)
		)
		(layer "In4.Cu")
	)
	(gr_line
		(start 63.693548 -211.406994)
		(end 64.506348 -211.406994)
		(stroke
			(width 0.2)
			(type default)
		)
		(layer "In4.Cu")
	)
	(gr_arc
		(start 63.693802 -210.385914)
		(mid 63.183008 -210.896327)
		(end 63.693548 -211.406994)
		(stroke
			(width 0.2)
			(type default)
		)
		(layer "In4.Cu")
	)
	(gr_arc
		(start 64.506348 -211.406994)
		(mid 65.016888 -210.896454)
		(end 64.506348 -210.385914)
		(stroke
			(width 0.2)
			(type default)
		)
		(layer "In4.Cu")
	)
	(gr_line
		(start 64.506348 -210.385914)
		(end 63.693802 -210.385914)
		(stroke
			(width 0.2)
			(type default)
		)
		(layer "In4.Cu")
	)
	(gr_line
		(start 65.293494 -222.805244)
		(end 66.10604 -222.805244)
		(stroke
			(width 0.2)
			(type default)
		)
		(layer "In4.Cu")
	)
	(gr_arc
		(start 65.293494 -221.784164)
		(mid 64.782954 -222.294704)
		(end 65.293494 -222.805244)
		(stroke
			(width 0.2)
			(type default)
		)
		(layer "In4.Cu")
	)
	(gr_line
		(start 65.330578 -128.189736)
		(end 66.143378 -128.189736)
		(stroke
			(width 0.2)
			(type default)
		)
		(layer "In4.Cu")
	)
	(gr_arc
		(start 65.330832 -127.168656)
		(mid 64.820038 -127.679069)
		(end 65.330578 -128.189736)
		(stroke
			(width 0.2)
			(type default)
		)
		(layer "In4.Cu")
	)
	(gr_arc
		(start 66.10604 -222.805244)
		(mid 66.616834 -222.294831)
		(end 66.106294 -221.784164)
		(stroke
			(width 0.2)
			(type default)
		)
		(layer "In4.Cu")
	)
	(gr_line
		(start 66.106294 -221.784164)
		(end 65.293494 -221.784164)
		(stroke
			(width 0.2)
			(type default)
		)
		(layer "In4.Cu")
	)
	(gr_arc
		(start 66.143378 -128.189736)
		(mid 66.653918 -127.679196)
		(end 66.143378 -127.168656)
		(stroke
			(width 0.2)
			(type default)
		)
		(layer "In4.Cu")
	)
	(gr_line
		(start 66.143378 -127.168656)
		(end 65.330832 -127.168656)
		(stroke
			(width 0.2)
			(type default)
		)
		(layer "In4.Cu")
	)
	(gr_line
		(start 66.893694 -211.406994)
		(end 67.706494 -211.406994)
		(stroke
			(width 0.2)
			(type default)
		)
		(layer "In4.Cu")
	)
	(gr_arc
		(start 66.893948 -210.385914)
		(mid 66.383154 -210.896327)
		(end 66.893694 -211.406994)
		(stroke
			(width 0.2)
			(type default)
		)
		(layer "In4.Cu")
	)
	(gr_arc
		(start 67.706494 -211.406994)
		(mid 68.217034 -210.896454)
		(end 67.706494 -210.385914)
		(stroke
			(width 0.2)
			(type default)
		)
		(layer "In4.Cu")
	)
	(gr_line
		(start 67.706494 -210.385914)
		(end 66.893948 -210.385914)
		(stroke
			(width 0.2)
			(type default)
		)
		(layer "In4.Cu")
	)
	(gr_line
		(start 68.493386 -222.805244)
		(end 69.305932 -222.805244)
		(stroke
			(width 0.2)
			(type default)
		)
		(layer "In4.Cu")
	)
	(gr_arc
		(start 68.493386 -221.784164)
		(mid 67.982846 -222.294704)
		(end 68.493386 -222.805244)
		(stroke
			(width 0.2)
			(type default)
		)
		(layer "In4.Cu")
	)
	(gr_arc
		(start 69.305932 -222.805244)
		(mid 69.816726 -222.294831)
		(end 69.306186 -221.784164)
		(stroke
			(width 0.2)
			(type default)
		)
		(layer "In4.Cu")
	)
	(gr_line
		(start 69.306186 -221.784164)
		(end 68.493386 -221.784164)
		(stroke
			(width 0.2)
			(type default)
		)
		(layer "In4.Cu")
	)
	(gr_line
		(start 70.093586 -211.406994)
		(end 70.906386 -211.406994)
		(stroke
			(width 0.2)
			(type default)
		)
		(layer "In4.Cu")
	)
	(gr_arc
		(start 70.09384 -210.385914)
		(mid 69.583046 -210.896327)
		(end 70.093586 -211.406994)
		(stroke
			(width 0.2)
			(type default)
		)
		(layer "In4.Cu")
	)
	(gr_arc
		(start 70.906386 -211.406994)
		(mid 71.416926 -210.896454)
		(end 70.906386 -210.385914)
		(stroke
			(width 0.2)
			(type default)
		)
		(layer "In4.Cu")
	)
	(gr_line
		(start 70.906386 -210.385914)
		(end 70.09384 -210.385914)
		(stroke
			(width 0.2)
			(type default)
		)
		(layer "In4.Cu")
	)
	(gr_line
		(start 71.7042 -220.52534)
		(end 72.516746 -220.52534)
		(stroke
			(width 0.2)
			(type default)
		)
		(layer "In4.Cu")
	)
	(gr_arc
		(start 71.7042 -219.50426)
		(mid 71.19366 -220.0148)
		(end 71.7042 -220.52534)
		(stroke
			(width 0.2)
			(type default)
		)
		(layer "In4.Cu")
	)
	(gr_arc
		(start 72.516746 -220.52534)
		(mid 73.02754 -220.014927)
		(end 72.517 -219.50426)
		(stroke
			(width 0.2)
			(type default)
		)
		(layer "In4.Cu")
	)
	(gr_line
		(start 72.517 -219.50426)
		(end 71.7042 -219.50426)
		(stroke
			(width 0.2)
			(type default)
		)
		(layer "In4.Cu")
	)
	(gr_line
		(start 74.099928 -228.000052)
		(end 28.50007 -228.000052)
		(stroke
			(width 5.08)
			(type default)
		)
		(layer "In4.Cu")
	)
	(gr_line
		(start 74.099928 -222.600012)
		(end 74.099928 -228.000052)
		(stroke
			(width 1.524)
			(type default)
		)
		(layer "In4.Cu")
	)
	(gr_line
		(start 76.499974 -228.000052)
		(end 76.499974 -222.600012)
		(stroke
			(width 1.524)
			(type default)
		)
		(layer "In4.Cu")
	)
	(gr_arc
		(start 76.499974 -222.600012)
		(mid 75.300078 -221.400116)
		(end 74.099928 -222.600012)
		(stroke
			(width 1.524)
			(type default)
		)
		(layer "In4.Cu")
	)
	(gr_line
		(start 78.16977 -220.392244)
		(end 78.982316 -220.392244)
		(stroke
			(width 0.2)
			(type default)
		)
		(layer "In4.Cu")
	)
	(gr_arc
		(start 78.16977 -219.371164)
		(mid 77.65923 -219.881704)
		(end 78.16977 -220.392244)
		(stroke
			(width 0.2)
			(type default)
		)
		(layer "In4.Cu")
	)
	(gr_arc
		(start 78.982316 -220.392244)
		(mid 79.49311 -219.881831)
		(end 78.98257 -219.371164)
		(stroke
			(width 0.2)
			(type default)
		)
		(layer "In4.Cu")
	)
	(gr_line
		(start 78.98257 -219.371164)
		(end 78.16977 -219.371164)
		(stroke
			(width 0.2)
			(type default)
		)
		(layer "In4.Cu")
	)
	(gr_line
		(start 79.693516 -211.406994)
		(end 80.506316 -211.406994)
		(stroke
			(width 0.2)
			(type default)
		)
		(layer "In4.Cu")
	)
	(gr_arc
		(start 79.69377 -210.385914)
		(mid 79.182976 -210.896327)
		(end 79.693516 -211.406994)
		(stroke
			(width 0.2)
			(type default)
		)
		(layer "In4.Cu")
	)
	(gr_arc
		(start 80.506316 -211.406994)
		(mid 81.016856 -210.896454)
		(end 80.506316 -210.385914)
		(stroke
			(width 0.2)
			(type default)
		)
		(layer "In4.Cu")
	)
	(gr_line
		(start 80.506316 -210.385914)
		(end 79.69377 -210.385914)
		(stroke
			(width 0.2)
			(type default)
		)
		(layer "In4.Cu")
	)
	(gr_line
		(start 81.293462 -222.805244)
		(end 82.106008 -222.805244)
		(stroke
			(width 0.2)
			(type default)
		)
		(layer "In4.Cu")
	)
	(gr_arc
		(start 81.293462 -221.784164)
		(mid 80.782922 -222.294704)
		(end 81.293462 -222.805244)
		(stroke
			(width 0.2)
			(type default)
		)
		(layer "In4.Cu")
	)
	(gr_arc
		(start 82.106008 -222.805244)
		(mid 82.616802 -222.294831)
		(end 82.106262 -221.784164)
		(stroke
			(width 0.2)
			(type default)
		)
		(layer "In4.Cu")
	)
	(gr_line
		(start 82.106262 -221.784164)
		(end 81.293462 -221.784164)
		(stroke
			(width 0.2)
			(type default)
		)
		(layer "In4.Cu")
	)
	(gr_line
		(start 82.893662 -211.406994)
		(end 83.706462 -211.406994)
		(stroke
			(width 0.2)
			(type default)
		)
		(layer "In4.Cu")
	)
	(gr_arc
		(start 82.893916 -210.385914)
		(mid 82.383122 -210.896327)
		(end 82.893662 -211.406994)
		(stroke
			(width 0.2)
			(type default)
		)
		(layer "In4.Cu")
	)
	(gr_arc
		(start 83.706462 -211.406994)
		(mid 84.217002 -210.896454)
		(end 83.706462 -210.385914)
		(stroke
			(width 0.2)
			(type default)
		)
		(layer "In4.Cu")
	)
	(gr_line
		(start 83.706462 -210.385914)
		(end 82.893916 -210.385914)
		(stroke
			(width 0.2)
			(type default)
		)
		(layer "In4.Cu")
	)
	(gr_line
		(start 84.493354 -222.805244)
		(end 85.3059 -222.805244)
		(stroke
			(width 0.2)
			(type default)
		)
		(layer "In4.Cu")
	)
	(gr_arc
		(start 84.493354 -221.784164)
		(mid 83.982814 -222.294704)
		(end 84.493354 -222.805244)
		(stroke
			(width 0.2)
			(type default)
		)
		(layer "In4.Cu")
	)
	(gr_arc
		(start 85.3059 -222.805244)
		(mid 85.816694 -222.294831)
		(end 85.306154 -221.784164)
		(stroke
			(width 0.2)
			(type default)
		)
		(layer "In4.Cu")
	)
	(gr_line
		(start 85.306154 -221.784164)
		(end 84.493354 -221.784164)
		(stroke
			(width 0.2)
			(type default)
		)
		(layer "In4.Cu")
	)
	(gr_line
		(start 86.093554 -211.406994)
		(end 86.906354 -211.406994)
		(stroke
			(width 0.2)
			(type default)
		)
		(layer "In4.Cu")
	)
	(gr_arc
		(start 86.093808 -210.385914)
		(mid 85.583014 -210.896327)
		(end 86.093554 -211.406994)
		(stroke
			(width 0.2)
			(type default)
		)
		(layer "In4.Cu")
	)
	(gr_arc
		(start 86.269068 -77.478382)
		(mid 86.779481 -77.989176)
		(end 87.290148 -77.478636)
		(stroke
			(width 0.2)
			(type default)
		)
		(layer "In4.Cu")
	)
	(gr_line
		(start 86.269068 -76.589636)
		(end 86.269068 -77.478382)
		(stroke
			(width 0.2)
			(type default)
		)
		(layer "In4.Cu")
	)
	(gr_arc
		(start 86.906354 -211.406994)
		(mid 87.416894 -210.896454)
		(end 86.906354 -210.385914)
		(stroke
			(width 0.2)
			(type default)
		)
		(layer "In4.Cu")
	)
	(gr_line
		(start 86.906354 -210.385914)
		(end 86.093808 -210.385914)
		(stroke
			(width 0.2)
			(type default)
		)
		(layer "In4.Cu")
	)
	(gr_line
		(start 87.290148 -77.478636)
		(end 87.290148 -76.589636)
		(stroke
			(width 0.2)
			(type default)
		)
		(layer "In4.Cu")
	)
	(gr_arc
		(start 87.290148 -76.589636)
		(mid 86.779608 -76.079096)
		(end 86.269068 -76.589636)
		(stroke
			(width 0.2)
			(type default)
		)
		(layer "In4.Cu")
	)
	(gr_line
		(start 87.6935 -222.805244)
		(end 88.506046 -222.805244)
		(stroke
			(width 0.2)
			(type default)
		)
		(layer "In4.Cu")
	)
	(gr_arc
		(start 87.6935 -221.784164)
		(mid 87.18296 -222.294704)
		(end 87.6935 -222.805244)
		(stroke
			(width 0.2)
			(type default)
		)
		(layer "In4.Cu")
	)
	(gr_arc
		(start 88.506046 -222.805244)
		(mid 89.01684 -222.294831)
		(end 88.5063 -221.784164)
		(stroke
			(width 0.2)
			(type default)
		)
		(layer "In4.Cu")
	)
	(gr_line
		(start 88.5063 -221.784164)
		(end 87.6935 -221.784164)
		(stroke
			(width 0.2)
			(type default)
		)
		(layer "In4.Cu")
	)
	(gr_line
		(start 89.2937 -211.406994)
		(end 90.1065 -211.406994)
		(stroke
			(width 0.2)
			(type default)
		)
		(layer "In4.Cu")
	)
	(gr_arc
		(start 89.293954 -210.385914)
		(mid 88.78316 -210.896327)
		(end 89.2937 -211.406994)
		(stroke
			(width 0.2)
			(type default)
		)
		(layer "In4.Cu")
	)
	(gr_arc
		(start 90.1065 -211.406994)
		(mid 90.61704 -210.896454)
		(end 90.1065 -210.385914)
		(stroke
			(width 0.2)
			(type default)
		)
		(layer "In4.Cu")
	)
	(gr_line
		(start 90.1065 -210.385914)
		(end 89.293954 -210.385914)
		(stroke
			(width 0.2)
			(type default)
		)
		(layer "In4.Cu")
	)
	(gr_line
		(start 90.893392 -222.805244)
		(end 91.705938 -222.805244)
		(stroke
			(width 0.2)
			(type default)
		)
		(layer "In4.Cu")
	)
	(gr_arc
		(start 90.893392 -221.784164)
		(mid 90.382852 -222.294704)
		(end 90.893392 -222.805244)
		(stroke
			(width 0.2)
			(type default)
		)
		(layer "In4.Cu")
	)
	(gr_line
		(start 91.608402 -185.665364)
		(end 92.18295 -186.240166)
		(stroke
			(width 0.2)
			(type default)
		)
		(layer "In4.Cu")
	)
	(gr_line
		(start 91.61018 -185.663586)
		(end 91.608402 -185.665364)
		(stroke
			(width 0.2)
			(type default)
		)
		(layer "In4.Cu")
	)
	(gr_arc
		(start 91.705938 -222.805244)
		(mid 92.216732 -222.294831)
		(end 91.706192 -221.784164)
		(stroke
			(width 0.2)
			(type default)
		)
		(layer "In4.Cu")
	)
	(gr_line
		(start 91.706192 -221.784164)
		(end 90.893392 -221.784164)
		(stroke
			(width 0.2)
			(type default)
		)
		(layer "In4.Cu")
	)
	(gr_line
		(start 92.18295 -186.240166)
		(end 92.183204 -186.240166)
		(stroke
			(width 0.2)
			(type default)
		)
		(layer "In4.Cu")
	)
	(gr_line
		(start 92.183204 -186.240166)
		(end 92.184982 -186.238388)
		(stroke
			(width 0.2)
			(type default)
		)
		(layer "In4.Cu")
	)
	(gr_arc
		(start 92.184982 -186.238388)
		(mid 92.90685 -186.238388)
		(end 92.90685 -185.51652)
		(stroke
			(width 0.2)
			(type default)
		)
		(layer "In4.Cu")
	)
	(gr_arc
		(start 92.332048 -184.941718)
		(mid 91.61018 -184.941718)
		(end 91.61018 -185.663586)
		(stroke
			(width 0.2)
			(type default)
		)
		(layer "In4.Cu")
	)
	(gr_line
		(start 92.333826 -184.93994)
		(end 92.332048 -184.941718)
		(stroke
			(width 0.2)
			(type default)
		)
		(layer "In4.Cu")
	)
	(gr_line
		(start 92.493592 -211.406994)
		(end 93.306392 -211.406994)
		(stroke
			(width 0.2)
			(type default)
		)
		(layer "In4.Cu")
	)
	(gr_arc
		(start 92.493846 -210.385914)
		(mid 91.983052 -210.896327)
		(end 92.493592 -211.406994)
		(stroke
			(width 0.2)
			(type default)
		)
		(layer "In4.Cu")
	)
	(gr_line
		(start 92.90685 -185.51652)
		(end 92.908628 -185.514742)
		(stroke
			(width 0.2)
			(type default)
		)
		(layer "In4.Cu")
	)
	(gr_line
		(start 92.908628 -185.514742)
		(end 92.333826 -184.93994)
		(stroke
			(width 0.2)
			(type default)
		)
		(layer "In4.Cu")
	)
	(gr_arc
		(start 93.306392 -211.406994)
		(mid 93.816932 -210.896454)
		(end 93.306392 -210.385914)
		(stroke
			(width 0.2)
			(type default)
		)
		(layer "In4.Cu")
	)
	(gr_line
		(start 93.306392 -210.385914)
		(end 92.493846 -210.385914)
		(stroke
			(width 0.2)
			(type default)
		)
		(layer "In4.Cu")
	)
	(gr_line
		(start 93.38945 -184.15254)
		(end 94.201996 -184.15254)
		(stroke
			(width 0.2)
			(type default)
		)
		(layer "In4.Cu")
	)
	(gr_arc
		(start 93.38945 -183.13146)
		(mid 92.87891 -183.642)
		(end 93.38945 -184.15254)
		(stroke
			(width 0.2)
			(type default)
		)
		(layer "In4.Cu")
	)
	(gr_arc
		(start 94.201996 -184.15254)
		(mid 94.71279 -183.642127)
		(end 94.20225 -183.13146)
		(stroke
			(width 0.2)
			(type default)
		)
		(layer "In4.Cu")
	)
	(gr_line
		(start 94.20225 -183.13146)
		(end 93.38945 -183.13146)
		(stroke
			(width 0.2)
			(type default)
		)
		(layer "In4.Cu")
	)
	(gr_line
		(start 96.493584 -222.805244)
		(end 97.30613 -222.805244)
		(stroke
			(width 0.2)
			(type default)
		)
		(layer "In4.Cu")
	)
	(gr_arc
		(start 96.493584 -221.784164)
		(mid 95.983044 -222.294704)
		(end 96.493584 -222.805244)
		(stroke
			(width 0.2)
			(type default)
		)
		(layer "In4.Cu")
	)
	(gr_arc
		(start 97.30613 -222.805244)
		(mid 97.816924 -222.294831)
		(end 97.306384 -221.784164)
		(stroke
			(width 0.2)
			(type default)
		)
		(layer "In4.Cu")
	)
	(gr_line
		(start 97.306384 -221.784164)
		(end 96.493584 -221.784164)
		(stroke
			(width 0.2)
			(type default)
		)
		(layer "In4.Cu")
	)
	(gr_line
		(start 98.093784 -211.406994)
		(end 98.906584 -211.406994)
		(stroke
			(width 0.2)
			(type default)
		)
		(layer "In4.Cu")
	)
	(gr_arc
		(start 98.094038 -210.385914)
		(mid 97.583244 -210.896327)
		(end 98.093784 -211.406994)
		(stroke
			(width 0.2)
			(type default)
		)
		(layer "In4.Cu")
	)
	(gr_arc
		(start 98.906584 -211.406994)
		(mid 99.417124 -210.896454)
		(end 98.906584 -210.385914)
		(stroke
			(width 0.2)
			(type default)
		)
		(layer "In4.Cu")
	)
	(gr_line
		(start 98.906584 -210.385914)
		(end 98.094038 -210.385914)
		(stroke
			(width 0.2)
			(type default)
		)
		(layer "In4.Cu")
	)
	(gr_line
		(start 99.693476 -222.805244)
		(end 100.506022 -222.805244)
		(stroke
			(width 0.2)
			(type default)
		)
		(layer "In4.Cu")
	)
	(gr_arc
		(start 99.693476 -221.784164)
		(mid 99.182936 -222.294704)
		(end 99.693476 -222.805244)
		(stroke
			(width 0.2)
			(type default)
		)
		(layer "In4.Cu")
	)
	(gr_arc
		(start 100.506022 -222.805244)
		(mid 101.016816 -222.294831)
		(end 100.506276 -221.784164)
		(stroke
			(width 0.2)
			(type default)
		)
		(layer "In4.Cu")
	)
	(gr_line
		(start 100.506276 -221.784164)
		(end 99.693476 -221.784164)
		(stroke
			(width 0.2)
			(type default)
		)
		(layer "In4.Cu")
	)
	(gr_line
		(start 101.293676 -211.406994)
		(end 102.106222 -211.406994)
		(stroke
			(width 0.2)
			(type default)
		)
		(layer "In4.Cu")
	)
	(gr_arc
		(start 101.293676 -210.385914)
		(mid 100.783136 -210.896454)
		(end 101.293676 -211.406994)
		(stroke
			(width 0.2)
			(type default)
		)
		(layer "In4.Cu")
	)
	(gr_arc
		(start 101.41966 -39.80561)
		(mid 101.9302 -40.31615)
		(end 102.44074 -39.80561)
		(stroke
			(width 0.2)
			(type default)
		)
		(layer "In4.Cu")
	)
	(gr_line
		(start 101.41966 -38.91661)
		(end 101.41966 -39.80561)
		(stroke
			(width 0.2)
			(type default)
		)
		(layer "In4.Cu")
	)
	(gr_arc
		(start 102.00386 -37.094414)
		(mid 102.514273 -37.605208)
		(end 103.02494 -37.094668)
		(stroke
			(width 0.2)
			(type default)
		)
		(layer "In4.Cu")
	)
	(gr_line
		(start 102.00386 -36.205668)
		(end 102.00386 -37.094414)
		(stroke
			(width 0.2)
			(type default)
		)
		(layer "In4.Cu")
	)
	(gr_arc
		(start 102.01402 -82.1182)
		(mid 102.62616 -82.73034)
		(end 103.2383 -82.1182)
		(stroke
			(width 0.2)
			(type default)
		)
		(layer "In4.Cu")
	)
	(gr_line
		(start 102.01402 -81.0006)
		(end 102.01402 -82.1182)
		(stroke
			(width 0.2)
			(type default)
		)
		(layer "In4.Cu")
	)
	(gr_arc
		(start 102.106222 -211.406994)
		(mid 102.617016 -210.896581)
		(end 102.106476 -210.385914)
		(stroke
			(width 0.2)
			(type default)
		)
		(layer "In4.Cu")
	)
	(gr_line
		(start 102.106476 -210.385914)
		(end 101.293676 -210.385914)
		(stroke
			(width 0.2)
			(type default)
		)
		(layer "In4.Cu")
	)
	(gr_line
		(start 102.44074 -39.80561)
		(end 102.44074 -38.916864)
		(stroke
			(width 0.2)
			(type default)
		)
		(layer "In4.Cu")
	)
	(gr_arc
		(start 102.44074 -38.916864)
		(mid 101.930327 -38.40607)
		(end 101.41966 -38.91661)
		(stroke
			(width 0.2)
			(type default)
		)
		(layer "In4.Cu")
	)
	(gr_line
		(start 102.893368 -222.805244)
		(end 103.705914 -222.805244)
		(stroke
			(width 0.2)
			(type default)
		)
		(layer "In4.Cu")
	)
	(gr_arc
		(start 102.893368 -221.784164)
		(mid 102.382828 -222.294704)
		(end 102.893368 -222.805244)
		(stroke
			(width 0.2)
			(type default)
		)
		(layer "In4.Cu")
	)
	(gr_line
		(start 103.02494 -37.094668)
		(end 103.02494 -36.205668)
		(stroke
			(width 0.2)
			(type default)
		)
		(layer "In4.Cu")
	)
	(gr_arc
		(start 103.02494 -36.205668)
		(mid 102.5144 -35.695128)
		(end 102.00386 -36.205668)
		(stroke
			(width 0.2)
			(type default)
		)
		(layer "In4.Cu")
	)
	(gr_line
		(start 103.2383 -82.1182)
		(end 103.2383 -81.000854)
		(stroke
			(width 0.2)
			(type default)
		)
		(layer "In4.Cu")
	)
	(gr_arc
		(start 103.2383 -81.000854)
		(mid 102.626287 -80.38846)
		(end 102.01402 -81.0006)
		(stroke
			(width 0.2)
			(type default)
		)
		(layer "In4.Cu")
	)
	(gr_arc
		(start 103.705914 -222.805244)
		(mid 104.216708 -222.294831)
		(end 103.706168 -221.784164)
		(stroke
			(width 0.2)
			(type default)
		)
		(layer "In4.Cu")
	)
	(gr_line
		(start 103.706168 -221.784164)
		(end 102.893368 -221.784164)
		(stroke
			(width 0.2)
			(type default)
		)
		(layer "In4.Cu")
	)
	(gr_line
		(start 104.493822 -211.406994)
		(end 105.306622 -211.406994)
		(stroke
			(width 0.2)
			(type default)
		)
		(layer "In4.Cu")
	)
	(gr_arc
		(start 104.494076 -210.385914)
		(mid 103.983282 -210.896327)
		(end 104.493822 -211.406994)
		(stroke
			(width 0.2)
			(type default)
		)
		(layer "In4.Cu")
	)
	(gr_arc
		(start 105.306622 -211.406994)
		(mid 105.817162 -210.896454)
		(end 105.306622 -210.385914)
		(stroke
			(width 0.2)
			(type default)
		)
		(layer "In4.Cu")
	)
	(gr_line
		(start 105.306622 -210.385914)
		(end 104.494076 -210.385914)
		(stroke
			(width 0.2)
			(type default)
		)
		(layer "In4.Cu")
	)
	(gr_line
		(start 106.093514 -222.805244)
		(end 106.90606 -222.805244)
		(stroke
			(width 0.2)
			(type default)
		)
		(layer "In4.Cu")
	)
	(gr_arc
		(start 106.093514 -221.784164)
		(mid 105.582974 -222.294704)
		(end 106.093514 -222.805244)
		(stroke
			(width 0.2)
			(type default)
		)
		(layer "In4.Cu")
	)
	(gr_arc
		(start 106.90606 -222.805244)
		(mid 107.416854 -222.294831)
		(end 106.906314 -221.784164)
		(stroke
			(width 0.2)
			(type default)
		)
		(layer "In4.Cu")
	)
	(gr_line
		(start 106.906314 -221.784164)
		(end 106.093514 -221.784164)
		(stroke
			(width 0.2)
			(type default)
		)
		(layer "In4.Cu")
	)
	(gr_line
		(start 107.693714 -211.406994)
		(end 108.506514 -211.406994)
		(stroke
			(width 0.2)
			(type default)
		)
		(layer "In4.Cu")
	)
	(gr_arc
		(start 107.693968 -210.385914)
		(mid 107.183174 -210.896327)
		(end 107.693714 -211.406994)
		(stroke
			(width 0.2)
			(type default)
		)
		(layer "In4.Cu")
	)
	(gr_arc
		(start 108.506514 -211.406994)
		(mid 109.017054 -210.896454)
		(end 108.506514 -210.385914)
		(stroke
			(width 0.2)
			(type default)
		)
		(layer "In4.Cu")
	)
	(gr_line
		(start 108.506514 -210.385914)
		(end 107.693968 -210.385914)
		(stroke
			(width 0.2)
			(type default)
		)
		(layer "In4.Cu")
	)
	(gr_line
		(start 112.499902 -228.000052)
		(end 76.499974 -228.000052)
		(stroke
			(width 5.08)
			(type default)
		)
		(layer "In4.Cu")
	)
	(gr_line
		(start 112.499902 -222.400114)
		(end 112.499902 -228.000052)
		(stroke
			(width 1.524)
			(type default)
		)
		(layer "In4.Cu")
	)
	(gr_arc
		(start 113.000028 -221.899988)
		(mid 112.646386 -222.046472)
		(end 112.499902 -222.400114)
		(stroke
			(width 1.524)
			(type default)
		)
		(layer "In4.Cu")
	)
	(gr_line
		(start 113.799874 -221.899988)
		(end 113.000028 -221.899988)
		(stroke
			(width 1.524)
			(type default)
		)
		(layer "In4.Cu")
	)
	(gr_arc
		(start 113.799874 -221.899988)
		(mid 114.153489 -221.75366)
		(end 114.3 -221.400116)
		(stroke
			(width 1.524)
			(type default)
		)
		(layer "In4.Cu")
	)
	(gr_line
		(start 114.3 -214.799926)
		(end 114.3 -221.400116)
		(stroke
			(width 1.524)
			(type default)
		)
		(layer "In4.Cu")
	)
	(gr_arc
		(start 115.599972 -213.499954)
		(mid 114.680753 -213.880707)
		(end 114.3 -214.799926)
		(stroke
			(width 1.524)
			(type default)
		)
		(layer "In4.Cu")
	)
	(gr_arc
		(start 119.637556 0)
		(mid 121.051767 0.585785)
		(end 121.637552 1.999996)
		(stroke
			(width 1.524)
			(type default)
		)
		(layer "In4.Cu")
	)
	(gr_line
		(start 121.637552 1.999996)
		(end 121.637552 2.999994)
		(stroke
			(width 1.524)
			(type default)
		)
		(layer "In4.Cu")
	)
	(gr_arc
		(start 123.637548 4.99999)
		(mid 122.223308 4.414221)
		(end 121.637552 2.999994)
		(stroke
			(width 1.524)
			(type default)
		)
		(layer "In4.Cu")
	)
	(gr_line
		(start 123.637548 4.99999)
		(end 330.74991 4.99999)
		(stroke
			(width 1.524)
			(type default)
		)
		(layer "In4.Cu")
	)
	(gr_line
		(start 131.0894 -35.783774)
		(end 131.9022 -35.783774)
		(stroke
			(width 0.2)
			(type default)
		)
		(layer "In4.Cu")
	)
	(gr_arc
		(start 131.089654 -34.762694)
		(mid 130.57886 -35.273107)
		(end 131.0894 -35.783774)
		(stroke
			(width 0.2)
			(type default)
		)
		(layer "In4.Cu")
	)
	(gr_arc
		(start 131.134104 -42.7228)
		(mid 131.746244 -43.33494)
		(end 132.358384 -42.7228)
		(stroke
			(width 0.2)
			(type default)
		)
		(layer "In4.Cu")
	)
	(gr_line
		(start 131.134104 -41.6052)
		(end 131.134104 -42.7228)
		(stroke
			(width 0.2)
			(type default)
		)
		(layer "In4.Cu")
	)
	(gr_line
		(start 131.400042 -213.499954)
		(end 115.599972 -213.499954)
		(stroke
			(width 1.524)
			(type default)
		)
		(layer "In4.Cu")
	)
	(gr_arc
		(start 131.9022 -35.783774)
		(mid 132.41274 -35.273234)
		(end 131.9022 -34.762694)
		(stroke
			(width 0.2)
			(type default)
		)
		(layer "In4.Cu")
	)
	(gr_line
		(start 131.9022 -34.762694)
		(end 131.089654 -34.762694)
		(stroke
			(width 0.2)
			(type default)
		)
		(layer "In4.Cu")
	)
	(gr_line
		(start 132.358384 -42.7228)
		(end 132.358384 -41.605454)
		(stroke
			(width 0.2)
			(type default)
		)
		(layer "In4.Cu")
	)
	(gr_arc
		(start 132.358384 -41.605454)
		(mid 131.746371 -40.99306)
		(end 131.134104 -41.6052)
		(stroke
			(width 0.2)
			(type default)
		)
		(layer "In4.Cu")
	)
	(gr_line
		(start 132.581396 -25.033732)
		(end 132.58165 -25.033986)
		(stroke
			(width 0.2)
			(type default)
		)
		(layer "In4.Cu")
	)
	(gr_line
		(start 132.581396 -13.633958)
		(end 132.583428 -13.635228)
		(stroke
			(width 0.2)
			(type default)
		)
		(layer "In4.Cu")
	)
	(gr_line
		(start 132.58165 -25.033986)
		(end 132.583682 -25.035002)
		(stroke
			(width 0.2)
			(type default)
		)
		(layer "In4.Cu")
	)
	(gr_arc
		(start 132.583428 -13.635228)
		(mid 132.83946 -14.481048)
		(end 133.68528 -14.225016)
		(stroke
			(width 0.2)
			(type default)
		)
		(layer "In4.Cu")
	)
	(gr_arc
		(start 132.583682 -25.035002)
		(mid 132.839358 -25.880903)
		(end 133.68528 -25.625044)
		(stroke
			(width 0.2)
			(type default)
		)
		(layer "In4.Cu")
	)
	(gr_line
		(start 132.700014 -221.400116)
		(end 132.700014 -214.799926)
		(stroke
			(width 1.524)
			(type default)
		)
		(layer "In4.Cu")
	)
	(gr_arc
		(start 132.700014 -221.400116)
		(mid 132.846428 -221.753573)
		(end 133.199886 -221.899988)
		(stroke
			(width 1.524)
			(type default)
		)
		(layer "In4.Cu")
	)
	(gr_arc
		(start 132.700014 -214.799926)
		(mid 132.319261 -213.880707)
		(end 131.400042 -213.499954)
		(stroke
			(width 1.524)
			(type default)
		)
		(layer "In4.Cu")
	)
	(gr_line
		(start 133.331458 -23.633938)
		(end 132.581396 -25.033732)
		(stroke
			(width 0.2)
			(type default)
		)
		(layer "In4.Cu")
	)
	(gr_line
		(start 133.331458 -12.23391)
		(end 132.581396 -13.633958)
		(stroke
			(width 0.2)
			(type default)
		)
		(layer "In4.Cu")
	)
	(gr_line
		(start 133.33349 -23.635208)
		(end 133.331458 -23.633938)
		(stroke
			(width 0.2)
			(type default)
		)
		(layer "In4.Cu")
	)
	(gr_line
		(start 133.33349 -12.23518)
		(end 133.331458 -12.23391)
		(stroke
			(width 0.2)
			(type default)
		)
		(layer "In4.Cu")
	)
	(gr_line
		(start 133.68528 -25.625044)
		(end 133.687312 -25.626314)
		(stroke
			(width 0.2)
			(type default)
		)
		(layer "In4.Cu")
	)
	(gr_line
		(start 133.68528 -14.225016)
		(end 133.687312 -14.226286)
		(stroke
			(width 0.2)
			(type default)
		)
		(layer "In4.Cu")
	)
	(gr_line
		(start 133.687312 -25.626314)
		(end 134.437374 -24.226266)
		(stroke
			(width 0.2)
			(type default)
		)
		(layer "In4.Cu")
	)
	(gr_line
		(start 133.687312 -14.226286)
		(end 134.437374 -12.826492)
		(stroke
			(width 0.2)
			(type default)
		)
		(layer "In4.Cu")
	)
	(gr_line
		(start 133.852158 -36.250372)
		(end 134.664704 -36.250372)
		(stroke
			(width 0.2)
			(type default)
		)
		(layer "In4.Cu")
	)
	(gr_arc
		(start 133.852158 -35.229292)
		(mid 133.341618 -35.739832)
		(end 133.852158 -36.250372)
		(stroke
			(width 0.2)
			(type default)
		)
		(layer "In4.Cu")
	)
	(gr_line
		(start 133.999986 -221.899988)
		(end 133.199886 -221.899988)
		(stroke
			(width 1.524)
			(type default)
		)
		(layer "In4.Cu")
	)
	(gr_arc
		(start 134.435088 -12.825222)
		(mid 134.179412 -11.979321)
		(end 133.33349 -12.23518)
		(stroke
			(width 0.2)
			(type default)
		)
		(layer "In4.Cu")
	)
	(gr_arc
		(start 134.435342 -24.224996)
		(mid 134.17931 -23.379176)
		(end 133.33349 -23.635208)
		(stroke
			(width 0.2)
			(type default)
		)
		(layer "In4.Cu")
	)
	(gr_line
		(start 134.43712 -12.826238)
		(end 134.435088 -12.825222)
		(stroke
			(width 0.2)
			(type default)
		)
		(layer "In4.Cu")
	)
	(gr_line
		(start 134.437374 -24.226266)
		(end 134.435342 -24.224996)
		(stroke
			(width 0.2)
			(type default)
		)
		(layer "In4.Cu")
	)
	(gr_line
		(start 134.437374 -12.826492)
		(end 134.43712 -12.826238)
		(stroke
			(width 0.2)
			(type default)
		)
		(layer "In4.Cu")
	)
	(gr_line
		(start 134.500112 -228.000052)
		(end 134.500112 -222.400114)
		(stroke
			(width 1.524)
			(type default)
		)
		(layer "In4.Cu")
	)
	(gr_arc
		(start 134.500112 -222.400114)
		(mid 134.353628 -222.046472)
		(end 133.999986 -221.899988)
		(stroke
			(width 1.524)
			(type default)
		)
		(layer "In4.Cu")
	)
	(gr_arc
		(start 134.664704 -36.250372)
		(mid 135.175498 -35.739959)
		(end 134.664958 -35.229292)
		(stroke
			(width 0.2)
			(type default)
		)
		(layer "In4.Cu")
	)
	(gr_line
		(start 134.664958 -35.229292)
		(end 133.852158 -35.229292)
		(stroke
			(width 0.2)
			(type default)
		)
		(layer "In4.Cu")
	)
	(gr_line
		(start 134.831582 -17.433544)
		(end 134.831836 -17.433798)
		(stroke
			(width 0.2)
			(type default)
		)
		(layer "In4.Cu")
	)
	(gr_line
		(start 134.831836 -17.433798)
		(end 134.833868 -17.434814)
		(stroke
			(width 0.2)
			(type default)
		)
		(layer "In4.Cu")
	)
	(gr_arc
		(start 134.833614 -13.635228)
		(mid 135.089646 -14.481048)
		(end 135.935466 -14.225016)
		(stroke
			(width 0.2)
			(type default)
		)
		(layer "In4.Cu")
	)
	(gr_arc
		(start 134.833868 -17.434814)
		(mid 135.089544 -18.280715)
		(end 135.935466 -18.024856)
		(stroke
			(width 0.2)
			(type default)
		)
		(layer "In4.Cu")
	)
	(gr_arc
		(start 134.837678 -25.027636)
		(mid 135.085812 -25.879089)
		(end 135.935466 -25.625044)
		(stroke
			(width 0.2)
			(type default)
		)
		(layer "In4.Cu")
	)
	(gr_arc
		(start 134.837678 -21.227542)
		(mid 135.085812 -22.078995)
		(end 135.935466 -21.82495)
		(stroke
			(width 0.2)
			(type default)
		)
		(layer "In4.Cu")
	)
	(gr_line
		(start 135.58139 -16.034004)
		(end 134.831582 -17.433544)
		(stroke
			(width 0.2)
			(type default)
		)
		(layer "In4.Cu")
	)
	(gr_line
		(start 135.583422 -23.635208)
		(end 134.837678 -25.027636)
		(stroke
			(width 0.2)
			(type default)
		)
		(layer "In4.Cu")
	)
	(gr_line
		(start 135.583422 -19.835114)
		(end 134.837678 -21.227542)
		(stroke
			(width 0.2)
			(type default)
		)
		(layer "In4.Cu")
	)
	(gr_line
		(start 135.583422 -16.035274)
		(end 135.58139 -16.034004)
		(stroke
			(width 0.2)
			(type default)
		)
		(layer "In4.Cu")
	)
	(gr_line
		(start 135.583422 -12.23518)
		(end 134.833614 -13.635228)
		(stroke
			(width 0.2)
			(type default)
		)
		(layer "In4.Cu")
	)
	(gr_line
		(start 135.935466 -25.625044)
		(end 136.685274 -24.224996)
		(stroke
			(width 0.2)
			(type default)
		)
		(layer "In4.Cu")
	)
	(gr_line
		(start 135.935466 -21.82495)
		(end 136.685274 -20.424902)
		(stroke
			(width 0.2)
			(type default)
		)
		(layer "In4.Cu")
	)
	(gr_line
		(start 135.935466 -18.024856)
		(end 135.937498 -18.026126)
		(stroke
			(width 0.2)
			(type default)
		)
		(layer "In4.Cu")
	)
	(gr_line
		(start 135.935466 -14.225016)
		(end 136.68121 -12.832588)
		(stroke
			(width 0.2)
			(type default)
		)
		(layer "In4.Cu")
	)
	(gr_line
		(start 135.937498 -18.026126)
		(end 136.687306 -16.626332)
		(stroke
			(width 0.2)
			(type default)
		)
		(layer "In4.Cu")
	)
	(gr_arc
		(start 136.68121 -12.832588)
		(mid 136.433076 -11.981135)
		(end 135.583422 -12.23518)
		(stroke
			(width 0.2)
			(type default)
		)
		(layer "In4.Cu")
	)
	(gr_arc
		(start 136.685274 -24.224996)
		(mid 136.429242 -23.379176)
		(end 135.583422 -23.635208)
		(stroke
			(width 0.2)
			(type default)
		)
		(layer "In4.Cu")
	)
	(gr_arc
		(start 136.685274 -20.424902)
		(mid 136.429242 -19.579082)
		(end 135.583422 -19.835114)
		(stroke
			(width 0.2)
			(type default)
		)
		(layer "In4.Cu")
	)
	(gr_arc
		(start 136.685274 -16.625062)
		(mid 136.429242 -15.779242)
		(end 135.583422 -16.035274)
		(stroke
			(width 0.2)
			(type default)
		)
		(layer "In4.Cu")
	)
	(gr_line
		(start 136.687306 -16.626332)
		(end 136.685274 -16.625062)
		(stroke
			(width 0.2)
			(type default)
		)
		(layer "In4.Cu")
	)
	(gr_line
		(start 136.893554 -222.805244)
		(end 137.7061 -222.805244)
		(stroke
			(width 0.2)
			(type default)
		)
		(layer "In4.Cu")
	)
	(gr_arc
		(start 136.893554 -221.784164)
		(mid 136.383014 -222.294704)
		(end 136.893554 -222.805244)
		(stroke
			(width 0.2)
			(type default)
		)
		(layer "In4.Cu")
	)
	(gr_line
		(start 137.081514 -25.033732)
		(end 137.081768 -25.033986)
		(stroke
			(width 0.2)
			(type default)
		)
		(layer "In4.Cu")
	)
	(gr_line
		(start 137.081514 -21.233638)
		(end 137.081768 -21.233892)
		(stroke
			(width 0.2)
			(type default)
		)
		(layer "In4.Cu")
	)
	(gr_line
		(start 137.081514 -17.433544)
		(end 137.081768 -17.433798)
		(stroke
			(width 0.2)
			(type default)
		)
		(layer "In4.Cu")
	)
	(gr_line
		(start 137.081514 -13.633958)
		(end 137.083546 -13.635228)
		(stroke
			(width 0.2)
			(type default)
		)
		(layer "In4.Cu")
	)
	(gr_line
		(start 137.081768 -25.033986)
		(end 137.0838 -25.035002)
		(stroke
			(width 0.2)
			(type default)
		)
		(layer "In4.Cu")
	)
	(gr_line
		(start 137.081768 -21.233892)
		(end 137.0838 -21.234908)
		(stroke
			(width 0.2)
			(type default)
		)
		(layer "In4.Cu")
	)
	(gr_line
		(start 137.081768 -17.433798)
		(end 137.0838 -17.434814)
		(stroke
			(width 0.2)
			(type default)
		)
		(layer "In4.Cu")
	)
	(gr_arc
		(start 137.083546 -13.635228)
		(mid 137.339578 -14.481048)
		(end 138.185398 -14.225016)
		(stroke
			(width 0.2)
			(type default)
		)
		(layer "In4.Cu")
	)
	(gr_arc
		(start 137.0838 -25.035002)
		(mid 137.339476 -25.880903)
		(end 138.185398 -25.625044)
		(stroke
			(width 0.2)
			(type default)
		)
		(layer "In4.Cu")
	)
	(gr_arc
		(start 137.0838 -21.234908)
		(mid 137.339476 -22.080809)
		(end 138.185398 -21.82495)
		(stroke
			(width 0.2)
			(type default)
		)
		(layer "In4.Cu")
	)
	(gr_arc
		(start 137.0838 -17.434814)
		(mid 137.339324 -18.280634)
		(end 138.185144 -18.02511)
		(stroke
			(width 0.2)
			(type default)
		)
		(layer "In4.Cu")
	)
	(gr_line
		(start 137.5664 -35.503866)
		(end 138.378946 -35.503866)
		(stroke
			(width 0.2)
			(type default)
		)
		(layer "In4.Cu")
	)
	(gr_arc
		(start 137.5664 -34.482786)
		(mid 137.05586 -34.993326)
		(end 137.5664 -35.503866)
		(stroke
			(width 0.2)
			(type default)
		)
		(layer "In4.Cu")
	)
	(gr_arc
		(start 137.7061 -222.805244)
		(mid 138.216894 -222.294831)
		(end 137.706354 -221.784164)
		(stroke
			(width 0.2)
			(type default)
		)
		(layer "In4.Cu")
	)
	(gr_line
		(start 137.706354 -221.784164)
		(end 136.893554 -221.784164)
		(stroke
			(width 0.2)
			(type default)
		)
		(layer "In4.Cu")
	)
	(gr_line
		(start 137.831576 -23.633938)
		(end 137.081514 -25.033732)
		(stroke
			(width 0.2)
			(type default)
		)
		(layer "In4.Cu")
	)
	(gr_line
		(start 137.831576 -19.833844)
		(end 137.081514 -21.233638)
		(stroke
			(width 0.2)
			(type default)
		)
		(layer "In4.Cu")
	)
	(gr_line
		(start 137.831576 -16.03375)
		(end 137.081514 -17.433544)
		(stroke
			(width 0.2)
			(type default)
		)
		(layer "In4.Cu")
	)
	(gr_line
		(start 137.831576 -12.23391)
		(end 137.081514 -13.633958)
		(stroke
			(width 0.2)
			(type default)
		)
		(layer "In4.Cu")
	)
	(gr_line
		(start 137.833608 -23.635208)
		(end 137.831576 -23.633938)
		(stroke
			(width 0.2)
			(type default)
		)
		(layer "In4.Cu")
	)
	(gr_line
		(start 137.833608 -19.835114)
		(end 137.831576 -19.833844)
		(stroke
			(width 0.2)
			(type default)
		)
		(layer "In4.Cu")
	)
	(gr_line
		(start 137.833608 -12.23518)
		(end 137.831576 -12.23391)
		(stroke
			(width 0.2)
			(type default)
		)
		(layer "In4.Cu")
	)
	(gr_line
		(start 137.833862 -16.03502)
		(end 137.831576 -16.03375)
		(stroke
			(width 0.2)
			(type default)
		)
		(layer "In4.Cu")
	)
	(gr_line
		(start 138.185144 -18.02511)
		(end 138.18743 -18.02638)
		(stroke
			(width 0.2)
			(type default)
		)
		(layer "In4.Cu")
	)
	(gr_line
		(start 138.185398 -25.625044)
		(end 138.18743 -25.626314)
		(stroke
			(width 0.2)
			(type default)
		)
		(layer "In4.Cu")
	)
	(gr_line
		(start 138.185398 -21.82495)
		(end 138.18743 -21.82622)
		(stroke
			(width 0.2)
			(type default)
		)
		(layer "In4.Cu")
	)
	(gr_line
		(start 138.185398 -14.225016)
		(end 138.18743 -14.226286)
		(stroke
			(width 0.2)
			(type default)
		)
		(layer "In4.Cu")
	)
	(gr_line
		(start 138.18743 -25.626314)
		(end 138.937492 -24.226266)
		(stroke
			(width 0.2)
			(type default)
		)
		(layer "In4.Cu")
	)
	(gr_line
		(start 138.18743 -21.82622)
		(end 138.937492 -20.426172)
		(stroke
			(width 0.2)
			(type default)
		)
		(layer "In4.Cu")
	)
	(gr_line
		(start 138.18743 -18.02638)
		(end 138.937492 -16.626586)
		(stroke
			(width 0.2)
			(type default)
		)
		(layer "In4.Cu")
	)
	(gr_line
		(start 138.18743 -14.226286)
		(end 138.937492 -12.826492)
		(stroke
			(width 0.2)
			(type default)
		)
		(layer "In4.Cu")
	)
	(gr_arc
		(start 138.378946 -35.503866)
		(mid 138.88974 -34.993453)
		(end 138.3792 -34.482786)
		(stroke
			(width 0.2)
			(type default)
		)
		(layer "In4.Cu")
	)
	(gr_line
		(start 138.3792 -34.482786)
		(end 137.5664 -34.482786)
		(stroke
			(width 0.2)
			(type default)
		)
		(layer "In4.Cu")
	)
	(gr_line
		(start 138.493754 -211.406994)
		(end 139.306554 -211.406994)
		(stroke
			(width 0.2)
			(type default)
		)
		(layer "In4.Cu")
	)
	(gr_arc
		(start 138.494008 -210.385914)
		(mid 137.983214 -210.896327)
		(end 138.493754 -211.406994)
		(stroke
			(width 0.2)
			(type default)
		)
		(layer "In4.Cu")
	)
	(gr_line
		(start 138.557 -39.16934)
		(end 139.3698 -39.16934)
		(stroke
			(width 0.2)
			(type default)
		)
		(layer "In4.Cu")
	)
	(gr_arc
		(start 138.557254 -38.14826)
		(mid 138.04646 -38.658673)
		(end 138.557 -39.16934)
		(stroke
			(width 0.2)
			(type default)
		)
		(layer "In4.Cu")
	)
	(gr_arc
		(start 138.935206 -16.625316)
		(mid 138.679682 -15.779496)
		(end 137.833862 -16.03502)
		(stroke
			(width 0.2)
			(type default)
		)
		(layer "In4.Cu")
	)
	(gr_arc
		(start 138.935206 -12.825222)
		(mid 138.67953 -11.979321)
		(end 137.833608 -12.23518)
		(stroke
			(width 0.2)
			(type default)
		)
		(layer "In4.Cu")
	)
	(gr_arc
		(start 138.93546 -24.224996)
		(mid 138.679428 -23.379176)
		(end 137.833608 -23.635208)
		(stroke
			(width 0.2)
			(type default)
		)
		(layer "In4.Cu")
	)
	(gr_arc
		(start 138.93546 -20.424902)
		(mid 138.679428 -19.579082)
		(end 137.833608 -19.835114)
		(stroke
			(width 0.2)
			(type default)
		)
		(layer "In4.Cu")
	)
	(gr_line
		(start 138.937238 -12.826238)
		(end 138.935206 -12.825222)
		(stroke
			(width 0.2)
			(type default)
		)
		(layer "In4.Cu")
	)
	(gr_line
		(start 138.937492 -24.226266)
		(end 138.93546 -24.224996)
		(stroke
			(width 0.2)
			(type default)
		)
		(layer "In4.Cu")
	)
	(gr_line
		(start 138.937492 -20.426172)
		(end 138.93546 -20.424902)
		(stroke
			(width 0.2)
			(type default)
		)
		(layer "In4.Cu")
	)
	(gr_line
		(start 138.937492 -16.626586)
		(end 138.935206 -16.625316)
		(stroke
			(width 0.2)
			(type default)
		)
		(layer "In4.Cu")
	)
	(gr_line
		(start 138.937492 -12.826492)
		(end 138.937238 -12.826238)
		(stroke
			(width 0.2)
			(type default)
		)
		(layer "In4.Cu")
	)
	(gr_arc
		(start 139.306554 -211.406994)
		(mid 139.817094 -210.896454)
		(end 139.306554 -210.385914)
		(stroke
			(width 0.2)
			(type default)
		)
		(layer "In4.Cu")
	)
	(gr_line
		(start 139.306554 -210.385914)
		(end 138.494008 -210.385914)
		(stroke
			(width 0.2)
			(type default)
		)
		(layer "In4.Cu")
	)
	(gr_arc
		(start 139.3698 -39.16934)
		(mid 139.88034 -38.6588)
		(end 139.3698 -38.14826)
		(stroke
			(width 0.2)
			(type default)
		)
		(layer "In4.Cu")
	)
	(gr_line
		(start 139.3698 -38.14826)
		(end 138.557254 -38.14826)
		(stroke
			(width 0.2)
			(type default)
		)
		(layer "In4.Cu")
	)
	(gr_line
		(start 140.0937 -222.805244)
		(end 140.906246 -222.805244)
		(stroke
			(width 0.2)
			(type default)
		)
		(layer "In4.Cu")
	)
	(gr_arc
		(start 140.0937 -221.784164)
		(mid 139.58316 -222.294704)
		(end 140.0937 -222.805244)
		(stroke
			(width 0.2)
			(type default)
		)
		(layer "In4.Cu")
	)
	(gr_arc
		(start 140.906246 -222.805244)
		(mid 141.41704 -222.294831)
		(end 140.9065 -221.784164)
		(stroke
			(width 0.2)
			(type default)
		)
		(layer "In4.Cu")
	)
	(gr_line
		(start 140.9065 -221.784164)
		(end 140.0937 -221.784164)
		(stroke
			(width 0.2)
			(type default)
		)
		(layer "In4.Cu")
	)
	(gr_line
		(start 141.6939 -211.406994)
		(end 142.5067 -211.406994)
		(stroke
			(width 0.2)
			(type default)
		)
		(layer "In4.Cu")
	)
	(gr_arc
		(start 141.694154 -210.385914)
		(mid 141.18336 -210.896327)
		(end 141.6939 -211.406994)
		(stroke
			(width 0.2)
			(type default)
		)
		(layer "In4.Cu")
	)
	(gr_arc
		(start 142.5067 -211.406994)
		(mid 143.01724 -210.896454)
		(end 142.5067 -210.385914)
		(stroke
			(width 0.2)
			(type default)
		)
		(layer "In4.Cu")
	)
	(gr_line
		(start 142.5067 -210.385914)
		(end 141.694154 -210.385914)
		(stroke
			(width 0.2)
			(type default)
		)
		(layer "In4.Cu")
	)
	(gr_line
		(start 143.293592 -222.805244)
		(end 144.106138 -222.805244)
		(stroke
			(width 0.2)
			(type default)
		)
		(layer "In4.Cu")
	)
	(gr_arc
		(start 143.293592 -221.784164)
		(mid 142.783052 -222.294704)
		(end 143.293592 -222.805244)
		(stroke
			(width 0.2)
			(type default)
		)
		(layer "In4.Cu")
	)
	(gr_line
		(start 143.581374 -25.033986)
		(end 143.583406 -25.035256)
		(stroke
			(width 0.2)
			(type default)
		)
		(layer "In4.Cu")
	)
	(gr_line
		(start 143.581374 -13.633704)
		(end 143.581628 -13.633958)
		(stroke
			(width 0.2)
			(type default)
		)
		(layer "In4.Cu")
	)
	(gr_line
		(start 143.581628 -13.633958)
		(end 143.58366 -13.634974)
		(stroke
			(width 0.2)
			(type default)
		)
		(layer "In4.Cu")
	)
	(gr_arc
		(start 143.583406 -25.035256)
		(mid 143.839438 -25.881076)
		(end 144.685258 -25.625044)
		(stroke
			(width 0.2)
			(type default)
		)
		(layer "In4.Cu")
	)
	(gr_arc
		(start 143.58366 -13.634974)
		(mid 143.839336 -14.480875)
		(end 144.685258 -14.225016)
		(stroke
			(width 0.2)
			(type default)
		)
		(layer "In4.Cu")
	)
	(gr_arc
		(start 144.106138 -222.805244)
		(mid 144.616932 -222.294831)
		(end 144.106392 -221.784164)
		(stroke
			(width 0.2)
			(type default)
		)
		(layer "In4.Cu")
	)
	(gr_line
		(start 144.106392 -221.784164)
		(end 143.293592 -221.784164)
		(stroke
			(width 0.2)
			(type default)
		)
		(layer "In4.Cu")
	)
	(gr_line
		(start 144.331436 -23.633938)
		(end 143.581374 -25.033986)
		(stroke
			(width 0.2)
			(type default)
		)
		(layer "In4.Cu")
	)
	(gr_line
		(start 144.331436 -12.23391)
		(end 143.581374 -13.633704)
		(stroke
			(width 0.2)
			(type default)
		)
		(layer "In4.Cu")
	)
	(gr_line
		(start 144.333468 -23.635208)
		(end 144.331436 -23.633938)
		(stroke
			(width 0.2)
			(type default)
		)
		(layer "In4.Cu")
	)
	(gr_line
		(start 144.333468 -12.23518)
		(end 144.331436 -12.23391)
		(stroke
			(width 0.2)
			(type default)
		)
		(layer "In4.Cu")
	)
	(gr_line
		(start 144.685258 -25.625044)
		(end 144.68729 -25.626314)
		(stroke
			(width 0.2)
			(type default)
		)
		(layer "In4.Cu")
	)
	(gr_line
		(start 144.685258 -14.225016)
		(end 144.68729 -14.226286)
		(stroke
			(width 0.2)
			(type default)
		)
		(layer "In4.Cu")
	)
	(gr_line
		(start 144.68729 -25.626314)
		(end 145.437352 -24.22652)
		(stroke
			(width 0.2)
			(type default)
		)
		(layer "In4.Cu")
	)
	(gr_line
		(start 144.68729 -14.226286)
		(end 145.437352 -12.826238)
		(stroke
			(width 0.2)
			(type default)
		)
		(layer "In4.Cu")
	)
	(gr_line
		(start 144.893792 -211.406994)
		(end 145.706592 -211.406994)
		(stroke
			(width 0.2)
			(type default)
		)
		(layer "In4.Cu")
	)
	(gr_arc
		(start 144.894046 -210.385914)
		(mid 144.383252 -210.896327)
		(end 144.893792 -211.406994)
		(stroke
			(width 0.2)
			(type default)
		)
		(layer "In4.Cu")
	)
	(gr_arc
		(start 145.435066 -24.22525)
		(mid 145.17939 -23.379349)
		(end 144.333468 -23.635208)
		(stroke
			(width 0.2)
			(type default)
		)
		(layer "In4.Cu")
	)
	(gr_arc
		(start 145.43532 -12.824968)
		(mid 145.179288 -11.979148)
		(end 144.333468 -12.23518)
		(stroke
			(width 0.2)
			(type default)
		)
		(layer "In4.Cu")
	)
	(gr_line
		(start 145.437098 -24.226266)
		(end 145.435066 -24.22525)
		(stroke
			(width 0.2)
			(type default)
		)
		(layer "In4.Cu")
	)
	(gr_line
		(start 145.437352 -24.22652)
		(end 145.437098 -24.226266)
		(stroke
			(width 0.2)
			(type default)
		)
		(layer "In4.Cu")
	)
	(gr_line
		(start 145.437352 -12.826238)
		(end 145.43532 -12.824968)
		(stroke
			(width 0.2)
			(type default)
		)
		(layer "In4.Cu")
	)
	(gr_arc
		(start 145.706592 -211.406994)
		(mid 146.217132 -210.896454)
		(end 145.706592 -210.385914)
		(stroke
			(width 0.2)
			(type default)
		)
		(layer "In4.Cu")
	)
	(gr_line
		(start 145.706592 -210.385914)
		(end 144.894046 -210.385914)
		(stroke
			(width 0.2)
			(type default)
		)
		(layer "In4.Cu")
	)
	(gr_line
		(start 145.83156 -17.433544)
		(end 145.831814 -17.433798)
		(stroke
			(width 0.2)
			(type default)
		)
		(layer "In4.Cu")
	)
	(gr_line
		(start 145.831814 -17.433798)
		(end 145.833846 -17.434814)
		(stroke
			(width 0.2)
			(type default)
		)
		(layer "In4.Cu")
	)
	(gr_arc
		(start 145.833592 -21.235162)
		(mid 146.089624 -22.080982)
		(end 146.935444 -21.82495)
		(stroke
			(width 0.2)
			(type default)
		)
		(layer "In4.Cu")
	)
	(gr_arc
		(start 145.833846 -17.434814)
		(mid 146.089522 -18.280715)
		(end 146.935444 -18.024856)
		(stroke
			(width 0.2)
			(type default)
		)
		(layer "In4.Cu")
	)
	(gr_arc
		(start 145.837656 -25.027636)
		(mid 146.08579 -25.879089)
		(end 146.935444 -25.625044)
		(stroke
			(width 0.2)
			(type default)
		)
		(layer "In4.Cu")
	)
	(gr_arc
		(start 145.837656 -13.627608)
		(mid 146.08579 -14.479061)
		(end 146.935444 -14.225016)
		(stroke
			(width 0.2)
			(type default)
		)
		(layer "In4.Cu")
	)
	(gr_line
		(start 145.9103 -35.50666)
		(end 146.7231 -35.50666)
		(stroke
			(width 0.2)
			(type default)
		)
		(layer "In4.Cu")
	)
	(gr_arc
		(start 145.910554 -34.48558)
		(mid 145.39976 -34.995993)
		(end 145.9103 -35.50666)
		(stroke
			(width 0.2)
			(type default)
		)
		(layer "In4.Cu")
	)
	(gr_line
		(start 146.493738 -222.805244)
		(end 147.306284 -222.805244)
		(stroke
			(width 0.2)
			(type default)
		)
		(layer "In4.Cu")
	)
	(gr_arc
		(start 146.493738 -221.784164)
		(mid 145.983198 -222.294704)
		(end 146.493738 -222.805244)
		(stroke
			(width 0.2)
			(type default)
		)
		(layer "In4.Cu")
	)
	(gr_line
		(start 146.581368 -16.034004)
		(end 145.83156 -17.433544)
		(stroke
			(width 0.2)
			(type default)
		)
		(layer "In4.Cu")
	)
	(gr_line
		(start 146.5834 -23.635208)
		(end 145.837656 -25.027636)
		(stroke
			(width 0.2)
			(type default)
		)
		(layer "In4.Cu")
	)
	(gr_line
		(start 146.5834 -19.835114)
		(end 145.833592 -21.235162)
		(stroke
			(width 0.2)
			(type default)
		)
		(layer "In4.Cu")
	)
	(gr_line
		(start 146.5834 -16.035274)
		(end 146.581368 -16.034004)
		(stroke
			(width 0.2)
			(type default)
		)
		(layer "In4.Cu")
	)
	(gr_line
		(start 146.5834 -12.23518)
		(end 145.837656 -13.627608)
		(stroke
			(width 0.2)
			(type default)
		)
		(layer "In4.Cu")
	)
	(gr_arc
		(start 146.7231 -35.50666)
		(mid 147.23364 -34.99612)
		(end 146.7231 -34.48558)
		(stroke
			(width 0.2)
			(type default)
		)
		(layer "In4.Cu")
	)
	(gr_line
		(start 146.7231 -34.48558)
		(end 145.910554 -34.48558)
		(stroke
			(width 0.2)
			(type default)
		)
		(layer "In4.Cu")
	)
	(gr_line
		(start 146.935444 -25.625044)
		(end 147.685252 -24.224996)
		(stroke
			(width 0.2)
			(type default)
		)
		(layer "In4.Cu")
	)
	(gr_line
		(start 146.935444 -21.82495)
		(end 147.681188 -20.432522)
		(stroke
			(width 0.2)
			(type default)
		)
		(layer "In4.Cu")
	)
	(gr_line
		(start 146.935444 -18.024856)
		(end 146.937476 -18.026126)
		(stroke
			(width 0.2)
			(type default)
		)
		(layer "In4.Cu")
	)
	(gr_line
		(start 146.935444 -14.225016)
		(end 147.685252 -12.824968)
		(stroke
			(width 0.2)
			(type default)
		)
		(layer "In4.Cu")
	)
	(gr_line
		(start 146.937476 -18.026126)
		(end 147.687284 -16.626332)
		(stroke
			(width 0.2)
			(type default)
		)
		(layer "In4.Cu")
	)
	(gr_arc
		(start 147.306284 -222.805244)
		(mid 147.817078 -222.294831)
		(end 147.306538 -221.784164)
		(stroke
			(width 0.2)
			(type default)
		)
		(layer "In4.Cu")
	)
	(gr_line
		(start 147.306538 -221.784164)
		(end 146.493738 -221.784164)
		(stroke
			(width 0.2)
			(type default)
		)
		(layer "In4.Cu")
	)
	(gr_arc
		(start 147.681188 -20.432522)
		(mid 147.433054 -19.581069)
		(end 146.5834 -19.835114)
		(stroke
			(width 0.2)
			(type default)
		)
		(layer "In4.Cu")
	)
	(gr_arc
		(start 147.685252 -24.224996)
		(mid 147.42922 -23.379176)
		(end 146.5834 -23.635208)
		(stroke
			(width 0.2)
			(type default)
		)
		(layer "In4.Cu")
	)
	(gr_arc
		(start 147.685252 -16.625062)
		(mid 147.42922 -15.779242)
		(end 146.5834 -16.035274)
		(stroke
			(width 0.2)
			(type default)
		)
		(layer "In4.Cu")
	)
	(gr_arc
		(start 147.685252 -12.824968)
		(mid 147.42922 -11.979148)
		(end 146.5834 -12.23518)
		(stroke
			(width 0.2)
			(type default)
		)
		(layer "In4.Cu")
	)
	(gr_line
		(start 147.687284 -16.626332)
		(end 147.685252 -16.625062)
		(stroke
			(width 0.2)
			(type default)
		)
		(layer "In4.Cu")
	)
	(gr_line
		(start 148.081492 -25.033732)
		(end 148.081746 -25.033986)
		(stroke
			(width 0.2)
			(type default)
		)
		(layer "In4.Cu")
	)
	(gr_line
		(start 148.081492 -21.233892)
		(end 148.083524 -21.235162)
		(stroke
			(width 0.2)
			(type default)
		)
		(layer "In4.Cu")
	)
	(gr_line
		(start 148.081492 -17.433544)
		(end 148.081746 -17.433798)
		(stroke
			(width 0.2)
			(type default)
		)
		(layer "In4.Cu")
	)
	(gr_line
		(start 148.081492 -13.633704)
		(end 148.081746 -13.633958)
		(stroke
			(width 0.2)
			(type default)
		)
		(layer "In4.Cu")
	)
	(gr_line
		(start 148.081746 -25.033986)
		(end 148.083778 -25.035002)
		(stroke
			(width 0.2)
			(type default)
		)
		(layer "In4.Cu")
	)
	(gr_line
		(start 148.081746 -17.433798)
		(end 148.083778 -17.434814)
		(stroke
			(width 0.2)
			(type default)
		)
		(layer "In4.Cu")
	)
	(gr_line
		(start 148.081746 -13.633958)
		(end 148.083778 -13.634974)
		(stroke
			(width 0.2)
			(type default)
		)
		(layer "In4.Cu")
	)
	(gr_arc
		(start 148.083524 -21.235162)
		(mid 148.339556 -22.080982)
		(end 149.185376 -21.82495)
		(stroke
			(width 0.2)
			(type default)
		)
		(layer "In4.Cu")
	)
	(gr_arc
		(start 148.083778 -25.035002)
		(mid 148.339454 -25.880903)
		(end 149.185376 -25.625044)
		(stroke
			(width 0.2)
			(type default)
		)
		(layer "In4.Cu")
	)
	(gr_arc
		(start 148.083778 -17.434814)
		(mid 148.339302 -18.280634)
		(end 149.185122 -18.02511)
		(stroke
			(width 0.2)
			(type default)
		)
		(layer "In4.Cu")
	)
	(gr_arc
		(start 148.083778 -13.634974)
		(mid 148.339454 -14.480875)
		(end 149.185376 -14.225016)
		(stroke
			(width 0.2)
			(type default)
		)
		(layer "In4.Cu")
	)
	(gr_line
		(start 148.093684 -211.406994)
		(end 148.906484 -211.406994)
		(stroke
			(width 0.2)
			(type default)
		)
		(layer "In4.Cu")
	)
	(gr_arc
		(start 148.093938 -210.385914)
		(mid 147.583144 -210.896327)
		(end 148.093684 -211.406994)
		(stroke
			(width 0.2)
			(type default)
		)
		(layer "In4.Cu")
	)
	(gr_line
		(start 148.5011 -35.51174)
		(end 149.313646 -35.51174)
		(stroke
			(width 0.2)
			(type default)
		)
		(layer "In4.Cu")
	)
	(gr_arc
		(start 148.5011 -34.49066)
		(mid 147.99056 -35.0012)
		(end 148.5011 -35.51174)
		(stroke
			(width 0.2)
			(type default)
		)
		(layer "In4.Cu")
	)
	(gr_line
		(start 148.831554 -23.633938)
		(end 148.081492 -25.033732)
		(stroke
			(width 0.2)
			(type default)
		)
		(layer "In4.Cu")
	)
	(gr_line
		(start 148.831554 -19.833844)
		(end 148.081492 -21.233892)
		(stroke
			(width 0.2)
			(type default)
		)
		(layer "In4.Cu")
	)
	(gr_line
		(start 148.831554 -16.03375)
		(end 148.081492 -17.433544)
		(stroke
			(width 0.2)
			(type default)
		)
		(layer "In4.Cu")
	)
	(gr_line
		(start 148.831554 -12.23391)
		(end 148.081492 -13.633704)
		(stroke
			(width 0.2)
			(type default)
		)
		(layer "In4.Cu")
	)
	(gr_line
		(start 148.833586 -23.635208)
		(end 148.831554 -23.633938)
		(stroke
			(width 0.2)
			(type default)
		)
		(layer "In4.Cu")
	)
	(gr_line
		(start 148.833586 -19.835114)
		(end 148.831554 -19.833844)
		(stroke
			(width 0.2)
			(type default)
		)
		(layer "In4.Cu")
	)
	(gr_line
		(start 148.833586 -12.23518)
		(end 148.831554 -12.23391)
		(stroke
			(width 0.2)
			(type default)
		)
		(layer "In4.Cu")
	)
	(gr_line
		(start 148.83384 -16.03502)
		(end 148.831554 -16.03375)
		(stroke
			(width 0.2)
			(type default)
		)
		(layer "In4.Cu")
	)
	(gr_arc
		(start 148.906484 -211.406994)
		(mid 149.417024 -210.896454)
		(end 148.906484 -210.385914)
		(stroke
			(width 0.2)
			(type default)
		)
		(layer "In4.Cu")
	)
	(gr_line
		(start 148.906484 -210.385914)
		(end 148.093938 -210.385914)
		(stroke
			(width 0.2)
			(type default)
		)
		(layer "In4.Cu")
	)
	(gr_line
		(start 149.185122 -18.02511)
		(end 149.187408 -18.02638)
		(stroke
			(width 0.2)
			(type default)
		)
		(layer "In4.Cu")
	)
	(gr_line
		(start 149.185376 -25.625044)
		(end 149.187408 -25.626314)
		(stroke
			(width 0.2)
			(type default)
		)
		(layer "In4.Cu")
	)
	(gr_line
		(start 149.185376 -21.82495)
		(end 149.187408 -21.82622)
		(stroke
			(width 0.2)
			(type default)
		)
		(layer "In4.Cu")
	)
	(gr_line
		(start 149.185376 -14.225016)
		(end 149.187408 -14.226286)
		(stroke
			(width 0.2)
			(type default)
		)
		(layer "In4.Cu")
	)
	(gr_line
		(start 149.187408 -25.626314)
		(end 149.93747 -24.226266)
		(stroke
			(width 0.2)
			(type default)
		)
		(layer "In4.Cu")
	)
	(gr_line
		(start 149.187408 -21.82622)
		(end 149.93747 -20.426426)
		(stroke
			(width 0.2)
			(type default)
		)
		(layer "In4.Cu")
	)
	(gr_line
		(start 149.187408 -18.02638)
		(end 149.93747 -16.626586)
		(stroke
			(width 0.2)
			(type default)
		)
		(layer "In4.Cu")
	)
	(gr_line
		(start 149.187408 -14.226286)
		(end 149.93747 -12.826238)
		(stroke
			(width 0.2)
			(type default)
		)
		(layer "In4.Cu")
	)
	(gr_arc
		(start 149.313646 -35.51174)
		(mid 149.82444 -35.001327)
		(end 149.3139 -34.49066)
		(stroke
			(width 0.2)
			(type default)
		)
		(layer "In4.Cu")
	)
	(gr_line
		(start 149.3139 -34.49066)
		(end 148.5011 -34.49066)
		(stroke
			(width 0.2)
			(type default)
		)
		(layer "In4.Cu")
	)
	(gr_line
		(start 149.69363 -222.805244)
		(end 150.506176 -222.805244)
		(stroke
			(width 0.2)
			(type default)
		)
		(layer "In4.Cu")
	)
	(gr_arc
		(start 149.69363 -221.784164)
		(mid 149.18309 -222.294704)
		(end 149.69363 -222.805244)
		(stroke
			(width 0.2)
			(type default)
		)
		(layer "In4.Cu")
	)
	(gr_arc
		(start 149.935184 -20.425156)
		(mid 149.679508 -19.579255)
		(end 148.833586 -19.835114)
		(stroke
			(width 0.2)
			(type default)
		)
		(layer "In4.Cu")
	)
	(gr_arc
		(start 149.935184 -16.625316)
		(mid 149.67966 -15.779496)
		(end 148.83384 -16.03502)
		(stroke
			(width 0.2)
			(type default)
		)
		(layer "In4.Cu")
	)
	(gr_arc
		(start 149.935438 -24.224996)
		(mid 149.679406 -23.379176)
		(end 148.833586 -23.635208)
		(stroke
			(width 0.2)
			(type default)
		)
		(layer "In4.Cu")
	)
	(gr_arc
		(start 149.935438 -12.824968)
		(mid 149.679406 -11.979148)
		(end 148.833586 -12.23518)
		(stroke
			(width 0.2)
			(type default)
		)
		(layer "In4.Cu")
	)
	(gr_line
		(start 149.937216 -20.426172)
		(end 149.935184 -20.425156)
		(stroke
			(width 0.2)
			(type default)
		)
		(layer "In4.Cu")
	)
	(gr_line
		(start 149.93747 -24.226266)
		(end 149.935438 -24.224996)
		(stroke
			(width 0.2)
			(type default)
		)
		(layer "In4.Cu")
	)
	(gr_line
		(start 149.93747 -20.426426)
		(end 149.937216 -20.426172)
		(stroke
			(width 0.2)
			(type default)
		)
		(layer "In4.Cu")
	)
	(gr_line
		(start 149.93747 -16.626586)
		(end 149.935184 -16.625316)
		(stroke
			(width 0.2)
			(type default)
		)
		(layer "In4.Cu")
	)
	(gr_line
		(start 149.93747 -12.826238)
		(end 149.935438 -12.824968)
		(stroke
			(width 0.2)
			(type default)
		)
		(layer "In4.Cu")
	)
	(gr_arc
		(start 150.506176 -222.805244)
		(mid 151.01697 -222.294831)
		(end 150.50643 -221.784164)
		(stroke
			(width 0.2)
			(type default)
		)
		(layer "In4.Cu")
	)
	(gr_line
		(start 150.50643 -221.784164)
		(end 149.69363 -221.784164)
		(stroke
			(width 0.2)
			(type default)
		)
		(layer "In4.Cu")
	)
	(gr_line
		(start 150.9141 -38.59784)
		(end 151.726646 -38.59784)
		(stroke
			(width 0.2)
			(type default)
		)
		(layer "In4.Cu")
	)
	(gr_arc
		(start 150.9141 -37.57676)
		(mid 150.40356 -38.0873)
		(end 150.9141 -38.59784)
		(stroke
			(width 0.2)
			(type default)
		)
		(layer "In4.Cu")
	)
	(gr_line
		(start 151.29383 -211.406994)
		(end 152.10663 -211.406994)
		(stroke
			(width 0.2)
			(type default)
		)
		(layer "In4.Cu")
	)
	(gr_arc
		(start 151.294084 -210.385914)
		(mid 150.78329 -210.896327)
		(end 151.29383 -211.406994)
		(stroke
			(width 0.2)
			(type default)
		)
		(layer "In4.Cu")
	)
	(gr_arc
		(start 151.726646 -38.59784)
		(mid 152.23744 -38.087427)
		(end 151.7269 -37.57676)
		(stroke
			(width 0.2)
			(type default)
		)
		(layer "In4.Cu")
	)
	(gr_line
		(start 151.7269 -37.57676)
		(end 150.9141 -37.57676)
		(stroke
			(width 0.2)
			(type default)
		)
		(layer "In4.Cu")
	)
	(gr_arc
		(start 152.10663 -211.406994)
		(mid 152.61717 -210.896454)
		(end 152.10663 -210.385914)
		(stroke
			(width 0.2)
			(type default)
		)
		(layer "In4.Cu")
	)
	(gr_line
		(start 152.10663 -210.385914)
		(end 151.294084 -210.385914)
		(stroke
			(width 0.2)
			(type default)
		)
		(layer "In4.Cu")
	)
	(gr_line
		(start 152.7175 -35.50666)
		(end 153.530046 -35.50666)
		(stroke
			(width 0.2)
			(type default)
		)
		(layer "In4.Cu")
	)
	(gr_arc
		(start 152.7175 -34.48558)
		(mid 152.20696 -34.99612)
		(end 152.7175 -35.50666)
		(stroke
			(width 0.2)
			(type default)
		)
		(layer "In4.Cu")
	)
	(gr_line
		(start 152.893776 -222.805244)
		(end 153.706322 -222.805244)
		(stroke
			(width 0.2)
			(type default)
		)
		(layer "In4.Cu")
	)
	(gr_arc
		(start 152.893776 -221.784164)
		(mid 152.383236 -222.294704)
		(end 152.893776 -222.805244)
		(stroke
			(width 0.2)
			(type default)
		)
		(layer "In4.Cu")
	)
	(gr_arc
		(start 153.530046 -35.50666)
		(mid 154.04084 -34.996247)
		(end 153.5303 -34.48558)
		(stroke
			(width 0.2)
			(type default)
		)
		(layer "In4.Cu")
	)
	(gr_line
		(start 153.5303 -34.48558)
		(end 152.7175 -34.48558)
		(stroke
			(width 0.2)
			(type default)
		)
		(layer "In4.Cu")
	)
	(gr_arc
		(start 153.706322 -222.805244)
		(mid 154.217116 -222.294831)
		(end 153.706576 -221.784164)
		(stroke
			(width 0.2)
			(type default)
		)
		(layer "In4.Cu")
	)
	(gr_line
		(start 153.706576 -221.784164)
		(end 152.893776 -221.784164)
		(stroke
			(width 0.2)
			(type default)
		)
		(layer "In4.Cu")
	)
	(gr_line
		(start 154.493722 -211.406994)
		(end 155.306522 -211.406994)
		(stroke
			(width 0.2)
			(type default)
		)
		(layer "In4.Cu")
	)
	(gr_arc
		(start 154.493976 -210.385914)
		(mid 153.983182 -210.896327)
		(end 154.493722 -211.406994)
		(stroke
			(width 0.2)
			(type default)
		)
		(layer "In4.Cu")
	)
	(gr_arc
		(start 154.583638 -25.035256)
		(mid 154.83967 -25.881076)
		(end 155.68549 -25.625044)
		(stroke
			(width 0.2)
			(type default)
		)
		(layer "In4.Cu")
	)
	(gr_arc
		(start 154.587702 -13.627608)
		(mid 154.835836 -14.479061)
		(end 155.68549 -14.225016)
		(stroke
			(width 0.2)
			(type default)
		)
		(layer "In4.Cu")
	)
	(gr_arc
		(start 155.306522 -211.406994)
		(mid 155.817062 -210.896454)
		(end 155.306522 -210.385914)
		(stroke
			(width 0.2)
			(type default)
		)
		(layer "In4.Cu")
	)
	(gr_line
		(start 155.306522 -210.385914)
		(end 154.493976 -210.385914)
		(stroke
			(width 0.2)
			(type default)
		)
		(layer "In4.Cu")
	)
	(gr_line
		(start 155.333446 -23.635208)
		(end 154.583638 -25.035256)
		(stroke
			(width 0.2)
			(type default)
		)
		(layer "In4.Cu")
	)
	(gr_line
		(start 155.333446 -12.23518)
		(end 154.587702 -13.627608)
		(stroke
			(width 0.2)
			(type default)
		)
		(layer "In4.Cu")
	)
	(gr_line
		(start 155.68549 -25.625044)
		(end 156.431234 -24.232616)
		(stroke
			(width 0.2)
			(type default)
		)
		(layer "In4.Cu")
	)
	(gr_line
		(start 155.68549 -14.225016)
		(end 156.435298 -12.824968)
		(stroke
			(width 0.2)
			(type default)
		)
		(layer "In4.Cu")
	)
	(gr_line
		(start 156.093668 -222.805244)
		(end 156.906214 -222.805244)
		(stroke
			(width 0.2)
			(type default)
		)
		(layer "In4.Cu")
	)
	(gr_arc
		(start 156.093668 -221.784164)
		(mid 155.583128 -222.294704)
		(end 156.093668 -222.805244)
		(stroke
			(width 0.2)
			(type default)
		)
		(layer "In4.Cu")
	)
	(gr_arc
		(start 156.431234 -24.232616)
		(mid 156.1831 -23.381163)
		(end 155.333446 -23.635208)
		(stroke
			(width 0.2)
			(type default)
		)
		(layer "In4.Cu")
	)
	(gr_arc
		(start 156.435298 -12.824968)
		(mid 156.179266 -11.979148)
		(end 155.333446 -12.23518)
		(stroke
			(width 0.2)
			(type default)
		)
		(layer "In4.Cu")
	)
	(gr_line
		(start 156.831538 -25.033732)
		(end 156.831792 -25.033986)
		(stroke
			(width 0.2)
			(type default)
		)
		(layer "In4.Cu")
	)
	(gr_line
		(start 156.831538 -21.233892)
		(end 156.83357 -21.235162)
		(stroke
			(width 0.2)
			(type default)
		)
		(layer "In4.Cu")
	)
	(gr_line
		(start 156.831538 -17.433544)
		(end 156.831792 -17.433798)
		(stroke
			(width 0.2)
			(type default)
		)
		(layer "In4.Cu")
	)
	(gr_line
		(start 156.831538 -13.633704)
		(end 156.831792 -13.633958)
		(stroke
			(width 0.2)
			(type default)
		)
		(layer "In4.Cu")
	)
	(gr_line
		(start 156.831792 -25.033986)
		(end 156.833824 -25.035002)
		(stroke
			(width 0.2)
			(type default)
		)
		(layer "In4.Cu")
	)
	(gr_line
		(start 156.831792 -17.433798)
		(end 156.833824 -17.434814)
		(stroke
			(width 0.2)
			(type default)
		)
		(layer "In4.Cu")
	)
	(gr_line
		(start 156.831792 -13.633958)
		(end 156.833824 -13.634974)
		(stroke
			(width 0.2)
			(type default)
		)
		(layer "In4.Cu")
	)
	(gr_arc
		(start 156.83357 -21.235162)
		(mid 157.089602 -22.080982)
		(end 157.935422 -21.82495)
		(stroke
			(width 0.2)
			(type default)
		)
		(layer "In4.Cu")
	)
	(gr_arc
		(start 156.833824 -25.035002)
		(mid 157.0895 -25.880903)
		(end 157.935422 -25.625044)
		(stroke
			(width 0.2)
			(type default)
		)
		(layer "In4.Cu")
	)
	(gr_arc
		(start 156.833824 -17.434814)
		(mid 157.089348 -18.280634)
		(end 157.935168 -18.02511)
		(stroke
			(width 0.2)
			(type default)
		)
		(layer "In4.Cu")
	)
	(gr_arc
		(start 156.833824 -13.634974)
		(mid 157.0895 -14.480875)
		(end 157.935422 -14.225016)
		(stroke
			(width 0.2)
			(type default)
		)
		(layer "In4.Cu")
	)
	(gr_arc
		(start 156.906214 -222.805244)
		(mid 157.417008 -222.294831)
		(end 156.906468 -221.784164)
		(stroke
			(width 0.2)
			(type default)
		)
		(layer "In4.Cu")
	)
	(gr_line
		(start 156.906468 -221.784164)
		(end 156.093668 -221.784164)
		(stroke
			(width 0.2)
			(type default)
		)
		(layer "In4.Cu")
	)
	(gr_line
		(start 157.5816 -23.633938)
		(end 156.831538 -25.033732)
		(stroke
			(width 0.2)
			(type default)
		)
		(layer "In4.Cu")
	)
	(gr_line
		(start 157.5816 -19.833844)
		(end 156.831538 -21.233892)
		(stroke
			(width 0.2)
			(type default)
		)
		(layer "In4.Cu")
	)
	(gr_line
		(start 157.5816 -16.03375)
		(end 156.831538 -17.433544)
		(stroke
			(width 0.2)
			(type default)
		)
		(layer "In4.Cu")
	)
	(gr_line
		(start 157.5816 -12.23391)
		(end 156.831538 -13.633704)
		(stroke
			(width 0.2)
			(type default)
		)
		(layer "In4.Cu")
	)
	(gr_line
		(start 157.583632 -23.635208)
		(end 157.5816 -23.633938)
		(stroke
			(width 0.2)
			(type default)
		)
		(layer "In4.Cu")
	)
	(gr_line
		(start 157.583632 -19.835114)
		(end 157.5816 -19.833844)
		(stroke
			(width 0.2)
			(type default)
		)
		(layer "In4.Cu")
	)
	(gr_line
		(start 157.583632 -12.23518)
		(end 157.5816 -12.23391)
		(stroke
			(width 0.2)
			(type default)
		)
		(layer "In4.Cu")
	)
	(gr_line
		(start 157.583886 -16.03502)
		(end 157.5816 -16.03375)
		(stroke
			(width 0.2)
			(type default)
		)
		(layer "In4.Cu")
	)
	(gr_line
		(start 157.693868 -211.406994)
		(end 158.506668 -211.406994)
		(stroke
			(width 0.2)
			(type default)
		)
		(layer "In4.Cu")
	)
	(gr_arc
		(start 157.694122 -210.385914)
		(mid 157.183328 -210.896327)
		(end 157.693868 -211.406994)
		(stroke
			(width 0.2)
			(type default)
		)
		(layer "In4.Cu")
	)
	(gr_line
		(start 157.935168 -18.02511)
		(end 157.937454 -18.02638)
		(stroke
			(width 0.2)
			(type default)
		)
		(layer "In4.Cu")
	)
	(gr_line
		(start 157.935422 -25.625044)
		(end 157.937454 -25.626314)
		(stroke
			(width 0.2)
			(type default)
		)
		(layer "In4.Cu")
	)
	(gr_line
		(start 157.935422 -21.82495)
		(end 157.937454 -21.82622)
		(stroke
			(width 0.2)
			(type default)
		)
		(layer "In4.Cu")
	)
	(gr_line
		(start 157.935422 -14.225016)
		(end 157.937454 -14.226286)
		(stroke
			(width 0.2)
			(type default)
		)
		(layer "In4.Cu")
	)
	(gr_line
		(start 157.937454 -25.626314)
		(end 158.687516 -24.226266)
		(stroke
			(width 0.2)
			(type default)
		)
		(layer "In4.Cu")
	)
	(gr_line
		(start 157.937454 -21.82622)
		(end 158.687516 -20.426426)
		(stroke
			(width 0.2)
			(type default)
		)
		(layer "In4.Cu")
	)
	(gr_line
		(start 157.937454 -18.02638)
		(end 158.687516 -16.626586)
		(stroke
			(width 0.2)
			(type default)
		)
		(layer "In4.Cu")
	)
	(gr_line
		(start 157.937454 -14.226286)
		(end 158.687516 -12.826238)
		(stroke
			(width 0.2)
			(type default)
		)
		(layer "In4.Cu")
	)
	(gr_arc
		(start 158.506668 -211.406994)
		(mid 159.017208 -210.896454)
		(end 158.506668 -210.385914)
		(stroke
			(width 0.2)
			(type default)
		)
		(layer "In4.Cu")
	)
	(gr_line
		(start 158.506668 -210.385914)
		(end 157.694122 -210.385914)
		(stroke
			(width 0.2)
			(type default)
		)
		(layer "In4.Cu")
	)
	(gr_line
		(start 158.655004 -35.53206)
		(end 159.467804 -35.53206)
		(stroke
			(width 0.2)
			(type default)
		)
		(layer "In4.Cu")
	)
	(gr_arc
		(start 158.655258 -34.51098)
		(mid 158.144464 -35.021393)
		(end 158.655004 -35.53206)
		(stroke
			(width 0.2)
			(type default)
		)
		(layer "In4.Cu")
	)
	(gr_arc
		(start 158.68523 -20.425156)
		(mid 158.429554 -19.579255)
		(end 157.583632 -19.835114)
		(stroke
			(width 0.2)
			(type default)
		)
		(layer "In4.Cu")
	)
	(gr_arc
		(start 158.68523 -16.625316)
		(mid 158.429706 -15.779496)
		(end 157.583886 -16.03502)
		(stroke
			(width 0.2)
			(type default)
		)
		(layer "In4.Cu")
	)
	(gr_arc
		(start 158.685484 -24.224996)
		(mid 158.429452 -23.379176)
		(end 157.583632 -23.635208)
		(stroke
			(width 0.2)
			(type default)
		)
		(layer "In4.Cu")
	)
	(gr_arc
		(start 158.685484 -12.824968)
		(mid 158.429452 -11.979148)
		(end 157.583632 -12.23518)
		(stroke
			(width 0.2)
			(type default)
		)
		(layer "In4.Cu")
	)
	(gr_line
		(start 158.687262 -20.426172)
		(end 158.68523 -20.425156)
		(stroke
			(width 0.2)
			(type default)
		)
		(layer "In4.Cu")
	)
	(gr_line
		(start 158.687516 -24.226266)
		(end 158.685484 -24.224996)
		(stroke
			(width 0.2)
			(type default)
		)
		(layer "In4.Cu")
	)
	(gr_line
		(start 158.687516 -20.426426)
		(end 158.687262 -20.426172)
		(stroke
			(width 0.2)
			(type default)
		)
		(layer "In4.Cu")
	)
	(gr_line
		(start 158.687516 -16.626586)
		(end 158.68523 -16.625316)
		(stroke
			(width 0.2)
			(type default)
		)
		(layer "In4.Cu")
	)
	(gr_line
		(start 158.687516 -12.826238)
		(end 158.685484 -12.824968)
		(stroke
			(width 0.2)
			(type default)
		)
		(layer "In4.Cu")
	)
	(gr_line
		(start 159.08147 -25.033732)
		(end 159.081724 -25.033986)
		(stroke
			(width 0.2)
			(type default)
		)
		(layer "In4.Cu")
	)
	(gr_line
		(start 159.08147 -21.233892)
		(end 159.083502 -21.235162)
		(stroke
			(width 0.2)
			(type default)
		)
		(layer "In4.Cu")
	)
	(gr_line
		(start 159.08147 -17.433544)
		(end 159.081724 -17.433798)
		(stroke
			(width 0.2)
			(type default)
		)
		(layer "In4.Cu")
	)
	(gr_line
		(start 159.08147 -13.633704)
		(end 159.081724 -13.633958)
		(stroke
			(width 0.2)
			(type default)
		)
		(layer "In4.Cu")
	)
	(gr_line
		(start 159.081724 -25.033986)
		(end 159.083756 -25.035002)
		(stroke
			(width 0.2)
			(type default)
		)
		(layer "In4.Cu")
	)
	(gr_line
		(start 159.081724 -17.433798)
		(end 159.083756 -17.434814)
		(stroke
			(width 0.2)
			(type default)
		)
		(layer "In4.Cu")
	)
	(gr_line
		(start 159.081724 -13.633958)
		(end 159.083756 -13.634974)
		(stroke
			(width 0.2)
			(type default)
		)
		(layer "In4.Cu")
	)
	(gr_arc
		(start 159.083502 -21.235162)
		(mid 159.339534 -22.080982)
		(end 160.185354 -21.82495)
		(stroke
			(width 0.2)
			(type default)
		)
		(layer "In4.Cu")
	)
	(gr_arc
		(start 159.083756 -25.035002)
		(mid 159.339432 -25.880903)
		(end 160.185354 -25.625044)
		(stroke
			(width 0.2)
			(type default)
		)
		(layer "In4.Cu")
	)
	(gr_arc
		(start 159.083756 -17.434814)
		(mid 159.33928 -18.280634)
		(end 160.1851 -18.02511)
		(stroke
			(width 0.2)
			(type default)
		)
		(layer "In4.Cu")
	)
	(gr_arc
		(start 159.083756 -13.634974)
		(mid 159.339432 -14.480875)
		(end 160.185354 -14.225016)
		(stroke
			(width 0.2)
			(type default)
		)
		(layer "In4.Cu")
	)
	(gr_line
		(start 159.29356 -222.805244)
		(end 160.106106 -222.805244)
		(stroke
			(width 0.2)
			(type default)
		)
		(layer "In4.Cu")
	)
	(gr_arc
		(start 159.29356 -221.784164)
		(mid 158.78302 -222.294704)
		(end 159.29356 -222.805244)
		(stroke
			(width 0.2)
			(type default)
		)
		(layer "In4.Cu")
	)
	(gr_arc
		(start 159.467804 -35.53206)
		(mid 159.978344 -35.02152)
		(end 159.467804 -34.51098)
		(stroke
			(width 0.2)
			(type default)
		)
		(layer "In4.Cu")
	)
	(gr_line
		(start 159.467804 -34.51098)
		(end 158.655258 -34.51098)
		(stroke
			(width 0.2)
			(type default)
		)
		(layer "In4.Cu")
	)
	(gr_line
		(start 159.831532 -23.633938)
		(end 159.08147 -25.033732)
		(stroke
			(width 0.2)
			(type default)
		)
		(layer "In4.Cu")
	)
	(gr_line
		(start 159.831532 -19.833844)
		(end 159.08147 -21.233892)
		(stroke
			(width 0.2)
			(type default)
		)
		(layer "In4.Cu")
	)
	(gr_line
		(start 159.831532 -16.03375)
		(end 159.08147 -17.433544)
		(stroke
			(width 0.2)
			(type default)
		)
		(layer "In4.Cu")
	)
	(gr_line
		(start 159.831532 -12.23391)
		(end 159.08147 -13.633704)
		(stroke
			(width 0.2)
			(type default)
		)
		(layer "In4.Cu")
	)
	(gr_line
		(start 159.833564 -23.635208)
		(end 159.831532 -23.633938)
		(stroke
			(width 0.2)
			(type default)
		)
		(layer "In4.Cu")
	)
	(gr_line
		(start 159.833564 -19.835114)
		(end 159.831532 -19.833844)
		(stroke
			(width 0.2)
			(type default)
		)
		(layer "In4.Cu")
	)
	(gr_line
		(start 159.833564 -12.23518)
		(end 159.831532 -12.23391)
		(stroke
			(width 0.2)
			(type default)
		)
		(layer "In4.Cu")
	)
	(gr_line
		(start 159.833818 -16.03502)
		(end 159.831532 -16.03375)
		(stroke
			(width 0.2)
			(type default)
		)
		(layer "In4.Cu")
	)
	(gr_arc
		(start 160.106106 -222.805244)
		(mid 160.6169 -222.294831)
		(end 160.10636 -221.784164)
		(stroke
			(width 0.2)
			(type default)
		)
		(layer "In4.Cu")
	)
	(gr_line
		(start 160.10636 -221.784164)
		(end 159.29356 -221.784164)
		(stroke
			(width 0.2)
			(type default)
		)
		(layer "In4.Cu")
	)
	(gr_line
		(start 160.1851 -18.02511)
		(end 160.187386 -18.02638)
		(stroke
			(width 0.2)
			(type default)
		)
		(layer "In4.Cu")
	)
	(gr_line
		(start 160.185354 -25.625044)
		(end 160.187386 -25.626314)
		(stroke
			(width 0.2)
			(type default)
		)
		(layer "In4.Cu")
	)
	(gr_line
		(start 160.185354 -21.82495)
		(end 160.187386 -21.82622)
		(stroke
			(width 0.2)
			(type default)
		)
		(layer "In4.Cu")
	)
	(gr_line
		(start 160.185354 -14.225016)
		(end 160.187386 -14.226286)
		(stroke
			(width 0.2)
			(type default)
		)
		(layer "In4.Cu")
	)
	(gr_line
		(start 160.187386 -25.626314)
		(end 160.937448 -24.226266)
		(stroke
			(width 0.2)
			(type default)
		)
		(layer "In4.Cu")
	)
	(gr_line
		(start 160.187386 -21.82622)
		(end 160.937448 -20.426426)
		(stroke
			(width 0.2)
			(type default)
		)
		(layer "In4.Cu")
	)
	(gr_line
		(start 160.187386 -18.02638)
		(end 160.937448 -16.626586)
		(stroke
			(width 0.2)
			(type default)
		)
		(layer "In4.Cu")
	)
	(gr_line
		(start 160.187386 -14.226286)
		(end 160.937448 -12.826238)
		(stroke
			(width 0.2)
			(type default)
		)
		(layer "In4.Cu")
	)
	(gr_line
		(start 160.89376 -211.406994)
		(end 161.70656 -211.406994)
		(stroke
			(width 0.2)
			(type default)
		)
		(layer "In4.Cu")
	)
	(gr_arc
		(start 160.894014 -210.385914)
		(mid 160.38322 -210.896327)
		(end 160.89376 -211.406994)
		(stroke
			(width 0.2)
			(type default)
		)
		(layer "In4.Cu")
	)
	(gr_arc
		(start 160.935162 -20.425156)
		(mid 160.679486 -19.579255)
		(end 159.833564 -19.835114)
		(stroke
			(width 0.2)
			(type default)
		)
		(layer "In4.Cu")
	)
	(gr_arc
		(start 160.935162 -16.625316)
		(mid 160.679638 -15.779496)
		(end 159.833818 -16.03502)
		(stroke
			(width 0.2)
			(type default)
		)
		(layer "In4.Cu")
	)
	(gr_arc
		(start 160.935416 -24.224996)
		(mid 160.679384 -23.379176)
		(end 159.833564 -23.635208)
		(stroke
			(width 0.2)
			(type default)
		)
		(layer "In4.Cu")
	)
	(gr_arc
		(start 160.935416 -12.824968)
		(mid 160.679384 -11.979148)
		(end 159.833564 -12.23518)
		(stroke
			(width 0.2)
			(type default)
		)
		(layer "In4.Cu")
	)
	(gr_line
		(start 160.937194 -20.426172)
		(end 160.935162 -20.425156)
		(stroke
			(width 0.2)
			(type default)
		)
		(layer "In4.Cu")
	)
	(gr_line
		(start 160.937448 -24.226266)
		(end 160.935416 -24.224996)
		(stroke
			(width 0.2)
			(type default)
		)
		(layer "In4.Cu")
	)
	(gr_line
		(start 160.937448 -20.426426)
		(end 160.937194 -20.426172)
		(stroke
			(width 0.2)
			(type default)
		)
		(layer "In4.Cu")
	)
	(gr_line
		(start 160.937448 -16.626586)
		(end 160.935162 -16.625316)
		(stroke
			(width 0.2)
			(type default)
		)
		(layer "In4.Cu")
	)
	(gr_line
		(start 160.937448 -12.826238)
		(end 160.935416 -12.824968)
		(stroke
			(width 0.2)
			(type default)
		)
		(layer "In4.Cu")
	)
	(gr_line
		(start 161.2773 -35.53206)
		(end 162.0901 -35.53206)
		(stroke
			(width 0.2)
			(type default)
		)
		(layer "In4.Cu")
	)
	(gr_arc
		(start 161.277554 -34.51098)
		(mid 160.76676 -35.021393)
		(end 161.2773 -35.53206)
		(stroke
			(width 0.2)
			(type default)
		)
		(layer "In4.Cu")
	)
	(gr_arc
		(start 161.70656 -211.406994)
		(mid 162.2171 -210.896454)
		(end 161.70656 -210.385914)
		(stroke
			(width 0.2)
			(type default)
		)
		(layer "In4.Cu")
	)
	(gr_line
		(start 161.70656 -210.385914)
		(end 160.894014 -210.385914)
		(stroke
			(width 0.2)
			(type default)
		)
		(layer "In4.Cu")
	)
	(gr_line
		(start 161.7853 -38.52164)
		(end 162.597846 -38.52164)
		(stroke
			(width 0.2)
			(type default)
		)
		(layer "In4.Cu")
	)
	(gr_arc
		(start 161.7853 -37.50056)
		(mid 161.27476 -38.0111)
		(end 161.7853 -38.52164)
		(stroke
			(width 0.2)
			(type default)
		)
		(layer "In4.Cu")
	)
	(gr_arc
		(start 162.0901 -35.53206)
		(mid 162.60064 -35.02152)
		(end 162.0901 -34.51098)
		(stroke
			(width 0.2)
			(type default)
		)
		(layer "In4.Cu")
	)
	(gr_line
		(start 162.0901 -34.51098)
		(end 161.277554 -34.51098)
		(stroke
			(width 0.2)
			(type default)
		)
		(layer "In4.Cu")
	)
	(gr_arc
		(start 162.597846 -38.52164)
		(mid 163.10864 -38.011227)
		(end 162.5981 -37.50056)
		(stroke
			(width 0.2)
			(type default)
		)
		(layer "In4.Cu")
	)
	(gr_line
		(start 162.5981 -37.50056)
		(end 161.7853 -37.50056)
		(stroke
			(width 0.2)
			(type default)
		)
		(layer "In4.Cu")
	)
	(gr_line
		(start 162.6997 -82.17154)
		(end 163.512246 -82.17154)
		(stroke
			(width 0.2)
			(type default)
		)
		(layer "In4.Cu")
	)
	(gr_arc
		(start 162.6997 -81.15046)
		(mid 162.18916 -81.661)
		(end 162.6997 -82.17154)
		(stroke
			(width 0.2)
			(type default)
		)
		(layer "In4.Cu")
	)
	(gr_line
		(start 162.941 -70.612)
		(end 162.941 -62.738)
		(stroke
			(width 0.381)
			(type default)
		)
		(layer "In4.Cu")
	)
	(gr_line
		(start 162.941 -62.738)
		(end 163.957 -61.722)
		(stroke
			(width 0.381)
			(type default)
		)
		(layer "In4.Cu")
	)
	(gr_line
		(start 163.322 -70.993)
		(end 162.941 -70.612)
		(stroke
			(width 0.381)
			(type default)
		)
		(layer "In4.Cu")
	)
	(gr_line
		(start 163.322 -70.993)
		(end 177.546 -70.993)
		(stroke
			(width 0.381)
			(type default)
		)
		(layer "In4.Cu")
	)
	(gr_arc
		(start 163.512246 -82.17154)
		(mid 164.02304 -81.661127)
		(end 163.5125 -81.15046)
		(stroke
			(width 0.2)
			(type default)
		)
		(layer "In4.Cu")
	)
	(gr_line
		(start 163.5125 -81.15046)
		(end 162.6997 -81.15046)
		(stroke
			(width 0.2)
			(type default)
		)
		(layer "In4.Cu")
	)
	(gr_line
		(start 163.957 -61.722)
		(end 178.181 -61.722)
		(stroke
			(width 0.381)
			(type default)
		)
		(layer "In4.Cu")
	)
	(gr_line
		(start 164.893752 -222.805244)
		(end 165.706298 -222.805244)
		(stroke
			(width 0.2)
			(type default)
		)
		(layer "In4.Cu")
	)
	(gr_arc
		(start 164.893752 -221.784164)
		(mid 164.383212 -222.294704)
		(end 164.893752 -222.805244)
		(stroke
			(width 0.2)
			(type default)
		)
		(layer "In4.Cu")
	)
	(gr_arc
		(start 165.583616 -25.035256)
		(mid 165.839648 -25.881076)
		(end 166.685468 -25.625044)
		(stroke
			(width 0.2)
			(type default)
		)
		(layer "In4.Cu")
	)
	(gr_arc
		(start 165.58768 -13.627608)
		(mid 165.835814 -14.479061)
		(end 166.685468 -14.225016)
		(stroke
			(width 0.2)
			(type default)
		)
		(layer "In4.Cu")
	)
	(gr_arc
		(start 165.706298 -222.805244)
		(mid 166.217092 -222.294831)
		(end 165.706552 -221.784164)
		(stroke
			(width 0.2)
			(type default)
		)
		(layer "In4.Cu")
	)
	(gr_line
		(start 165.706552 -221.784164)
		(end 164.893752 -221.784164)
		(stroke
			(width 0.2)
			(type default)
		)
		(layer "In4.Cu")
	)
	(gr_line
		(start 166.333424 -23.635208)
		(end 165.583616 -25.035256)
		(stroke
			(width 0.2)
			(type default)
		)
		(layer "In4.Cu")
	)
	(gr_line
		(start 166.333424 -12.23518)
		(end 165.58768 -13.627608)
		(stroke
			(width 0.2)
			(type default)
		)
		(layer "In4.Cu")
	)
	(gr_line
		(start 166.493698 -211.406994)
		(end 167.306498 -211.406994)
		(stroke
			(width 0.2)
			(type default)
		)
		(layer "In4.Cu")
	)
	(gr_arc
		(start 166.493952 -210.385914)
		(mid 165.983158 -210.896327)
		(end 166.493698 -211.406994)
		(stroke
			(width 0.2)
			(type default)
		)
		(layer "In4.Cu")
	)
	(gr_line
		(start 166.685468 -25.625044)
		(end 167.431212 -24.232616)
		(stroke
			(width 0.2)
			(type default)
		)
		(layer "In4.Cu")
	)
	(gr_line
		(start 166.685468 -14.225016)
		(end 167.435276 -12.824968)
		(stroke
			(width 0.2)
			(type default)
		)
		(layer "In4.Cu")
	)
	(gr_arc
		(start 167.191436 -89.4588)
		(mid 167.701976 -89.96934)
		(end 168.212516 -89.4588)
		(stroke
			(width 0.2)
			(type default)
		)
		(layer "In4.Cu")
	)
	(gr_line
		(start 167.191436 -88.646)
		(end 167.191436 -89.4588)
		(stroke
			(width 0.2)
			(type default)
		)
		(layer "In4.Cu")
	)
	(gr_arc
		(start 167.306498 -211.406994)
		(mid 167.817038 -210.896454)
		(end 167.306498 -210.385914)
		(stroke
			(width 0.2)
			(type default)
		)
		(layer "In4.Cu")
	)
	(gr_line
		(start 167.306498 -210.385914)
		(end 166.493952 -210.385914)
		(stroke
			(width 0.2)
			(type default)
		)
		(layer "In4.Cu")
	)
	(gr_arc
		(start 167.431212 -24.232616)
		(mid 167.183078 -23.381163)
		(end 166.333424 -23.635208)
		(stroke
			(width 0.2)
			(type default)
		)
		(layer "In4.Cu")
	)
	(gr_arc
		(start 167.435276 -12.824968)
		(mid 167.179244 -11.979148)
		(end 166.333424 -12.23518)
		(stroke
			(width 0.2)
			(type default)
		)
		(layer "In4.Cu")
	)
	(gr_line
		(start 167.831516 -25.033732)
		(end 167.83177 -25.033986)
		(stroke
			(width 0.2)
			(type default)
		)
		(layer "In4.Cu")
	)
	(gr_line
		(start 167.831516 -21.233892)
		(end 167.833548 -21.235162)
		(stroke
			(width 0.2)
			(type default)
		)
		(layer "In4.Cu")
	)
	(gr_line
		(start 167.831516 -17.433544)
		(end 167.83177 -17.433798)
		(stroke
			(width 0.2)
			(type default)
		)
		(layer "In4.Cu")
	)
	(gr_line
		(start 167.831516 -13.633704)
		(end 167.83177 -13.633958)
		(stroke
			(width 0.2)
			(type default)
		)
		(layer "In4.Cu")
	)
	(gr_line
		(start 167.83177 -25.033986)
		(end 167.833802 -25.035002)
		(stroke
			(width 0.2)
			(type default)
		)
		(layer "In4.Cu")
	)
	(gr_line
		(start 167.83177 -17.433798)
		(end 167.833802 -17.434814)
		(stroke
			(width 0.2)
			(type default)
		)
		(layer "In4.Cu")
	)
	(gr_line
		(start 167.83177 -13.633958)
		(end 167.833802 -13.634974)
		(stroke
			(width 0.2)
			(type default)
		)
		(layer "In4.Cu")
	)
	(gr_arc
		(start 167.833548 -21.235162)
		(mid 168.08958 -22.080982)
		(end 168.9354 -21.82495)
		(stroke
			(width 0.2)
			(type default)
		)
		(layer "In4.Cu")
	)
	(gr_arc
		(start 167.833802 -25.035002)
		(mid 168.089478 -25.880903)
		(end 168.9354 -25.625044)
		(stroke
			(width 0.2)
			(type default)
		)
		(layer "In4.Cu")
	)
	(gr_arc
		(start 167.833802 -17.434814)
		(mid 168.089326 -18.280634)
		(end 168.935146 -18.02511)
		(stroke
			(width 0.2)
			(type default)
		)
		(layer "In4.Cu")
	)
	(gr_arc
		(start 167.833802 -13.634974)
		(mid 168.089478 -14.480875)
		(end 168.9354 -14.225016)
		(stroke
			(width 0.2)
			(type default)
		)
		(layer "In4.Cu")
	)
	(gr_line
		(start 168.093644 -222.805244)
		(end 168.90619 -222.805244)
		(stroke
			(width 0.2)
			(type default)
		)
		(layer "In4.Cu")
	)
	(gr_arc
		(start 168.093644 -221.784164)
		(mid 167.583104 -222.294704)
		(end 168.093644 -222.805244)
		(stroke
			(width 0.2)
			(type default)
		)
		(layer "In4.Cu")
	)
	(gr_line
		(start 168.212516 -89.4588)
		(end 168.212516 -88.646254)
		(stroke
			(width 0.2)
			(type default)
		)
		(layer "In4.Cu")
	)
	(gr_arc
		(start 168.212516 -88.646254)
		(mid 167.702103 -88.13546)
		(end 167.191436 -88.646)
		(stroke
			(width 0.2)
			(type default)
		)
		(layer "In4.Cu")
	)
	(gr_line
		(start 168.581578 -23.633938)
		(end 167.831516 -25.033732)
		(stroke
			(width 0.2)
			(type default)
		)
		(layer "In4.Cu")
	)
	(gr_line
		(start 168.581578 -19.833844)
		(end 167.831516 -21.233892)
		(stroke
			(width 0.2)
			(type default)
		)
		(layer "In4.Cu")
	)
	(gr_line
		(start 168.581578 -16.03375)
		(end 167.831516 -17.433544)
		(stroke
			(width 0.2)
			(type default)
		)
		(layer "In4.Cu")
	)
	(gr_line
		(start 168.581578 -12.23391)
		(end 167.831516 -13.633704)
		(stroke
			(width 0.2)
			(type default)
		)
		(layer "In4.Cu")
	)
	(gr_line
		(start 168.58361 -23.635208)
		(end 168.581578 -23.633938)
		(stroke
			(width 0.2)
			(type default)
		)
		(layer "In4.Cu")
	)
	(gr_line
		(start 168.58361 -19.835114)
		(end 168.581578 -19.833844)
		(stroke
			(width 0.2)
			(type default)
		)
		(layer "In4.Cu")
	)
	(gr_line
		(start 168.58361 -12.23518)
		(end 168.581578 -12.23391)
		(stroke
			(width 0.2)
			(type default)
		)
		(layer "In4.Cu")
	)
	(gr_line
		(start 168.583864 -16.03502)
		(end 168.581578 -16.03375)
		(stroke
			(width 0.2)
			(type default)
		)
		(layer "In4.Cu")
	)
	(gr_arc
		(start 168.90619 -222.805244)
		(mid 169.416984 -222.294831)
		(end 168.906444 -221.784164)
		(stroke
			(width 0.2)
			(type default)
		)
		(layer "In4.Cu")
	)
	(gr_line
		(start 168.906444 -221.784164)
		(end 168.093644 -221.784164)
		(stroke
			(width 0.2)
			(type default)
		)
		(layer "In4.Cu")
	)
	(gr_line
		(start 168.935146 -18.02511)
		(end 168.937432 -18.02638)
		(stroke
			(width 0.2)
			(type default)
		)
		(layer "In4.Cu")
	)
	(gr_line
		(start 168.9354 -25.625044)
		(end 168.937432 -25.626314)
		(stroke
			(width 0.2)
			(type default)
		)
		(layer "In4.Cu")
	)
	(gr_line
		(start 168.9354 -21.82495)
		(end 168.937432 -21.82622)
		(stroke
			(width 0.2)
			(type default)
		)
		(layer "In4.Cu")
	)
	(gr_line
		(start 168.9354 -14.225016)
		(end 168.937432 -14.226286)
		(stroke
			(width 0.2)
			(type default)
		)
		(layer "In4.Cu")
	)
	(gr_line
		(start 168.937432 -25.626314)
		(end 169.687494 -24.226266)
		(stroke
			(width 0.2)
			(type default)
		)
		(layer "In4.Cu")
	)
	(gr_line
		(start 168.937432 -21.82622)
		(end 169.687494 -20.426426)
		(stroke
			(width 0.2)
			(type default)
		)
		(layer "In4.Cu")
	)
	(gr_line
		(start 168.937432 -18.02638)
		(end 169.687494 -16.626586)
		(stroke
			(width 0.2)
			(type default)
		)
		(layer "In4.Cu")
	)
	(gr_line
		(start 168.937432 -14.226286)
		(end 169.687494 -12.826238)
		(stroke
			(width 0.2)
			(type default)
		)
		(layer "In4.Cu")
	)
	(gr_arc
		(start 169.685208 -20.425156)
		(mid 169.429532 -19.579255)
		(end 168.58361 -19.835114)
		(stroke
			(width 0.2)
			(type default)
		)
		(layer "In4.Cu")
	)
	(gr_arc
		(start 169.685208 -16.625316)
		(mid 169.429684 -15.779496)
		(end 168.583864 -16.03502)
		(stroke
			(width 0.2)
			(type default)
		)
		(layer "In4.Cu")
	)
	(gr_arc
		(start 169.685462 -24.224996)
		(mid 169.42943 -23.379176)
		(end 168.58361 -23.635208)
		(stroke
			(width 0.2)
			(type default)
		)
		(layer "In4.Cu")
	)
	(gr_arc
		(start 169.685462 -12.824968)
		(mid 169.42943 -11.979148)
		(end 168.58361 -12.23518)
		(stroke
			(width 0.2)
			(type default)
		)
		(layer "In4.Cu")
	)
	(gr_line
		(start 169.68724 -20.426172)
		(end 169.685208 -20.425156)
		(stroke
			(width 0.2)
			(type default)
		)
		(layer "In4.Cu")
	)
	(gr_line
		(start 169.687494 -24.226266)
		(end 169.685462 -24.224996)
		(stroke
			(width 0.2)
			(type default)
		)
		(layer "In4.Cu")
	)
	(gr_line
		(start 169.687494 -20.426426)
		(end 169.68724 -20.426172)
		(stroke
			(width 0.2)
			(type default)
		)
		(layer "In4.Cu")
	)
	(gr_line
		(start 169.687494 -16.626586)
		(end 169.685208 -16.625316)
		(stroke
			(width 0.2)
			(type default)
		)
		(layer "In4.Cu")
	)
	(gr_line
		(start 169.687494 -12.826238)
		(end 169.685462 -12.824968)
		(stroke
			(width 0.2)
			(type default)
		)
		(layer "In4.Cu")
	)
	(gr_line
		(start 169.69359 -211.406994)
		(end 170.50639 -211.406994)
		(stroke
			(width 0.2)
			(type default)
		)
		(layer "In4.Cu")
	)
	(gr_arc
		(start 169.693844 -210.385914)
		(mid 169.18305 -210.896327)
		(end 169.69359 -211.406994)
		(stroke
			(width 0.2)
			(type default)
		)
		(layer "In4.Cu")
	)
	(gr_line
		(start 170.081448 -25.033732)
		(end 170.081702 -25.033986)
		(stroke
			(width 0.2)
			(type default)
		)
		(layer "In4.Cu")
	)
	(gr_line
		(start 170.081448 -21.233892)
		(end 170.08348 -21.235162)
		(stroke
			(width 0.2)
			(type default)
		)
		(layer "In4.Cu")
	)
	(gr_line
		(start 170.081448 -17.433544)
		(end 170.081702 -17.433798)
		(stroke
			(width 0.2)
			(type default)
		)
		(layer "In4.Cu")
	)
	(gr_line
		(start 170.081448 -13.633704)
		(end 170.081702 -13.633958)
		(stroke
			(width 0.2)
			(type default)
		)
		(layer "In4.Cu")
	)
	(gr_line
		(start 170.081702 -25.033986)
		(end 170.083734 -25.035002)
		(stroke
			(width 0.2)
			(type default)
		)
		(layer "In4.Cu")
	)
	(gr_line
		(start 170.081702 -17.433798)
		(end 170.083734 -17.434814)
		(stroke
			(width 0.2)
			(type default)
		)
		(layer "In4.Cu")
	)
	(gr_line
		(start 170.081702 -13.633958)
		(end 170.083734 -13.634974)
		(stroke
			(width 0.2)
			(type default)
		)
		(layer "In4.Cu")
	)
	(gr_arc
		(start 170.08348 -21.235162)
		(mid 170.339512 -22.080982)
		(end 171.185332 -21.82495)
		(stroke
			(width 0.2)
			(type default)
		)
		(layer "In4.Cu")
	)
	(gr_arc
		(start 170.083734 -25.035002)
		(mid 170.33941 -25.880903)
		(end 171.185332 -25.625044)
		(stroke
			(width 0.2)
			(type default)
		)
		(layer "In4.Cu")
	)
	(gr_arc
		(start 170.083734 -17.434814)
		(mid 170.339258 -18.280634)
		(end 171.185078 -18.02511)
		(stroke
			(width 0.2)
			(type default)
		)
		(layer "In4.Cu")
	)
	(gr_arc
		(start 170.083734 -13.634974)
		(mid 170.33941 -14.480875)
		(end 171.185332 -14.225016)
		(stroke
			(width 0.2)
			(type default)
		)
		(layer "In4.Cu")
	)
	(gr_arc
		(start 170.50639 -211.406994)
		(mid 171.01693 -210.896454)
		(end 170.50639 -210.385914)
		(stroke
			(width 0.2)
			(type default)
		)
		(layer "In4.Cu")
	)
	(gr_line
		(start 170.50639 -210.385914)
		(end 169.693844 -210.385914)
		(stroke
			(width 0.2)
			(type default)
		)
		(layer "In4.Cu")
	)
	(gr_line
		(start 170.83151 -23.633938)
		(end 170.081448 -25.033732)
		(stroke
			(width 0.2)
			(type default)
		)
		(layer "In4.Cu")
	)
	(gr_line
		(start 170.83151 -19.833844)
		(end 170.081448 -21.233892)
		(stroke
			(width 0.2)
			(type default)
		)
		(layer "In4.Cu")
	)
	(gr_line
		(start 170.83151 -16.03375)
		(end 170.081448 -17.433544)
		(stroke
			(width 0.2)
			(type default)
		)
		(layer "In4.Cu")
	)
	(gr_line
		(start 170.83151 -12.23391)
		(end 170.081448 -13.633704)
		(stroke
			(width 0.2)
			(type default)
		)
		(layer "In4.Cu")
	)
	(gr_line
		(start 170.833542 -23.635208)
		(end 170.83151 -23.633938)
		(stroke
			(width 0.2)
			(type default)
		)
		(layer "In4.Cu")
	)
	(gr_line
		(start 170.833542 -19.835114)
		(end 170.83151 -19.833844)
		(stroke
			(width 0.2)
			(type default)
		)
		(layer "In4.Cu")
	)
	(gr_line
		(start 170.833542 -12.23518)
		(end 170.83151 -12.23391)
		(stroke
			(width 0.2)
			(type default)
		)
		(layer "In4.Cu")
	)
	(gr_line
		(start 170.833796 -16.03502)
		(end 170.83151 -16.03375)
		(stroke
			(width 0.2)
			(type default)
		)
		(layer "In4.Cu")
	)
	(gr_line
		(start 171.185078 -18.02511)
		(end 171.187364 -18.02638)
		(stroke
			(width 0.2)
			(type default)
		)
		(layer "In4.Cu")
	)
	(gr_line
		(start 171.185332 -25.625044)
		(end 171.187364 -25.626314)
		(stroke
			(width 0.2)
			(type default)
		)
		(layer "In4.Cu")
	)
	(gr_line
		(start 171.185332 -21.82495)
		(end 171.187364 -21.82622)
		(stroke
			(width 0.2)
			(type default)
		)
		(layer "In4.Cu")
	)
	(gr_line
		(start 171.185332 -14.225016)
		(end 171.187364 -14.226286)
		(stroke
			(width 0.2)
			(type default)
		)
		(layer "In4.Cu")
	)
	(gr_line
		(start 171.187364 -25.626314)
		(end 171.937426 -24.226266)
		(stroke
			(width 0.2)
			(type default)
		)
		(layer "In4.Cu")
	)
	(gr_line
		(start 171.187364 -21.82622)
		(end 171.937426 -20.426426)
		(stroke
			(width 0.2)
			(type default)
		)
		(layer "In4.Cu")
	)
	(gr_line
		(start 171.187364 -18.02638)
		(end 171.937426 -16.626586)
		(stroke
			(width 0.2)
			(type default)
		)
		(layer "In4.Cu")
	)
	(gr_line
		(start 171.187364 -14.226286)
		(end 171.937426 -12.826238)
		(stroke
			(width 0.2)
			(type default)
		)
		(layer "In4.Cu")
	)
	(gr_line
		(start 171.29379 -222.805244)
		(end 172.106336 -222.805244)
		(stroke
			(width 0.2)
			(type default)
		)
		(layer "In4.Cu")
	)
	(gr_arc
		(start 171.29379 -221.784164)
		(mid 170.78325 -222.294704)
		(end 171.29379 -222.805244)
		(stroke
			(width 0.2)
			(type default)
		)
		(layer "In4.Cu")
	)
	(gr_line
		(start 171.822364 -71.632318)
		(end 171.199048 -71.009002)
		(stroke
			(width 0.381)
			(type default)
		)
		(layer "In4.Cu")
	)
	(gr_line
		(start 171.82592 -71.632318)
		(end 171.822364 -71.632318)
		(stroke
			(width 0.381)
			(type default)
		)
		(layer "In4.Cu")
	)
	(gr_line
		(start 171.831 -79.375)
		(end 171.831 -71.12)
		(stroke
			(width 0.381)
			(type default)
		)
		(layer "In4.Cu")
	)
	(gr_arc
		(start 171.93514 -20.425156)
		(mid 171.679464 -19.579255)
		(end 170.833542 -19.835114)
		(stroke
			(width 0.2)
			(type default)
		)
		(layer "In4.Cu")
	)
	(gr_arc
		(start 171.93514 -16.625316)
		(mid 171.679616 -15.779496)
		(end 170.833796 -16.03502)
		(stroke
			(width 0.2)
			(type default)
		)
		(layer "In4.Cu")
	)
	(gr_arc
		(start 171.935394 -24.224996)
		(mid 171.679362 -23.379176)
		(end 170.833542 -23.635208)
		(stroke
			(width 0.2)
			(type default)
		)
		(layer "In4.Cu")
	)
	(gr_arc
		(start 171.935394 -12.824968)
		(mid 171.679362 -11.979148)
		(end 170.833542 -12.23518)
		(stroke
			(width 0.2)
			(type default)
		)
		(layer "In4.Cu")
	)
	(gr_line
		(start 171.937172 -20.426172)
		(end 171.93514 -20.425156)
		(stroke
			(width 0.2)
			(type default)
		)
		(layer "In4.Cu")
	)
	(gr_line
		(start 171.937426 -24.226266)
		(end 171.935394 -24.224996)
		(stroke
			(width 0.2)
			(type default)
		)
		(layer "In4.Cu")
	)
	(gr_line
		(start 171.937426 -20.426426)
		(end 171.937172 -20.426172)
		(stroke
			(width 0.2)
			(type default)
		)
		(layer "In4.Cu")
	)
	(gr_line
		(start 171.937426 -16.626586)
		(end 171.93514 -16.625316)
		(stroke
			(width 0.2)
			(type default)
		)
		(layer "In4.Cu")
	)
	(gr_line
		(start 171.937426 -12.826238)
		(end 171.935394 -12.824968)
		(stroke
			(width 0.2)
			(type default)
		)
		(layer "In4.Cu")
	)
	(gr_arc
		(start 172.106336 -222.805244)
		(mid 172.61713 -222.294831)
		(end 172.10659 -221.784164)
		(stroke
			(width 0.2)
			(type default)
		)
		(layer "In4.Cu")
	)
	(gr_line
		(start 172.10659 -221.784164)
		(end 171.29379 -221.784164)
		(stroke
			(width 0.2)
			(type default)
		)
		(layer "In4.Cu")
	)
	(gr_line
		(start 172.422312 -71.035926)
		(end 171.82592 -71.632318)
		(stroke
			(width 0.381)
			(type default)
		)
		(layer "In4.Cu")
	)
	(gr_line
		(start 172.7454 -96.704912)
		(end 173.6344 -96.704912)
		(stroke
			(width 0.2)
			(type default)
		)
		(layer "In4.Cu")
	)
	(gr_arc
		(start 172.745654 -95.683832)
		(mid 172.23486 -96.194245)
		(end 172.7454 -96.704912)
		(stroke
			(width 0.2)
			(type default)
		)
		(layer "In4.Cu")
	)
	(gr_line
		(start 172.893736 -211.406994)
		(end 173.706536 -211.406994)
		(stroke
			(width 0.2)
			(type default)
		)
		(layer "In4.Cu")
	)
	(gr_arc
		(start 172.89399 -210.385914)
		(mid 172.383196 -210.896327)
		(end 172.893736 -211.406994)
		(stroke
			(width 0.2)
			(type default)
		)
		(layer "In4.Cu")
	)
	(gr_arc
		(start 173.6344 -96.704912)
		(mid 174.14494 -96.194372)
		(end 173.6344 -95.683832)
		(stroke
			(width 0.2)
			(type default)
		)
		(layer "In4.Cu")
	)
	(gr_line
		(start 173.6344 -95.683832)
		(end 172.745654 -95.683832)
		(stroke
			(width 0.2)
			(type default)
		)
		(layer "In4.Cu")
	)
	(gr_arc
		(start 173.706536 -211.406994)
		(mid 174.217076 -210.896454)
		(end 173.706536 -210.385914)
		(stroke
			(width 0.2)
			(type default)
		)
		(layer "In4.Cu")
	)
	(gr_line
		(start 173.706536 -210.385914)
		(end 172.89399 -210.385914)
		(stroke
			(width 0.2)
			(type default)
		)
		(layer "In4.Cu")
	)
	(gr_line
		(start 174.493682 -222.805244)
		(end 175.306228 -222.805244)
		(stroke
			(width 0.2)
			(type default)
		)
		(layer "In4.Cu")
	)
	(gr_arc
		(start 174.493682 -221.784164)
		(mid 173.983142 -222.294704)
		(end 174.493682 -222.805244)
		(stroke
			(width 0.2)
			(type default)
		)
		(layer "In4.Cu")
	)
	(gr_arc
		(start 175.306228 -222.805244)
		(mid 175.817022 -222.294831)
		(end 175.306482 -221.784164)
		(stroke
			(width 0.2)
			(type default)
		)
		(layer "In4.Cu")
	)
	(gr_line
		(start 175.306482 -221.784164)
		(end 174.493682 -221.784164)
		(stroke
			(width 0.2)
			(type default)
		)
		(layer "In4.Cu")
	)
	(gr_line
		(start 176.093628 -211.406994)
		(end 176.906428 -211.406994)
		(stroke
			(width 0.2)
			(type default)
		)
		(layer "In4.Cu")
	)
	(gr_arc
		(start 176.093882 -210.385914)
		(mid 175.583088 -210.896327)
		(end 176.093628 -211.406994)
		(stroke
			(width 0.2)
			(type default)
		)
		(layer "In4.Cu")
	)
	(gr_arc
		(start 176.906428 -211.406994)
		(mid 177.416968 -210.896454)
		(end 176.906428 -210.385914)
		(stroke
			(width 0.2)
			(type default)
		)
		(layer "In4.Cu")
	)
	(gr_line
		(start 176.906428 -210.385914)
		(end 176.093882 -210.385914)
		(stroke
			(width 0.2)
			(type default)
		)
		(layer "In4.Cu")
	)
	(gr_line
		(start 177.543206 -61.72962)
		(end 177.543206 -61.726064)
		(stroke
			(width 0.381)
			(type default)
		)
		(layer "In4.Cu")
	)
	(gr_line
		(start 177.543206 -61.726064)
		(end 178.166522 -61.102748)
		(stroke
			(width 0.381)
			(type default)
		)
		(layer "In4.Cu")
	)
	(gr_line
		(start 177.546 -70.993)
		(end 178.181 -70.358)
		(stroke
			(width 0.381)
			(type default)
		)
		(layer "In4.Cu")
	)
	(gr_line
		(start 177.5968 -221.18574)
		(end 178.409346 -221.18574)
		(stroke
			(width 0.2)
			(type default)
		)
		(layer "In4.Cu")
	)
	(gr_arc
		(start 177.5968 -220.16466)
		(mid 177.08626 -220.6752)
		(end 177.5968 -221.18574)
		(stroke
			(width 0.2)
			(type default)
		)
		(layer "In4.Cu")
	)
	(gr_line
		(start 178.139598 -62.326012)
		(end 177.543206 -61.72962)
		(stroke
			(width 0.381)
			(type default)
		)
		(layer "In4.Cu")
	)
	(gr_line
		(start 178.181 -70.612)
		(end 178.181 -70.358)
		(stroke
			(width 0.381)
			(type default)
		)
		(layer "In4.Cu")
	)
	(gr_line
		(start 178.181 -70.358)
		(end 178.181 -60.071)
		(stroke
			(width 0.381)
			(type default)
		)
		(layer "In4.Cu")
	)
	(gr_line
		(start 178.181 -60.071)
		(end 179.324 -58.928)
		(stroke
			(width 0.381)
			(type default)
		)
		(layer "In4.Cu")
	)
	(gr_arc
		(start 178.409346 -221.18574)
		(mid 178.92014 -220.675327)
		(end 178.4096 -220.16466)
		(stroke
			(width 0.2)
			(type default)
		)
		(layer "In4.Cu")
	)
	(gr_line
		(start 178.4096 -220.16466)
		(end 177.5968 -220.16466)
		(stroke
			(width 0.2)
			(type default)
		)
		(layer "In4.Cu")
	)
	(gr_line
		(start 178.689 -71.12)
		(end 178.181 -70.612)
		(stroke
			(width 0.381)
			(type default)
		)
		(layer "In4.Cu")
	)
	(gr_line
		(start 178.816 -86.36)
		(end 171.831 -79.375)
		(stroke
			(width 0.381)
			(type default)
		)
		(layer "In4.Cu")
	)
	(gr_line
		(start 179.324 -58.928)
		(end 187.325 -58.928)
		(stroke
			(width 0.381)
			(type default)
		)
		(layer "In4.Cu")
	)
	(gr_line
		(start 180.09997 -228.000052)
		(end 134.500112 -228.000052)
		(stroke
			(width 5.08)
			(type default)
		)
		(layer "In4.Cu")
	)
	(gr_line
		(start 180.09997 -222.600012)
		(end 180.09997 -228.000052)
		(stroke
			(width 1.524)
			(type default)
		)
		(layer "In4.Cu")
	)
	(gr_line
		(start 182.500016 -228.000052)
		(end 182.500016 -222.600012)
		(stroke
			(width 1.524)
			(type default)
		)
		(layer "In4.Cu")
	)
	(gr_arc
		(start 182.500016 -222.600012)
		(mid 181.30012 -221.400116)
		(end 180.09997 -222.600012)
		(stroke
			(width 1.524)
			(type default)
		)
		(layer "In4.Cu")
	)
	(gr_arc
		(start 182.57266 -29.8069)
		(mid 183.0832 -30.31744)
		(end 183.59374 -29.8069)
		(stroke
			(width 0.2)
			(type default)
		)
		(layer "In4.Cu")
	)
	(gr_line
		(start 182.57266 -28.9941)
		(end 182.57266 -29.8069)
		(stroke
			(width 0.2)
			(type default)
		)
		(layer "In4.Cu")
	)
	(gr_arc
		(start 182.57266 -26.7589)
		(mid 183.0832 -27.26944)
		(end 183.59374 -26.7589)
		(stroke
			(width 0.2)
			(type default)
		)
		(layer "In4.Cu")
	)
	(gr_line
		(start 182.57266 -25.9461)
		(end 182.57266 -26.7589)
		(stroke
			(width 0.2)
			(type default)
		)
		(layer "In4.Cu")
	)
	(gr_arc
		(start 182.57266 -24.472646)
		(mid 183.083073 -24.98344)
		(end 183.59374 -24.4729)
		(stroke
			(width 0.2)
			(type default)
		)
		(layer "In4.Cu")
	)
	(gr_line
		(start 182.57266 -23.6601)
		(end 182.57266 -24.472646)
		(stroke
			(width 0.2)
			(type default)
		)
		(layer "In4.Cu")
	)
	(gr_arc
		(start 182.57266 -20.6629)
		(mid 183.0832 -21.17344)
		(end 183.59374 -20.6629)
		(stroke
			(width 0.2)
			(type default)
		)
		(layer "In4.Cu")
	)
	(gr_line
		(start 182.57266 -19.8501)
		(end 182.57266 -20.6629)
		(stroke
			(width 0.2)
			(type default)
		)
		(layer "In4.Cu")
	)
	(gr_line
		(start 183.59374 -29.8069)
		(end 183.59374 -28.994354)
		(stroke
			(width 0.2)
			(type default)
		)
		(layer "In4.Cu")
	)
	(gr_arc
		(start 183.59374 -28.994354)
		(mid 183.083327 -28.48356)
		(end 182.57266 -28.9941)
		(stroke
			(width 0.2)
			(type default)
		)
		(layer "In4.Cu")
	)
	(gr_line
		(start 183.59374 -26.7589)
		(end 183.59374 -25.946354)
		(stroke
			(width 0.2)
			(type default)
		)
		(layer "In4.Cu")
	)
	(gr_arc
		(start 183.59374 -25.946354)
		(mid 183.083327 -25.43556)
		(end 182.57266 -25.9461)
		(stroke
			(width 0.2)
			(type default)
		)
		(layer "In4.Cu")
	)
	(gr_line
		(start 183.59374 -24.4729)
		(end 183.59374 -23.6601)
		(stroke
			(width 0.2)
			(type default)
		)
		(layer "In4.Cu")
	)
	(gr_arc
		(start 183.59374 -23.6601)
		(mid 183.0832 -23.14956)
		(end 182.57266 -23.6601)
		(stroke
			(width 0.2)
			(type default)
		)
		(layer "In4.Cu")
	)
	(gr_line
		(start 183.59374 -20.6629)
		(end 183.59374 -19.850354)
		(stroke
			(width 0.2)
			(type default)
		)
		(layer "In4.Cu")
	)
	(gr_arc
		(start 183.59374 -19.850354)
		(mid 183.083327 -19.33956)
		(end 182.57266 -19.8501)
		(stroke
			(width 0.2)
			(type default)
		)
		(layer "In4.Cu")
	)
	(gr_line
		(start 183.63057 -8.91667)
		(end 184.443116 -8.91667)
		(stroke
			(width 0.2)
			(type default)
		)
		(layer "In4.Cu")
	)
	(gr_arc
		(start 183.63057 -7.89559)
		(mid 183.12003 -8.40613)
		(end 183.63057 -8.91667)
		(stroke
			(width 0.2)
			(type default)
		)
		(layer "In4.Cu")
	)
	(gr_arc
		(start 184.048146 -12.509754)
		(mid 184.558686 -13.020294)
		(end 185.069226 -12.509754)
		(stroke
			(width 0.2)
			(type default)
		)
		(layer "In4.Cu")
	)
	(gr_line
		(start 184.048146 -11.696954)
		(end 184.048146 -12.509754)
		(stroke
			(width 0.2)
			(type default)
		)
		(layer "In4.Cu")
	)
	(gr_line
		(start 184.093612 -211.406994)
		(end 184.906412 -211.406994)
		(stroke
			(width 0.2)
			(type default)
		)
		(layer "In4.Cu")
	)
	(gr_arc
		(start 184.093866 -210.385914)
		(mid 183.583072 -210.896327)
		(end 184.093612 -211.406994)
		(stroke
			(width 0.2)
			(type default)
		)
		(layer "In4.Cu")
	)
	(gr_arc
		(start 184.443116 -8.91667)
		(mid 184.95391 -8.406257)
		(end 184.44337 -7.89559)
		(stroke
			(width 0.2)
			(type default)
		)
		(layer "In4.Cu")
	)
	(gr_line
		(start 184.44337 -7.89559)
		(end 183.63057 -7.89559)
		(stroke
			(width 0.2)
			(type default)
		)
		(layer "In4.Cu")
	)
	(gr_arc
		(start 184.906412 -211.406994)
		(mid 185.416952 -210.896454)
		(end 184.906412 -210.385914)
		(stroke
			(width 0.2)
			(type default)
		)
		(layer "In4.Cu")
	)
	(gr_line
		(start 184.906412 -210.385914)
		(end 184.093866 -210.385914)
		(stroke
			(width 0.2)
			(type default)
		)
		(layer "In4.Cu")
	)
	(gr_line
		(start 185.069226 -12.509754)
		(end 185.069226 -11.697208)
		(stroke
			(width 0.2)
			(type default)
		)
		(layer "In4.Cu")
	)
	(gr_arc
		(start 185.069226 -11.697208)
		(mid 184.558813 -11.186414)
		(end 184.048146 -11.696954)
		(stroke
			(width 0.2)
			(type default)
		)
		(layer "In4.Cu")
	)
	(gr_arc
		(start 185.54446 -25.811734)
		(mid 186.055 -26.322274)
		(end 186.56554 -25.811734)
		(stroke
			(width 0.2)
			(type default)
		)
		(layer "In4.Cu")
	)
	(gr_line
		(start 185.54446 -24.998934)
		(end 185.54446 -25.811734)
		(stroke
			(width 0.2)
			(type default)
		)
		(layer "In4.Cu")
	)
	(gr_line
		(start 185.693558 -222.805244)
		(end 186.506358 -222.805244)
		(stroke
			(width 0.2)
			(type default)
		)
		(layer "In4.Cu")
	)
	(gr_arc
		(start 185.693812 -221.784164)
		(mid 185.183018 -222.294577)
		(end 185.693558 -222.805244)
		(stroke
			(width 0.2)
			(type default)
		)
		(layer "In4.Cu")
	)
	(gr_arc
		(start 186.506358 -222.805244)
		(mid 187.016898 -222.294704)
		(end 186.506358 -221.784164)
		(stroke
			(width 0.2)
			(type default)
		)
		(layer "In4.Cu")
	)
	(gr_line
		(start 186.506358 -221.784164)
		(end 185.693812 -221.784164)
		(stroke
			(width 0.2)
			(type default)
		)
		(layer "In4.Cu")
	)
	(gr_line
		(start 186.56554 -25.811734)
		(end 186.56554 -24.999188)
		(stroke
			(width 0.2)
			(type default)
		)
		(layer "In4.Cu")
	)
	(gr_arc
		(start 186.56554 -24.999188)
		(mid 186.055127 -24.488394)
		(end 185.54446 -24.998934)
		(stroke
			(width 0.2)
			(type default)
		)
		(layer "In4.Cu")
	)
	(gr_line
		(start 187.293758 -211.406994)
		(end 188.106558 -211.406994)
		(stroke
			(width 0.2)
			(type default)
		)
		(layer "In4.Cu")
	)
	(gr_arc
		(start 187.294012 -210.385914)
		(mid 186.783218 -210.896327)
		(end 187.293758 -211.406994)
		(stroke
			(width 0.2)
			(type default)
		)
		(layer "In4.Cu")
	)
	(gr_line
		(start 187.325 -58.928)
		(end 201.295 -44.958)
		(stroke
			(width 0.381)
			(type default)
		)
		(layer "In4.Cu")
	)
	(gr_line
		(start 187.96 -54.864)
		(end 189.611 -56.515)
		(stroke
			(width 0.381)
			(type default)
		)
		(layer "In4.Cu")
	)
	(gr_line
		(start 187.96 -48.133)
		(end 187.96 -54.864)
		(stroke
			(width 0.381)
			(type default)
		)
		(layer "In4.Cu")
	)
	(gr_arc
		(start 188.106558 -211.406994)
		(mid 188.617098 -210.896454)
		(end 188.106558 -210.385914)
		(stroke
			(width 0.2)
			(type default)
		)
		(layer "In4.Cu")
	)
	(gr_line
		(start 188.106558 -210.385914)
		(end 187.294012 -210.385914)
		(stroke
			(width 0.2)
			(type default)
		)
		(layer "In4.Cu")
	)
	(gr_line
		(start 188.893704 -222.805244)
		(end 189.70625 -222.805244)
		(stroke
			(width 0.2)
			(type default)
		)
		(layer "In4.Cu")
	)
	(gr_arc
		(start 188.893704 -221.784164)
		(mid 188.383164 -222.294704)
		(end 188.893704 -222.805244)
		(stroke
			(width 0.2)
			(type default)
		)
		(layer "In4.Cu")
	)
	(gr_line
		(start 189.24524 -56.97728)
		(end 189.24524 -56.134)
		(stroke
			(width 0.381)
			(type default)
		)
		(layer "In4.Cu")
	)
	(gr_line
		(start 189.24524 -56.134)
		(end 189.24778 -56.13146)
		(stroke
			(width 0.381)
			(type default)
		)
		(layer "In4.Cu")
	)
	(gr_line
		(start 189.24778 -56.13146)
		(end 190.12916 -56.13146)
		(stroke
			(width 0.381)
			(type default)
		)
		(layer "In4.Cu")
	)
	(gr_line
		(start 189.611 -71.12)
		(end 178.689 -71.12)
		(stroke
			(width 0.381)
			(type default)
		)
		(layer "In4.Cu")
	)
	(gr_arc
		(start 189.70625 -222.805244)
		(mid 190.217044 -222.294831)
		(end 189.706504 -221.784164)
		(stroke
			(width 0.2)
			(type default)
		)
		(layer "In4.Cu")
	)
	(gr_line
		(start 189.706504 -221.784164)
		(end 188.893704 -221.784164)
		(stroke
			(width 0.2)
			(type default)
		)
		(layer "In4.Cu")
	)
	(gr_line
		(start 190.49365 -211.406994)
		(end 191.30645 -211.406994)
		(stroke
			(width 0.2)
			(type default)
		)
		(layer "In4.Cu")
	)
	(gr_arc
		(start 190.493904 -210.385914)
		(mid 189.98311 -210.896327)
		(end 190.49365 -211.406994)
		(stroke
			(width 0.2)
			(type default)
		)
		(layer "In4.Cu")
	)
	(gr_arc
		(start 191.30645 -211.406994)
		(mid 191.81699 -210.896454)
		(end 191.30645 -210.385914)
		(stroke
			(width 0.2)
			(type default)
		)
		(layer "In4.Cu")
	)
	(gr_line
		(start 191.30645 -210.385914)
		(end 190.493904 -210.385914)
		(stroke
			(width 0.2)
			(type default)
		)
		(layer "In4.Cu")
	)
	(gr_line
		(start 192.093596 -222.805244)
		(end 192.906142 -222.805244)
		(stroke
			(width 0.2)
			(type default)
		)
		(layer "In4.Cu")
	)
	(gr_arc
		(start 192.093596 -221.784164)
		(mid 191.583056 -222.294704)
		(end 192.093596 -222.805244)
		(stroke
			(width 0.2)
			(type default)
		)
		(layer "In4.Cu")
	)
	(gr_arc
		(start 192.906142 -222.805244)
		(mid 193.416936 -222.294831)
		(end 192.906396 -221.784164)
		(stroke
			(width 0.2)
			(type default)
		)
		(layer "In4.Cu")
	)
	(gr_line
		(start 192.906396 -221.784164)
		(end 192.093596 -221.784164)
		(stroke
			(width 0.2)
			(type default)
		)
		(layer "In4.Cu")
	)
	(gr_line
		(start 193.693796 -211.406994)
		(end 194.506596 -211.406994)
		(stroke
			(width 0.2)
			(type default)
		)
		(layer "In4.Cu")
	)
	(gr_arc
		(start 193.69405 -210.385914)
		(mid 193.183256 -210.896327)
		(end 193.693796 -211.406994)
		(stroke
			(width 0.2)
			(type default)
		)
		(layer "In4.Cu")
	)
	(gr_arc
		(start 194.506596 -211.406994)
		(mid 195.017136 -210.896454)
		(end 194.506596 -210.385914)
		(stroke
			(width 0.2)
			(type default)
		)
		(layer "In4.Cu")
	)
	(gr_line
		(start 194.506596 -210.385914)
		(end 193.69405 -210.385914)
		(stroke
			(width 0.2)
			(type default)
		)
		(layer "In4.Cu")
	)
	(gr_line
		(start 194.945 -76.454)
		(end 189.611 -71.12)
		(stroke
			(width 0.381)
			(type default)
		)
		(layer "In4.Cu")
	)
	(gr_line
		(start 195.293742 -222.805244)
		(end 196.106288 -222.805244)
		(stroke
			(width 0.2)
			(type default)
		)
		(layer "In4.Cu")
	)
	(gr_arc
		(start 195.293742 -221.784164)
		(mid 194.783202 -222.294704)
		(end 195.293742 -222.805244)
		(stroke
			(width 0.2)
			(type default)
		)
		(layer "In4.Cu")
	)
	(gr_arc
		(start 196.106288 -222.805244)
		(mid 196.617082 -222.294831)
		(end 196.106542 -221.784164)
		(stroke
			(width 0.2)
			(type default)
		)
		(layer "In4.Cu")
	)
	(gr_line
		(start 196.106542 -221.784164)
		(end 195.293742 -221.784164)
		(stroke
			(width 0.2)
			(type default)
		)
		(layer "In4.Cu")
	)
	(gr_line
		(start 196.215 -39.878)
		(end 187.96 -48.133)
		(stroke
			(width 0.381)
			(type default)
		)
		(layer "In4.Cu")
	)
	(gr_line
		(start 196.893688 -211.406994)
		(end 197.706488 -211.406994)
		(stroke
			(width 0.2)
			(type default)
		)
		(layer "In4.Cu")
	)
	(gr_arc
		(start 196.893942 -210.385914)
		(mid 196.383148 -210.896327)
		(end 196.893688 -211.406994)
		(stroke
			(width 0.2)
			(type default)
		)
		(layer "In4.Cu")
	)
	(gr_arc
		(start 197.204838 -46.70806)
		(mid 197.816978 -47.3202)
		(end 198.429118 -46.70806)
		(stroke
			(width 0.2)
			(type default)
		)
		(layer "In4.Cu")
	)
	(gr_line
		(start 197.204838 -45.59046)
		(end 197.204838 -46.70806)
		(stroke
			(width 0.2)
			(type default)
		)
		(layer "In4.Cu")
	)
	(gr_arc
		(start 197.706488 -211.406994)
		(mid 198.217028 -210.896454)
		(end 197.706488 -210.385914)
		(stroke
			(width 0.2)
			(type default)
		)
		(layer "In4.Cu")
	)
	(gr_line
		(start 197.706488 -210.385914)
		(end 196.893942 -210.385914)
		(stroke
			(width 0.2)
			(type default)
		)
		(layer "In4.Cu")
	)
	(gr_line
		(start 198.429118 -46.70806)
		(end 198.429118 -45.590714)
		(stroke
			(width 0.2)
			(type default)
		)
		(layer "In4.Cu")
	)
	(gr_arc
		(start 198.429118 -45.590714)
		(mid 197.817105 -44.97832)
		(end 197.204838 -45.59046)
		(stroke
			(width 0.2)
			(type default)
		)
		(layer "In4.Cu")
	)
	(gr_line
		(start 198.493634 -222.805244)
		(end 199.30618 -222.805244)
		(stroke
			(width 0.2)
			(type default)
		)
		(layer "In4.Cu")
	)
	(gr_arc
		(start 198.493634 -221.784164)
		(mid 197.983094 -222.294704)
		(end 198.493634 -222.805244)
		(stroke
			(width 0.2)
			(type default)
		)
		(layer "In4.Cu")
	)
	(gr_arc
		(start 199.30618 -222.805244)
		(mid 199.816974 -222.294831)
		(end 199.306434 -221.784164)
		(stroke
			(width 0.2)
			(type default)
		)
		(layer "In4.Cu")
	)
	(gr_line
		(start 199.306434 -221.784164)
		(end 198.493634 -221.784164)
		(stroke
			(width 0.2)
			(type default)
		)
		(layer "In4.Cu")
	)
	(gr_arc
		(start 200.046844 -49.122076)
		(mid 199.43826 -49.737772)
		(end 200.053956 -50.346356)
		(stroke
			(width 0.2)
			(type default)
		)
		(layer "In4.Cu")
	)
	(gr_line
		(start 200.053956 -50.346356)
		(end 201.171302 -50.339752)
		(stroke
			(width 0.2)
			(type default)
		)
		(layer "In4.Cu")
	)
	(gr_line
		(start 200.09358 -211.406994)
		(end 200.90638 -211.406994)
		(stroke
			(width 0.2)
			(type default)
		)
		(layer "In4.Cu")
	)
	(gr_arc
		(start 200.093834 -210.385914)
		(mid 199.58304 -210.896327)
		(end 200.09358 -211.406994)
		(stroke
			(width 0.2)
			(type default)
		)
		(layer "In4.Cu")
	)
	(gr_arc
		(start 200.7489 -45.832268)
		(mid 201.360913 -46.444662)
		(end 201.97318 -45.832522)
		(stroke
			(width 0.2)
			(type default)
		)
		(layer "In4.Cu")
	)
	(gr_line
		(start 200.7489 -44.714922)
		(end 200.7489 -45.832268)
		(stroke
			(width 0.2)
			(type default)
		)
		(layer "In4.Cu")
	)
	(gr_arc
		(start 200.90638 -211.406994)
		(mid 201.41692 -210.896454)
		(end 200.90638 -210.385914)
		(stroke
			(width 0.2)
			(type default)
		)
		(layer "In4.Cu")
	)
	(gr_line
		(start 200.90638 -210.385914)
		(end 200.093834 -210.385914)
		(stroke
			(width 0.2)
			(type default)
		)
		(layer "In4.Cu")
	)
	(gr_line
		(start 201.164444 -49.115472)
		(end 200.046844 -49.122076)
		(stroke
			(width 0.2)
			(type default)
		)
		(layer "In4.Cu")
	)
	(gr_arc
		(start 201.171302 -50.339752)
		(mid 201.780139 -49.724183)
		(end 201.164444 -49.115472)
		(stroke
			(width 0.2)
			(type default)
		)
		(layer "In4.Cu")
	)
	(gr_line
		(start 201.295 -44.958)
		(end 228.3714 -44.958)
		(stroke
			(width 0.381)
			(type default)
		)
		(layer "In4.Cu")
	)
	(gr_line
		(start 201.69378 -222.805244)
		(end 202.506326 -222.805244)
		(stroke
			(width 0.2)
			(type default)
		)
		(layer "In4.Cu")
	)
	(gr_arc
		(start 201.69378 -221.784164)
		(mid 201.18324 -222.294704)
		(end 201.69378 -222.805244)
		(stroke
			(width 0.2)
			(type default)
		)
		(layer "In4.Cu")
	)
	(gr_line
		(start 201.97318 -45.832522)
		(end 201.97318 -44.714922)
		(stroke
			(width 0.2)
			(type default)
		)
		(layer "In4.Cu")
	)
	(gr_arc
		(start 201.97318 -44.714922)
		(mid 201.36104 -44.102782)
		(end 200.7489 -44.714922)
		(stroke
			(width 0.2)
			(type default)
		)
		(layer "In4.Cu")
	)
	(gr_arc
		(start 202.506326 -222.805244)
		(mid 203.01712 -222.294831)
		(end 202.50658 -221.784164)
		(stroke
			(width 0.2)
			(type default)
		)
		(layer "In4.Cu")
	)
	(gr_line
		(start 202.50658 -221.784164)
		(end 201.69378 -221.784164)
		(stroke
			(width 0.2)
			(type default)
		)
		(layer "In4.Cu")
	)
	(gr_line
		(start 202.946 -50.29454)
		(end 203.7588 -50.29454)
		(stroke
			(width 0.2)
			(type default)
		)
		(layer "In4.Cu")
	)
	(gr_arc
		(start 202.946254 -49.27346)
		(mid 202.43546 -49.783873)
		(end 202.946 -50.29454)
		(stroke
			(width 0.2)
			(type default)
		)
		(layer "In4.Cu")
	)
	(gr_line
		(start 203.293726 -211.406994)
		(end 204.106526 -211.406994)
		(stroke
			(width 0.2)
			(type default)
		)
		(layer "In4.Cu")
	)
	(gr_arc
		(start 203.29398 -210.385914)
		(mid 202.783186 -210.896327)
		(end 203.293726 -211.406994)
		(stroke
			(width 0.2)
			(type default)
		)
		(layer "In4.Cu")
	)
	(gr_arc
		(start 203.7588 -50.29454)
		(mid 204.26934 -49.784)
		(end 203.7588 -49.27346)
		(stroke
			(width 0.2)
			(type default)
		)
		(layer "In4.Cu")
	)
	(gr_line
		(start 203.7588 -49.27346)
		(end 202.946254 -49.27346)
		(stroke
			(width 0.2)
			(type default)
		)
		(layer "In4.Cu")
	)
	(gr_arc
		(start 204.106526 -211.406994)
		(mid 204.617066 -210.896454)
		(end 204.106526 -210.385914)
		(stroke
			(width 0.2)
			(type default)
		)
		(layer "In4.Cu")
	)
	(gr_line
		(start 204.106526 -210.385914)
		(end 203.29398 -210.385914)
		(stroke
			(width 0.2)
			(type default)
		)
		(layer "In4.Cu")
	)
	(gr_line
		(start 204.893672 -222.805244)
		(end 205.706218 -222.805244)
		(stroke
			(width 0.2)
			(type default)
		)
		(layer "In4.Cu")
	)
	(gr_arc
		(start 204.893672 -221.784164)
		(mid 204.383132 -222.294704)
		(end 204.893672 -222.805244)
		(stroke
			(width 0.2)
			(type default)
		)
		(layer "In4.Cu")
	)
	(gr_arc
		(start 205.706218 -222.805244)
		(mid 206.217012 -222.294831)
		(end 205.706472 -221.784164)
		(stroke
			(width 0.2)
			(type default)
		)
		(layer "In4.Cu")
	)
	(gr_line
		(start 205.706472 -221.784164)
		(end 204.893672 -221.784164)
		(stroke
			(width 0.2)
			(type default)
		)
		(layer "In4.Cu")
	)
	(gr_line
		(start 206.493618 -211.406994)
		(end 207.306418 -211.406994)
		(stroke
			(width 0.2)
			(type default)
		)
		(layer "In4.Cu")
	)
	(gr_arc
		(start 206.493872 -210.385914)
		(mid 205.983078 -210.896327)
		(end 206.493618 -211.406994)
		(stroke
			(width 0.2)
			(type default)
		)
		(layer "In4.Cu")
	)
	(gr_arc
		(start 207.306418 -211.406994)
		(mid 207.816958 -210.896454)
		(end 207.306418 -210.385914)
		(stroke
			(width 0.2)
			(type default)
		)
		(layer "In4.Cu")
	)
	(gr_line
		(start 207.306418 -210.385914)
		(end 206.493872 -210.385914)
		(stroke
			(width 0.2)
			(type default)
		)
		(layer "In4.Cu")
	)
	(gr_line
		(start 211.29371 -222.805244)
		(end 212.106256 -222.805244)
		(stroke
			(width 0.2)
			(type default)
		)
		(layer "In4.Cu")
	)
	(gr_arc
		(start 211.29371 -221.784164)
		(mid 210.78317 -222.294704)
		(end 211.29371 -222.805244)
		(stroke
			(width 0.2)
			(type default)
		)
		(layer "In4.Cu")
	)
	(gr_arc
		(start 212.106256 -222.805244)
		(mid 212.61705 -222.294831)
		(end 212.10651 -221.784164)
		(stroke
			(width 0.2)
			(type default)
		)
		(layer "In4.Cu")
	)
	(gr_line
		(start 212.10651 -221.784164)
		(end 211.29371 -221.784164)
		(stroke
			(width 0.2)
			(type default)
		)
		(layer "In4.Cu")
	)
	(gr_line
		(start 212.893656 -211.406994)
		(end 213.706456 -211.406994)
		(stroke
			(width 0.2)
			(type default)
		)
		(layer "In4.Cu")
	)
	(gr_arc
		(start 212.89391 -210.385914)
		(mid 212.383116 -210.896327)
		(end 212.893656 -211.406994)
		(stroke
			(width 0.2)
			(type default)
		)
		(layer "In4.Cu")
	)
	(gr_arc
		(start 213.706456 -211.406994)
		(mid 214.216996 -210.896454)
		(end 213.706456 -210.385914)
		(stroke
			(width 0.2)
			(type default)
		)
		(layer "In4.Cu")
	)
	(gr_line
		(start 213.706456 -210.385914)
		(end 212.89391 -210.385914)
		(stroke
			(width 0.2)
			(type default)
		)
		(layer "In4.Cu")
	)
	(gr_line
		(start 214.493602 -222.805244)
		(end 215.306148 -222.805244)
		(stroke
			(width 0.2)
			(type default)
		)
		(layer "In4.Cu")
	)
	(gr_arc
		(start 214.493602 -221.784164)
		(mid 213.983062 -222.294704)
		(end 214.493602 -222.805244)
		(stroke
			(width 0.2)
			(type default)
		)
		(layer "In4.Cu")
	)
	(gr_line
		(start 214.5284 -20.3454)
		(end 214.5284 -14.732)
		(stroke
			(width 0.381)
			(type default)
		)
		(layer "In4.Cu")
	)
	(gr_line
		(start 214.5284 -14.732)
		(end 217.7542 -11.5062)
		(stroke
			(width 0.381)
			(type default)
		)
		(layer "In4.Cu")
	)
	(gr_line
		(start 214.9856 -20.8026)
		(end 214.5284 -20.3454)
		(stroke
			(width 0.381)
			(type default)
		)
		(layer "In4.Cu")
	)
	(gr_arc
		(start 215.306148 -222.805244)
		(mid 215.816942 -222.294831)
		(end 215.306402 -221.784164)
		(stroke
			(width 0.2)
			(type default)
		)
		(layer "In4.Cu")
	)
	(gr_line
		(start 215.306402 -221.784164)
		(end 214.493602 -221.784164)
		(stroke
			(width 0.2)
			(type default)
		)
		(layer "In4.Cu")
	)
	(gr_line
		(start 216.093548 -211.406994)
		(end 216.906348 -211.406994)
		(stroke
			(width 0.2)
			(type default)
		)
		(layer "In4.Cu")
	)
	(gr_arc
		(start 216.093802 -210.385914)
		(mid 215.583008 -210.896327)
		(end 216.093548 -211.406994)
		(stroke
			(width 0.2)
			(type default)
		)
		(layer "In4.Cu")
	)
	(gr_arc
		(start 216.906348 -211.406994)
		(mid 217.416888 -210.896454)
		(end 216.906348 -210.385914)
		(stroke
			(width 0.2)
			(type default)
		)
		(layer "In4.Cu")
	)
	(gr_line
		(start 216.906348 -210.385914)
		(end 216.093802 -210.385914)
		(stroke
			(width 0.2)
			(type default)
		)
		(layer "In4.Cu")
	)
	(gr_line
		(start 217.7542 -11.5062)
		(end 218.7194 -11.5062)
		(stroke
			(width 0.381)
			(type default)
		)
		(layer "In4.Cu")
	)
	(gr_line
		(start 217.805 -39.878)
		(end 196.215 -39.878)
		(stroke
			(width 0.381)
			(type default)
		)
		(layer "In4.Cu")
	)
	(gr_line
		(start 218.499944 -228.000052)
		(end 182.500016 -228.000052)
		(stroke
			(width 5.08)
			(type default)
		)
		(layer "In4.Cu")
	)
	(gr_line
		(start 218.499944 -222.400114)
		(end 218.499944 -228.000052)
		(stroke
			(width 1.524)
			(type default)
		)
		(layer "In4.Cu")
	)
	(gr_line
		(start 218.7194 -11.5062)
		(end 221.8182 -8.4074)
		(stroke
			(width 0.381)
			(type default)
		)
		(layer "In4.Cu")
	)
	(gr_arc
		(start 219.00007 -221.899988)
		(mid 218.646428 -222.046472)
		(end 218.499944 -222.400114)
		(stroke
			(width 1.524)
			(type default)
		)
		(layer "In4.Cu")
	)
	(gr_line
		(start 219.799916 -221.899988)
		(end 219.00007 -221.899988)
		(stroke
			(width 1.524)
			(type default)
		)
		(layer "In4.Cu")
	)
	(gr_arc
		(start 219.799916 -221.899988)
		(mid 220.153445 -221.753586)
		(end 220.300042 -221.400116)
		(stroke
			(width 1.524)
			(type default)
		)
		(layer "In4.Cu")
	)
	(gr_line
		(start 220.300042 -214.799926)
		(end 220.300042 -221.400116)
		(stroke
			(width 1.524)
			(type default)
		)
		(layer "In4.Cu")
	)
	(gr_arc
		(start 221.600014 -213.499954)
		(mid 220.680795 -213.880707)
		(end 220.300042 -214.799926)
		(stroke
			(width 1.524)
			(type default)
		)
		(layer "In4.Cu")
	)
	(gr_line
		(start 221.8182 -8.4074)
		(end 234.6198 -8.4074)
		(stroke
			(width 0.381)
			(type default)
		)
		(layer "In4.Cu")
	)
	(gr_line
		(start 225.298 -76.454)
		(end 194.945 -76.454)
		(stroke
			(width 0.381)
			(type default)
		)
		(layer "In4.Cu")
	)
	(gr_line
		(start 226.343972 -39.802308)
		(end 226.586796 -39.559484)
		(stroke
			(width 0.381)
			(type default)
		)
		(layer "In4.Cu")
	)
	(gr_line
		(start 226.586796 -39.640256)
		(end 226.766628 -39.820088)
		(stroke
			(width 0.381)
			(type default)
		)
		(layer "In4.Cu")
	)
	(gr_line
		(start 226.586796 -39.559484)
		(end 226.586796 -39.640256)
		(stroke
			(width 0.381)
			(type default)
		)
		(layer "In4.Cu")
	)
	(gr_line
		(start 226.586796 -39.559484)
		(end 226.586796 -33.275524)
		(stroke
			(width 0.381)
			(type default)
		)
		(layer "In4.Cu")
	)
	(gr_line
		(start 226.586796 -33.275524)
		(end 226.81946 -33.04286)
		(stroke
			(width 0.381)
			(type default)
		)
		(layer "In4.Cu")
	)
	(gr_line
		(start 226.81946 -33.04286)
		(end 229.173532 -33.04286)
		(stroke
			(width 0.381)
			(type default)
		)
		(layer "In4.Cu")
	)
	(gr_line
		(start 228.3714 -44.958)
		(end 228.727 -45.3136)
		(stroke
			(width 0.381)
			(type default)
		)
		(layer "In4.Cu")
	)
	(gr_line
		(start 228.698806 -20.796758)
		(end 214.9856 -20.8026)
		(stroke
			(width 0.381)
			(type default)
		)
		(layer "In4.Cu")
	)
	(gr_line
		(start 228.727 -54.61)
		(end 229.108 -54.991)
		(stroke
			(width 0.381)
			(type default)
		)
		(layer "In4.Cu")
	)
	(gr_line
		(start 228.727 -45.3136)
		(end 228.727 -54.61)
		(stroke
			(width 0.381)
			(type default)
		)
		(layer "In4.Cu")
	)
	(gr_line
		(start 229.108 -54.991)
		(end 229.87 -54.991)
		(stroke
			(width 0.381)
			(type default)
		)
		(layer "In4.Cu")
	)
	(gr_line
		(start 229.142036 -213.499954)
		(end 221.600014 -213.499954)
		(stroke
			(width 1.524)
			(type default)
		)
		(layer "In4.Cu")
	)
	(gr_arc
		(start 229.142036 -213.499954)
		(mid 232.677527 -212.035476)
		(end 234.142026 -208.499964)
		(stroke
			(width 1.524)
			(type default)
		)
		(layer "In4.Cu")
	)
	(gr_line
		(start 229.173532 -33.04286)
		(end 229.570788 -32.645604)
		(stroke
			(width 0.381)
			(type default)
		)
		(layer "In4.Cu")
	)
	(gr_line
		(start 229.570788 -32.645604)
		(end 229.570788 -21.66874)
		(stroke
			(width 0.381)
			(type default)
		)
		(layer "In4.Cu")
	)
	(gr_line
		(start 229.570788 -21.66874)
		(end 228.698806 -20.796758)
		(stroke
			(width 0.381)
			(type default)
		)
		(layer "In4.Cu")
	)
	(gr_circle
		(center 231.550464 -3.499612)
		(end 232.492804 -3.499612)
		(stroke
			(width 0.2)
			(type default)
		)
		(fill no)
		(layer "In4.Cu")
	)
	(gr_line
		(start 232.029 -39.878)
		(end 217.805 -39.878)
		(stroke
			(width 0.381)
			(type default)
		)
		(layer "In4.Cu")
	)
	(gr_line
		(start 232.029 -39.878)
		(end 232.4862 -39.878)
		(stroke
			(width 0.381)
			(type default)
		)
		(layer "In4.Cu")
	)
	(gr_line
		(start 232.537 -53.6194)
		(end 232.918 -54.0004)
		(stroke
			(width 0.381)
			(type default)
		)
		(layer "In4.Cu")
	)
	(gr_line
		(start 232.537 -40.513)
		(end 232.537 -53.6194)
		(stroke
			(width 0.381)
			(type default)
		)
		(layer "In4.Cu")
	)
	(gr_line
		(start 232.537 -40.513)
		(end 232.537 -40.386)
		(stroke
			(width 0.381)
			(type default)
		)
		(layer "In4.Cu")
	)
	(gr_line
		(start 232.537 -40.386)
		(end 232.029 -39.878)
		(stroke
			(width 0.381)
			(type default)
		)
		(layer "In4.Cu")
	)
	(gr_line
		(start 232.537 -39.878)
		(end 232.537 -40.386)
		(stroke
			(width 0.381)
			(type default)
		)
		(layer "In4.Cu")
	)
	(gr_line
		(start 232.918 -54.0004)
		(end 233.2736 -54.0004)
		(stroke
			(width 0.381)
			(type default)
		)
		(layer "In4.Cu")
	)
	(gr_line
		(start 233.172 -39.878)
		(end 232.537 -40.513)
		(stroke
			(width 0.381)
			(type default)
		)
		(layer "In4.Cu")
	)
	(gr_line
		(start 233.172 -39.878)
		(end 232.537 -39.878)
		(stroke
			(width 0.381)
			(type default)
		)
		(layer "In4.Cu")
	)
	(gr_line
		(start 233.2736 -54.9148)
		(end 233.5022 -54.6862)
		(stroke
			(width 0.381)
			(type default)
		)
		(layer "In4.Cu")
	)
	(gr_line
		(start 233.2736 -54.0004)
		(end 233.553 -54.2798)
		(stroke
			(width 0.381)
			(type default)
		)
		(layer "In4.Cu")
	)
	(gr_line
		(start 233.553 -54.2798)
		(end 233.553 -54.991)
		(stroke
			(width 0.381)
			(type default)
		)
		(layer "In4.Cu")
	)
	(gr_line
		(start 233.8832 -54.9148)
		(end 233.6546 -54.6862)
		(stroke
			(width 0.381)
			(type default)
		)
		(layer "In4.Cu")
	)
	(gr_line
		(start 234.142026 -165.269926)
		(end 234.142026 -208.499964)
		(stroke
			(width 1.524)
			(type default)
		)
		(layer "In4.Cu")
	)
	(gr_line
		(start 234.5436 -55.3212)
		(end 234.315 -55.0926)
		(stroke
			(width 0.381)
			(type default)
		)
		(layer "In4.Cu")
	)
	(gr_line
		(start 234.569 -67.183)
		(end 225.298 -76.454)
		(stroke
			(width 0.381)
			(type default)
		)
		(layer "In4.Cu")
	)
	(gr_line
		(start 234.569 -54.991)
		(end 229.87 -54.991)
		(stroke
			(width 0.381)
			(type default)
		)
		(layer "In4.Cu")
	)
	(gr_line
		(start 234.569 -54.991)
		(end 234.569 -67.183)
		(stroke
			(width 0.381)
			(type default)
		)
		(layer "In4.Cu")
	)
	(gr_line
		(start 234.6198 -8.4074)
		(end 235.331 -9.1186)
		(stroke
			(width 0.381)
			(type default)
		)
		(layer "In4.Cu")
	)
	(gr_line
		(start 234.6706 -55.3212)
		(end 234.8992 -55.0926)
		(stroke
			(width 0.381)
			(type default)
		)
		(layer "In4.Cu")
	)
	(gr_line
		(start 235.331 -9.1186)
		(end 250.7996 -9.1186)
		(stroke
			(width 0.381)
			(type default)
		)
		(layer "In4.Cu")
	)
	(gr_arc
		(start 235.412026 -163.999926)
		(mid 234.514 -164.3719)
		(end 234.142026 -165.269926)
		(stroke
			(width 1.524)
			(type default)
		)
		(layer "In4.Cu")
	)
	(gr_line
		(start 236.474 -86.36)
		(end 178.816 -86.36)
		(stroke
			(width 0.381)
			(type default)
		)
		(layer "In4.Cu")
	)
	(gr_line
		(start 239.2426 -39.878)
		(end 233.172 -39.878)
		(stroke
			(width 0.381)
			(type default)
		)
		(layer "In4.Cu")
	)
	(gr_line
		(start 239.522 -39.5986)
		(end 239.2426 -39.878)
		(stroke
			(width 0.381)
			(type default)
		)
		(layer "In4.Cu")
	)
	(gr_line
		(start 239.522 -27.305)
		(end 239.522 -39.5986)
		(stroke
			(width 0.381)
			(type default)
		)
		(layer "In4.Cu")
	)
	(gr_line
		(start 240.665 -26.162)
		(end 285.496 -26.162)
		(stroke
			(width 0.381)
			(type default)
		)
		(layer "In4.Cu")
	)
	(gr_line
		(start 245.491 -54.991)
		(end 234.569 -54.991)
		(stroke
			(width 0.381)
			(type default)
		)
		(layer "In4.Cu")
	)
	(gr_line
		(start 245.491 -54.991)
		(end 246.3038 -54.991)
		(stroke
			(width 0.381)
			(type default)
		)
		(layer "In4.Cu")
	)
	(gr_line
		(start 246.3038 -54.991)
		(end 246.761 -55.4482)
		(stroke
			(width 0.381)
			(type default)
		)
		(layer "In4.Cu")
	)
	(gr_line
		(start 246.761 -76.073)
		(end 236.474 -86.36)
		(stroke
			(width 0.381)
			(type default)
		)
		(layer "In4.Cu")
	)
	(gr_line
		(start 246.761 -73.66)
		(end 309.245 -73.66)
		(stroke
			(width 0.381)
			(type default)
		)
		(layer "In4.Cu")
	)
	(gr_line
		(start 246.761 -55.4482)
		(end 246.761 -76.073)
		(stroke
			(width 0.381)
			(type default)
		)
		(layer "In4.Cu")
	)
	(gr_line
		(start 246.796306 -73.063608)
		(end 247.392698 -73.66)
		(stroke
			(width 0.381)
			(type default)
		)
		(layer "In4.Cu")
	)
	(gr_line
		(start 247.392698 -73.663556)
		(end 246.769382 -74.286872)
		(stroke
			(width 0.381)
			(type default)
		)
		(layer "In4.Cu")
	)
	(gr_line
		(start 247.392698 -73.66)
		(end 247.392698 -73.663556)
		(stroke
			(width 0.381)
			(type default)
		)
		(layer "In4.Cu")
	)
	(gr_line
		(start 249.871992 -163.999926)
		(end 235.412026 -163.999926)
		(stroke
			(width 1.524)
			(type default)
		)
		(layer "In4.Cu")
	)
	(gr_line
		(start 250.7996 -9.1186)
		(end 251.6124 -9.9314)
		(stroke
			(width 0.381)
			(type default)
		)
		(layer "In4.Cu")
	)
	(gr_line
		(start 251.141992 -208.499964)
		(end 251.141992 -165.269926)
		(stroke
			(width 1.524)
			(type default)
		)
		(layer "In4.Cu")
	)
	(gr_arc
		(start 251.141992 -208.499964)
		(mid 252.606441 -212.03552)
		(end 256.141982 -213.499954)
		(stroke
			(width 1.524)
			(type default)
		)
		(layer "In4.Cu")
	)
	(gr_arc
		(start 251.141992 -165.269926)
		(mid 250.770018 -164.3719)
		(end 249.871992 -163.999926)
		(stroke
			(width 1.524)
			(type default)
		)
		(layer "In4.Cu")
	)
	(gr_line
		(start 251.6124 -15.2146)
		(end 239.522 -27.305)
		(stroke
			(width 0.381)
			(type default)
		)
		(layer "In4.Cu")
	)
	(gr_line
		(start 251.6124 -9.9314)
		(end 251.6124 -15.2146)
		(stroke
			(width 0.381)
			(type default)
		)
		(layer "In4.Cu")
	)
	(gr_line
		(start 257.400044 -213.499954)
		(end 256.141982 -213.499954)
		(stroke
			(width 1.524)
			(type default)
		)
		(layer "In4.Cu")
	)
	(gr_line
		(start 258.700016 -221.400116)
		(end 258.700016 -214.799926)
		(stroke
			(width 1.524)
			(type default)
		)
		(layer "In4.Cu")
	)
	(gr_arc
		(start 258.700016 -221.400116)
		(mid 258.84643 -221.753573)
		(end 259.199888 -221.899988)
		(stroke
			(width 1.524)
			(type default)
		)
		(layer "In4.Cu")
	)
	(gr_arc
		(start 258.700016 -214.799926)
		(mid 258.319263 -213.880707)
		(end 257.400044 -213.499954)
		(stroke
			(width 1.524)
			(type default)
		)
		(layer "In4.Cu")
	)
	(gr_line
		(start 259.999988 -221.899988)
		(end 259.199888 -221.899988)
		(stroke
			(width 1.524)
			(type default)
		)
		(layer "In4.Cu")
	)
	(gr_line
		(start 260.500114 -228.000052)
		(end 260.500114 -222.400114)
		(stroke
			(width 1.524)
			(type default)
		)
		(layer "In4.Cu")
	)
	(gr_arc
		(start 260.500114 -222.400114)
		(mid 260.35363 -222.046472)
		(end 259.999988 -221.899988)
		(stroke
			(width 1.524)
			(type default)
		)
		(layer "In4.Cu")
	)
	(gr_line
		(start 262.893556 -222.805244)
		(end 263.706102 -222.805244)
		(stroke
			(width 0.2)
			(type default)
		)
		(layer "In4.Cu")
	)
	(gr_arc
		(start 262.893556 -221.784164)
		(mid 262.383016 -222.294704)
		(end 262.893556 -222.805244)
		(stroke
			(width 0.2)
			(type default)
		)
		(layer "In4.Cu")
	)
	(gr_arc
		(start 263.706102 -222.805244)
		(mid 264.216896 -222.294831)
		(end 263.706356 -221.784164)
		(stroke
			(width 0.2)
			(type default)
		)
		(layer "In4.Cu")
	)
	(gr_line
		(start 263.706356 -221.784164)
		(end 262.893556 -221.784164)
		(stroke
			(width 0.2)
			(type default)
		)
		(layer "In4.Cu")
	)
	(gr_line
		(start 264.493756 -211.406994)
		(end 265.306556 -211.406994)
		(stroke
			(width 0.2)
			(type default)
		)
		(layer "In4.Cu")
	)
	(gr_arc
		(start 264.49401 -210.385914)
		(mid 263.983216 -210.896327)
		(end 264.493756 -211.406994)
		(stroke
			(width 0.2)
			(type default)
		)
		(layer "In4.Cu")
	)
	(gr_arc
		(start 265.306556 -211.406994)
		(mid 265.817096 -210.896454)
		(end 265.306556 -210.385914)
		(stroke
			(width 0.2)
			(type default)
		)
		(layer "In4.Cu")
	)
	(gr_line
		(start 265.306556 -210.385914)
		(end 264.49401 -210.385914)
		(stroke
			(width 0.2)
			(type default)
		)
		(layer "In4.Cu")
	)
	(gr_line
		(start 266.093702 -222.805244)
		(end 266.906248 -222.805244)
		(stroke
			(width 0.2)
			(type default)
		)
		(layer "In4.Cu")
	)
	(gr_arc
		(start 266.093702 -221.784164)
		(mid 265.583162 -222.294704)
		(end 266.093702 -222.805244)
		(stroke
			(width 0.2)
			(type default)
		)
		(layer "In4.Cu")
	)
	(gr_arc
		(start 266.906248 -222.805244)
		(mid 267.417042 -222.294831)
		(end 266.906502 -221.784164)
		(stroke
			(width 0.2)
			(type default)
		)
		(layer "In4.Cu")
	)
	(gr_line
		(start 266.906502 -221.784164)
		(end 266.093702 -221.784164)
		(stroke
			(width 0.2)
			(type default)
		)
		(layer "In4.Cu")
	)
	(gr_line
		(start 267.693648 -211.406994)
		(end 268.506448 -211.406994)
		(stroke
			(width 0.2)
			(type default)
		)
		(layer "In4.Cu")
	)
	(gr_arc
		(start 267.693902 -210.385914)
		(mid 267.183108 -210.896327)
		(end 267.693648 -211.406994)
		(stroke
			(width 0.2)
			(type default)
		)
		(layer "In4.Cu")
	)
	(gr_arc
		(start 267.96746 -14.6558)
		(mid 268.478 -15.16634)
		(end 268.98854 -14.6558)
		(stroke
			(width 0.2)
			(type default)
		)
		(layer "In4.Cu")
	)
	(gr_line
		(start 267.96746 -13.843)
		(end 267.96746 -14.6558)
		(stroke
			(width 0.2)
			(type default)
		)
		(layer "In4.Cu")
	)
	(gr_arc
		(start 268.506448 -211.406994)
		(mid 269.016988 -210.896454)
		(end 268.506448 -210.385914)
		(stroke
			(width 0.2)
			(type default)
		)
		(layer "In4.Cu")
	)
	(gr_line
		(start 268.506448 -210.385914)
		(end 267.693902 -210.385914)
		(stroke
			(width 0.2)
			(type default)
		)
		(layer "In4.Cu")
	)
	(gr_line
		(start 268.98854 -14.6558)
		(end 268.98854 -13.843254)
		(stroke
			(width 0.2)
			(type default)
		)
		(layer "In4.Cu")
	)
	(gr_arc
		(start 268.98854 -13.843254)
		(mid 268.478127 -13.33246)
		(end 267.96746 -13.843)
		(stroke
			(width 0.2)
			(type default)
		)
		(layer "In4.Cu")
	)
	(gr_arc
		(start 269.03426 -6.118352)
		(mid 269.5448 -6.628892)
		(end 270.05534 -6.118352)
		(stroke
			(width 0.2)
			(type default)
		)
		(layer "In4.Cu")
	)
	(gr_line
		(start 269.03426 -5.305552)
		(end 269.03426 -6.118352)
		(stroke
			(width 0.2)
			(type default)
		)
		(layer "In4.Cu")
	)
	(gr_line
		(start 270.05534 -6.118352)
		(end 270.05534 -5.305806)
		(stroke
			(width 0.2)
			(type default)
		)
		(layer "In4.Cu")
	)
	(gr_arc
		(start 270.05534 -5.305806)
		(mid 269.544927 -4.795012)
		(end 269.03426 -5.305552)
		(stroke
			(width 0.2)
			(type default)
		)
		(layer "In4.Cu")
	)
	(gr_arc
		(start 270.17726 -9.166352)
		(mid 270.6878 -9.676892)
		(end 271.19834 -9.166352)
		(stroke
			(width 0.2)
			(type default)
		)
		(layer "In4.Cu")
	)
	(gr_line
		(start 270.17726 -8.353552)
		(end 270.17726 -9.166352)
		(stroke
			(width 0.2)
			(type default)
		)
		(layer "In4.Cu")
	)
	(gr_line
		(start 270.893794 -211.406994)
		(end 271.706594 -211.406994)
		(stroke
			(width 0.2)
			(type default)
		)
		(layer "In4.Cu")
	)
	(gr_arc
		(start 270.894048 -210.385914)
		(mid 270.383254 -210.896327)
		(end 270.893794 -211.406994)
		(stroke
			(width 0.2)
			(type default)
		)
		(layer "In4.Cu")
	)
	(gr_line
		(start 271.19834 -9.166352)
		(end 271.19834 -8.353806)
		(stroke
			(width 0.2)
			(type default)
		)
		(layer "In4.Cu")
	)
	(gr_arc
		(start 271.19834 -8.353806)
		(mid 270.687927 -7.843012)
		(end 270.17726 -8.353552)
		(stroke
			(width 0.2)
			(type default)
		)
		(layer "In4.Cu")
	)
	(gr_arc
		(start 271.55775 -15.334996)
		(mid 272.068163 -15.84579)
		(end 272.57883 -15.33525)
		(stroke
			(width 0.2)
			(type default)
		)
		(layer "In4.Cu")
	)
	(gr_line
		(start 271.55775 -14.52245)
		(end 271.55775 -15.334996)
		(stroke
			(width 0.2)
			(type default)
		)
		(layer "In4.Cu")
	)
	(gr_arc
		(start 271.706594 -211.406994)
		(mid 272.217134 -210.896454)
		(end 271.706594 -210.385914)
		(stroke
			(width 0.2)
			(type default)
		)
		(layer "In4.Cu")
	)
	(gr_line
		(start 271.706594 -210.385914)
		(end 270.894048 -210.385914)
		(stroke
			(width 0.2)
			(type default)
		)
		(layer "In4.Cu")
	)
	(gr_line
		(start 272.49374 -222.805244)
		(end 273.306286 -222.805244)
		(stroke
			(width 0.2)
			(type default)
		)
		(layer "In4.Cu")
	)
	(gr_arc
		(start 272.49374 -221.784164)
		(mid 271.9832 -222.294704)
		(end 272.49374 -222.805244)
		(stroke
			(width 0.2)
			(type default)
		)
		(layer "In4.Cu")
	)
	(gr_line
		(start 272.57883 -15.33525)
		(end 272.57883 -14.52245)
		(stroke
			(width 0.2)
			(type default)
		)
		(layer "In4.Cu")
	)
	(gr_arc
		(start 272.57883 -14.52245)
		(mid 272.06829 -14.01191)
		(end 271.55775 -14.52245)
		(stroke
			(width 0.2)
			(type default)
		)
		(layer "In4.Cu")
	)
	(gr_circle
		(center 273.100038 -23.400004)
		(end 274.118578 -23.400004)
		(stroke
			(width 0.2)
			(type default)
		)
		(fill no)
		(layer "In4.Cu")
	)
	(gr_arc
		(start 273.306286 -222.805244)
		(mid 273.81708 -222.294831)
		(end 273.30654 -221.784164)
		(stroke
			(width 0.2)
			(type default)
		)
		(layer "In4.Cu")
	)
	(gr_line
		(start 273.30654 -221.784164)
		(end 272.49374 -221.784164)
		(stroke
			(width 0.2)
			(type default)
		)
		(layer "In4.Cu")
	)
	(gr_line
		(start 274.093686 -211.406994)
		(end 274.906486 -211.406994)
		(stroke
			(width 0.2)
			(type default)
		)
		(layer "In4.Cu")
	)
	(gr_arc
		(start 274.09394 -210.385914)
		(mid 273.583146 -210.896327)
		(end 274.093686 -211.406994)
		(stroke
			(width 0.2)
			(type default)
		)
		(layer "In4.Cu")
	)
	(gr_arc
		(start 274.906486 -211.406994)
		(mid 275.417026 -210.896454)
		(end 274.906486 -210.385914)
		(stroke
			(width 0.2)
			(type default)
		)
		(layer "In4.Cu")
	)
	(gr_line
		(start 274.906486 -210.385914)
		(end 274.09394 -210.385914)
		(stroke
			(width 0.2)
			(type default)
		)
		(layer "In4.Cu")
	)
	(gr_line
		(start 275.693632 -222.805244)
		(end 276.506178 -222.805244)
		(stroke
			(width 0.2)
			(type default)
		)
		(layer "In4.Cu")
	)
	(gr_arc
		(start 275.693632 -221.784164)
		(mid 275.183092 -222.294704)
		(end 275.693632 -222.805244)
		(stroke
			(width 0.2)
			(type default)
		)
		(layer "In4.Cu")
	)
	(gr_arc
		(start 276.506178 -222.805244)
		(mid 277.016972 -222.294831)
		(end 276.506432 -221.784164)
		(stroke
			(width 0.2)
			(type default)
		)
		(layer "In4.Cu")
	)
	(gr_line
		(start 276.506432 -221.784164)
		(end 275.693632 -221.784164)
		(stroke
			(width 0.2)
			(type default)
		)
		(layer "In4.Cu")
	)
	(gr_line
		(start 277.293578 -211.406994)
		(end 278.106378 -211.406994)
		(stroke
			(width 0.2)
			(type default)
		)
		(layer "In4.Cu")
	)
	(gr_arc
		(start 277.293832 -210.385914)
		(mid 276.783038 -210.896327)
		(end 277.293578 -211.406994)
		(stroke
			(width 0.2)
			(type default)
		)
		(layer "In4.Cu")
	)
	(gr_arc
		(start 278.106378 -211.406994)
		(mid 278.616918 -210.896454)
		(end 278.106378 -210.385914)
		(stroke
			(width 0.2)
			(type default)
		)
		(layer "In4.Cu")
	)
	(gr_line
		(start 278.106378 -210.385914)
		(end 277.293832 -210.385914)
		(stroke
			(width 0.2)
			(type default)
		)
		(layer "In4.Cu")
	)
	(gr_line
		(start 278.893778 -222.805244)
		(end 279.706324 -222.805244)
		(stroke
			(width 0.2)
			(type default)
		)
		(layer "In4.Cu")
	)
	(gr_arc
		(start 278.893778 -221.784164)
		(mid 278.383238 -222.294704)
		(end 278.893778 -222.805244)
		(stroke
			(width 0.2)
			(type default)
		)
		(layer "In4.Cu")
	)
	(gr_arc
		(start 279.706324 -222.805244)
		(mid 280.217118 -222.294831)
		(end 279.706578 -221.784164)
		(stroke
			(width 0.2)
			(type default)
		)
		(layer "In4.Cu")
	)
	(gr_line
		(start 279.706578 -221.784164)
		(end 278.893778 -221.784164)
		(stroke
			(width 0.2)
			(type default)
		)
		(layer "In4.Cu")
	)
	(gr_arc
		(start 279.72766 -18.762726)
		(mid 280.230326 -19.28114)
		(end 280.74874 -18.778474)
		(stroke
			(width 0.2)
			(type default)
		)
		(layer "In4.Cu")
	)
	(gr_line
		(start 279.740106 -17.949926)
		(end 279.72766 -18.762726)
		(stroke
			(width 0.2)
			(type default)
		)
		(layer "In4.Cu")
	)
	(gr_line
		(start 280.493724 -211.406994)
		(end 281.306524 -211.406994)
		(stroke
			(width 0.2)
			(type default)
		)
		(layer "In4.Cu")
	)
	(gr_arc
		(start 280.493978 -210.385914)
		(mid 279.983184 -210.896327)
		(end 280.493724 -211.406994)
		(stroke
			(width 0.2)
			(type default)
		)
		(layer "In4.Cu")
	)
	(gr_line
		(start 280.74874 -18.778474)
		(end 280.761186 -17.965928)
		(stroke
			(width 0.2)
			(type default)
		)
		(layer "In4.Cu")
	)
	(gr_arc
		(start 280.761186 -17.965928)
		(mid 280.258647 -17.447516)
		(end 279.740106 -17.949926)
		(stroke
			(width 0.2)
			(type default)
		)
		(layer "In4.Cu")
	)
	(gr_arc
		(start 281.306524 -211.406994)
		(mid 281.817064 -210.896454)
		(end 281.306524 -210.385914)
		(stroke
			(width 0.2)
			(type default)
		)
		(layer "In4.Cu")
	)
	(gr_line
		(start 281.306524 -210.385914)
		(end 280.493978 -210.385914)
		(stroke
			(width 0.2)
			(type default)
		)
		(layer "In4.Cu")
	)
	(gr_line
		(start 282.09367 -222.805244)
		(end 282.906216 -222.805244)
		(stroke
			(width 0.2)
			(type default)
		)
		(layer "In4.Cu")
	)
	(gr_arc
		(start 282.09367 -221.784164)
		(mid 281.58313 -222.294704)
		(end 282.09367 -222.805244)
		(stroke
			(width 0.2)
			(type default)
		)
		(layer "In4.Cu")
	)
	(gr_line
		(start 282.244546 -20.841208)
		(end 282.788614 -21.44522)
		(stroke
			(width 0.2)
			(type default)
		)
		(layer "In4.Cu")
	)
	(gr_line
		(start 282.246578 -20.83943)
		(end 282.244546 -20.841208)
		(stroke
			(width 0.2)
			(type default)
		)
		(layer "In4.Cu")
	)
	(gr_line
		(start 282.788614 -21.44522)
		(end 282.790646 -21.443442)
		(stroke
			(width 0.2)
			(type default)
		)
		(layer "In4.Cu")
	)
	(gr_arc
		(start 282.790646 -21.443442)
		(mid 283.511498 -21.481034)
		(end 283.54909 -20.760182)
		(stroke
			(width 0.2)
			(type default)
		)
		(layer "In4.Cu")
	)
	(gr_arc
		(start 282.906216 -222.805244)
		(mid 283.41701 -222.294831)
		(end 282.90647 -221.784164)
		(stroke
			(width 0.2)
			(type default)
		)
		(layer "In4.Cu")
	)
	(gr_line
		(start 282.90647 -221.784164)
		(end 282.09367 -221.784164)
		(stroke
			(width 0.2)
			(type default)
		)
		(layer "In4.Cu")
	)
	(gr_arc
		(start 283.005276 -20.15617)
		(mid 282.284107 -20.118381)
		(end 282.246578 -20.83943)
		(stroke
			(width 0.2)
			(type default)
		)
		(layer "In4.Cu")
	)
	(gr_line
		(start 283.0068 -20.154646)
		(end 283.005276 -20.15617)
		(stroke
			(width 0.2)
			(type default)
		)
		(layer "In4.Cu")
	)
	(gr_line
		(start 283.007308 -20.154646)
		(end 283.0068 -20.154646)
		(stroke
			(width 0.2)
			(type default)
		)
		(layer "In4.Cu")
	)
	(gr_line
		(start 283.54909 -20.760182)
		(end 283.551122 -20.758404)
		(stroke
			(width 0.2)
			(type default)
		)
		(layer "In4.Cu")
	)
	(gr_line
		(start 283.551122 -20.758404)
		(end 283.007308 -20.154646)
		(stroke
			(width 0.2)
			(type default)
		)
		(layer "In4.Cu")
	)
	(gr_line
		(start 283.693616 -211.406994)
		(end 284.506416 -211.406994)
		(stroke
			(width 0.2)
			(type default)
		)
		(layer "In4.Cu")
	)
	(gr_arc
		(start 283.69387 -210.385914)
		(mid 283.183076 -210.896327)
		(end 283.693616 -211.406994)
		(stroke
			(width 0.2)
			(type default)
		)
		(layer "In4.Cu")
	)
	(gr_arc
		(start 284.477714 -33.864042)
		(mid 284.988127 -34.374836)
		(end 285.498794 -33.864296)
		(stroke
			(width 0.2)
			(type default)
		)
		(layer "In4.Cu")
	)
	(gr_line
		(start 284.477714 -33.051496)
		(end 284.477714 -33.864042)
		(stroke
			(width 0.2)
			(type default)
		)
		(layer "In4.Cu")
	)
	(gr_arc
		(start 284.506416 -211.406994)
		(mid 285.016956 -210.896454)
		(end 284.506416 -210.385914)
		(stroke
			(width 0.2)
			(type default)
		)
		(layer "In4.Cu")
	)
	(gr_line
		(start 284.506416 -210.385914)
		(end 283.69387 -210.385914)
		(stroke
			(width 0.2)
			(type default)
		)
		(layer "In4.Cu")
	)
	(gr_line
		(start 285.293562 -222.805244)
		(end 286.106108 -222.805244)
		(stroke
			(width 0.2)
			(type default)
		)
		(layer "In4.Cu")
	)
	(gr_arc
		(start 285.293562 -221.784164)
		(mid 284.783022 -222.294704)
		(end 285.293562 -222.805244)
		(stroke
			(width 0.2)
			(type default)
		)
		(layer "In4.Cu")
	)
	(gr_line
		(start 285.496 -26.162)
		(end 310.134 -50.8)
		(stroke
			(width 0.381)
			(type default)
		)
		(layer "In4.Cu")
	)
	(gr_line
		(start 285.498794 -33.864296)
		(end 285.498794 -33.051496)
		(stroke
			(width 0.2)
			(type default)
		)
		(layer "In4.Cu")
	)
	(gr_arc
		(start 285.498794 -33.051496)
		(mid 284.988254 -32.540956)
		(end 284.477714 -33.051496)
		(stroke
			(width 0.2)
			(type default)
		)
		(layer "In4.Cu")
	)
	(gr_line
		(start 285.581344 -25.033732)
		(end 285.581598 -25.033986)
		(stroke
			(width 0.2)
			(type default)
		)
		(layer "In4.Cu")
	)
	(gr_line
		(start 285.581344 -13.633958)
		(end 285.583376 -13.635228)
		(stroke
			(width 0.2)
			(type default)
		)
		(layer "In4.Cu")
	)
	(gr_line
		(start 285.581598 -25.033986)
		(end 285.58363 -25.035002)
		(stroke
			(width 0.2)
			(type default)
		)
		(layer "In4.Cu")
	)
	(gr_arc
		(start 285.583376 -13.635228)
		(mid 285.839408 -14.481048)
		(end 286.685228 -14.225016)
		(stroke
			(width 0.2)
			(type default)
		)
		(layer "In4.Cu")
	)
	(gr_arc
		(start 285.58363 -25.035002)
		(mid 285.839306 -25.880903)
		(end 286.685228 -25.625044)
		(stroke
			(width 0.2)
			(type default)
		)
		(layer "In4.Cu")
	)
	(gr_arc
		(start 286.106108 -222.805244)
		(mid 286.616902 -222.294831)
		(end 286.106362 -221.784164)
		(stroke
			(width 0.2)
			(type default)
		)
		(layer "In4.Cu")
	)
	(gr_line
		(start 286.106362 -221.784164)
		(end 285.293562 -221.784164)
		(stroke
			(width 0.2)
			(type default)
		)
		(layer "In4.Cu")
	)
	(gr_line
		(start 286.331406 -23.633938)
		(end 285.581344 -25.033732)
		(stroke
			(width 0.2)
			(type default)
		)
		(layer "In4.Cu")
	)
	(gr_line
		(start 286.331406 -12.23391)
		(end 285.581344 -13.633958)
		(stroke
			(width 0.2)
			(type default)
		)
		(layer "In4.Cu")
	)
	(gr_line
		(start 286.333438 -23.635208)
		(end 286.331406 -23.633938)
		(stroke
			(width 0.2)
			(type default)
		)
		(layer "In4.Cu")
	)
	(gr_line
		(start 286.333438 -12.23518)
		(end 286.331406 -12.23391)
		(stroke
			(width 0.2)
			(type default)
		)
		(layer "In4.Cu")
	)
	(gr_line
		(start 286.685228 -25.625044)
		(end 286.68726 -25.626314)
		(stroke
			(width 0.2)
			(type default)
		)
		(layer "In4.Cu")
	)
	(gr_line
		(start 286.685228 -14.225016)
		(end 286.68726 -14.226286)
		(stroke
			(width 0.2)
			(type default)
		)
		(layer "In4.Cu")
	)
	(gr_line
		(start 286.68726 -25.626314)
		(end 287.437322 -24.226266)
		(stroke
			(width 0.2)
			(type default)
		)
		(layer "In4.Cu")
	)
	(gr_line
		(start 286.68726 -14.226286)
		(end 287.437322 -12.826492)
		(stroke
			(width 0.2)
			(type default)
		)
		(layer "In4.Cu")
	)
	(gr_line
		(start 286.893762 -211.406994)
		(end 287.706308 -211.406994)
		(stroke
			(width 0.2)
			(type default)
		)
		(layer "In4.Cu")
	)
	(gr_arc
		(start 286.893762 -210.385914)
		(mid 286.383222 -210.896454)
		(end 286.893762 -211.406994)
		(stroke
			(width 0.2)
			(type default)
		)
		(layer "In4.Cu")
	)
	(gr_arc
		(start 287.435036 -12.825222)
		(mid 287.17936 -11.979321)
		(end 286.333438 -12.23518)
		(stroke
			(width 0.2)
			(type default)
		)
		(layer "In4.Cu")
	)
	(gr_arc
		(start 287.43529 -24.224996)
		(mid 287.179258 -23.379176)
		(end 286.333438 -23.635208)
		(stroke
			(width 0.2)
			(type default)
		)
		(layer "In4.Cu")
	)
	(gr_line
		(start 287.437068 -12.826238)
		(end 287.435036 -12.825222)
		(stroke
			(width 0.2)
			(type default)
		)
		(layer "In4.Cu")
	)
	(gr_line
		(start 287.437322 -24.226266)
		(end 287.43529 -24.224996)
		(stroke
			(width 0.2)
			(type default)
		)
		(layer "In4.Cu")
	)
	(gr_line
		(start 287.437322 -12.826492)
		(end 287.437068 -12.826238)
		(stroke
			(width 0.2)
			(type default)
		)
		(layer "In4.Cu")
	)
	(gr_arc
		(start 287.706308 -211.406994)
		(mid 288.217102 -210.896581)
		(end 287.706562 -210.385914)
		(stroke
			(width 0.2)
			(type default)
		)
		(layer "In4.Cu")
	)
	(gr_line
		(start 287.706562 -210.385914)
		(end 286.893762 -210.385914)
		(stroke
			(width 0.2)
			(type default)
		)
		(layer "In4.Cu")
	)
	(gr_line
		(start 287.83153 -17.433544)
		(end 287.831784 -17.433798)
		(stroke
			(width 0.2)
			(type default)
		)
		(layer "In4.Cu")
	)
	(gr_line
		(start 287.831784 -17.433798)
		(end 287.833816 -17.434814)
		(stroke
			(width 0.2)
			(type default)
		)
		(layer "In4.Cu")
	)
	(gr_arc
		(start 287.833562 -13.635228)
		(mid 288.089594 -14.481048)
		(end 288.935414 -14.225016)
		(stroke
			(width 0.2)
			(type default)
		)
		(layer "In4.Cu")
	)
	(gr_arc
		(start 287.833816 -17.434814)
		(mid 288.089492 -18.280715)
		(end 288.935414 -18.024856)
		(stroke
			(width 0.2)
			(type default)
		)
		(layer "In4.Cu")
	)
	(gr_arc
		(start 287.837626 -25.027636)
		(mid 288.08576 -25.879089)
		(end 288.935414 -25.625044)
		(stroke
			(width 0.2)
			(type default)
		)
		(layer "In4.Cu")
	)
	(gr_arc
		(start 287.837626 -21.227542)
		(mid 288.08576 -22.078995)
		(end 288.935414 -21.82495)
		(stroke
			(width 0.2)
			(type default)
		)
		(layer "In4.Cu")
	)
	(gr_line
		(start 288.493708 -222.805244)
		(end 289.306254 -222.805244)
		(stroke
			(width 0.2)
			(type default)
		)
		(layer "In4.Cu")
	)
	(gr_arc
		(start 288.493708 -221.784164)
		(mid 287.983168 -222.294704)
		(end 288.493708 -222.805244)
		(stroke
			(width 0.2)
			(type default)
		)
		(layer "In4.Cu")
	)
	(gr_line
		(start 288.581338 -16.034004)
		(end 287.83153 -17.433544)
		(stroke
			(width 0.2)
			(type default)
		)
		(layer "In4.Cu")
	)
	(gr_line
		(start 288.58337 -23.635208)
		(end 287.837626 -25.027636)
		(stroke
			(width 0.2)
			(type default)
		)
		(layer "In4.Cu")
	)
	(gr_line
		(start 288.58337 -19.835114)
		(end 287.837626 -21.227542)
		(stroke
			(width 0.2)
			(type default)
		)
		(layer "In4.Cu")
	)
	(gr_line
		(start 288.58337 -16.035274)
		(end 288.581338 -16.034004)
		(stroke
			(width 0.2)
			(type default)
		)
		(layer "In4.Cu")
	)
	(gr_line
		(start 288.58337 -12.23518)
		(end 287.833562 -13.635228)
		(stroke
			(width 0.2)
			(type default)
		)
		(layer "In4.Cu")
	)
	(gr_line
		(start 288.935414 -25.625044)
		(end 289.685222 -24.224996)
		(stroke
			(width 0.2)
			(type default)
		)
		(layer "In4.Cu")
	)
	(gr_line
		(start 288.935414 -21.82495)
		(end 289.685222 -20.424902)
		(stroke
			(width 0.2)
			(type default)
		)
		(layer "In4.Cu")
	)
	(gr_line
		(start 288.935414 -18.024856)
		(end 288.937446 -18.026126)
		(stroke
			(width 0.2)
			(type default)
		)
		(layer "In4.Cu")
	)
	(gr_line
		(start 288.935414 -14.225016)
		(end 289.681158 -12.832588)
		(stroke
			(width 0.2)
			(type default)
		)
		(layer "In4.Cu")
	)
	(gr_line
		(start 288.937446 -18.026126)
		(end 289.687254 -16.626332)
		(stroke
			(width 0.2)
			(type default)
		)
		(layer "In4.Cu")
	)
	(gr_line
		(start 289.2298 -35.524694)
		(end 290.042346 -35.524694)
		(stroke
			(width 0.2)
			(type default)
		)
		(layer "In4.Cu")
	)
	(gr_arc
		(start 289.2298 -34.503614)
		(mid 288.71926 -35.014154)
		(end 289.2298 -35.524694)
		(stroke
			(width 0.2)
			(type default)
		)
		(layer "In4.Cu")
	)
	(gr_arc
		(start 289.306254 -222.805244)
		(mid 289.817048 -222.294831)
		(end 289.306508 -221.784164)
		(stroke
			(width 0.2)
			(type default)
		)
		(layer "In4.Cu")
	)
	(gr_line
		(start 289.306508 -221.784164)
		(end 288.493708 -221.784164)
		(stroke
			(width 0.2)
			(type default)
		)
		(layer "In4.Cu")
	)
	(gr_arc
		(start 289.681158 -12.832588)
		(mid 289.433024 -11.981135)
		(end 288.58337 -12.23518)
		(stroke
			(width 0.2)
			(type default)
		)
		(layer "In4.Cu")
	)
	(gr_arc
		(start 289.685222 -24.224996)
		(mid 289.42919 -23.379176)
		(end 288.58337 -23.635208)
		(stroke
			(width 0.2)
			(type default)
		)
		(layer "In4.Cu")
	)
	(gr_arc
		(start 289.685222 -20.424902)
		(mid 289.42919 -19.579082)
		(end 288.58337 -19.835114)
		(stroke
			(width 0.2)
			(type default)
		)
		(layer "In4.Cu")
	)
	(gr_arc
		(start 289.685222 -16.625062)
		(mid 289.42919 -15.779242)
		(end 288.58337 -16.035274)
		(stroke
			(width 0.2)
			(type default)
		)
		(layer "In4.Cu")
	)
	(gr_line
		(start 289.687254 -16.626332)
		(end 289.685222 -16.625062)
		(stroke
			(width 0.2)
			(type default)
		)
		(layer "In4.Cu")
	)
	(gr_arc
		(start 290.042346 -35.524694)
		(mid 290.55314 -35.014281)
		(end 290.0426 -34.503614)
		(stroke
			(width 0.2)
			(type default)
		)
		(layer "In4.Cu")
	)
	(gr_line
		(start 290.0426 -34.503614)
		(end 289.2298 -34.503614)
		(stroke
			(width 0.2)
			(type default)
		)
		(layer "In4.Cu")
	)
	(gr_line
		(start 290.081462 -25.033732)
		(end 290.081716 -25.033986)
		(stroke
			(width 0.2)
			(type default)
		)
		(layer "In4.Cu")
	)
	(gr_line
		(start 290.081462 -21.233638)
		(end 290.081716 -21.233892)
		(stroke
			(width 0.2)
			(type default)
		)
		(layer "In4.Cu")
	)
	(gr_line
		(start 290.081462 -17.433544)
		(end 290.081716 -17.433798)
		(stroke
			(width 0.2)
			(type default)
		)
		(layer "In4.Cu")
	)
	(gr_line
		(start 290.081462 -13.633958)
		(end 290.083494 -13.635228)
		(stroke
			(width 0.2)
			(type default)
		)
		(layer "In4.Cu")
	)
	(gr_line
		(start 290.081716 -25.033986)
		(end 290.083748 -25.035002)
		(stroke
			(width 0.2)
			(type default)
		)
		(layer "In4.Cu")
	)
	(gr_line
		(start 290.081716 -21.233892)
		(end 290.083748 -21.234908)
		(stroke
			(width 0.2)
			(type default)
		)
		(layer "In4.Cu")
	)
	(gr_line
		(start 290.081716 -17.433798)
		(end 290.083748 -17.434814)
		(stroke
			(width 0.2)
			(type default)
		)
		(layer "In4.Cu")
	)
	(gr_arc
		(start 290.083494 -13.635228)
		(mid 290.339526 -14.481048)
		(end 291.185346 -14.225016)
		(stroke
			(width 0.2)
			(type default)
		)
		(layer "In4.Cu")
	)
	(gr_arc
		(start 290.083748 -25.035002)
		(mid 290.339424 -25.880903)
		(end 291.185346 -25.625044)
		(stroke
			(width 0.2)
			(type default)
		)
		(layer "In4.Cu")
	)
	(gr_arc
		(start 290.083748 -21.234908)
		(mid 290.339424 -22.080809)
		(end 291.185346 -21.82495)
		(stroke
			(width 0.2)
			(type default)
		)
		(layer "In4.Cu")
	)
	(gr_arc
		(start 290.083748 -17.434814)
		(mid 290.339272 -18.280634)
		(end 291.185092 -18.02511)
		(stroke
			(width 0.2)
			(type default)
		)
		(layer "In4.Cu")
	)
	(gr_line
		(start 290.093654 -211.406994)
		(end 290.906454 -211.406994)
		(stroke
			(width 0.2)
			(type default)
		)
		(layer "In4.Cu")
	)
	(gr_arc
		(start 290.093908 -210.385914)
		(mid 289.583114 -210.896327)
		(end 290.093654 -211.406994)
		(stroke
			(width 0.2)
			(type default)
		)
		(layer "In4.Cu")
	)
	(gr_line
		(start 290.831524 -23.633938)
		(end 290.081462 -25.033732)
		(stroke
			(width 0.2)
			(type default)
		)
		(layer "In4.Cu")
	)
	(gr_line
		(start 290.831524 -19.833844)
		(end 290.081462 -21.233638)
		(stroke
			(width 0.2)
			(type default)
		)
		(layer "In4.Cu")
	)
	(gr_line
		(start 290.831524 -16.03375)
		(end 290.081462 -17.433544)
		(stroke
			(width 0.2)
			(type default)
		)
		(layer "In4.Cu")
	)
	(gr_line
		(start 290.831524 -12.23391)
		(end 290.081462 -13.633958)
		(stroke
			(width 0.2)
			(type default)
		)
		(layer "In4.Cu")
	)
	(gr_line
		(start 290.833556 -23.635208)
		(end 290.831524 -23.633938)
		(stroke
			(width 0.2)
			(type default)
		)
		(layer "In4.Cu")
	)
	(gr_line
		(start 290.833556 -19.835114)
		(end 290.831524 -19.833844)
		(stroke
			(width 0.2)
			(type default)
		)
		(layer "In4.Cu")
	)
	(gr_line
		(start 290.833556 -12.23518)
		(end 290.831524 -12.23391)
		(stroke
			(width 0.2)
			(type default)
		)
		(layer "In4.Cu")
	)
	(gr_line
		(start 290.83381 -16.03502)
		(end 290.831524 -16.03375)
		(stroke
			(width 0.2)
			(type default)
		)
		(layer "In4.Cu")
	)
	(gr_arc
		(start 290.906454 -211.406994)
		(mid 291.416994 -210.896454)
		(end 290.906454 -210.385914)
		(stroke
			(width 0.2)
			(type default)
		)
		(layer "In4.Cu")
	)
	(gr_line
		(start 290.906454 -210.385914)
		(end 290.093908 -210.385914)
		(stroke
			(width 0.2)
			(type default)
		)
		(layer "In4.Cu")
	)
	(gr_line
		(start 291.185092 -18.02511)
		(end 291.187378 -18.02638)
		(stroke
			(width 0.2)
			(type default)
		)
		(layer "In4.Cu")
	)
	(gr_line
		(start 291.185346 -25.625044)
		(end 291.187378 -25.626314)
		(stroke
			(width 0.2)
			(type default)
		)
		(layer "In4.Cu")
	)
	(gr_line
		(start 291.185346 -21.82495)
		(end 291.187378 -21.82622)
		(stroke
			(width 0.2)
			(type default)
		)
		(layer "In4.Cu")
	)
	(gr_line
		(start 291.185346 -14.225016)
		(end 291.187378 -14.226286)
		(stroke
			(width 0.2)
			(type default)
		)
		(layer "In4.Cu")
	)
	(gr_line
		(start 291.187378 -25.626314)
		(end 291.93744 -24.226266)
		(stroke
			(width 0.2)
			(type default)
		)
		(layer "In4.Cu")
	)
	(gr_line
		(start 291.187378 -21.82622)
		(end 291.93744 -20.426172)
		(stroke
			(width 0.2)
			(type default)
		)
		(layer "In4.Cu")
	)
	(gr_line
		(start 291.187378 -18.02638)
		(end 291.93744 -16.626586)
		(stroke
			(width 0.2)
			(type default)
		)
		(layer "In4.Cu")
	)
	(gr_line
		(start 291.187378 -14.226286)
		(end 291.93744 -12.826492)
		(stroke
			(width 0.2)
			(type default)
		)
		(layer "In4.Cu")
	)
	(gr_line
		(start 291.6936 -222.805244)
		(end 292.506146 -222.805244)
		(stroke
			(width 0.2)
			(type default)
		)
		(layer "In4.Cu")
	)
	(gr_arc
		(start 291.6936 -221.784164)
		(mid 291.18306 -222.294704)
		(end 291.6936 -222.805244)
		(stroke
			(width 0.2)
			(type default)
		)
		(layer "In4.Cu")
	)
	(gr_arc
		(start 291.935154 -16.625316)
		(mid 291.67963 -15.779496)
		(end 290.83381 -16.03502)
		(stroke
			(width 0.2)
			(type default)
		)
		(layer "In4.Cu")
	)
	(gr_arc
		(start 291.935154 -12.825222)
		(mid 291.679478 -11.979321)
		(end 290.833556 -12.23518)
		(stroke
			(width 0.2)
			(type default)
		)
		(layer "In4.Cu")
	)
	(gr_arc
		(start 291.935408 -24.224996)
		(mid 291.679376 -23.379176)
		(end 290.833556 -23.635208)
		(stroke
			(width 0.2)
			(type default)
		)
		(layer "In4.Cu")
	)
	(gr_arc
		(start 291.935408 -20.424902)
		(mid 291.679376 -19.579082)
		(end 290.833556 -19.835114)
		(stroke
			(width 0.2)
			(type default)
		)
		(layer "In4.Cu")
	)
	(gr_line
		(start 291.937186 -12.826238)
		(end 291.935154 -12.825222)
		(stroke
			(width 0.2)
			(type default)
		)
		(layer "In4.Cu")
	)
	(gr_line
		(start 291.93744 -24.226266)
		(end 291.935408 -24.224996)
		(stroke
			(width 0.2)
			(type default)
		)
		(layer "In4.Cu")
	)
	(gr_line
		(start 291.93744 -20.426172)
		(end 291.935408 -20.424902)
		(stroke
			(width 0.2)
			(type default)
		)
		(layer "In4.Cu")
	)
	(gr_line
		(start 291.93744 -16.626586)
		(end 291.935154 -16.625316)
		(stroke
			(width 0.2)
			(type default)
		)
		(layer "In4.Cu")
	)
	(gr_line
		(start 291.93744 -12.826492)
		(end 291.937186 -12.826238)
		(stroke
			(width 0.2)
			(type default)
		)
		(layer "In4.Cu")
	)
	(gr_arc
		(start 292.506146 -222.805244)
		(mid 293.01694 -222.294831)
		(end 292.5064 -221.784164)
		(stroke
			(width 0.2)
			(type default)
		)
		(layer "In4.Cu")
	)
	(gr_line
		(start 292.5064 -221.784164)
		(end 291.6936 -221.784164)
		(stroke
			(width 0.2)
			(type default)
		)
		(layer "In4.Cu")
	)
	(gr_line
		(start 293.293546 -211.406994)
		(end 294.106346 -211.406994)
		(stroke
			(width 0.2)
			(type default)
		)
		(layer "In4.Cu")
	)
	(gr_arc
		(start 293.2938 -210.385914)
		(mid 292.783006 -210.896327)
		(end 293.293546 -211.406994)
		(stroke
			(width 0.2)
			(type default)
		)
		(layer "In4.Cu")
	)
	(gr_arc
		(start 294.106346 -211.406994)
		(mid 294.616886 -210.896454)
		(end 294.106346 -210.385914)
		(stroke
			(width 0.2)
			(type default)
		)
		(layer "In4.Cu")
	)
	(gr_line
		(start 294.106346 -210.385914)
		(end 293.2938 -210.385914)
		(stroke
			(width 0.2)
			(type default)
		)
		(layer "In4.Cu")
	)
	(gr_line
		(start 294.159178 -35.69081)
		(end 294.971978 -35.69081)
		(stroke
			(width 0.2)
			(type default)
		)
		(layer "In4.Cu")
	)
	(gr_arc
		(start 294.159432 -34.66973)
		(mid 293.648638 -35.180143)
		(end 294.159178 -35.69081)
		(stroke
			(width 0.2)
			(type default)
		)
		(layer "In4.Cu")
	)
	(gr_line
		(start 294.893746 -222.805244)
		(end 295.706292 -222.805244)
		(stroke
			(width 0.2)
			(type default)
		)
		(layer "In4.Cu")
	)
	(gr_arc
		(start 294.893746 -221.784164)
		(mid 294.383206 -222.294704)
		(end 294.893746 -222.805244)
		(stroke
			(width 0.2)
			(type default)
		)
		(layer "In4.Cu")
	)
	(gr_arc
		(start 294.971978 -35.69081)
		(mid 295.482518 -35.18027)
		(end 294.971978 -34.66973)
		(stroke
			(width 0.2)
			(type default)
		)
		(layer "In4.Cu")
	)
	(gr_line
		(start 294.971978 -34.66973)
		(end 294.159432 -34.66973)
		(stroke
			(width 0.2)
			(type default)
		)
		(layer "In4.Cu")
	)
	(gr_arc
		(start 295.706292 -222.805244)
		(mid 296.217086 -222.294831)
		(end 295.706546 -221.784164)
		(stroke
			(width 0.2)
			(type default)
		)
		(layer "In4.Cu")
	)
	(gr_line
		(start 295.706546 -221.784164)
		(end 294.893746 -221.784164)
		(stroke
			(width 0.2)
			(type default)
		)
		(layer "In4.Cu")
	)
	(gr_line
		(start 296.581322 -25.033986)
		(end 296.583354 -25.035256)
		(stroke
			(width 0.2)
			(type default)
		)
		(layer "In4.Cu")
	)
	(gr_line
		(start 296.581322 -13.633704)
		(end 296.581576 -13.633958)
		(stroke
			(width 0.2)
			(type default)
		)
		(layer "In4.Cu")
	)
	(gr_line
		(start 296.581576 -13.633958)
		(end 296.583608 -13.634974)
		(stroke
			(width 0.2)
			(type default)
		)
		(layer "In4.Cu")
	)
	(gr_arc
		(start 296.583354 -25.035256)
		(mid 296.839386 -25.881076)
		(end 297.685206 -25.625044)
		(stroke
			(width 0.2)
			(type default)
		)
		(layer "In4.Cu")
	)
	(gr_arc
		(start 296.583608 -13.634974)
		(mid 296.839284 -14.480875)
		(end 297.685206 -14.225016)
		(stroke
			(width 0.2)
			(type default)
		)
		(layer "In4.Cu")
	)
	(gr_line
		(start 297.331384 -23.633938)
		(end 296.581322 -25.033986)
		(stroke
			(width 0.2)
			(type default)
		)
		(layer "In4.Cu")
	)
	(gr_line
		(start 297.331384 -12.23391)
		(end 296.581322 -13.633704)
		(stroke
			(width 0.2)
			(type default)
		)
		(layer "In4.Cu")
	)
	(gr_line
		(start 297.333416 -23.635208)
		(end 297.331384 -23.633938)
		(stroke
			(width 0.2)
			(type default)
		)
		(layer "In4.Cu")
	)
	(gr_line
		(start 297.333416 -12.23518)
		(end 297.331384 -12.23391)
		(stroke
			(width 0.2)
			(type default)
		)
		(layer "In4.Cu")
	)
	(gr_line
		(start 297.685206 -25.625044)
		(end 297.687238 -25.626314)
		(stroke
			(width 0.2)
			(type default)
		)
		(layer "In4.Cu")
	)
	(gr_line
		(start 297.685206 -14.225016)
		(end 297.687238 -14.226286)
		(stroke
			(width 0.2)
			(type default)
		)
		(layer "In4.Cu")
	)
	(gr_line
		(start 297.687238 -25.626314)
		(end 298.4373 -24.22652)
		(stroke
			(width 0.2)
			(type default)
		)
		(layer "In4.Cu")
	)
	(gr_line
		(start 297.687238 -14.226286)
		(end 298.4373 -12.826238)
		(stroke
			(width 0.2)
			(type default)
		)
		(layer "In4.Cu")
	)
	(gr_arc
		(start 298.435014 -24.22525)
		(mid 298.179338 -23.379349)
		(end 297.333416 -23.635208)
		(stroke
			(width 0.2)
			(type default)
		)
		(layer "In4.Cu")
	)
	(gr_arc
		(start 298.435268 -12.824968)
		(mid 298.179236 -11.979148)
		(end 297.333416 -12.23518)
		(stroke
			(width 0.2)
			(type default)
		)
		(layer "In4.Cu")
	)
	(gr_line
		(start 298.437046 -24.226266)
		(end 298.435014 -24.22525)
		(stroke
			(width 0.2)
			(type default)
		)
		(layer "In4.Cu")
	)
	(gr_line
		(start 298.4373 -24.22652)
		(end 298.437046 -24.226266)
		(stroke
			(width 0.2)
			(type default)
		)
		(layer "In4.Cu")
	)
	(gr_line
		(start 298.4373 -12.826238)
		(end 298.435268 -12.824968)
		(stroke
			(width 0.2)
			(type default)
		)
		(layer "In4.Cu")
	)
	(gr_line
		(start 298.831508 -17.433544)
		(end 298.831762 -17.433798)
		(stroke
			(width 0.2)
			(type default)
		)
		(layer "In4.Cu")
	)
	(gr_line
		(start 298.831762 -17.433798)
		(end 298.833794 -17.434814)
		(stroke
			(width 0.2)
			(type default)
		)
		(layer "In4.Cu")
	)
	(gr_arc
		(start 298.83354 -21.235162)
		(mid 299.089572 -22.080982)
		(end 299.935392 -21.82495)
		(stroke
			(width 0.2)
			(type default)
		)
		(layer "In4.Cu")
	)
	(gr_arc
		(start 298.833794 -17.434814)
		(mid 299.08947 -18.280715)
		(end 299.935392 -18.024856)
		(stroke
			(width 0.2)
			(type default)
		)
		(layer "In4.Cu")
	)
	(gr_arc
		(start 298.837604 -25.027636)
		(mid 299.085738 -25.879089)
		(end 299.935392 -25.625044)
		(stroke
			(width 0.2)
			(type default)
		)
		(layer "In4.Cu")
	)
	(gr_arc
		(start 298.837604 -13.627608)
		(mid 299.085738 -14.479061)
		(end 299.935392 -14.225016)
		(stroke
			(width 0.2)
			(type default)
		)
		(layer "In4.Cu")
	)
	(gr_line
		(start 298.893738 -211.406994)
		(end 299.706538 -211.406994)
		(stroke
			(width 0.2)
			(type default)
		)
		(layer "In4.Cu")
	)
	(gr_arc
		(start 298.893992 -210.385914)
		(mid 298.383198 -210.896327)
		(end 298.893738 -211.406994)
		(stroke
			(width 0.2)
			(type default)
		)
		(layer "In4.Cu")
	)
	(gr_line
		(start 299.430694 -36.699952)
		(end 300.243494 -36.699952)
		(stroke
			(width 0.2)
			(type default)
		)
		(layer "In4.Cu")
	)
	(gr_arc
		(start 299.430948 -35.678872)
		(mid 298.920154 -36.189285)
		(end 299.430694 -36.699952)
		(stroke
			(width 0.2)
			(type default)
		)
		(layer "In4.Cu")
	)
	(gr_line
		(start 299.581316 -16.034004)
		(end 298.831508 -17.433544)
		(stroke
			(width 0.2)
			(type default)
		)
		(layer "In4.Cu")
	)
	(gr_line
		(start 299.583348 -23.635208)
		(end 298.837604 -25.027636)
		(stroke
			(width 0.2)
			(type default)
		)
		(layer "In4.Cu")
	)
	(gr_line
		(start 299.583348 -19.835114)
		(end 298.83354 -21.235162)
		(stroke
			(width 0.2)
			(type default)
		)
		(layer "In4.Cu")
	)
	(gr_line
		(start 299.583348 -16.035274)
		(end 299.581316 -16.034004)
		(stroke
			(width 0.2)
			(type default)
		)
		(layer "In4.Cu")
	)
	(gr_line
		(start 299.583348 -12.23518)
		(end 298.837604 -13.627608)
		(stroke
			(width 0.2)
			(type default)
		)
		(layer "In4.Cu")
	)
	(gr_arc
		(start 299.706538 -211.406994)
		(mid 300.217078 -210.896454)
		(end 299.706538 -210.385914)
		(stroke
			(width 0.2)
			(type default)
		)
		(layer "In4.Cu")
	)
	(gr_line
		(start 299.706538 -210.385914)
		(end 298.893992 -210.385914)
		(stroke
			(width 0.2)
			(type default)
		)
		(layer "In4.Cu")
	)
	(gr_line
		(start 299.935392 -25.625044)
		(end 300.6852 -24.224996)
		(stroke
			(width 0.2)
			(type default)
		)
		(layer "In4.Cu")
	)
	(gr_line
		(start 299.935392 -21.82495)
		(end 300.681136 -20.432522)
		(stroke
			(width 0.2)
			(type default)
		)
		(layer "In4.Cu")
	)
	(gr_line
		(start 299.935392 -18.024856)
		(end 299.937424 -18.026126)
		(stroke
			(width 0.2)
			(type default)
		)
		(layer "In4.Cu")
	)
	(gr_line
		(start 299.935392 -14.225016)
		(end 300.6852 -12.824968)
		(stroke
			(width 0.2)
			(type default)
		)
		(layer "In4.Cu")
	)
	(gr_line
		(start 299.937424 -18.026126)
		(end 300.687232 -16.626332)
		(stroke
			(width 0.2)
			(type default)
		)
		(layer "In4.Cu")
	)
	(gr_arc
		(start 300.243494 -36.699952)
		(mid 300.754034 -36.189412)
		(end 300.243494 -35.678872)
		(stroke
			(width 0.2)
			(type default)
		)
		(layer "In4.Cu")
	)
	(gr_line
		(start 300.243494 -35.678872)
		(end 299.430948 -35.678872)
		(stroke
			(width 0.2)
			(type default)
		)
		(layer "In4.Cu")
	)
	(gr_line
		(start 300.493684 -222.805244)
		(end 301.30623 -222.805244)
		(stroke
			(width 0.2)
			(type default)
		)
		(layer "In4.Cu")
	)
	(gr_arc
		(start 300.493684 -221.784164)
		(mid 299.983144 -222.294704)
		(end 300.493684 -222.805244)
		(stroke
			(width 0.2)
			(type default)
		)
		(layer "In4.Cu")
	)
	(gr_arc
		(start 300.681136 -20.432522)
		(mid 300.433002 -19.581069)
		(end 299.583348 -19.835114)
		(stroke
			(width 0.2)
			(type default)
		)
		(layer "In4.Cu")
	)
	(gr_arc
		(start 300.6852 -24.224996)
		(mid 300.429168 -23.379176)
		(end 299.583348 -23.635208)
		(stroke
			(width 0.2)
			(type default)
		)
		(layer "In4.Cu")
	)
	(gr_arc
		(start 300.6852 -16.625062)
		(mid 300.429168 -15.779242)
		(end 299.583348 -16.035274)
		(stroke
			(width 0.2)
			(type default)
		)
		(layer "In4.Cu")
	)
	(gr_arc
		(start 300.6852 -12.824968)
		(mid 300.429168 -11.979148)
		(end 299.583348 -12.23518)
		(stroke
			(width 0.2)
			(type default)
		)
		(layer "In4.Cu")
	)
	(gr_line
		(start 300.687232 -16.626332)
		(end 300.6852 -16.625062)
		(stroke
			(width 0.2)
			(type default)
		)
		(layer "In4.Cu")
	)
	(gr_line
		(start 301.08144 -25.033732)
		(end 301.081694 -25.033986)
		(stroke
			(width 0.2)
			(type default)
		)
		(layer "In4.Cu")
	)
	(gr_line
		(start 301.08144 -21.233892)
		(end 301.083472 -21.235162)
		(stroke
			(width 0.2)
			(type default)
		)
		(layer "In4.Cu")
	)
	(gr_line
		(start 301.08144 -17.433544)
		(end 301.081694 -17.433798)
		(stroke
			(width 0.2)
			(type default)
		)
		(layer "In4.Cu")
	)
	(gr_line
		(start 301.08144 -13.633704)
		(end 301.081694 -13.633958)
		(stroke
			(width 0.2)
			(type default)
		)
		(layer "In4.Cu")
	)
	(gr_line
		(start 301.081694 -25.033986)
		(end 301.083726 -25.035002)
		(stroke
			(width 0.2)
			(type default)
		)
		(layer "In4.Cu")
	)
	(gr_line
		(start 301.081694 -17.433798)
		(end 301.083726 -17.434814)
		(stroke
			(width 0.2)
			(type default)
		)
		(layer "In4.Cu")
	)
	(gr_line
		(start 301.081694 -13.633958)
		(end 301.083726 -13.634974)
		(stroke
			(width 0.2)
			(type default)
		)
		(layer "In4.Cu")
	)
	(gr_arc
		(start 301.083472 -21.235162)
		(mid 301.339504 -22.080982)
		(end 302.185324 -21.82495)
		(stroke
			(width 0.2)
			(type default)
		)
		(layer "In4.Cu")
	)
	(gr_arc
		(start 301.083726 -25.035002)
		(mid 301.339402 -25.880903)
		(end 302.185324 -25.625044)
		(stroke
			(width 0.2)
			(type default)
		)
		(layer "In4.Cu")
	)
	(gr_arc
		(start 301.083726 -17.434814)
		(mid 301.33925 -18.280634)
		(end 302.18507 -18.02511)
		(stroke
			(width 0.2)
			(type default)
		)
		(layer "In4.Cu")
	)
	(gr_arc
		(start 301.083726 -13.634974)
		(mid 301.339402 -14.480875)
		(end 302.185324 -14.225016)
		(stroke
			(width 0.2)
			(type default)
		)
		(layer "In4.Cu")
	)
	(gr_arc
		(start 301.30623 -222.805244)
		(mid 301.817024 -222.294831)
		(end 301.306484 -221.784164)
		(stroke
			(width 0.2)
			(type default)
		)
		(layer "In4.Cu")
	)
	(gr_line
		(start 301.306484 -221.784164)
		(end 300.493684 -221.784164)
		(stroke
			(width 0.2)
			(type default)
		)
		(layer "In4.Cu")
	)
	(gr_line
		(start 301.65929 -35.536886)
		(end 302.471836 -35.536886)
		(stroke
			(width 0.2)
			(type default)
		)
		(layer "In4.Cu")
	)
	(gr_arc
		(start 301.65929 -34.515806)
		(mid 301.14875 -35.026346)
		(end 301.65929 -35.536886)
		(stroke
			(width 0.2)
			(type default)
		)
		(layer "In4.Cu")
	)
	(gr_line
		(start 301.831502 -23.633938)
		(end 301.08144 -25.033732)
		(stroke
			(width 0.2)
			(type default)
		)
		(layer "In4.Cu")
	)
	(gr_line
		(start 301.831502 -19.833844)
		(end 301.08144 -21.233892)
		(stroke
			(width 0.2)
			(type default)
		)
		(layer "In4.Cu")
	)
	(gr_line
		(start 301.831502 -16.03375)
		(end 301.08144 -17.433544)
		(stroke
			(width 0.2)
			(type default)
		)
		(layer "In4.Cu")
	)
	(gr_line
		(start 301.831502 -12.23391)
		(end 301.08144 -13.633704)
		(stroke
			(width 0.2)
			(type default)
		)
		(layer "In4.Cu")
	)
	(gr_line
		(start 301.833534 -23.635208)
		(end 301.831502 -23.633938)
		(stroke
			(width 0.2)
			(type default)
		)
		(layer "In4.Cu")
	)
	(gr_line
		(start 301.833534 -19.835114)
		(end 301.831502 -19.833844)
		(stroke
			(width 0.2)
			(type default)
		)
		(layer "In4.Cu")
	)
	(gr_line
		(start 301.833534 -12.23518)
		(end 301.831502 -12.23391)
		(stroke
			(width 0.2)
			(type default)
		)
		(layer "In4.Cu")
	)
	(gr_line
		(start 301.833788 -16.03502)
		(end 301.831502 -16.03375)
		(stroke
			(width 0.2)
			(type default)
		)
		(layer "In4.Cu")
	)
	(gr_line
		(start 302.09363 -211.406994)
		(end 302.90643 -211.406994)
		(stroke
			(width 0.2)
			(type default)
		)
		(layer "In4.Cu")
	)
	(gr_arc
		(start 302.093884 -210.385914)
		(mid 301.58309 -210.896327)
		(end 302.09363 -211.406994)
		(stroke
			(width 0.2)
			(type default)
		)
		(layer "In4.Cu")
	)
	(gr_line
		(start 302.18507 -18.02511)
		(end 302.187356 -18.02638)
		(stroke
			(width 0.2)
			(type default)
		)
		(layer "In4.Cu")
	)
	(gr_line
		(start 302.185324 -25.625044)
		(end 302.187356 -25.626314)
		(stroke
			(width 0.2)
			(type default)
		)
		(layer "In4.Cu")
	)
	(gr_line
		(start 302.185324 -21.82495)
		(end 302.187356 -21.82622)
		(stroke
			(width 0.2)
			(type default)
		)
		(layer "In4.Cu")
	)
	(gr_line
		(start 302.185324 -14.225016)
		(end 302.187356 -14.226286)
		(stroke
			(width 0.2)
			(type default)
		)
		(layer "In4.Cu")
	)
	(gr_line
		(start 302.187356 -25.626314)
		(end 302.937418 -24.226266)
		(stroke
			(width 0.2)
			(type default)
		)
		(layer "In4.Cu")
	)
	(gr_line
		(start 302.187356 -21.82622)
		(end 302.937418 -20.426426)
		(stroke
			(width 0.2)
			(type default)
		)
		(layer "In4.Cu")
	)
	(gr_line
		(start 302.187356 -18.02638)
		(end 302.937418 -16.626586)
		(stroke
			(width 0.2)
			(type default)
		)
		(layer "In4.Cu")
	)
	(gr_line
		(start 302.187356 -14.226286)
		(end 302.937418 -12.826238)
		(stroke
			(width 0.2)
			(type default)
		)
		(layer "In4.Cu")
	)
	(gr_arc
		(start 302.471836 -35.536886)
		(mid 302.98263 -35.026473)
		(end 302.47209 -34.515806)
		(stroke
			(width 0.2)
			(type default)
		)
		(layer "In4.Cu")
	)
	(gr_line
		(start 302.47209 -34.515806)
		(end 301.65929 -34.515806)
		(stroke
			(width 0.2)
			(type default)
		)
		(layer "In4.Cu")
	)
	(gr_arc
		(start 302.90643 -211.406994)
		(mid 303.41697 -210.896454)
		(end 302.90643 -210.385914)
		(stroke
			(width 0.2)
			(type default)
		)
		(layer "In4.Cu")
	)
	(gr_line
		(start 302.90643 -210.385914)
		(end 302.093884 -210.385914)
		(stroke
			(width 0.2)
			(type default)
		)
		(layer "In4.Cu")
	)
	(gr_arc
		(start 302.935132 -20.425156)
		(mid 302.679456 -19.579255)
		(end 301.833534 -19.835114)
		(stroke
			(width 0.2)
			(type default)
		)
		(layer "In4.Cu")
	)
	(gr_arc
		(start 302.935132 -16.625316)
		(mid 302.679608 -15.779496)
		(end 301.833788 -16.03502)
		(stroke
			(width 0.2)
			(type default)
		)
		(layer "In4.Cu")
	)
	(gr_arc
		(start 302.935386 -24.224996)
		(mid 302.679354 -23.379176)
		(end 301.833534 -23.635208)
		(stroke
			(width 0.2)
			(type default)
		)
		(layer "In4.Cu")
	)
	(gr_arc
		(start 302.935386 -12.824968)
		(mid 302.679354 -11.979148)
		(end 301.833534 -12.23518)
		(stroke
			(width 0.2)
			(type default)
		)
		(layer "In4.Cu")
	)
	(gr_line
		(start 302.937164 -20.426172)
		(end 302.935132 -20.425156)
		(stroke
			(width 0.2)
			(type default)
		)
		(layer "In4.Cu")
	)
	(gr_line
		(start 302.937418 -24.226266)
		(end 302.935386 -24.224996)
		(stroke
			(width 0.2)
			(type default)
		)
		(layer "In4.Cu")
	)
	(gr_line
		(start 302.937418 -20.426426)
		(end 302.937164 -20.426172)
		(stroke
			(width 0.2)
			(type default)
		)
		(layer "In4.Cu")
	)
	(gr_line
		(start 302.937418 -16.626586)
		(end 302.935132 -16.625316)
		(stroke
			(width 0.2)
			(type default)
		)
		(layer "In4.Cu")
	)
	(gr_line
		(start 302.937418 -12.826238)
		(end 302.935386 -12.824968)
		(stroke
			(width 0.2)
			(type default)
		)
		(layer "In4.Cu")
	)
	(gr_arc
		(start 303.717198 -219.783914)
		(mid 303.222914 -220.310202)
		(end 303.749202 -220.804486)
		(stroke
			(width 0.2)
			(type default)
		)
		(layer "In4.Cu")
	)
	(gr_line
		(start 303.717198 -219.781374)
		(end 303.717198 -219.783914)
		(stroke
			(width 0.2)
			(type default)
		)
		(layer "In4.Cu")
	)
	(gr_line
		(start 303.749202 -220.807026)
		(end 304.561748 -220.781626)
		(stroke
			(width 0.2)
			(type default)
		)
		(layer "In4.Cu")
	)
	(gr_line
		(start 303.749202 -220.804486)
		(end 303.749202 -220.807026)
		(stroke
			(width 0.2)
			(type default)
		)
		(layer "In4.Cu")
	)
	(gr_line
		(start 303.8348 -36.794694)
		(end 304.647346 -36.794694)
		(stroke
			(width 0.2)
			(type default)
		)
		(layer "In4.Cu")
	)
	(gr_arc
		(start 303.8348 -35.773614)
		(mid 303.32426 -36.284154)
		(end 303.8348 -36.794694)
		(stroke
			(width 0.2)
			(type default)
		)
		(layer "In4.Cu")
	)
	(gr_line
		(start 304.529998 -219.758514)
		(end 304.529998 -219.755974)
		(stroke
			(width 0.2)
			(type default)
		)
		(layer "In4.Cu")
	)
	(gr_line
		(start 304.529998 -219.755974)
		(end 303.717198 -219.781374)
		(stroke
			(width 0.2)
			(type default)
		)
		(layer "In4.Cu")
	)
	(gr_line
		(start 304.561748 -220.781626)
		(end 304.562002 -220.781372)
		(stroke
			(width 0.2)
			(type default)
		)
		(layer "In4.Cu")
	)
	(gr_line
		(start 304.562002 -220.781372)
		(end 304.562002 -220.779086)
		(stroke
			(width 0.2)
			(type default)
		)
		(layer "In4.Cu")
	)
	(gr_arc
		(start 304.562002 -220.779086)
		(mid 305.056286 -220.252798)
		(end 304.529998 -219.758514)
		(stroke
			(width 0.2)
			(type default)
		)
		(layer "In4.Cu")
	)
	(gr_arc
		(start 304.647346 -36.794694)
		(mid 305.15814 -36.284281)
		(end 304.6476 -35.773614)
		(stroke
			(width 0.2)
			(type default)
		)
		(layer "In4.Cu")
	)
	(gr_line
		(start 304.6476 -35.773614)
		(end 303.8348 -35.773614)
		(stroke
			(width 0.2)
			(type default)
		)
		(layer "In4.Cu")
	)
	(gr_line
		(start 305.762914 -40.31996)
		(end 306.57546 -40.31996)
		(stroke
			(width 0.2)
			(type default)
		)
		(layer "In4.Cu")
	)
	(gr_arc
		(start 305.762914 -39.29888)
		(mid 305.252374 -39.80942)
		(end 305.762914 -40.31996)
		(stroke
			(width 0.2)
			(type default)
		)
		(layer "In4.Cu")
	)
	(gr_line
		(start 306.099972 -228.000052)
		(end 260.500114 -228.000052)
		(stroke
			(width 5.08)
			(type default)
		)
		(layer "In4.Cu")
	)
	(gr_line
		(start 306.099972 -222.600012)
		(end 306.099972 -228.000052)
		(stroke
			(width 1.524)
			(type default)
		)
		(layer "In4.Cu")
	)
	(gr_arc
		(start 306.57546 -40.31996)
		(mid 307.086254 -39.809547)
		(end 306.575714 -39.29888)
		(stroke
			(width 0.2)
			(type default)
		)
		(layer "In4.Cu")
	)
	(gr_line
		(start 306.575714 -39.29888)
		(end 305.762914 -39.29888)
		(stroke
			(width 0.2)
			(type default)
		)
		(layer "In4.Cu")
	)
	(gr_arc
		(start 307.583586 -25.035256)
		(mid 307.839618 -25.881076)
		(end 308.685438 -25.625044)
		(stroke
			(width 0.2)
			(type default)
		)
		(layer "In4.Cu")
	)
	(gr_arc
		(start 307.58765 -13.627608)
		(mid 307.835784 -14.479061)
		(end 308.685438 -14.225016)
		(stroke
			(width 0.2)
			(type default)
		)
		(layer "In4.Cu")
	)
	(gr_line
		(start 308.333394 -23.635208)
		(end 307.583586 -25.035256)
		(stroke
			(width 0.2)
			(type default)
		)
		(layer "In4.Cu")
	)
	(gr_line
		(start 308.333394 -12.23518)
		(end 307.58765 -13.627608)
		(stroke
			(width 0.2)
			(type default)
		)
		(layer "In4.Cu")
	)
	(gr_line
		(start 308.500018 -228.000052)
		(end 308.500018 -222.600012)
		(stroke
			(width 1.524)
			(type default)
		)
		(layer "In4.Cu")
	)
	(gr_arc
		(start 308.500018 -222.600012)
		(mid 307.300122 -221.400116)
		(end 306.099972 -222.600012)
		(stroke
			(width 1.524)
			(type default)
		)
		(layer "In4.Cu")
	)
	(gr_line
		(start 308.685438 -25.625044)
		(end 309.431182 -24.232616)
		(stroke
			(width 0.2)
			(type default)
		)
		(layer "In4.Cu")
	)
	(gr_line
		(start 308.685438 -14.225016)
		(end 309.435246 -12.824968)
		(stroke
			(width 0.2)
			(type default)
		)
		(layer "In4.Cu")
	)
	(gr_line
		(start 309.245 -73.66)
		(end 310.134 -72.771)
		(stroke
			(width 0.381)
			(type default)
		)
		(layer "In4.Cu")
	)
	(gr_arc
		(start 309.431182 -24.232616)
		(mid 309.183048 -23.381163)
		(end 308.333394 -23.635208)
		(stroke
			(width 0.2)
			(type default)
		)
		(layer "In4.Cu")
	)
	(gr_arc
		(start 309.435246 -12.824968)
		(mid 309.179214 -11.979148)
		(end 308.333394 -12.23518)
		(stroke
			(width 0.2)
			(type default)
		)
		(layer "In4.Cu")
	)
	(gr_line
		(start 309.831486 -25.033732)
		(end 309.83174 -25.033986)
		(stroke
			(width 0.2)
			(type default)
		)
		(layer "In4.Cu")
	)
	(gr_line
		(start 309.831486 -21.233892)
		(end 309.833518 -21.235162)
		(stroke
			(width 0.2)
			(type default)
		)
		(layer "In4.Cu")
	)
	(gr_line
		(start 309.831486 -17.433544)
		(end 309.83174 -17.433798)
		(stroke
			(width 0.2)
			(type default)
		)
		(layer "In4.Cu")
	)
	(gr_line
		(start 309.831486 -13.633704)
		(end 309.83174 -13.633958)
		(stroke
			(width 0.2)
			(type default)
		)
		(layer "In4.Cu")
	)
	(gr_line
		(start 309.83174 -25.033986)
		(end 309.833772 -25.035002)
		(stroke
			(width 0.2)
			(type default)
		)
		(layer "In4.Cu")
	)
	(gr_line
		(start 309.83174 -17.433798)
		(end 309.833772 -17.434814)
		(stroke
			(width 0.2)
			(type default)
		)
		(layer "In4.Cu")
	)
	(gr_line
		(start 309.83174 -13.633958)
		(end 309.833772 -13.634974)
		(stroke
			(width 0.2)
			(type default)
		)
		(layer "In4.Cu")
	)
	(gr_arc
		(start 309.833518 -21.235162)
		(mid 310.08955 -22.080982)
		(end 310.93537 -21.82495)
		(stroke
			(width 0.2)
			(type default)
		)
		(layer "In4.Cu")
	)
	(gr_arc
		(start 309.833772 -25.035002)
		(mid 310.089448 -25.880903)
		(end 310.93537 -25.625044)
		(stroke
			(width 0.2)
			(type default)
		)
		(layer "In4.Cu")
	)
	(gr_arc
		(start 309.833772 -17.434814)
		(mid 310.089296 -18.280634)
		(end 310.935116 -18.02511)
		(stroke
			(width 0.2)
			(type default)
		)
		(layer "In4.Cu")
	)
	(gr_arc
		(start 309.833772 -13.634974)
		(mid 310.089448 -14.480875)
		(end 310.93537 -14.225016)
		(stroke
			(width 0.2)
			(type default)
		)
		(layer "In4.Cu")
	)
	(gr_line
		(start 310.093868 -211.406994)
		(end 310.906414 -211.406994)
		(stroke
			(width 0.2)
			(type default)
		)
		(layer "In4.Cu")
	)
	(gr_arc
		(start 310.093868 -210.385914)
		(mid 309.583328 -210.896454)
		(end 310.093868 -211.406994)
		(stroke
			(width 0.2)
			(type default)
		)
		(layer "In4.Cu")
	)
	(gr_line
		(start 310.134 -72.771)
		(end 310.134 -68.326)
		(stroke
			(width 0.381)
			(type default)
		)
		(layer "In4.Cu")
	)
	(gr_line
		(start 310.134 -68.326)
		(end 310.134 -54.991)
		(stroke
			(width 0.381)
			(type default)
		)
		(layer "In4.Cu")
	)
	(gr_line
		(start 310.134 -54.991)
		(end 324.866 -54.991)
		(stroke
			(width 0.381)
			(type default)
		)
		(layer "In4.Cu")
	)
	(gr_line
		(start 310.134 -50.8)
		(end 310.134 -54.991)
		(stroke
			(width 0.381)
			(type default)
		)
		(layer "In4.Cu")
	)
	(gr_line
		(start 310.161686 -54.404768)
		(end 310.758078 -55.00116)
		(stroke
			(width 0.381)
			(type default)
		)
		(layer "In4.Cu")
	)
	(gr_line
		(start 310.176926 -67.861688)
		(end 310.773318 -68.45808)
		(stroke
			(width 0.381)
			(type default)
		)
		(layer "In4.Cu")
	)
	(gr_line
		(start 310.261 -68.453)
		(end 310.134 -68.326)
		(stroke
			(width 0.381)
			(type default)
		)
		(layer "In4.Cu")
	)
	(gr_line
		(start 310.425592 -35.55238)
		(end 311.238138 -35.55238)
		(stroke
			(width 0.2)
			(type default)
		)
		(layer "In4.Cu")
	)
	(gr_arc
		(start 310.425592 -34.5313)
		(mid 309.915052 -35.04184)
		(end 310.425592 -35.55238)
		(stroke
			(width 0.2)
			(type default)
		)
		(layer "In4.Cu")
	)
	(gr_line
		(start 310.581548 -23.633938)
		(end 309.831486 -25.033732)
		(stroke
			(width 0.2)
			(type default)
		)
		(layer "In4.Cu")
	)
	(gr_line
		(start 310.581548 -19.833844)
		(end 309.831486 -21.233892)
		(stroke
			(width 0.2)
			(type default)
		)
		(layer "In4.Cu")
	)
	(gr_line
		(start 310.581548 -16.03375)
		(end 309.831486 -17.433544)
		(stroke
			(width 0.2)
			(type default)
		)
		(layer "In4.Cu")
	)
	(gr_line
		(start 310.581548 -12.23391)
		(end 309.831486 -13.633704)
		(stroke
			(width 0.2)
			(type default)
		)
		(layer "In4.Cu")
	)
	(gr_line
		(start 310.58358 -23.635208)
		(end 310.581548 -23.633938)
		(stroke
			(width 0.2)
			(type default)
		)
		(layer "In4.Cu")
	)
	(gr_line
		(start 310.58358 -19.835114)
		(end 310.581548 -19.833844)
		(stroke
			(width 0.2)
			(type default)
		)
		(layer "In4.Cu")
	)
	(gr_line
		(start 310.58358 -12.23518)
		(end 310.581548 -12.23391)
		(stroke
			(width 0.2)
			(type default)
		)
		(layer "In4.Cu")
	)
	(gr_line
		(start 310.583834 -16.03502)
		(end 310.581548 -16.03375)
		(stroke
			(width 0.2)
			(type default)
		)
		(layer "In4.Cu")
	)
	(gr_line
		(start 310.758078 -55.004716)
		(end 310.134762 -55.628032)
		(stroke
			(width 0.381)
			(type default)
		)
		(layer "In4.Cu")
	)
	(gr_line
		(start 310.758078 -55.00116)
		(end 310.758078 -55.004716)
		(stroke
			(width 0.381)
			(type default)
		)
		(layer "In4.Cu")
	)
	(gr_line
		(start 310.773318 -68.461636)
		(end 310.150002 -69.084952)
		(stroke
			(width 0.381)
			(type default)
		)
		(layer "In4.Cu")
	)
	(gr_line
		(start 310.773318 -68.45808)
		(end 310.773318 -68.461636)
		(stroke
			(width 0.381)
			(type default)
		)
		(layer "In4.Cu")
	)
	(gr_arc
		(start 310.906414 -211.406994)
		(mid 311.417208 -210.896581)
		(end 310.906668 -210.385914)
		(stroke
			(width 0.2)
			(type default)
		)
		(layer "In4.Cu")
	)
	(gr_line
		(start 310.906668 -210.385914)
		(end 310.093868 -210.385914)
		(stroke
			(width 0.2)
			(type default)
		)
		(layer "In4.Cu")
	)
	(gr_line
		(start 310.935116 -18.02511)
		(end 310.937402 -18.02638)
		(stroke
			(width 0.2)
			(type default)
		)
		(layer "In4.Cu")
	)
	(gr_line
		(start 310.93537 -25.625044)
		(end 310.937402 -25.626314)
		(stroke
			(width 0.2)
			(type default)
		)
		(layer "In4.Cu")
	)
	(gr_line
		(start 310.93537 -21.82495)
		(end 310.937402 -21.82622)
		(stroke
			(width 0.2)
			(type default)
		)
		(layer "In4.Cu")
	)
	(gr_line
		(start 310.93537 -14.225016)
		(end 310.937402 -14.226286)
		(stroke
			(width 0.2)
			(type default)
		)
		(layer "In4.Cu")
	)
	(gr_line
		(start 310.937402 -25.626314)
		(end 311.687464 -24.226266)
		(stroke
			(width 0.2)
			(type default)
		)
		(layer "In4.Cu")
	)
	(gr_line
		(start 310.937402 -21.82622)
		(end 311.687464 -20.426426)
		(stroke
			(width 0.2)
			(type default)
		)
		(layer "In4.Cu")
	)
	(gr_line
		(start 310.937402 -18.02638)
		(end 311.687464 -16.626586)
		(stroke
			(width 0.2)
			(type default)
		)
		(layer "In4.Cu")
	)
	(gr_line
		(start 310.937402 -14.226286)
		(end 311.687464 -12.826238)
		(stroke
			(width 0.2)
			(type default)
		)
		(layer "In4.Cu")
	)
	(gr_arc
		(start 311.238138 -35.55238)
		(mid 311.748932 -35.041967)
		(end 311.238392 -34.5313)
		(stroke
			(width 0.2)
			(type default)
		)
		(layer "In4.Cu")
	)
	(gr_line
		(start 311.238392 -34.5313)
		(end 310.425592 -34.5313)
		(stroke
			(width 0.2)
			(type default)
		)
		(layer "In4.Cu")
	)
	(gr_arc
		(start 311.685178 -20.425156)
		(mid 311.429502 -19.579255)
		(end 310.58358 -19.835114)
		(stroke
			(width 0.2)
			(type default)
		)
		(layer "In4.Cu")
	)
	(gr_arc
		(start 311.685178 -16.625316)
		(mid 311.429654 -15.779496)
		(end 310.583834 -16.03502)
		(stroke
			(width 0.2)
			(type default)
		)
		(layer "In4.Cu")
	)
	(gr_arc
		(start 311.685432 -24.224996)
		(mid 311.4294 -23.379176)
		(end 310.58358 -23.635208)
		(stroke
			(width 0.2)
			(type default)
		)
		(layer "In4.Cu")
	)
	(gr_arc
		(start 311.685432 -12.824968)
		(mid 311.4294 -11.979148)
		(end 310.58358 -12.23518)
		(stroke
			(width 0.2)
			(type default)
		)
		(layer "In4.Cu")
	)
	(gr_line
		(start 311.68721 -20.426172)
		(end 311.685178 -20.425156)
		(stroke
			(width 0.2)
			(type default)
		)
		(layer "In4.Cu")
	)
	(gr_line
		(start 311.687464 -24.226266)
		(end 311.685432 -24.224996)
		(stroke
			(width 0.2)
			(type default)
		)
		(layer "In4.Cu")
	)
	(gr_line
		(start 311.687464 -20.426426)
		(end 311.68721 -20.426172)
		(stroke
			(width 0.2)
			(type default)
		)
		(layer "In4.Cu")
	)
	(gr_line
		(start 311.687464 -16.626586)
		(end 311.685178 -16.625316)
		(stroke
			(width 0.2)
			(type default)
		)
		(layer "In4.Cu")
	)
	(gr_line
		(start 311.687464 -12.826238)
		(end 311.685432 -12.824968)
		(stroke
			(width 0.2)
			(type default)
		)
		(layer "In4.Cu")
	)
	(gr_line
		(start 311.69356 -222.805244)
		(end 312.506106 -222.805244)
		(stroke
			(width 0.2)
			(type default)
		)
		(layer "In4.Cu")
	)
	(gr_arc
		(start 311.69356 -221.784164)
		(mid 311.18302 -222.294704)
		(end 311.69356 -222.805244)
		(stroke
			(width 0.2)
			(type default)
		)
		(layer "In4.Cu")
	)
	(gr_line
		(start 312.081418 -25.033732)
		(end 312.081672 -25.033986)
		(stroke
			(width 0.2)
			(type default)
		)
		(layer "In4.Cu")
	)
	(gr_line
		(start 312.081418 -21.233892)
		(end 312.08345 -21.235162)
		(stroke
			(width 0.2)
			(type default)
		)
		(layer "In4.Cu")
	)
	(gr_line
		(start 312.081418 -17.433544)
		(end 312.081672 -17.433798)
		(stroke
			(width 0.2)
			(type default)
		)
		(layer "In4.Cu")
	)
	(gr_line
		(start 312.081418 -13.633704)
		(end 312.081672 -13.633958)
		(stroke
			(width 0.2)
			(type default)
		)
		(layer "In4.Cu")
	)
	(gr_line
		(start 312.081672 -25.033986)
		(end 312.083704 -25.035002)
		(stroke
			(width 0.2)
			(type default)
		)
		(layer "In4.Cu")
	)
	(gr_line
		(start 312.081672 -17.433798)
		(end 312.083704 -17.434814)
		(stroke
			(width 0.2)
			(type default)
		)
		(layer "In4.Cu")
	)
	(gr_line
		(start 312.081672 -13.633958)
		(end 312.083704 -13.634974)
		(stroke
			(width 0.2)
			(type default)
		)
		(layer "In4.Cu")
	)
	(gr_arc
		(start 312.08345 -21.235162)
		(mid 312.339482 -22.080982)
		(end 313.185302 -21.82495)
		(stroke
			(width 0.2)
			(type default)
		)
		(layer "In4.Cu")
	)
	(gr_arc
		(start 312.083704 -25.035002)
		(mid 312.33938 -25.880903)
		(end 313.185302 -25.625044)
		(stroke
			(width 0.2)
			(type default)
		)
		(layer "In4.Cu")
	)
	(gr_arc
		(start 312.083704 -17.434814)
		(mid 312.339228 -18.280634)
		(end 313.185048 -18.02511)
		(stroke
			(width 0.2)
			(type default)
		)
		(layer "In4.Cu")
	)
	(gr_arc
		(start 312.083704 -13.634974)
		(mid 312.33938 -14.480875)
		(end 313.185302 -14.225016)
		(stroke
			(width 0.2)
			(type default)
		)
		(layer "In4.Cu")
	)
	(gr_arc
		(start 312.506106 -222.805244)
		(mid 313.0169 -222.294831)
		(end 312.50636 -221.784164)
		(stroke
			(width 0.2)
			(type default)
		)
		(layer "In4.Cu")
	)
	(gr_line
		(start 312.50636 -221.784164)
		(end 311.69356 -221.784164)
		(stroke
			(width 0.2)
			(type default)
		)
		(layer "In4.Cu")
	)
	(gr_line
		(start 312.676286 -36.696142)
		(end 313.489086 -36.696142)
		(stroke
			(width 0.2)
			(type default)
		)
		(layer "In4.Cu")
	)
	(gr_arc
		(start 312.67654 -35.675062)
		(mid 312.165746 -36.185475)
		(end 312.676286 -36.696142)
		(stroke
			(width 0.2)
			(type default)
		)
		(layer "In4.Cu")
	)
	(gr_line
		(start 312.83148 -23.633938)
		(end 312.081418 -25.033732)
		(stroke
			(width 0.2)
			(type default)
		)
		(layer "In4.Cu")
	)
	(gr_line
		(start 312.83148 -19.833844)
		(end 312.081418 -21.233892)
		(stroke
			(width 0.2)
			(type default)
		)
		(layer "In4.Cu")
	)
	(gr_line
		(start 312.83148 -16.03375)
		(end 312.081418 -17.433544)
		(stroke
			(width 0.2)
			(type default)
		)
		(layer "In4.Cu")
	)
	(gr_line
		(start 312.83148 -12.23391)
		(end 312.081418 -13.633704)
		(stroke
			(width 0.2)
			(type default)
		)
		(layer "In4.Cu")
	)
	(gr_line
		(start 312.833512 -23.635208)
		(end 312.83148 -23.633938)
		(stroke
			(width 0.2)
			(type default)
		)
		(layer "In4.Cu")
	)
	(gr_line
		(start 312.833512 -19.835114)
		(end 312.83148 -19.833844)
		(stroke
			(width 0.2)
			(type default)
		)
		(layer "In4.Cu")
	)
	(gr_line
		(start 312.833512 -12.23518)
		(end 312.83148 -12.23391)
		(stroke
			(width 0.2)
			(type default)
		)
		(layer "In4.Cu")
	)
	(gr_line
		(start 312.833766 -16.03502)
		(end 312.83148 -16.03375)
		(stroke
			(width 0.2)
			(type default)
		)
		(layer "In4.Cu")
	)
	(gr_line
		(start 313.185048 -18.02511)
		(end 313.187334 -18.02638)
		(stroke
			(width 0.2)
			(type default)
		)
		(layer "In4.Cu")
	)
	(gr_line
		(start 313.185302 -25.625044)
		(end 313.187334 -25.626314)
		(stroke
			(width 0.2)
			(type default)
		)
		(layer "In4.Cu")
	)
	(gr_line
		(start 313.185302 -21.82495)
		(end 313.187334 -21.82622)
		(stroke
			(width 0.2)
			(type default)
		)
		(layer "In4.Cu")
	)
	(gr_line
		(start 313.185302 -14.225016)
		(end 313.187334 -14.226286)
		(stroke
			(width 0.2)
			(type default)
		)
		(layer "In4.Cu")
	)
	(gr_line
		(start 313.187334 -25.626314)
		(end 313.937396 -24.226266)
		(stroke
			(width 0.2)
			(type default)
		)
		(layer "In4.Cu")
	)
	(gr_line
		(start 313.187334 -21.82622)
		(end 313.937396 -20.426426)
		(stroke
			(width 0.2)
			(type default)
		)
		(layer "In4.Cu")
	)
	(gr_line
		(start 313.187334 -18.02638)
		(end 313.937396 -16.626586)
		(stroke
			(width 0.2)
			(type default)
		)
		(layer "In4.Cu")
	)
	(gr_line
		(start 313.187334 -14.226286)
		(end 313.937396 -12.826238)
		(stroke
			(width 0.2)
			(type default)
		)
		(layer "In4.Cu")
	)
	(gr_line
		(start 313.29376 -211.406994)
		(end 314.10656 -211.406994)
		(stroke
			(width 0.2)
			(type default)
		)
		(layer "In4.Cu")
	)
	(gr_arc
		(start 313.294014 -210.385914)
		(mid 312.78322 -210.896327)
		(end 313.29376 -211.406994)
		(stroke
			(width 0.2)
			(type default)
		)
		(layer "In4.Cu")
	)
	(gr_arc
		(start 313.489086 -36.696142)
		(mid 313.999626 -36.185602)
		(end 313.489086 -35.675062)
		(stroke
			(width 0.2)
			(type default)
		)
		(layer "In4.Cu")
	)
	(gr_line
		(start 313.489086 -35.675062)
		(end 312.67654 -35.675062)
		(stroke
			(width 0.2)
			(type default)
		)
		(layer "In4.Cu")
	)
	(gr_arc
		(start 313.93511 -20.425156)
		(mid 313.679434 -19.579255)
		(end 312.833512 -19.835114)
		(stroke
			(width 0.2)
			(type default)
		)
		(layer "In4.Cu")
	)
	(gr_arc
		(start 313.93511 -16.625316)
		(mid 313.679586 -15.779496)
		(end 312.833766 -16.03502)
		(stroke
			(width 0.2)
			(type default)
		)
		(layer "In4.Cu")
	)
	(gr_arc
		(start 313.935364 -24.224996)
		(mid 313.679332 -23.379176)
		(end 312.833512 -23.635208)
		(stroke
			(width 0.2)
			(type default)
		)
		(layer "In4.Cu")
	)
	(gr_arc
		(start 313.935364 -12.824968)
		(mid 313.679332 -11.979148)
		(end 312.833512 -12.23518)
		(stroke
			(width 0.2)
			(type default)
		)
		(layer "In4.Cu")
	)
	(gr_line
		(start 313.937142 -20.426172)
		(end 313.93511 -20.425156)
		(stroke
			(width 0.2)
			(type default)
		)
		(layer "In4.Cu")
	)
	(gr_line
		(start 313.937396 -24.226266)
		(end 313.935364 -24.224996)
		(stroke
			(width 0.2)
			(type default)
		)
		(layer "In4.Cu")
	)
	(gr_line
		(start 313.937396 -20.426426)
		(end 313.937142 -20.426172)
		(stroke
			(width 0.2)
			(type default)
		)
		(layer "In4.Cu")
	)
	(gr_line
		(start 313.937396 -16.626586)
		(end 313.93511 -16.625316)
		(stroke
			(width 0.2)
			(type default)
		)
		(layer "In4.Cu")
	)
	(gr_line
		(start 313.937396 -12.826238)
		(end 313.935364 -12.824968)
		(stroke
			(width 0.2)
			(type default)
		)
		(layer "In4.Cu")
	)
	(gr_arc
		(start 314.10656 -211.406994)
		(mid 314.6171 -210.896454)
		(end 314.10656 -210.385914)
		(stroke
			(width 0.2)
			(type default)
		)
		(layer "In4.Cu")
	)
	(gr_line
		(start 314.10656 -210.385914)
		(end 313.294014 -210.385914)
		(stroke
			(width 0.2)
			(type default)
		)
		(layer "In4.Cu")
	)
	(gr_line
		(start 314.8838 -35.524694)
		(end 315.696346 -35.524694)
		(stroke
			(width 0.2)
			(type default)
		)
		(layer "In4.Cu")
	)
	(gr_arc
		(start 314.8838 -34.503614)
		(mid 314.37326 -35.014154)
		(end 314.8838 -35.524694)
		(stroke
			(width 0.2)
			(type default)
		)
		(layer "In4.Cu")
	)
	(gr_line
		(start 314.893706 -222.805244)
		(end 315.706252 -222.805244)
		(stroke
			(width 0.2)
			(type default)
		)
		(layer "In4.Cu")
	)
	(gr_arc
		(start 314.893706 -221.784164)
		(mid 314.383166 -222.294704)
		(end 314.893706 -222.805244)
		(stroke
			(width 0.2)
			(type default)
		)
		(layer "In4.Cu")
	)
	(gr_arc
		(start 315.696346 -35.524694)
		(mid 316.20714 -35.014281)
		(end 315.6966 -34.503614)
		(stroke
			(width 0.2)
			(type default)
		)
		(layer "In4.Cu")
	)
	(gr_line
		(start 315.6966 -34.503614)
		(end 314.8838 -34.503614)
		(stroke
			(width 0.2)
			(type default)
		)
		(layer "In4.Cu")
	)
	(gr_arc
		(start 315.706252 -222.805244)
		(mid 316.217046 -222.294831)
		(end 315.706506 -221.784164)
		(stroke
			(width 0.2)
			(type default)
		)
		(layer "In4.Cu")
	)
	(gr_line
		(start 315.706506 -221.784164)
		(end 314.893706 -221.784164)
		(stroke
			(width 0.2)
			(type default)
		)
		(layer "In4.Cu")
	)
	(gr_line
		(start 316.493906 -211.406994)
		(end 317.306706 -211.406994)
		(stroke
			(width 0.2)
			(type default)
		)
		(layer "In4.Cu")
	)
	(gr_arc
		(start 316.49416 -210.385914)
		(mid 315.983366 -210.896327)
		(end 316.493906 -211.406994)
		(stroke
			(width 0.2)
			(type default)
		)
		(layer "In4.Cu")
	)
	(gr_arc
		(start 317.306706 -211.406994)
		(mid 317.817246 -210.896454)
		(end 317.306706 -210.385914)
		(stroke
			(width 0.2)
			(type default)
		)
		(layer "In4.Cu")
	)
	(gr_line
		(start 317.306706 -210.385914)
		(end 316.49416 -210.385914)
		(stroke
			(width 0.2)
			(type default)
		)
		(layer "In4.Cu")
	)
	(gr_line
		(start 318.093598 -222.805244)
		(end 318.906144 -222.805244)
		(stroke
			(width 0.2)
			(type default)
		)
		(layer "In4.Cu")
	)
	(gr_arc
		(start 318.093598 -221.784164)
		(mid 317.583058 -222.294704)
		(end 318.093598 -222.805244)
		(stroke
			(width 0.2)
			(type default)
		)
		(layer "In4.Cu")
	)
	(gr_arc
		(start 318.583564 -25.035256)
		(mid 318.839596 -25.881076)
		(end 319.685416 -25.625044)
		(stroke
			(width 0.2)
			(type default)
		)
		(layer "In4.Cu")
	)
	(gr_arc
		(start 318.587628 -13.627608)
		(mid 318.835762 -14.479061)
		(end 319.685416 -14.225016)
		(stroke
			(width 0.2)
			(type default)
		)
		(layer "In4.Cu")
	)
	(gr_arc
		(start 318.906144 -222.805244)
		(mid 319.416938 -222.294831)
		(end 318.906398 -221.784164)
		(stroke
			(width 0.2)
			(type default)
		)
		(layer "In4.Cu")
	)
	(gr_line
		(start 318.906398 -221.784164)
		(end 318.093598 -221.784164)
		(stroke
			(width 0.2)
			(type default)
		)
		(layer "In4.Cu")
	)
	(gr_line
		(start 319.333372 -23.635208)
		(end 318.583564 -25.035256)
		(stroke
			(width 0.2)
			(type default)
		)
		(layer "In4.Cu")
	)
	(gr_line
		(start 319.333372 -12.23518)
		(end 318.587628 -13.627608)
		(stroke
			(width 0.2)
			(type default)
		)
		(layer "In4.Cu")
	)
	(gr_line
		(start 319.685416 -25.625044)
		(end 320.43116 -24.232616)
		(stroke
			(width 0.2)
			(type default)
		)
		(layer "In4.Cu")
	)
	(gr_line
		(start 319.685416 -14.225016)
		(end 320.435224 -12.824968)
		(stroke
			(width 0.2)
			(type default)
		)
		(layer "In4.Cu")
	)
	(gr_line
		(start 319.693798 -211.406994)
		(end 320.506598 -211.406994)
		(stroke
			(width 0.2)
			(type default)
		)
		(layer "In4.Cu")
	)
	(gr_arc
		(start 319.694052 -210.385914)
		(mid 319.183258 -210.896327)
		(end 319.693798 -211.406994)
		(stroke
			(width 0.2)
			(type default)
		)
		(layer "In4.Cu")
	)
	(gr_line
		(start 319.720976 -37.53612)
		(end 320.533522 -37.53612)
		(stroke
			(width 0.2)
			(type default)
		)
		(layer "In4.Cu")
	)
	(gr_line
		(start 319.720976 -37.53612)
		(end 320.533776 -37.53612)
		(stroke
			(width 0.2)
			(type default)
		)
		(layer "In4.Cu")
	)
	(gr_arc
		(start 319.720976 -36.51504)
		(mid 319.210436 -37.02558)
		(end 319.720976 -37.53612)
		(stroke
			(width 0.2)
			(type default)
		)
		(layer "In4.Cu")
	)
	(gr_arc
		(start 319.72123 -36.51504)
		(mid 319.210436 -37.025453)
		(end 319.720976 -37.53612)
		(stroke
			(width 0.2)
			(type default)
		)
		(layer "In4.Cu")
	)
	(gr_arc
		(start 320.43116 -24.232616)
		(mid 320.183026 -23.381163)
		(end 319.333372 -23.635208)
		(stroke
			(width 0.2)
			(type default)
		)
		(layer "In4.Cu")
	)
	(gr_arc
		(start 320.435224 -12.824968)
		(mid 320.179192 -11.979148)
		(end 319.333372 -12.23518)
		(stroke
			(width 0.2)
			(type default)
		)
		(layer "In4.Cu")
	)
	(gr_arc
		(start 320.506598 -211.406994)
		(mid 321.017138 -210.896454)
		(end 320.506598 -210.385914)
		(stroke
			(width 0.2)
			(type default)
		)
		(layer "In4.Cu")
	)
	(gr_line
		(start 320.506598 -210.385914)
		(end 319.694052 -210.385914)
		(stroke
			(width 0.2)
			(type default)
		)
		(layer "In4.Cu")
	)
	(gr_arc
		(start 320.533522 -37.53612)
		(mid 321.044316 -37.025707)
		(end 320.533776 -36.51504)
		(stroke
			(width 0.2)
			(type default)
		)
		(layer "In4.Cu")
	)
	(gr_arc
		(start 320.533776 -37.53612)
		(mid 321.044316 -37.02558)
		(end 320.533776 -36.51504)
		(stroke
			(width 0.2)
			(type default)
		)
		(layer "In4.Cu")
	)
	(gr_line
		(start 320.533776 -36.51504)
		(end 319.720976 -36.51504)
		(stroke
			(width 0.2)
			(type default)
		)
		(layer "In4.Cu")
	)
	(gr_line
		(start 320.533776 -36.51504)
		(end 319.72123 -36.51504)
		(stroke
			(width 0.2)
			(type default)
		)
		(layer "In4.Cu")
	)
	(gr_line
		(start 320.831464 -25.033732)
		(end 320.831718 -25.033986)
		(stroke
			(width 0.2)
			(type default)
		)
		(layer "In4.Cu")
	)
	(gr_line
		(start 320.831464 -21.233892)
		(end 320.833496 -21.235162)
		(stroke
			(width 0.2)
			(type default)
		)
		(layer "In4.Cu")
	)
	(gr_line
		(start 320.831464 -17.433544)
		(end 320.831718 -17.433798)
		(stroke
			(width 0.2)
			(type default)
		)
		(layer "In4.Cu")
	)
	(gr_line
		(start 320.831464 -13.633704)
		(end 320.831718 -13.633958)
		(stroke
			(width 0.2)
			(type default)
		)
		(layer "In4.Cu")
	)
	(gr_line
		(start 320.831718 -25.033986)
		(end 320.83375 -25.035002)
		(stroke
			(width 0.2)
			(type default)
		)
		(layer "In4.Cu")
	)
	(gr_line
		(start 320.831718 -17.433798)
		(end 320.83375 -17.434814)
		(stroke
			(width 0.2)
			(type default)
		)
		(layer "In4.Cu")
	)
	(gr_line
		(start 320.831718 -13.633958)
		(end 320.83375 -13.634974)
		(stroke
			(width 0.2)
			(type default)
		)
		(layer "In4.Cu")
	)
	(gr_arc
		(start 320.833496 -21.235162)
		(mid 321.089528 -22.080982)
		(end 321.935348 -21.82495)
		(stroke
			(width 0.2)
			(type default)
		)
		(layer "In4.Cu")
	)
	(gr_arc
		(start 320.83375 -25.035002)
		(mid 321.089426 -25.880903)
		(end 321.935348 -25.625044)
		(stroke
			(width 0.2)
			(type default)
		)
		(layer "In4.Cu")
	)
	(gr_arc
		(start 320.83375 -17.434814)
		(mid 321.089274 -18.280634)
		(end 321.935094 -18.02511)
		(stroke
			(width 0.2)
			(type default)
		)
		(layer "In4.Cu")
	)
	(gr_arc
		(start 320.83375 -13.634974)
		(mid 321.089426 -14.480875)
		(end 321.935348 -14.225016)
		(stroke
			(width 0.2)
			(type default)
		)
		(layer "In4.Cu")
	)
	(gr_line
		(start 321.293744 -222.805244)
		(end 322.10629 -222.805244)
		(stroke
			(width 0.2)
			(type default)
		)
		(layer "In4.Cu")
	)
	(gr_arc
		(start 321.293744 -221.784164)
		(mid 320.783204 -222.294704)
		(end 321.293744 -222.805244)
		(stroke
			(width 0.2)
			(type default)
		)
		(layer "In4.Cu")
	)
	(gr_line
		(start 321.581526 -23.633938)
		(end 320.831464 -25.033732)
		(stroke
			(width 0.2)
			(type default)
		)
		(layer "In4.Cu")
	)
	(gr_line
		(start 321.581526 -19.833844)
		(end 320.831464 -21.233892)
		(stroke
			(width 0.2)
			(type default)
		)
		(layer "In4.Cu")
	)
	(gr_line
		(start 321.581526 -16.03375)
		(end 320.831464 -17.433544)
		(stroke
			(width 0.2)
			(type default)
		)
		(layer "In4.Cu")
	)
	(gr_line
		(start 321.581526 -12.23391)
		(end 320.831464 -13.633704)
		(stroke
			(width 0.2)
			(type default)
		)
		(layer "In4.Cu")
	)
	(gr_line
		(start 321.583558 -23.635208)
		(end 321.581526 -23.633938)
		(stroke
			(width 0.2)
			(type default)
		)
		(layer "In4.Cu")
	)
	(gr_line
		(start 321.583558 -19.835114)
		(end 321.581526 -19.833844)
		(stroke
			(width 0.2)
			(type default)
		)
		(layer "In4.Cu")
	)
	(gr_line
		(start 321.583558 -12.23518)
		(end 321.581526 -12.23391)
		(stroke
			(width 0.2)
			(type default)
		)
		(layer "In4.Cu")
	)
	(gr_line
		(start 321.583812 -16.03502)
		(end 321.581526 -16.03375)
		(stroke
			(width 0.2)
			(type default)
		)
		(layer "In4.Cu")
	)
	(gr_line
		(start 321.935094 -18.02511)
		(end 321.93738 -18.02638)
		(stroke
			(width 0.2)
			(type default)
		)
		(layer "In4.Cu")
	)
	(gr_line
		(start 321.935348 -25.625044)
		(end 321.93738 -25.626314)
		(stroke
			(width 0.2)
			(type default)
		)
		(layer "In4.Cu")
	)
	(gr_line
		(start 321.935348 -21.82495)
		(end 321.93738 -21.82622)
		(stroke
			(width 0.2)
			(type default)
		)
		(layer "In4.Cu")
	)
	(gr_line
		(start 321.935348 -14.225016)
		(end 321.93738 -14.226286)
		(stroke
			(width 0.2)
			(type default)
		)
		(layer "In4.Cu")
	)
	(gr_line
		(start 321.93738 -25.626314)
		(end 322.687442 -24.226266)
		(stroke
			(width 0.2)
			(type default)
		)
		(layer "In4.Cu")
	)
	(gr_line
		(start 321.93738 -21.82622)
		(end 322.687442 -20.426426)
		(stroke
			(width 0.2)
			(type default)
		)
		(layer "In4.Cu")
	)
	(gr_line
		(start 321.93738 -18.02638)
		(end 322.687442 -16.626586)
		(stroke
			(width 0.2)
			(type default)
		)
		(layer "In4.Cu")
	)
	(gr_line
		(start 321.93738 -14.226286)
		(end 322.687442 -12.826238)
		(stroke
			(width 0.2)
			(type default)
		)
		(layer "In4.Cu")
	)
	(gr_arc
		(start 322.10629 -222.805244)
		(mid 322.617084 -222.294831)
		(end 322.106544 -221.784164)
		(stroke
			(width 0.2)
			(type default)
		)
		(layer "In4.Cu")
	)
	(gr_line
		(start 322.106544 -221.784164)
		(end 321.293744 -221.784164)
		(stroke
			(width 0.2)
			(type default)
		)
		(layer "In4.Cu")
	)
	(gr_arc
		(start 322.685156 -20.425156)
		(mid 322.42948 -19.579255)
		(end 321.583558 -19.835114)
		(stroke
			(width 0.2)
			(type default)
		)
		(layer "In4.Cu")
	)
	(gr_arc
		(start 322.685156 -16.625316)
		(mid 322.429632 -15.779496)
		(end 321.583812 -16.03502)
		(stroke
			(width 0.2)
			(type default)
		)
		(layer "In4.Cu")
	)
	(gr_arc
		(start 322.68541 -24.224996)
		(mid 322.429378 -23.379176)
		(end 321.583558 -23.635208)
		(stroke
			(width 0.2)
			(type default)
		)
		(layer "In4.Cu")
	)
	(gr_arc
		(start 322.68541 -12.824968)
		(mid 322.429378 -11.979148)
		(end 321.583558 -12.23518)
		(stroke
			(width 0.2)
			(type default)
		)
		(layer "In4.Cu")
	)
	(gr_line
		(start 322.687188 -20.426172)
		(end 322.685156 -20.425156)
		(stroke
			(width 0.2)
			(type default)
		)
		(layer "In4.Cu")
	)
	(gr_line
		(start 322.687442 -24.226266)
		(end 322.68541 -24.224996)
		(stroke
			(width 0.2)
			(type default)
		)
		(layer "In4.Cu")
	)
	(gr_line
		(start 322.687442 -20.426426)
		(end 322.687188 -20.426172)
		(stroke
			(width 0.2)
			(type default)
		)
		(layer "In4.Cu")
	)
	(gr_line
		(start 322.687442 -16.626586)
		(end 322.685156 -16.625316)
		(stroke
			(width 0.2)
			(type default)
		)
		(layer "In4.Cu")
	)
	(gr_line
		(start 322.687442 -12.826238)
		(end 322.68541 -12.824968)
		(stroke
			(width 0.2)
			(type default)
		)
		(layer "In4.Cu")
	)
	(gr_line
		(start 322.89369 -211.406994)
		(end 323.70649 -211.406994)
		(stroke
			(width 0.2)
			(type default)
		)
		(layer "In4.Cu")
	)
	(gr_arc
		(start 322.893944 -210.385914)
		(mid 322.38315 -210.896327)
		(end 322.89369 -211.406994)
		(stroke
			(width 0.2)
			(type default)
		)
		(layer "In4.Cu")
	)
	(gr_line
		(start 323.081396 -25.033732)
		(end 323.08165 -25.033986)
		(stroke
			(width 0.2)
			(type default)
		)
		(layer "In4.Cu")
	)
	(gr_line
		(start 323.081396 -21.233892)
		(end 323.083428 -21.235162)
		(stroke
			(width 0.2)
			(type default)
		)
		(layer "In4.Cu")
	)
	(gr_line
		(start 323.081396 -17.433544)
		(end 323.08165 -17.433798)
		(stroke
			(width 0.2)
			(type default)
		)
		(layer "In4.Cu")
	)
	(gr_line
		(start 323.081396 -13.633704)
		(end 323.08165 -13.633958)
		(stroke
			(width 0.2)
			(type default)
		)
		(layer "In4.Cu")
	)
	(gr_line
		(start 323.08165 -25.033986)
		(end 323.083682 -25.035002)
		(stroke
			(width 0.2)
			(type default)
		)
		(layer "In4.Cu")
	)
	(gr_line
		(start 323.08165 -17.433798)
		(end 323.083682 -17.434814)
		(stroke
			(width 0.2)
			(type default)
		)
		(layer "In4.Cu")
	)
	(gr_line
		(start 323.08165 -13.633958)
		(end 323.083682 -13.634974)
		(stroke
			(width 0.2)
			(type default)
		)
		(layer "In4.Cu")
	)
	(gr_arc
		(start 323.083428 -21.235162)
		(mid 323.33946 -22.080982)
		(end 324.18528 -21.82495)
		(stroke
			(width 0.2)
			(type default)
		)
		(layer "In4.Cu")
	)
	(gr_arc
		(start 323.083682 -25.035002)
		(mid 323.339358 -25.880903)
		(end 324.18528 -25.625044)
		(stroke
			(width 0.2)
			(type default)
		)
		(layer "In4.Cu")
	)
	(gr_arc
		(start 323.083682 -17.434814)
		(mid 323.339206 -18.280634)
		(end 324.185026 -18.02511)
		(stroke
			(width 0.2)
			(type default)
		)
		(layer "In4.Cu")
	)
	(gr_arc
		(start 323.083682 -13.634974)
		(mid 323.339358 -14.480875)
		(end 324.18528 -14.225016)
		(stroke
			(width 0.2)
			(type default)
		)
		(layer "In4.Cu")
	)
	(gr_line
		(start 323.61251 -35.479482)
		(end 324.425056 -35.479482)
		(stroke
			(width 0.2)
			(type default)
		)
		(layer "In4.Cu")
	)
	(gr_line
		(start 323.61251 -35.479482)
		(end 324.42531 -35.479482)
		(stroke
			(width 0.2)
			(type default)
		)
		(layer "In4.Cu")
	)
	(gr_arc
		(start 323.61251 -34.458402)
		(mid 323.10197 -34.968942)
		(end 323.61251 -35.479482)
		(stroke
			(width 0.2)
			(type default)
		)
		(layer "In4.Cu")
	)
	(gr_arc
		(start 323.612764 -34.458402)
		(mid 323.10197 -34.968815)
		(end 323.61251 -35.479482)
		(stroke
			(width 0.2)
			(type default)
		)
		(layer "In4.Cu")
	)
	(gr_arc
		(start 323.70649 -211.406994)
		(mid 324.21703 -210.896454)
		(end 323.70649 -210.385914)
		(stroke
			(width 0.2)
			(type default)
		)
		(layer "In4.Cu")
	)
	(gr_line
		(start 323.70649 -210.385914)
		(end 322.893944 -210.385914)
		(stroke
			(width 0.2)
			(type default)
		)
		(layer "In4.Cu")
	)
	(gr_line
		(start 323.831458 -23.633938)
		(end 323.081396 -25.033732)
		(stroke
			(width 0.2)
			(type default)
		)
		(layer "In4.Cu")
	)
	(gr_line
		(start 323.831458 -19.833844)
		(end 323.081396 -21.233892)
		(stroke
			(width 0.2)
			(type default)
		)
		(layer "In4.Cu")
	)
	(gr_line
		(start 323.831458 -16.03375)
		(end 323.081396 -17.433544)
		(stroke
			(width 0.2)
			(type default)
		)
		(layer "In4.Cu")
	)
	(gr_line
		(start 323.831458 -12.23391)
		(end 323.081396 -13.633704)
		(stroke
			(width 0.2)
			(type default)
		)
		(layer "In4.Cu")
	)
	(gr_line
		(start 323.83349 -23.635208)
		(end 323.831458 -23.633938)
		(stroke
			(width 0.2)
			(type default)
		)
		(layer "In4.Cu")
	)
	(gr_line
		(start 323.83349 -19.835114)
		(end 323.831458 -19.833844)
		(stroke
			(width 0.2)
			(type default)
		)
		(layer "In4.Cu")
	)
	(gr_line
		(start 323.83349 -12.23518)
		(end 323.831458 -12.23391)
		(stroke
			(width 0.2)
			(type default)
		)
		(layer "In4.Cu")
	)
	(gr_line
		(start 323.833744 -16.03502)
		(end 323.831458 -16.03375)
		(stroke
			(width 0.2)
			(type default)
		)
		(layer "In4.Cu")
	)
	(gr_line
		(start 324.185026 -18.02511)
		(end 324.187312 -18.02638)
		(stroke
			(width 0.2)
			(type default)
		)
		(layer "In4.Cu")
	)
	(gr_line
		(start 324.18528 -25.625044)
		(end 324.187312 -25.626314)
		(stroke
			(width 0.2)
			(type default)
		)
		(layer "In4.Cu")
	)
	(gr_line
		(start 324.18528 -21.82495)
		(end 324.187312 -21.82622)
		(stroke
			(width 0.2)
			(type default)
		)
		(layer "In4.Cu")
	)
	(gr_line
		(start 324.18528 -14.225016)
		(end 324.187312 -14.226286)
		(stroke
			(width 0.2)
			(type default)
		)
		(layer "In4.Cu")
	)
	(gr_line
		(start 324.187312 -25.626314)
		(end 324.937374 -24.226266)
		(stroke
			(width 0.2)
			(type default)
		)
		(layer "In4.Cu")
	)
	(gr_line
		(start 324.187312 -21.82622)
		(end 324.937374 -20.426426)
		(stroke
			(width 0.2)
			(type default)
		)
		(layer "In4.Cu")
	)
	(gr_line
		(start 324.187312 -18.02638)
		(end 324.937374 -16.626586)
		(stroke
			(width 0.2)
			(type default)
		)
		(layer "In4.Cu")
	)
	(gr_line
		(start 324.187312 -14.226286)
		(end 324.937374 -12.826238)
		(stroke
			(width 0.2)
			(type default)
		)
		(layer "In4.Cu")
	)
	(gr_arc
		(start 324.425056 -35.479482)
		(mid 324.93585 -34.969069)
		(end 324.42531 -34.458402)
		(stroke
			(width 0.2)
			(type default)
		)
		(layer "In4.Cu")
	)
	(gr_arc
		(start 324.42531 -35.479482)
		(mid 324.93585 -34.968942)
		(end 324.42531 -34.458402)
		(stroke
			(width 0.2)
			(type default)
		)
		(layer "In4.Cu")
	)
	(gr_line
		(start 324.42531 -34.458402)
		(end 323.61251 -34.458402)
		(stroke
			(width 0.2)
			(type default)
		)
		(layer "In4.Cu")
	)
	(gr_line
		(start 324.42531 -34.458402)
		(end 323.612764 -34.458402)
		(stroke
			(width 0.2)
			(type default)
		)
		(layer "In4.Cu")
	)
	(gr_line
		(start 324.493636 -222.805244)
		(end 325.306182 -222.805244)
		(stroke
			(width 0.2)
			(type default)
		)
		(layer "In4.Cu")
	)
	(gr_arc
		(start 324.493636 -221.784164)
		(mid 323.983096 -222.294704)
		(end 324.493636 -222.805244)
		(stroke
			(width 0.2)
			(type default)
		)
		(layer "In4.Cu")
	)
	(gr_line
		(start 324.866 -54.991)
		(end 325.755 -55.88)
		(stroke
			(width 0.381)
			(type default)
		)
		(layer "In4.Cu")
	)
	(gr_arc
		(start 324.935088 -20.425156)
		(mid 324.679412 -19.579255)
		(end 323.83349 -19.835114)
		(stroke
			(width 0.2)
			(type default)
		)
		(layer "In4.Cu")
	)
	(gr_arc
		(start 324.935088 -16.625316)
		(mid 324.679564 -15.779496)
		(end 323.833744 -16.03502)
		(stroke
			(width 0.2)
			(type default)
		)
		(layer "In4.Cu")
	)
	(gr_arc
		(start 324.935342 -24.224996)
		(mid 324.67931 -23.379176)
		(end 323.83349 -23.635208)
		(stroke
			(width 0.2)
			(type default)
		)
		(layer "In4.Cu")
	)
	(gr_arc
		(start 324.935342 -12.824968)
		(mid 324.67931 -11.979148)
		(end 323.83349 -12.23518)
		(stroke
			(width 0.2)
			(type default)
		)
		(layer "In4.Cu")
	)
	(gr_line
		(start 324.93712 -20.426172)
		(end 324.935088 -20.425156)
		(stroke
			(width 0.2)
			(type default)
		)
		(layer "In4.Cu")
	)
	(gr_line
		(start 324.937374 -24.226266)
		(end 324.935342 -24.224996)
		(stroke
			(width 0.2)
			(type default)
		)
		(layer "In4.Cu")
	)
	(gr_line
		(start 324.937374 -20.426426)
		(end 324.93712 -20.426172)
		(stroke
			(width 0.2)
			(type default)
		)
		(layer "In4.Cu")
	)
	(gr_line
		(start 324.937374 -16.626586)
		(end 324.935088 -16.625316)
		(stroke
			(width 0.2)
			(type default)
		)
		(layer "In4.Cu")
	)
	(gr_line
		(start 324.937374 -12.826238)
		(end 324.935342 -12.824968)
		(stroke
			(width 0.2)
			(type default)
		)
		(layer "In4.Cu")
	)
	(gr_line
		(start 325.247 -68.453)
		(end 310.261 -68.453)
		(stroke
			(width 0.381)
			(type default)
		)
		(layer "In4.Cu")
	)
	(gr_arc
		(start 325.306182 -222.805244)
		(mid 325.816976 -222.294831)
		(end 325.306436 -221.784164)
		(stroke
			(width 0.2)
			(type default)
		)
		(layer "In4.Cu")
	)
	(gr_line
		(start 325.306436 -221.784164)
		(end 324.493636 -221.784164)
		(stroke
			(width 0.2)
			(type default)
		)
		(layer "In4.Cu")
	)
	(gr_line
		(start 325.755 -67.945)
		(end 325.247 -68.453)
		(stroke
			(width 0.381)
			(type default)
		)
		(layer "In4.Cu")
	)
	(gr_line
		(start 325.755 -55.88)
		(end 325.755 -67.945)
		(stroke
			(width 0.381)
			(type default)
		)
		(layer "In4.Cu")
	)
	(gr_line
		(start 325.969122 -36.472114)
		(end 326.781668 -36.472114)
		(stroke
			(width 0.2)
			(type default)
		)
		(layer "In4.Cu")
	)
	(gr_arc
		(start 325.969122 -35.451034)
		(mid 325.458582 -35.961574)
		(end 325.969122 -36.472114)
		(stroke
			(width 0.2)
			(type default)
		)
		(layer "In4.Cu")
	)
	(gr_line
		(start 326.093582 -211.406994)
		(end 326.906382 -211.406994)
		(stroke
			(width 0.2)
			(type default)
		)
		(layer "In4.Cu")
	)
	(gr_arc
		(start 326.093836 -210.385914)
		(mid 325.583042 -210.896327)
		(end 326.093582 -211.406994)
		(stroke
			(width 0.2)
			(type default)
		)
		(layer "In4.Cu")
	)
	(gr_arc
		(start 326.781668 -36.472114)
		(mid 327.292462 -35.961701)
		(end 326.781922 -35.451034)
		(stroke
			(width 0.2)
			(type default)
		)
		(layer "In4.Cu")
	)
	(gr_line
		(start 326.781922 -35.451034)
		(end 325.969122 -35.451034)
		(stroke
			(width 0.2)
			(type default)
		)
		(layer "In4.Cu")
	)
	(gr_arc
		(start 326.906382 -211.406994)
		(mid 327.416922 -210.896454)
		(end 326.906382 -210.385914)
		(stroke
			(width 0.2)
			(type default)
		)
		(layer "In4.Cu")
	)
	(gr_line
		(start 326.906382 -210.385914)
		(end 326.093836 -210.385914)
		(stroke
			(width 0.2)
			(type default)
		)
		(layer "In4.Cu")
	)
	(gr_line
		(start 327.693782 -222.805244)
		(end 328.506328 -222.805244)
		(stroke
			(width 0.2)
			(type default)
		)
		(layer "In4.Cu")
	)
	(gr_arc
		(start 327.693782 -221.784164)
		(mid 327.183242 -222.294704)
		(end 327.693782 -222.805244)
		(stroke
			(width 0.2)
			(type default)
		)
		(layer "In4.Cu")
	)
	(gr_line
		(start 328.375518 -35.429952)
		(end 329.188064 -35.429952)
		(stroke
			(width 0.2)
			(type default)
		)
		(layer "In4.Cu")
	)
	(gr_arc
		(start 328.375518 -34.408872)
		(mid 327.864978 -34.919412)
		(end 328.375518 -35.429952)
		(stroke
			(width 0.2)
			(type default)
		)
		(layer "In4.Cu")
	)
	(gr_arc
		(start 328.506328 -222.805244)
		(mid 329.017122 -222.294831)
		(end 328.506582 -221.784164)
		(stroke
			(width 0.2)
			(type default)
		)
		(layer "In4.Cu")
	)
	(gr_line
		(start 328.506582 -221.784164)
		(end 327.693782 -221.784164)
		(stroke
			(width 0.2)
			(type default)
		)
		(layer "In4.Cu")
	)
	(gr_arc
		(start 329.188064 -35.429952)
		(mid 329.698858 -34.919539)
		(end 329.188318 -34.408872)
		(stroke
			(width 0.2)
			(type default)
		)
		(layer "In4.Cu")
	)
	(gr_line
		(start 329.188318 -34.408872)
		(end 328.375518 -34.408872)
		(stroke
			(width 0.2)
			(type default)
		)
		(layer "In4.Cu")
	)
	(gr_line
		(start 330.893674 -222.805244)
		(end 331.70622 -222.805244)
		(stroke
			(width 0.2)
			(type default)
		)
		(layer "In4.Cu")
	)
	(gr_arc
		(start 330.893674 -221.784164)
		(mid 330.383134 -222.294704)
		(end 330.893674 -222.805244)
		(stroke
			(width 0.2)
			(type default)
		)
		(layer "In4.Cu")
	)
	(gr_arc
		(start 331.70622 -222.805244)
		(mid 332.217014 -222.294831)
		(end 331.706474 -221.784164)
		(stroke
			(width 0.2)
			(type default)
		)
		(layer "In4.Cu")
	)
	(gr_line
		(start 331.706474 -221.784164)
		(end 330.893674 -221.784164)
		(stroke
			(width 0.2)
			(type default)
		)
		(layer "In4.Cu")
	)
	(gr_arc
		(start 331.749908 0.999998)
		(mid 332.042801 0.292893)
		(end 332.749906 0)
		(stroke
			(width 1.524)
			(type default)
		)
		(layer "In4.Cu")
	)
	(gr_arc
		(start 331.749908 3.999992)
		(mid 331.457019 4.707106)
		(end 330.74991 4.99999)
		(stroke
			(width 1.524)
			(type default)
		)
		(layer "In4.Cu")
	)
	(gr_line
		(start 331.749908 3.999992)
		(end 331.749908 0.999998)
		(stroke
			(width 1.524)
			(type default)
		)
		(layer "In4.Cu")
	)
	(gr_line
		(start 332.493874 -211.406994)
		(end 333.306674 -211.406994)
		(stroke
			(width 0.2)
			(type default)
		)
		(layer "In4.Cu")
	)
	(gr_arc
		(start 332.494128 -210.385914)
		(mid 331.983334 -210.896327)
		(end 332.493874 -211.406994)
		(stroke
			(width 0.2)
			(type default)
		)
		(layer "In4.Cu")
	)
	(gr_line
		(start 332.749906 0)
		(end 354.600002 0)
		(stroke
			(width 1.524)
			(type default)
		)
		(layer "In4.Cu")
	)
	(gr_arc
		(start 333.306674 -211.406994)
		(mid 333.817214 -210.896454)
		(end 333.306674 -210.385914)
		(stroke
			(width 0.2)
			(type default)
		)
		(layer "In4.Cu")
	)
	(gr_line
		(start 333.306674 -210.385914)
		(end 332.494128 -210.385914)
		(stroke
			(width 0.2)
			(type default)
		)
		(layer "In4.Cu")
	)
	(gr_line
		(start 334.093566 -222.805244)
		(end 334.906112 -222.805244)
		(stroke
			(width 0.2)
			(type default)
		)
		(layer "In4.Cu")
	)
	(gr_arc
		(start 334.093566 -221.784164)
		(mid 333.583026 -222.294704)
		(end 334.093566 -222.805244)
		(stroke
			(width 0.2)
			(type default)
		)
		(layer "In4.Cu")
	)
	(gr_arc
		(start 334.906112 -222.805244)
		(mid 335.416906 -222.294831)
		(end 334.906366 -221.784164)
		(stroke
			(width 0.2)
			(type default)
		)
		(layer "In4.Cu")
	)
	(gr_line
		(start 334.906366 -221.784164)
		(end 334.093566 -221.784164)
		(stroke
			(width 0.2)
			(type default)
		)
		(layer "In4.Cu")
	)
	(gr_line
		(start 335.693766 -211.406994)
		(end 336.506566 -211.406994)
		(stroke
			(width 0.2)
			(type default)
		)
		(layer "In4.Cu")
	)
	(gr_arc
		(start 335.69402 -210.385914)
		(mid 335.183226 -210.896327)
		(end 335.693766 -211.406994)
		(stroke
			(width 0.2)
			(type default)
		)
		(layer "In4.Cu")
	)
	(gr_arc
		(start 336.506566 -211.406994)
		(mid 337.017106 -210.896454)
		(end 336.506566 -210.385914)
		(stroke
			(width 0.2)
			(type default)
		)
		(layer "In4.Cu")
	)
	(gr_line
		(start 336.506566 -210.385914)
		(end 335.69402 -210.385914)
		(stroke
			(width 0.2)
			(type default)
		)
		(layer "In4.Cu")
	)
	(gr_line
		(start 337.293712 -222.805244)
		(end 338.106258 -222.805244)
		(stroke
			(width 0.2)
			(type default)
		)
		(layer "In4.Cu")
	)
	(gr_arc
		(start 337.293712 -221.784164)
		(mid 336.783172 -222.294704)
		(end 337.293712 -222.805244)
		(stroke
			(width 0.2)
			(type default)
		)
		(layer "In4.Cu")
	)
	(gr_arc
		(start 338.106258 -222.805244)
		(mid 338.617052 -222.294831)
		(end 338.106512 -221.784164)
		(stroke
			(width 0.2)
			(type default)
		)
		(layer "In4.Cu")
	)
	(gr_line
		(start 338.106512 -221.784164)
		(end 337.293712 -221.784164)
		(stroke
			(width 0.2)
			(type default)
		)
		(layer "In4.Cu")
	)
	(gr_line
		(start 338.893658 -211.406994)
		(end 339.706204 -211.406994)
		(stroke
			(width 0.2)
			(type default)
		)
		(layer "In4.Cu")
	)
	(gr_arc
		(start 338.893658 -210.385914)
		(mid 338.383118 -210.896454)
		(end 338.893658 -211.406994)
		(stroke
			(width 0.2)
			(type default)
		)
		(layer "In4.Cu")
	)
	(gr_arc
		(start 339.706204 -211.406994)
		(mid 340.216998 -210.896581)
		(end 339.706458 -210.385914)
		(stroke
			(width 0.2)
			(type default)
		)
		(layer "In4.Cu")
	)
	(gr_line
		(start 339.706458 -210.385914)
		(end 338.893658 -210.385914)
		(stroke
			(width 0.2)
			(type default)
		)
		(layer "In4.Cu")
	)
	(gr_line
		(start 340.493604 -222.805244)
		(end 341.306404 -222.805244)
		(stroke
			(width 0.2)
			(type default)
		)
		(layer "In4.Cu")
	)
	(gr_arc
		(start 340.493858 -221.784164)
		(mid 339.983064 -222.294577)
		(end 340.493604 -222.805244)
		(stroke
			(width 0.2)
			(type default)
		)
		(layer "In4.Cu")
	)
	(gr_arc
		(start 341.306404 -222.805244)
		(mid 341.816944 -222.294704)
		(end 341.306404 -221.784164)
		(stroke
			(width 0.2)
			(type default)
		)
		(layer "In4.Cu")
	)
	(gr_line
		(start 341.306404 -221.784164)
		(end 340.493858 -221.784164)
		(stroke
			(width 0.2)
			(type default)
		)
		(layer "In4.Cu")
	)
	(gr_line
		(start 342.09355 -211.406994)
		(end 342.906096 -211.406994)
		(stroke
			(width 0.2)
			(type default)
		)
		(layer "In4.Cu")
	)
	(gr_arc
		(start 342.09355 -210.385914)
		(mid 341.58301 -210.896454)
		(end 342.09355 -211.406994)
		(stroke
			(width 0.2)
			(type default)
		)
		(layer "In4.Cu")
	)
	(gr_arc
		(start 342.906096 -211.406994)
		(mid 343.41689 -210.896581)
		(end 342.90635 -210.385914)
		(stroke
			(width 0.2)
			(type default)
		)
		(layer "In4.Cu")
	)
	(gr_line
		(start 342.90635 -210.385914)
		(end 342.09355 -210.385914)
		(stroke
			(width 0.2)
			(type default)
		)
		(layer "In4.Cu")
	)
	(gr_line
		(start 344.499946 -228.000052)
		(end 308.500018 -228.000052)
		(stroke
			(width 5.08)
			(type default)
		)
		(layer "In4.Cu")
	)
	(gr_line
		(start 344.499946 -222.400114)
		(end 344.499946 -228.000052)
		(stroke
			(width 1.524)
			(type default)
		)
		(layer "In4.Cu")
	)
	(gr_arc
		(start 345.000072 -221.899988)
		(mid 344.64643 -222.046472)
		(end 344.499946 -222.400114)
		(stroke
			(width 1.524)
			(type default)
		)
		(layer "In4.Cu")
	)
	(gr_line
		(start 345.799918 -221.899988)
		(end 345.000072 -221.899988)
		(stroke
			(width 1.524)
			(type default)
		)
		(layer "In4.Cu")
	)
	(gr_arc
		(start 345.799918 -221.899988)
		(mid 346.153446 -221.753586)
		(end 346.300044 -221.400116)
		(stroke
			(width 1.524)
			(type default)
		)
		(layer "In4.Cu")
	)
	(gr_line
		(start 346.300044 -214.799926)
		(end 346.300044 -221.400116)
		(stroke
			(width 1.524)
			(type default)
		)
		(layer "In4.Cu")
	)
	(gr_arc
		(start 347.600016 -213.499954)
		(mid 346.680797 -213.880707)
		(end 346.300044 -214.799926)
		(stroke
			(width 1.524)
			(type default)
		)
		(layer "In4.Cu")
	)
	(gr_arc
		(start 354.24999 -18.200116)
		(mid 354.396563 -18.553594)
		(end 354.750116 -18.699988)
		(stroke
			(width 1.524)
			(type default)
		)
		(layer "In4.Cu")
	)
	(gr_line
		(start 354.24999 -10.199878)
		(end 354.24999 -18.200116)
		(stroke
			(width 1.524)
			(type default)
		)
		(layer "In4.Cu")
	)
	(gr_line
		(start 354.600002 -213.499954)
		(end 347.600016 -213.499954)
		(stroke
			(width 1.524)
			(type default)
		)
		(layer "In4.Cu")
	)
	(gr_arc
		(start 354.600002 -213.499954)
		(mid 355.307091 -213.207058)
		(end 355.6 -212.499956)
		(stroke
			(width 1.524)
			(type default)
		)
		(layer "In4.Cu")
	)
	(gr_line
		(start 354.750116 -18.699988)
		(end 355.099874 -18.699988)
		(stroke
			(width 1.524)
			(type default)
		)
		(layer "In4.Cu")
	)
	(gr_arc
		(start 354.750116 -9.700006)
		(mid 354.396563 -9.8464)
		(end 354.24999 -10.199878)
		(stroke
			(width 1.524)
			(type default)
		)
		(layer "In4.Cu")
	)
	(gr_line
		(start 355.099874 -9.700006)
		(end 354.750116 -9.700006)
		(stroke
			(width 1.524)
			(type default)
		)
		(layer "In4.Cu")
	)
	(gr_arc
		(start 355.099874 -9.700006)
		(mid 355.453526 -9.55353)
		(end 355.6 -9.19988)
		(stroke
			(width 1.524)
			(type default)
		)
		(layer "In4.Cu")
	)
	(gr_arc
		(start 355.6 -19.200114)
		(mid 355.45352 -18.846472)
		(end 355.099874 -18.699988)
		(stroke
			(width 1.524)
			(type default)
		)
		(layer "In4.Cu")
	)
	(gr_line
		(start 355.6 -19.200114)
		(end 355.6 -212.499956)
		(stroke
			(width 1.524)
			(type default)
		)
		(layer "In4.Cu")
	)
	(gr_arc
		(start 355.6 -0.999998)
		(mid 355.307107 -0.292893)
		(end 354.600002 0)
		(stroke
			(width 1.524)
			(type default)
		)
		(layer "In4.Cu")
	)
	(gr_line
		(start 355.6 -0.999998)
		(end 355.6 -9.19988)
		(stroke
			(width 1.524)
			(type default)
		)
		(layer "In4.Cu")
	)
	(gr_line
		(start 5.361432 -186.109102)
		(end 5.566664 -185.90387)
		(stroke
			(width 0.0635)
			(type default)
		)
		(layer "In5.Cu")
	)
	(gr_line
		(start 5.4102 -185.025538)
		(end 5.566664 -185.182002)
		(stroke
			(width 0.0635)
			(type default)
		)
		(layer "In5.Cu")
	)
	(gr_line
		(start 5.4102 -185.0136)
		(end 5.4102 -185.025538)
		(stroke
			(width 0.0635)
			(type default)
		)
		(layer "In5.Cu")
	)
	(gr_line
		(start 6.563106 -64.216534)
		(end 6.7564 -64.409828)
		(stroke
			(width 0.0635)
			(type default)
		)
		(layer "In5.Cu")
	)
	(gr_line
		(start 6.563106 -63.494412)
		(end 6.7564 -63.301118)
		(stroke
			(width 0.0635)
			(type default)
		)
		(layer "In5.Cu")
	)
	(gr_line
		(start 8.000238 -61.223906)
		(end 8.000238 -61.295026)
		(stroke
			(width 0.0508)
			(type default)
		)
		(layer "In5.Cu")
	)
	(gr_line
		(start 8.000238 -60.233306)
		(end 8.000238 -60.304426)
		(stroke
			(width 0.0508)
			(type default)
		)
		(layer "In5.Cu")
	)
	(gr_line
		(start 8.307578 -61.599826)
		(end 8.495538 -61.411866)
		(stroke
			(width 0.0508)
			(type default)
		)
		(layer "In5.Cu")
	)
	(gr_line
		(start 8.307578 -60.919106)
		(end 8.495538 -61.107066)
		(stroke
			(width 0.0508)
			(type default)
		)
		(layer "In5.Cu")
	)
	(gr_line
		(start 8.307578 -60.609226)
		(end 8.495538 -60.421266)
		(stroke
			(width 0.0508)
			(type default)
		)
		(layer "In5.Cu")
	)
	(gr_line
		(start 8.307578 -59.928506)
		(end 8.495538 -60.116466)
		(stroke
			(width 0.0508)
			(type default)
		)
		(layer "In5.Cu")
	)
	(gr_line
		(start 8.495538 -61.107066)
		(end 8.495538 -61.411866)
		(stroke
			(width 0.0508)
			(type default)
		)
		(layer "In5.Cu")
	)
	(gr_line
		(start 8.495538 -60.116466)
		(end 8.495538 -60.421266)
		(stroke
			(width 0.0508)
			(type default)
		)
		(layer "In5.Cu")
	)
	(gr_line
		(start 8.6106 -119.2022)
		(end 10.15365 -120.392444)
		(stroke
			(width 0.0635)
			(type default)
		)
		(layer "In5.Cu")
	)
	(gr_line
		(start 8.674862 -95.736664)
		(end 8.868156 -95.929958)
		(stroke
			(width 0.0635)
			(type default)
		)
		(layer "In5.Cu")
	)
	(gr_line
		(start 9.153144 -63.40729)
		(end 9.203436 -63.457582)
		(stroke
			(width 0.0508)
			(type default)
		)
		(layer "In5.Cu")
	)
	(gr_line
		(start 9.154668 -62.97422)
		(end 9.42086 -62.97422)
		(stroke
			(width 0.0508)
			(type default)
		)
		(layer "In5.Cu")
	)
	(gr_line
		(start 9.42086 -62.97422)
		(end 9.636506 -63.189866)
		(stroke
			(width 0.0508)
			(type default)
		)
		(layer "In5.Cu")
	)
	(gr_line
		(start 9.590278 -95.929958)
		(end 9.783572 -95.736664)
		(stroke
			(width 0.0635)
			(type default)
		)
		(layer "In5.Cu")
	)
	(gr_line
		(start 9.636506 -63.189866)
		(end 9.636506 -63.456058)
		(stroke
			(width 0.0508)
			(type default)
		)
		(layer "In5.Cu")
	)
	(gr_line
		(start 9.6647 -55.048912)
		(end 9.853676 -55.237888)
		(stroke
			(width 0.0508)
			(type default)
		)
		(layer "In5.Cu")
	)
	(gr_line
		(start 9.853676 -64.107822)
		(end 9.903714 -64.15786)
		(stroke
			(width 0.0508)
			(type default)
		)
		(layer "In5.Cu")
	)
	(gr_line
		(start 9.8552 -63.674752)
		(end 10.121392 -63.674752)
		(stroke
			(width 0.0508)
			(type default)
		)
		(layer "In5.Cu")
	)
	(gr_line
		(start 10.121392 -63.674752)
		(end 10.336784 -63.890398)
		(stroke
			(width 0.0508)
			(type default)
		)
		(layer "In5.Cu")
	)
	(gr_line
		(start 10.15365 -120.392444)
		(end 10.175748 -120.567196)
		(stroke
			(width 0.0635)
			(type default)
		)
		(layer "In5.Cu")
	)
	(gr_line
		(start 10.240772 -121.242074)
		(end 10.355072 -121.12752)
		(stroke
			(width 0.0635)
			(type default)
		)
		(layer "In5.Cu")
	)
	(gr_line
		(start 10.288524 -55.237888)
		(end 10.4775 -55.048912)
		(stroke
			(width 0.0508)
			(type default)
		)
		(layer "In5.Cu")
	)
	(gr_line
		(start 10.336784 -63.890398)
		(end 10.336784 -64.156336)
		(stroke
			(width 0.0508)
			(type default)
		)
		(layer "In5.Cu")
	)
	(gr_line
		(start 10.554208 -64.808354)
		(end 10.604246 -64.858392)
		(stroke
			(width 0.0508)
			(type default)
		)
		(layer "In5.Cu")
	)
	(gr_line
		(start 10.555732 -64.375284)
		(end 10.82167 -64.375284)
		(stroke
			(width 0.0508)
			(type default)
		)
		(layer "In5.Cu")
	)
	(gr_line
		(start 10.582148 -120.879616)
		(end 10.787634 -120.879616)
		(stroke
			(width 0.0635)
			(type default)
		)
		(layer "In5.Cu")
	)
	(gr_line
		(start 10.787634 -120.879616)
		(end 11.484102 -121.416826)
		(stroke
			(width 0.0635)
			(type default)
		)
		(layer "In5.Cu")
	)
	(gr_line
		(start 10.82167 -64.375284)
		(end 11.037316 -64.590676)
		(stroke
			(width 0.0508)
			(type default)
		)
		(layer "In5.Cu")
	)
	(gr_line
		(start 11.037316 -64.590676)
		(end 11.037316 -64.856868)
		(stroke
			(width 0.0508)
			(type default)
		)
		(layer "In5.Cu")
	)
	(gr_line
		(start 11.188954 -119.451374)
		(end 11.324844 -119.587264)
		(stroke
			(width 0.0635)
			(type default)
		)
		(layer "In5.Cu")
	)
	(gr_line
		(start 11.254486 -65.508632)
		(end 11.304778 -65.558924)
		(stroke
			(width 0.0508)
			(type default)
		)
		(layer "In5.Cu")
	)
	(gr_line
		(start 11.25601 -65.075562)
		(end 11.522202 -65.075562)
		(stroke
			(width 0.0508)
			(type default)
		)
		(layer "In5.Cu")
	)
	(gr_line
		(start 11.324844 -119.587264)
		(end 11.526012 -119.587264)
		(stroke
			(width 0.0635)
			(type default)
		)
		(layer "In5.Cu")
	)
	(gr_line
		(start 11.484102 -121.416826)
		(end 12.16914 -121.416826)
		(stroke
			(width 0.0635)
			(type default)
		)
		(layer "In5.Cu")
	)
	(gr_line
		(start 11.51763 -119.058182)
		(end 11.613388 -119.082566)
		(stroke
			(width 0.0635)
			(type default)
		)
		(layer "In5.Cu")
	)
	(gr_line
		(start 11.522202 -65.075562)
		(end 11.737848 -65.291208)
		(stroke
			(width 0.0508)
			(type default)
		)
		(layer "In5.Cu")
	)
	(gr_line
		(start 11.564874 -120.4976)
		(end 11.750548 -119.773192)
		(stroke
			(width 0.0635)
			(type default)
		)
		(layer "In5.Cu")
	)
	(gr_line
		(start 11.660378 -119.621808)
		(end 11.750548 -119.773192)
		(stroke
			(width 0.0635)
			(type default)
		)
		(layer "In5.Cu")
	)
	(gr_line
		(start 11.737848 -65.291208)
		(end 11.737848 -65.5574)
		(stroke
			(width 0.0508)
			(type default)
		)
		(layer "In5.Cu")
	)
	(gr_line
		(start 11.787632 -119.12473)
		(end 11.939016 -119.035068)
		(stroke
			(width 0.0635)
			(type default)
		)
		(layer "In5.Cu")
	)
	(gr_line
		(start 11.939016 -119.035068)
		(end 12.124436 -118.311168)
		(stroke
			(width 0.0635)
			(type default)
		)
		(layer "In5.Cu")
	)
	(gr_line
		(start 12.16914 -121.416826)
		(end 12.652248 -121.899934)
		(stroke
			(width 0.0635)
			(type default)
		)
		(layer "In5.Cu")
	)
	(gr_line
		(start 13.5636 -53.829712)
		(end 13.752576 -54.018688)
		(stroke
			(width 0.0508)
			(type default)
		)
		(layer "In5.Cu")
	)
	(gr_line
		(start 14.1732 -68.451222)
		(end 14.362176 -68.262246)
		(stroke
			(width 0.0508)
			(type default)
		)
		(layer "In5.Cu")
	)
	(gr_line
		(start 14.1732 -67.638422)
		(end 14.362176 -67.827398)
		(stroke
			(width 0.0508)
			(type default)
		)
		(layer "In5.Cu")
	)
	(gr_line
		(start 14.187424 -54.018688)
		(end 14.3764 -53.829712)
		(stroke
			(width 0.0508)
			(type default)
		)
		(layer "In5.Cu")
	)
	(gr_line
		(start 15.7988 -73.217024)
		(end 15.987776 -73.028048)
		(stroke
			(width 0.0508)
			(type default)
		)
		(layer "In5.Cu")
	)
	(gr_line
		(start 15.990824 -66.847974)
		(end 16.1798 -67.03695)
		(stroke
			(width 0.0508)
			(type default)
		)
		(layer "In5.Cu")
	)
	(gr_line
		(start 15.990824 -66.413126)
		(end 16.1798 -66.22415)
		(stroke
			(width 0.0508)
			(type default)
		)
		(layer "In5.Cu")
	)
	(gr_line
		(start 16.422624 -73.028048)
		(end 16.6116 -73.217024)
		(stroke
			(width 0.0508)
			(type default)
		)
		(layer "In5.Cu")
	)
	(gr_line
		(start 17.361154 -82.158332)
		(end 17.365218 -82.181192)
		(stroke
			(width 0.06985)
			(type default)
		)
		(layer "In5.Cu")
	)
	(gr_line
		(start 17.361154 -82.158332)
		(end 17.36598 -82.135472)
		(stroke
			(width 0.06985)
			(type default)
		)
		(layer "In5.Cu")
	)
	(gr_line
		(start 17.498568 -82.949288)
		(end 17.50314 -82.97672)
		(stroke
			(width 0.06985)
			(type default)
		)
		(layer "In5.Cu")
	)
	(gr_line
		(start 17.50314 -82.97672)
		(end 17.518888 -83.001104)
		(stroke
			(width 0.06985)
			(type default)
		)
		(layer "In5.Cu")
	)
	(gr_line
		(start 17.65554 -83.211162)
		(end 17.672812 -83.237578)
		(stroke
			(width 0.06985)
			(type default)
		)
		(layer "In5.Cu")
	)
	(gr_line
		(start 17.672812 -83.237578)
		(end 17.698466 -83.254088)
		(stroke
			(width 0.06985)
			(type default)
		)
		(layer "In5.Cu")
	)
	(gr_line
		(start 18.354548 -77.44587)
		(end 18.35912 -77.42428)
		(stroke
			(width 0.06985)
			(type default)
		)
		(layer "In5.Cu")
	)
	(gr_line
		(start 18.35912 -77.42428)
		(end 18.371058 -77.405738)
		(stroke
			(width 0.06985)
			(type default)
		)
		(layer "In5.Cu")
	)
	(gr_line
		(start 18.57375 -73.210674)
		(end 18.762726 -73.39965)
		(stroke
			(width 0.0508)
			(type default)
		)
		(layer "In5.Cu")
	)
	(gr_line
		(start 18.8468 -54.998112)
		(end 19.035776 -55.187088)
		(stroke
			(width 0.0508)
			(type default)
		)
		(layer "In5.Cu")
	)
	(gr_line
		(start 18.852134 -81.90738)
		(end 19.02333 -81.736184)
		(stroke
			(width 0.06985)
			(type default)
		)
		(layer "In5.Cu")
	)
	(gr_line
		(start 19.197574 -73.39965)
		(end 19.38655 -73.210674)
		(stroke
			(width 0.0508)
			(type default)
		)
		(layer "In5.Cu")
	)
	(gr_line
		(start 19.304762 -80.297528)
		(end 19.309334 -80.276192)
		(stroke
			(width 0.06985)
			(type default)
		)
		(layer "In5.Cu")
	)
	(gr_line
		(start 19.309334 -80.276192)
		(end 19.321272 -80.25765)
		(stroke
			(width 0.06985)
			(type default)
		)
		(layer "In5.Cu")
	)
	(gr_line
		(start 19.470624 -55.187088)
		(end 19.6596 -54.998112)
		(stroke
			(width 0.0508)
			(type default)
		)
		(layer "In5.Cu")
	)
	(gr_line
		(start 19.493738 -81.736184)
		(end 19.664934 -81.90738)
		(stroke
			(width 0.06985)
			(type default)
		)
		(layer "In5.Cu")
	)
	(gr_line
		(start 20.3962 -87.4268)
		(end 20.565618 -87.257382)
		(stroke
			(width 0.06985)
			(type default)
		)
		(layer "In5.Cu")
	)
	(gr_line
		(start 20.40382 -84.616544)
		(end 20.428712 -84.6328)
		(stroke
			(width 0.06985)
			(type default)
		)
		(layer "In5.Cu")
	)
	(gr_line
		(start 20.428712 -84.6328)
		(end 20.444968 -84.657692)
		(stroke
			(width 0.06985)
			(type default)
		)
		(layer "In5.Cu")
	)
	(gr_line
		(start 20.536408 -78.38694)
		(end 20.552664 -78.362048)
		(stroke
			(width 0.06985)
			(type default)
		)
		(layer "In5.Cu")
	)
	(gr_line
		(start 20.552664 -78.362048)
		(end 20.577556 -78.345792)
		(stroke
			(width 0.06985)
			(type default)
		)
		(layer "In5.Cu")
	)
	(gr_arc
		(start 20.565618 -87.257382)
		(mid 20.614285 -87.184547)
		(end 20.631404 -87.098632)
		(stroke
			(width 0.06985)
			(type default)
		)
		(layer "In5.Cu")
	)
	(gr_line
		(start 20.801584 -85.20684)
		(end 20.813014 -85.22462)
		(stroke
			(width 0.06985)
			(type default)
		)
		(layer "In5.Cu")
	)
	(gr_line
		(start 20.813014 -85.22462)
		(end 20.817332 -85.24494)
		(stroke
			(width 0.06985)
			(type default)
		)
		(layer "In5.Cu")
	)
	(gr_line
		(start 20.9169 -68.110354)
		(end 20.92325 -68.079874)
		(stroke
			(width 0.06985)
			(type default)
		)
		(layer "In5.Cu")
	)
	(gr_line
		(start 20.9169 -68.110354)
		(end 20.923504 -68.141088)
		(stroke
			(width 0.06985)
			(type default)
		)
		(layer "In5.Cu")
	)
	(gr_arc
		(start 20.961604 -87.098632)
		(mid 20.976456 -87.173283)
		(end 21.018754 -87.236554)
		(stroke
			(width 0.06985)
			(type default)
		)
		(layer "In5.Cu")
	)
	(gr_line
		(start 21.018754 -87.236554)
		(end 21.209 -87.4268)
		(stroke
			(width 0.06985)
			(type default)
		)
		(layer "In5.Cu")
	)
	(gr_line
		(start 21.318728 -75.387708)
		(end 21.3995 -75.33513)
		(stroke
			(width 0.06985)
			(type default)
		)
		(layer "In5.Cu")
	)
	(gr_line
		(start 21.3995 -75.33513)
		(end 21.419566 -75.240896)
		(stroke
			(width 0.06985)
			(type default)
		)
		(layer "In5.Cu")
	)
	(gr_line
		(start 21.7932 -63.991998)
		(end 21.805392 -63.934848)
		(stroke
			(width 0.06985)
			(type default)
		)
		(layer "In5.Cu")
	)
	(gr_line
		(start 21.805392 -63.934848)
		(end 21.847048 -63.893192)
		(stroke
			(width 0.06985)
			(type default)
		)
		(layer "In5.Cu")
	)
	(gr_line
		(start 22.088094 -72.093836)
		(end 22.094698 -72.063102)
		(stroke
			(width 0.06985)
			(type default)
		)
		(layer "In5.Cu")
	)
	(gr_line
		(start 22.088348 -72.033638)
		(end 22.094698 -72.063102)
		(stroke
			(width 0.06985)
			(type default)
		)
		(layer "In5.Cu")
	)
	(gr_line
		(start 22.374098 -77.573378)
		(end 22.39899 -77.557122)
		(stroke
			(width 0.06985)
			(type default)
		)
		(layer "In5.Cu")
	)
	(gr_line
		(start 22.39899 -77.557122)
		(end 22.415246 -77.53223)
		(stroke
			(width 0.06985)
			(type default)
		)
		(layer "In5.Cu")
	)
	(gr_line
		(start 22.5552 -53.556154)
		(end 22.744176 -53.74513)
		(stroke
			(width 0.0508)
			(type default)
		)
		(layer "In5.Cu")
	)
	(gr_line
		(start 22.758908 -68.642738)
		(end 22.765258 -68.672964)
		(stroke
			(width 0.06985)
			(type default)
		)
		(layer "In5.Cu")
	)
	(gr_line
		(start 22.758908 -68.642738)
		(end 22.765258 -68.612258)
		(stroke
			(width 0.06985)
			(type default)
		)
		(layer "In5.Cu")
	)
	(gr_line
		(start 23.107142 -67.006724)
		(end 23.111714 -66.985388)
		(stroke
			(width 0.06985)
			(type default)
		)
		(layer "In5.Cu")
	)
	(gr_line
		(start 23.111714 -66.985388)
		(end 23.123652 -66.966846)
		(stroke
			(width 0.06985)
			(type default)
		)
		(layer "In5.Cu")
	)
	(gr_line
		(start 23.171404 -76.368148)
		(end 23.182834 -76.350368)
		(stroke
			(width 0.06985)
			(type default)
		)
		(layer "In5.Cu")
	)
	(gr_line
		(start 23.179024 -53.74513)
		(end 23.368 -53.556154)
		(stroke
			(width 0.0508)
			(type default)
		)
		(layer "In5.Cu")
	)
	(gr_line
		(start 23.182834 -76.350368)
		(end 23.186898 -76.330556)
		(stroke
			(width 0.06985)
			(type default)
		)
		(layer "In5.Cu")
	)
	(gr_line
		(start 23.952454 -72.729598)
		(end 23.959058 -72.698864)
		(stroke
			(width 0.06985)
			(type default)
		)
		(layer "In5.Cu")
	)
	(gr_line
		(start 23.952708 -72.6694)
		(end 23.959058 -72.698864)
		(stroke
			(width 0.06985)
			(type default)
		)
		(layer "In5.Cu")
	)
	(gr_line
		(start 24.2316 -185.8264)
		(end 24.302466 -185.755534)
		(stroke
			(width 0.0635)
			(type default)
		)
		(layer "In5.Cu")
	)
	(gr_line
		(start 24.2316 -184.9628)
		(end 24.302466 -185.033666)
		(stroke
			(width 0.0635)
			(type default)
		)
		(layer "In5.Cu")
	)
	(gr_line
		(start 24.75992 -67.67068)
		(end 27.682444 -64.748156)
		(stroke
			(width 0.0635)
			(type default)
		)
		(layer "In5.Cu")
	)
	(gr_line
		(start 27.511248 -60.2107)
		(end 27.527504 -60.185808)
		(stroke
			(width 0.06985)
			(type default)
		)
		(layer "In5.Cu")
	)
	(gr_line
		(start 27.527504 -60.185808)
		(end 27.552396 -60.169552)
		(stroke
			(width 0.06985)
			(type default)
		)
		(layer "In5.Cu")
	)
	(gr_line
		(start 27.682444 -64.748156)
		(end 27.83586 -64.748156)
		(stroke
			(width 0.0635)
			(type default)
		)
		(layer "In5.Cu")
	)
	(gr_line
		(start 27.8384 -64.748156)
		(end 27.98699 -64.748156)
		(stroke
			(width 0.0635)
			(type default)
		)
		(layer "In5.Cu")
	)
	(gr_line
		(start 28.3464 -64.240156)
		(end 28.3464 -64.389)
		(stroke
			(width 0.0635)
			(type default)
		)
		(layer "In5.Cu")
	)
	(gr_line
		(start 28.3464 -61.653674)
		(end 28.3464 -64.237616)
		(stroke
			(width 0.0635)
			(type default)
		)
		(layer "In5.Cu")
	)
	(gr_line
		(start 28.3464 -61.653674)
		(end 30.4292 -59.570874)
		(stroke
			(width 0.0635)
			(type default)
		)
		(layer "In5.Cu")
	)
	(gr_line
		(start 31.208218 -57.79516)
		(end 31.225998 -57.78373)
		(stroke
			(width 0.06985)
			(type default)
		)
		(layer "In5.Cu")
	)
	(gr_line
		(start 31.225998 -57.78373)
		(end 31.24581 -57.779666)
		(stroke
			(width 0.06985)
			(type default)
		)
		(layer "In5.Cu")
	)
	(gr_line
		(start 35.63366 -185.5851)
		(end 36.4363 -185.5851)
		(stroke
			(width 0.0635)
			(type default)
		)
		(layer "In5.Cu")
	)
	(gr_line
		(start 35.733482 -184.9628)
		(end 36.6776 -184.9628)
		(stroke
			(width 0.0635)
			(type default)
		)
		(layer "In5.Cu")
	)
	(gr_line
		(start 36.4363 -185.5851)
		(end 36.6776 -185.8264)
		(stroke
			(width 0.0635)
			(type default)
		)
		(layer "In5.Cu")
	)
	(gr_line
		(start 37.04717 -51.86299)
		(end 37.06495 -51.85156)
		(stroke
			(width 0.06985)
			(type default)
		)
		(layer "In5.Cu")
	)
	(gr_line
		(start 37.06495 -51.85156)
		(end 37.084762 -51.847496)
		(stroke
			(width 0.06985)
			(type default)
		)
		(layer "In5.Cu")
	)
	(gr_line
		(start 37.367718 -155.18003)
		(end 37.389054 -155.158694)
		(stroke
			(width 0.06985)
			(type default)
		)
		(layer "In5.Cu")
	)
	(gr_line
		(start 37.859462 -155.158694)
		(end 37.880544 -155.179776)
		(stroke
			(width 0.06985)
			(type default)
		)
		(layer "In5.Cu")
	)
	(gr_line
		(start 37.880544 -155.179776)
		(end 38.168072 -155.179776)
		(stroke
			(width 0.06985)
			(type default)
		)
		(layer "In5.Cu")
	)
	(gr_line
		(start 38.605206 -141.513052)
		(end 38.672516 -141.580362)
		(stroke
			(width 0.06985)
			(type default)
		)
		(layer "In5.Cu")
	)
	(gr_line
		(start 38.605206 -140.928852)
		(end 39.005256 -141.328902)
		(stroke
			(width 0.06985)
			(type default)
		)
		(layer "In5.Cu")
	)
	(gr_line
		(start 40.567864 -152.546558)
		(end 40.567864 -152.77973)
		(stroke
			(width 0.06985)
			(type default)
		)
		(layer "In5.Cu")
	)
	(gr_line
		(start 40.567864 -152.546558)
		(end 40.67048 -152.443942)
		(stroke
			(width 0.06985)
			(type default)
		)
		(layer "In5.Cu")
	)
	(gr_line
		(start 40.7416 -195.834)
		(end 40.812466 -195.904866)
		(stroke
			(width 0.0635)
			(type default)
		)
		(layer "In5.Cu")
	)
	(gr_line
		(start 40.96512 -141.2494)
		(end 41.21658 -141.50086)
		(stroke
			(width 0.06985)
			(type default)
		)
		(layer "In5.Cu")
	)
	(gr_line
		(start 41.139364 -152.6286)
		(end 41.290494 -152.77973)
		(stroke
			(width 0.06985)
			(type default)
		)
		(layer "In5.Cu")
	)
	(gr_line
		(start 41.139364 -152.445466)
		(end 41.139364 -152.6286)
		(stroke
			(width 0.06985)
			(type default)
		)
		(layer "In5.Cu")
	)
	(gr_line
		(start 41.290494 -152.77973)
		(end 41.36771 -152.77973)
		(stroke
			(width 0.06985)
			(type default)
		)
		(layer "In5.Cu")
	)
	(gr_line
		(start 41.534334 -195.904866)
		(end 41.6052 -195.834)
		(stroke
			(width 0.0635)
			(type default)
		)
		(layer "In5.Cu")
	)
	(gr_line
		(start 42.402506 -75.214734)
		(end 42.5958 -75.408028)
		(stroke
			(width 0.0635)
			(type default)
		)
		(layer "In5.Cu")
	)
	(gr_line
		(start 42.402506 -74.492612)
		(end 42.5958 -74.299318)
		(stroke
			(width 0.0635)
			(type default)
		)
		(layer "In5.Cu")
	)
	(gr_line
		(start 42.5704 -181.8386)
		(end 42.641266 -181.909466)
		(stroke
			(width 0.0635)
			(type default)
		)
		(layer "In5.Cu")
	)
	(gr_line
		(start 43.363134 -181.909466)
		(end 43.434 -181.8386)
		(stroke
			(width 0.0635)
			(type default)
		)
		(layer "In5.Cu")
	)
	(gr_line
		(start 46.932596 -49.754282)
		(end 46.96206 -49.747932)
		(stroke
			(width 0.06985)
			(type default)
		)
		(layer "In5.Cu")
	)
	(gr_line
		(start 46.96206 -49.747932)
		(end 46.991524 -49.754282)
		(stroke
			(width 0.06985)
			(type default)
		)
		(layer "In5.Cu")
	)
	(gr_line
		(start 46.99 -106.6546)
		(end 47.879254 -105.765346)
		(stroke
			(width 0.0635)
			(type default)
		)
		(layer "In5.Cu")
	)
	(gr_line
		(start 47.879254 -105.471976)
		(end 47.879254 -105.765346)
		(stroke
			(width 0.0635)
			(type default)
		)
		(layer "In5.Cu")
	)
	(gr_line
		(start 48.102774 -114.654076)
		(end 48.141636 -114.654076)
		(stroke
			(width 0.0635)
			(type default)
		)
		(layer "In5.Cu")
	)
	(gr_line
		(start 48.134778 -54.189376)
		(end 48.164242 -54.183026)
		(stroke
			(width 0.06985)
			(type default)
		)
		(layer "In5.Cu")
	)
	(gr_line
		(start 48.141636 -114.654076)
		(end 48.31207 -114.82451)
		(stroke
			(width 0.0635)
			(type default)
		)
		(layer "In5.Cu")
	)
	(gr_line
		(start 48.164242 -54.183026)
		(end 48.193706 -54.189376)
		(stroke
			(width 0.06985)
			(type default)
		)
		(layer "In5.Cu")
	)
	(gr_line
		(start 48.398176 -207.4799)
		(end 48.404018 -207.44688)
		(stroke
			(width 0.06985)
			(type default)
		)
		(layer "In5.Cu")
	)
	(gr_line
		(start 48.404018 -207.44688)
		(end 48.423576 -207.41894)
		(stroke
			(width 0.06985)
			(type default)
		)
		(layer "In5.Cu")
	)
	(gr_line
		(start 48.49368 -210.896454)
		(end 48.582072 -210.807808)
		(stroke
			(width 0.06985)
			(type default)
		)
		(layer "In5.Cu")
	)
	(gr_line
		(start 48.5648 -105.4354)
		(end 50.8254 -105.4354)
		(stroke
			(width 0.0635)
			(type default)
		)
		(layer "In5.Cu")
	)
	(gr_arc
		(start 48.582072 -210.807808)
		(mid 48.695227 -210.638622)
		(end 48.73498 -210.439)
		(stroke
			(width 0.06985)
			(type default)
		)
		(layer "In5.Cu")
	)
	(gr_line
		(start 48.8061 -103.232966)
		(end 49.0982 -102.940866)
		(stroke
			(width 0.0635)
			(type default)
		)
		(layer "In5.Cu")
	)
	(gr_line
		(start 49.033938 -114.82451)
		(end 49.204372 -114.654076)
		(stroke
			(width 0.0635)
			(type default)
		)
		(layer "In5.Cu")
	)
	(gr_arc
		(start 49.06518 -210.22945)
		(mid 49.127329 -210.584118)
		(end 49.30648 -210.896454)
		(stroke
			(width 0.06985)
			(type default)
		)
		(layer "In5.Cu")
	)
	(gr_line
		(start 49.0982 -102.677722)
		(end 49.0982 -102.940866)
		(stroke
			(width 0.0635)
			(type default)
		)
		(layer "In5.Cu")
	)
	(gr_line
		(start 49.32172 -50.587402)
		(end 49.351184 -50.593752)
		(stroke
			(width 0.06985)
			(type default)
		)
		(layer "In5.Cu")
	)
	(gr_line
		(start 49.351184 -50.593752)
		(end 49.380648 -50.587402)
		(stroke
			(width 0.06985)
			(type default)
		)
		(layer "In5.Cu")
	)
	(gr_line
		(start 49.434242 -205.975458)
		(end 49.445164 -205.959964)
		(stroke
			(width 0.06985)
			(type default)
		)
		(layer "In5.Cu")
	)
	(gr_line
		(start 49.445164 -205.959964)
		(end 49.460658 -205.949042)
		(stroke
			(width 0.06985)
			(type default)
		)
		(layer "In5.Cu")
	)
	(gr_line
		(start 49.7586 -102.616)
		(end 50.038 -102.616)
		(stroke
			(width 0.0635)
			(type default)
		)
		(layer "In5.Cu")
	)
	(gr_line
		(start 50.172874 -114.601498)
		(end 50.362612 -114.41176)
		(stroke
			(width 0.0635)
			(type default)
		)
		(layer "In5.Cu")
	)
	(gr_line
		(start 50.7365 -112.4966)
		(end 50.7365 -112.501934)
		(stroke
			(width 0.0635)
			(type default)
		)
		(layer "In5.Cu")
	)
	(gr_line
		(start 50.7746 -189.865)
		(end 50.845466 -189.794134)
		(stroke
			(width 0.0635)
			(type default)
		)
		(layer "In5.Cu")
	)
	(gr_line
		(start 50.7746 -175.768)
		(end 50.845466 -175.697134)
		(stroke
			(width 0.0635)
			(type default)
		)
		(layer "In5.Cu")
	)
	(gr_line
		(start 50.9524 -113.0046)
		(end 50.9524 -113.009934)
		(stroke
			(width 0.0635)
			(type default)
		)
		(layer "In5.Cu")
	)
	(gr_line
		(start 51.084734 -114.41176)
		(end 51.274472 -114.601498)
		(stroke
			(width 0.0635)
			(type default)
		)
		(layer "In5.Cu")
	)
	(gr_line
		(start 51.567334 -189.794134)
		(end 51.6382 -189.865)
		(stroke
			(width 0.0635)
			(type default)
		)
		(layer "In5.Cu")
	)
	(gr_line
		(start 51.567334 -175.697134)
		(end 51.6382 -175.768)
		(stroke
			(width 0.0635)
			(type default)
		)
		(layer "In5.Cu")
	)
	(gr_arc
		(start 51.693572 -210.896454)
		(mid 51.87271 -210.584109)
		(end 51.934872 -210.22945)
		(stroke
			(width 0.06985)
			(type default)
		)
		(layer "In5.Cu")
	)
	(gr_line
		(start 51.934872 -209.707226)
		(end 51.97094 -209.655664)
		(stroke
			(width 0.06985)
			(type default)
		)
		(layer "In5.Cu")
	)
	(gr_arc
		(start 52.265072 -210.22945)
		(mid 52.327221 -210.584119)
		(end 52.506372 -210.896454)
		(stroke
			(width 0.06985)
			(type default)
		)
		(layer "In5.Cu")
	)
	(gr_line
		(start 52.780692 -49.526952)
		(end 52.810156 -49.520602)
		(stroke
			(width 0.06985)
			(type default)
		)
		(layer "In5.Cu")
	)
	(gr_line
		(start 52.810156 -49.520602)
		(end 52.83962 -49.526952)
		(stroke
			(width 0.06985)
			(type default)
		)
		(layer "In5.Cu")
	)
	(gr_line
		(start 53.848 -111.433102)
		(end 54.50586 -111.433102)
		(stroke
			(width 0.0635)
			(type default)
		)
		(layer "In5.Cu")
	)
	(gr_line
		(start 53.8988 -108.9152)
		(end 54.211474 -108.602526)
		(stroke
			(width 0.0635)
			(type default)
		)
		(layer "In5.Cu")
	)
	(gr_line
		(start 54.5084 -111.433102)
		(end 54.530752 -111.433102)
		(stroke
			(width 0.0635)
			(type default)
		)
		(layer "In5.Cu")
	)
	(gr_line
		(start 54.660292 -119.01043)
		(end 54.966616 -119.316754)
		(stroke
			(width 0.0635)
			(type default)
		)
		(layer "In5.Cu")
	)
	(gr_line
		(start 54.660292 -118.288308)
		(end 54.935882 -118.012718)
		(stroke
			(width 0.0635)
			(type default)
		)
		(layer "In5.Cu")
	)
	(gr_arc
		(start 54.893718 -210.896454)
		(mid 55.072856 -210.584109)
		(end 55.135018 -210.22945)
		(stroke
			(width 0.06985)
			(type default)
		)
		(layer "In5.Cu")
	)
	(gr_line
		(start 54.933596 -108.602526)
		(end 55.16626 -108.83519)
		(stroke
			(width 0.0635)
			(type default)
		)
		(layer "In5.Cu")
	)
	(gr_line
		(start 54.935628 -117.675152)
		(end 54.935882 -117.675152)
		(stroke
			(width 0.0635)
			(type default)
		)
		(layer "In5.Cu")
	)
	(gr_line
		(start 54.935882 -117.675152)
		(end 54.935882 -118.012718)
		(stroke
			(width 0.0635)
			(type default)
		)
		(layer "In5.Cu")
	)
	(gr_line
		(start 55.005732 -205.321408)
		(end 55.016654 -205.305914)
		(stroke
			(width 0.06985)
			(type default)
		)
		(layer "In5.Cu")
	)
	(gr_line
		(start 55.0164 -112.037368)
		(end 55.245 -112.265968)
		(stroke
			(width 0.0635)
			(type default)
		)
		(layer "In5.Cu")
	)
	(gr_line
		(start 55.0164 -111.943642)
		(end 55.0164 -112.037368)
		(stroke
			(width 0.0635)
			(type default)
		)
		(layer "In5.Cu")
	)
	(gr_line
		(start 55.0164 -111.66602)
		(end 55.0164 -111.941102)
		(stroke
			(width 0.0635)
			(type default)
		)
		(layer "In5.Cu")
	)
	(gr_line
		(start 55.016654 -205.305914)
		(end 55.032148 -205.294992)
		(stroke
			(width 0.06985)
			(type default)
		)
		(layer "In5.Cu")
	)
	(gr_line
		(start 55.135018 -208.296002)
		(end 55.171086 -208.24444)
		(stroke
			(width 0.06985)
			(type default)
		)
		(layer "In5.Cu")
	)
	(gr_arc
		(start 55.465218 -210.22945)
		(mid 55.527364 -210.584121)
		(end 55.706518 -210.896454)
		(stroke
			(width 0.06985)
			(type default)
		)
		(layer "In5.Cu")
	)
	(gr_line
		(start 55.630572 -96.012)
		(end 55.823866 -96.205294)
		(stroke
			(width 0.0635)
			(type default)
		)
		(layer "In5.Cu")
	)
	(gr_line
		(start 55.664608 -204.851762)
		(end 56.252618 -204.440282)
		(stroke
			(width 0.06985)
			(type default)
		)
		(layer "In5.Cu")
	)
	(gr_line
		(start 55.827168 -205.144624)
		(end 56.085486 -205.19009)
		(stroke
			(width 0.06985)
			(type default)
		)
		(layer "In5.Cu")
	)
	(gr_line
		(start 55.932578 -56.170322)
		(end 55.96255 -56.176672)
		(stroke
			(width 0.06985)
			(type default)
		)
		(layer "In5.Cu")
	)
	(gr_line
		(start 55.96255 -56.176672)
		(end 55.992014 -56.170322)
		(stroke
			(width 0.06985)
			(type default)
		)
		(layer "In5.Cu")
	)
	(gr_line
		(start 56.085486 -205.19009)
		(end 56.42864 -204.949806)
		(stroke
			(width 0.06985)
			(type default)
		)
		(layer "In5.Cu")
	)
	(gr_line
		(start 56.301386 -201.15911)
		(end 56.329326 -201.139552)
		(stroke
			(width 0.06985)
			(type default)
		)
		(layer "In5.Cu")
	)
	(gr_line
		(start 56.329326 -201.139552)
		(end 56.362346 -201.13371)
		(stroke
			(width 0.06985)
			(type default)
		)
		(layer "In5.Cu")
	)
	(gr_line
		(start 56.42864 -204.949806)
		(end 56.47436 -204.69098)
		(stroke
			(width 0.06985)
			(type default)
		)
		(layer "In5.Cu")
	)
	(gr_line
		(start 56.45785 -50.296318)
		(end 56.477662 -50.300382)
		(stroke
			(width 0.06985)
			(type default)
		)
		(layer "In5.Cu")
	)
	(gr_line
		(start 56.477662 -50.300382)
		(end 56.495442 -50.311812)
		(stroke
			(width 0.06985)
			(type default)
		)
		(layer "In5.Cu")
	)
	(gr_line
		(start 56.545988 -96.205294)
		(end 56.739282 -96.012)
		(stroke
			(width 0.0635)
			(type default)
		)
		(layer "In5.Cu")
	)
	(gr_line
		(start 56.642 -126.212346)
		(end 56.642 -126.30658)
		(stroke
			(width 0.0635)
			(type default)
		)
		(layer "In5.Cu")
	)
	(gr_line
		(start 56.65978 -204.15504)
		(end 57.250076 -203.741528)
		(stroke
			(width 0.06985)
			(type default)
		)
		(layer "In5.Cu")
	)
	(gr_line
		(start 56.82107 -204.448156)
		(end 57.079896 -204.493876)
		(stroke
			(width 0.06985)
			(type default)
		)
		(layer "In5.Cu")
	)
	(gr_line
		(start 56.901842 -205.772258)
		(end 56.912764 -205.756764)
		(stroke
			(width 0.06985)
			(type default)
		)
		(layer "In5.Cu")
	)
	(gr_line
		(start 56.912764 -205.756764)
		(end 56.928258 -205.745842)
		(stroke
			(width 0.06985)
			(type default)
		)
		(layer "In5.Cu")
	)
	(gr_line
		(start 56.9468 -126.720346)
		(end 56.9468 -126.81458)
		(stroke
			(width 0.0635)
			(type default)
		)
		(layer "In5.Cu")
	)
	(gr_line
		(start 57.079896 -204.493876)
		(end 57.423304 -204.253338)
		(stroke
			(width 0.06985)
			(type default)
		)
		(layer "In5.Cu")
	)
	(gr_line
		(start 57.423304 -204.253338)
		(end 57.469024 -203.994512)
		(stroke
			(width 0.06985)
			(type default)
		)
		(layer "In5.Cu")
	)
	(gr_line
		(start 57.708292 -123.317)
		(end 57.796938 -123.317)
		(stroke
			(width 0.0635)
			(type default)
		)
		(layer "In5.Cu")
	)
	(gr_line
		(start 57.82183 -123.292108)
		(end 58.000138 -123.1138)
		(stroke
			(width 0.0635)
			(type default)
		)
		(layer "In5.Cu")
	)
	(gr_line
		(start 57.8358 -121.040398)
		(end 57.949338 -120.92686)
		(stroke
			(width 0.0635)
			(type default)
		)
		(layer "In5.Cu")
	)
	(gr_line
		(start 57.8358 -120.0912)
		(end 57.949338 -120.204738)
		(stroke
			(width 0.0635)
			(type default)
		)
		(layer "In5.Cu")
	)
	(gr_line
		(start 57.8358 -119.9388)
		(end 57.8358 -120.0912)
		(stroke
			(width 0.0635)
			(type default)
		)
		(layer "In5.Cu")
	)
	(gr_line
		(start 57.923176 -123.912884)
		(end 57.987692 -123.9774)
		(stroke
			(width 0.0635)
			(type default)
		)
		(layer "In5.Cu")
	)
	(gr_line
		(start 57.987692 -123.9774)
		(end 58.064654 -123.900438)
		(stroke
			(width 0.0635)
			(type default)
		)
		(layer "In5.Cu")
	)
	(gr_line
		(start 58.000138 -123.1138)
		(end 58.064654 -123.178316)
		(stroke
			(width 0.0635)
			(type default)
		)
		(layer "In5.Cu")
	)
	(gr_arc
		(start 58.0517 -196.2658)
		(mid 58.229786 -196.030804)
		(end 58.293 -195.742814)
		(stroke
			(width 0.06985)
			(type default)
		)
		(layer "In5.Cu")
	)
	(gr_arc
		(start 58.09361 -210.896454)
		(mid 58.272731 -210.584104)
		(end 58.33491 -210.22945)
		(stroke
			(width 0.06985)
			(type default)
		)
		(layer "In5.Cu")
	)
	(gr_line
		(start 58.216292 -123.7488)
		(end 58.304938 -123.7488)
		(stroke
			(width 0.0635)
			(type default)
		)
		(layer "In5.Cu")
	)
	(gr_line
		(start 58.264298 -204.81036)
		(end 58.848752 -204.401166)
		(stroke
			(width 0.06985)
			(type default)
		)
		(layer "In5.Cu")
	)
	(gr_line
		(start 58.292238 -186.762898)
		(end 58.293 -186.7662)
		(stroke
			(width 0.06985)
			(type default)
		)
		(layer "In5.Cu")
	)
	(gr_line
		(start 58.293 -186.7662)
		(end 58.293 -186.880246)
		(stroke
			(width 0.06985)
			(type default)
		)
		(layer "In5.Cu")
	)
	(gr_line
		(start 58.33491 -208.260442)
		(end 58.370978 -208.20888)
		(stroke
			(width 0.06985)
			(type default)
		)
		(layer "In5.Cu")
	)
	(gr_line
		(start 58.42381 -205.104746)
		(end 58.682382 -205.150466)
		(stroke
			(width 0.06985)
			(type default)
		)
		(layer "In5.Cu")
	)
	(gr_line
		(start 58.617612 -186.81954)
		(end 58.6232 -186.85129)
		(stroke
			(width 0.06985)
			(type default)
		)
		(layer "In5.Cu")
	)
	(gr_line
		(start 58.617612 -186.81954)
		(end 58.6232 -186.78779)
		(stroke
			(width 0.06985)
			(type default)
		)
		(layer "In5.Cu")
	)
	(gr_arc
		(start 58.6232 -195.8086)
		(mid 58.662875 -196.008058)
		(end 58.775854 -196.177154)
		(stroke
			(width 0.06985)
			(type default)
		)
		(layer "In5.Cu")
	)
	(gr_arc
		(start 58.66511 -210.22945)
		(mid 58.727294 -210.584101)
		(end 58.90641 -210.896454)
		(stroke
			(width 0.06985)
			(type default)
		)
		(layer "In5.Cu")
	)
	(gr_line
		(start 58.682382 -205.150466)
		(end 59.025536 -204.910182)
		(stroke
			(width 0.06985)
			(type default)
		)
		(layer "In5.Cu")
	)
	(gr_line
		(start 58.775854 -196.177154)
		(end 58.8645 -196.2658)
		(stroke
			(width 0.06985)
			(type default)
		)
		(layer "In5.Cu")
	)
	(gr_line
		(start 59.025536 -204.910182)
		(end 59.071256 -204.65161)
		(stroke
			(width 0.06985)
			(type default)
		)
		(layer "In5.Cu")
	)
	(gr_line
		(start 59.257184 -204.115162)
		(end 59.844178 -203.70419)
		(stroke
			(width 0.06985)
			(type default)
		)
		(layer "In5.Cu")
	)
	(gr_line
		(start 59.41822 -204.408532)
		(end 59.676792 -204.453998)
		(stroke
			(width 0.06985)
			(type default)
		)
		(layer "In5.Cu")
	)
	(gr_line
		(start 59.676792 -204.453998)
		(end 60.0202 -204.213714)
		(stroke
			(width 0.06985)
			(type default)
		)
		(layer "In5.Cu")
	)
	(gr_line
		(start 60.01766 -201.804016)
		(end 60.0456 -201.784458)
		(stroke
			(width 0.06985)
			(type default)
		)
		(layer "In5.Cu")
	)
	(gr_line
		(start 60.0202 -204.213714)
		(end 60.06592 -203.955142)
		(stroke
			(width 0.06985)
			(type default)
		)
		(layer "In5.Cu")
	)
	(gr_line
		(start 60.0456 -201.784458)
		(end 60.07862 -201.778616)
		(stroke
			(width 0.06985)
			(type default)
		)
		(layer "In5.Cu")
	)
	(gr_line
		(start 60.076842 -205.772258)
		(end 60.087764 -205.756764)
		(stroke
			(width 0.06985)
			(type default)
		)
		(layer "In5.Cu")
	)
	(gr_line
		(start 60.087764 -205.756764)
		(end 60.103258 -205.745842)
		(stroke
			(width 0.06985)
			(type default)
		)
		(layer "In5.Cu")
	)
	(gr_line
		(start 60.316872 -54.91353)
		(end 60.346336 -54.90718)
		(stroke
			(width 0.06985)
			(type default)
		)
		(layer "In5.Cu")
	)
	(gr_line
		(start 60.346336 -54.90718)
		(end 60.3758 -54.91353)
		(stroke
			(width 0.06985)
			(type default)
		)
		(layer "In5.Cu")
	)
	(gr_line
		(start 61.138054 -177.94097)
		(end 61.215524 -177.8635)
		(stroke
			(width 0.06985)
			(type default)
		)
		(layer "In5.Cu")
	)
	(gr_line
		(start 61.33338 -53.848)
		(end 61.35116 -53.85943)
		(stroke
			(width 0.06985)
			(type default)
		)
		(layer "In5.Cu")
	)
	(gr_line
		(start 61.35116 -53.85943)
		(end 61.370972 -53.863494)
		(stroke
			(width 0.06985)
			(type default)
		)
		(layer "In5.Cu")
	)
	(gr_line
		(start 61.392054 -178.154076)
		(end 61.40704 -178.132486)
		(stroke
			(width 0.06985)
			(type default)
		)
		(layer "In5.Cu")
	)
	(gr_line
		(start 61.40704 -178.132486)
		(end 61.42863 -178.117246)
		(stroke
			(width 0.06985)
			(type default)
		)
		(layer "In5.Cu")
	)
	(gr_line
		(start 61.502544 -202.542902)
		(end 61.530484 -202.523344)
		(stroke
			(width 0.06985)
			(type default)
		)
		(layer "In5.Cu")
	)
	(gr_line
		(start 61.530484 -202.523344)
		(end 61.563504 -202.517502)
		(stroke
			(width 0.06985)
			(type default)
		)
		(layer "In5.Cu")
	)
	(gr_line
		(start 61.976 -97.023428)
		(end 62.319408 -97.023428)
		(stroke
			(width 0.0635)
			(type default)
		)
		(layer "In5.Cu")
	)
	(gr_line
		(start 61.976 -95.914718)
		(end 62.359794 -96.298512)
		(stroke
			(width 0.0635)
			(type default)
		)
		(layer "In5.Cu")
	)
	(gr_line
		(start 62.317122 -123.2916)
		(end 62.5602 -123.2916)
		(stroke
			(width 0.0635)
			(type default)
		)
		(layer "In5.Cu")
	)
	(gr_line
		(start 62.359794 -96.298512)
		(end 62.359794 -96.341692)
		(stroke
			(width 0.0635)
			(type default)
		)
		(layer "In5.Cu")
	)
	(gr_line
		(start 62.381638 -123.949206)
		(end 62.587378 -124.154946)
		(stroke
			(width 0.0635)
			(type default)
		)
		(layer "In5.Cu")
	)
	(gr_line
		(start 63.332868 -111.522256)
		(end 64.926972 -110.045246)
		(stroke
			(width 0.0635)
			(type default)
		)
		(layer "In5.Cu")
	)
	(gr_line
		(start 63.4238 -107.686856)
		(end 63.737744 -108.0008)
		(stroke
			(width 0.0635)
			(type default)
		)
		(layer "In5.Cu")
	)
	(gr_line
		(start 63.4238 -107.59694)
		(end 63.4238 -107.686856)
		(stroke
			(width 0.0635)
			(type default)
		)
		(layer "In5.Cu")
	)
	(gr_arc
		(start 63.693548 -210.896454)
		(mid 63.872662 -210.584102)
		(end 63.934848 -210.22945)
		(stroke
			(width 0.06985)
			(type default)
		)
		(layer "In5.Cu")
	)
	(gr_line
		(start 63.737744 -108.0008)
		(end 63.9318 -108.0008)
		(stroke
			(width 0.0635)
			(type default)
		)
		(layer "In5.Cu")
	)
	(gr_line
		(start 63.934848 -207.78978)
		(end 63.970916 -207.738218)
		(stroke
			(width 0.06985)
			(type default)
		)
		(layer "In5.Cu")
	)
	(gr_line
		(start 64.18707 -202.88631)
		(end 64.21501 -202.866752)
		(stroke
			(width 0.06985)
			(type default)
		)
		(layer "In5.Cu")
	)
	(gr_line
		(start 64.21501 -202.866752)
		(end 64.24803 -202.86091)
		(stroke
			(width 0.06985)
			(type default)
		)
		(layer "In5.Cu")
	)
	(gr_arc
		(start 64.265048 -210.22945)
		(mid 64.327232 -210.584101)
		(end 64.506348 -210.896454)
		(stroke
			(width 0.06985)
			(type default)
		)
		(layer "In5.Cu")
	)
	(gr_line
		(start 64.712596 -109.62767)
		(end 64.815212 -109.738414)
		(stroke
			(width 0.0635)
			(type default)
		)
		(layer "In5.Cu")
	)
	(gr_line
		(start 64.926972 -110.045246)
		(end 64.933576 -109.869478)
		(stroke
			(width 0.0635)
			(type default)
		)
		(layer "In5.Cu")
	)
	(gr_line
		(start 65.31102 -109.522006)
		(end 65.486788 -109.528864)
		(stroke
			(width 0.0635)
			(type default)
		)
		(layer "In5.Cu")
	)
	(gr_line
		(start 65.486788 -109.528864)
		(end 67.0814 -108.0516)
		(stroke
			(width 0.0635)
			(type default)
		)
		(layer "In5.Cu")
	)
	(gr_line
		(start 65.791842 -205.137258)
		(end 65.802764 -205.121764)
		(stroke
			(width 0.06985)
			(type default)
		)
		(layer "In5.Cu")
	)
	(gr_line
		(start 65.802764 -205.121764)
		(end 65.818258 -205.110842)
		(stroke
			(width 0.06985)
			(type default)
		)
		(layer "In5.Cu")
	)
	(gr_arc
		(start 66.893694 -210.896454)
		(mid 67.072817 -210.584104)
		(end 67.134994 -210.22945)
		(stroke
			(width 0.06985)
			(type default)
		)
		(layer "In5.Cu")
	)
	(gr_line
		(start 67.134994 -207.954118)
		(end 67.171062 -207.902556)
		(stroke
			(width 0.06985)
			(type default)
		)
		(layer "In5.Cu")
	)
	(gr_arc
		(start 67.465194 -210.22945)
		(mid 67.527378 -210.584101)
		(end 67.706494 -210.896454)
		(stroke
			(width 0.06985)
			(type default)
		)
		(layer "In5.Cu")
	)
	(gr_line
		(start 67.545458 -202.279504)
		(end 68.250054 -202.155298)
		(stroke
			(width 0.06985)
			(type default)
		)
		(layer "In5.Cu")
	)
	(gr_line
		(start 67.567048 -202.613514)
		(end 67.781932 -202.764136)
		(stroke
			(width 0.06985)
			(type default)
		)
		(layer "In5.Cu")
	)
	(gr_line
		(start 67.781932 -202.764136)
		(end 68.194682 -202.691492)
		(stroke
			(width 0.06985)
			(type default)
		)
		(layer "In5.Cu")
	)
	(gr_line
		(start 67.922648 -203.637388)
		(end 67.950588 -203.61783)
		(stroke
			(width 0.06985)
			(type default)
		)
		(layer "In5.Cu")
	)
	(gr_line
		(start 67.950588 -203.61783)
		(end 67.983608 -203.611988)
		(stroke
			(width 0.06985)
			(type default)
		)
		(layer "In5.Cu")
	)
	(gr_line
		(start 68.194682 -202.691492)
		(end 68.345304 -202.476354)
		(stroke
			(width 0.06985)
			(type default)
		)
		(layer "In5.Cu")
	)
	(gr_line
		(start 68.718684 -205.691994)
		(end 68.729606 -205.6765)
		(stroke
			(width 0.06985)
			(type default)
		)
		(layer "In5.Cu")
	)
	(gr_line
		(start 68.729606 -205.6765)
		(end 68.7451 -205.665578)
		(stroke
			(width 0.06985)
			(type default)
		)
		(layer "In5.Cu")
	)
	(gr_line
		(start 68.741036 -202.068684)
		(end 69.445632 -201.944478)
		(stroke
			(width 0.06985)
			(type default)
		)
		(layer "In5.Cu")
	)
	(gr_line
		(start 68.757038 -55.433468)
		(end 68.786502 -55.439818)
		(stroke
			(width 0.06985)
			(type default)
		)
		(layer "In5.Cu")
	)
	(gr_line
		(start 68.762626 -202.402694)
		(end 68.977764 -202.553316)
		(stroke
			(width 0.06985)
			(type default)
		)
		(layer "In5.Cu")
	)
	(gr_line
		(start 68.786502 -55.439818)
		(end 68.815966 -55.433468)
		(stroke
			(width 0.06985)
			(type default)
		)
		(layer "In5.Cu")
	)
	(gr_line
		(start 68.792852 -57.040272)
		(end 68.822316 -57.046622)
		(stroke
			(width 0.06985)
			(type default)
		)
		(layer "In5.Cu")
	)
	(gr_line
		(start 68.822316 -57.046622)
		(end 68.85178 -57.040272)
		(stroke
			(width 0.06985)
			(type default)
		)
		(layer "In5.Cu")
	)
	(gr_line
		(start 68.977764 -202.553316)
		(end 69.390514 -202.480672)
		(stroke
			(width 0.06985)
			(type default)
		)
		(layer "In5.Cu")
	)
	(gr_line
		(start 69.390514 -202.480672)
		(end 69.540882 -202.265534)
		(stroke
			(width 0.06985)
			(type default)
		)
		(layer "In5.Cu")
	)
	(gr_arc
		(start 70.093586 -210.896454)
		(mid 70.273208 -210.520693)
		(end 70.334886 -210.1088)
		(stroke
			(width 0.06985)
			(type default)
		)
		(layer "In5.Cu")
	)
	(gr_line
		(start 70.334886 -208.081372)
		(end 70.370954 -208.02981)
		(stroke
			(width 0.06985)
			(type default)
		)
		(layer "In5.Cu")
	)
	(gr_arc
		(start 70.665086 -210.1088)
		(mid 70.726765 -210.520692)
		(end 70.906386 -210.896454)
		(stroke
			(width 0.06985)
			(type default)
		)
		(layer "In5.Cu")
	)
	(gr_line
		(start 70.744842 -204.26553)
		(end 70.772782 -204.245972)
		(stroke
			(width 0.06985)
			(type default)
		)
		(layer "In5.Cu")
	)
	(gr_line
		(start 70.772782 -204.245972)
		(end 70.805802 -204.24013)
		(stroke
			(width 0.06985)
			(type default)
		)
		(layer "In5.Cu")
	)
	(gr_line
		(start 70.931278 -57.49036)
		(end 71.124572 -57.683654)
		(stroke
			(width 0.0635)
			(type default)
		)
		(layer "In5.Cu")
	)
	(gr_line
		(start 71.506842 -206.407258)
		(end 71.517764 -206.391764)
		(stroke
			(width 0.06985)
			(type default)
		)
		(layer "In5.Cu")
	)
	(gr_line
		(start 71.517764 -206.391764)
		(end 71.533258 -206.380842)
		(stroke
			(width 0.06985)
			(type default)
		)
		(layer "In5.Cu")
	)
	(gr_line
		(start 71.72198 -198.760842)
		(end 71.755 -198.755)
		(stroke
			(width 0.06985)
			(type default)
		)
		(layer "In5.Cu")
	)
	(gr_line
		(start 71.755 -198.755)
		(end 71.78294 -198.735442)
		(stroke
			(width 0.06985)
			(type default)
		)
		(layer "In5.Cu")
	)
	(gr_line
		(start 71.846694 -57.683654)
		(end 72.039988 -57.49036)
		(stroke
			(width 0.0635)
			(type default)
		)
		(layer "In5.Cu")
	)
	(gr_line
		(start 71.89216 -54.44236)
		(end 71.921624 -54.43601)
		(stroke
			(width 0.06985)
			(type default)
		)
		(layer "In5.Cu")
	)
	(gr_line
		(start 71.921624 -54.43601)
		(end 71.951088 -54.44236)
		(stroke
			(width 0.06985)
			(type default)
		)
		(layer "In5.Cu")
	)
	(gr_line
		(start 71.937118 -204.040486)
		(end 72.645524 -203.915518)
		(stroke
			(width 0.06985)
			(type default)
		)
		(layer "In5.Cu")
	)
	(gr_line
		(start 71.947024 -56.0451)
		(end 71.976488 -56.03875)
		(stroke
			(width 0.06985)
			(type default)
		)
		(layer "In5.Cu")
	)
	(gr_line
		(start 71.958962 -204.37475)
		(end 72.1741 -204.525372)
		(stroke
			(width 0.06985)
			(type default)
		)
		(layer "In5.Cu")
	)
	(gr_line
		(start 71.976488 -56.03875)
		(end 72.005952 -56.0451)
		(stroke
			(width 0.06985)
			(type default)
		)
		(layer "In5.Cu")
	)
	(gr_line
		(start 72.1741 -204.525372)
		(end 72.58685 -204.452474)
		(stroke
			(width 0.06985)
			(type default)
		)
		(layer "In5.Cu")
	)
	(gr_line
		(start 72.58685 -204.452474)
		(end 72.737472 -204.237336)
		(stroke
			(width 0.06985)
			(type default)
		)
		(layer "In5.Cu")
	)
	(gr_line
		(start 73.131934 -203.829666)
		(end 73.840848 -203.704698)
		(stroke
			(width 0.06985)
			(type default)
		)
		(layer "In5.Cu")
	)
	(gr_line
		(start 73.154794 -204.163676)
		(end 73.369678 -204.314552)
		(stroke
			(width 0.06985)
			(type default)
		)
		(layer "In5.Cu")
	)
	(gr_line
		(start 73.369678 -204.314552)
		(end 73.782428 -204.241654)
		(stroke
			(width 0.06985)
			(type default)
		)
		(layer "In5.Cu")
	)
	(gr_line
		(start 73.65492 -204.89545)
		(end 73.68286 -204.875892)
		(stroke
			(width 0.06985)
			(type default)
		)
		(layer "In5.Cu")
	)
	(gr_line
		(start 73.68286 -204.875892)
		(end 73.71588 -204.87005)
		(stroke
			(width 0.06985)
			(type default)
		)
		(layer "In5.Cu")
	)
	(gr_line
		(start 73.782428 -204.241654)
		(end 73.93305 -204.026516)
		(stroke
			(width 0.06985)
			(type default)
		)
		(layer "In5.Cu")
	)
	(gr_line
		(start 74.212196 -202.513946)
		(end 74.91476 -202.389994)
		(stroke
			(width 0.06985)
			(type default)
		)
		(layer "In5.Cu")
	)
	(gr_line
		(start 74.232008 -202.847956)
		(end 74.447146 -202.998578)
		(stroke
			(width 0.06985)
			(type default)
		)
		(layer "In5.Cu")
	)
	(gr_line
		(start 74.447146 -202.998578)
		(end 74.859896 -202.92568)
		(stroke
			(width 0.06985)
			(type default)
		)
		(layer "In5.Cu")
	)
	(gr_line
		(start 74.694288 -196.293486)
		(end 74.722228 -196.273928)
		(stroke
			(width 0.06985)
			(type default)
		)
		(layer "In5.Cu")
	)
	(gr_line
		(start 74.722228 -196.273928)
		(end 74.755248 -196.268086)
		(stroke
			(width 0.06985)
			(type default)
		)
		(layer "In5.Cu")
	)
	(gr_line
		(start 74.859896 -202.92568)
		(end 75.010264 -202.710796)
		(stroke
			(width 0.06985)
			(type default)
		)
		(layer "In5.Cu")
	)
	(gr_line
		(start 75.348338 -55.502048)
		(end 75.377802 -55.508398)
		(stroke
			(width 0.06985)
			(type default)
		)
		(layer "In5.Cu")
	)
	(gr_line
		(start 75.377802 -55.508398)
		(end 75.407266 -55.502048)
		(stroke
			(width 0.06985)
			(type default)
		)
		(layer "In5.Cu")
	)
	(gr_line
		(start 75.405488 -202.303126)
		(end 76.111608 -202.178666)
		(stroke
			(width 0.06985)
			(type default)
		)
		(layer "In5.Cu")
	)
	(gr_line
		(start 75.427586 -202.637136)
		(end 75.642724 -202.787758)
		(stroke
			(width 0.06985)
			(type default)
		)
		(layer "In5.Cu")
	)
	(gr_line
		(start 75.642724 -202.787758)
		(end 76.055474 -202.71486)
		(stroke
			(width 0.06985)
			(type default)
		)
		(layer "In5.Cu")
	)
	(gr_line
		(start 75.86091 -204.49159)
		(end 76.568808 -204.366876)
		(stroke
			(width 0.06985)
			(type default)
		)
		(layer "In5.Cu")
	)
	(gr_line
		(start 75.884024 -204.8256)
		(end 76.099162 -204.976222)
		(stroke
			(width 0.06985)
			(type default)
		)
		(layer "In5.Cu")
	)
	(gr_line
		(start 76.055474 -202.71486)
		(end 76.20635 -202.499976)
		(stroke
			(width 0.06985)
			(type default)
		)
		(layer "In5.Cu")
	)
	(gr_line
		(start 76.099162 -204.976222)
		(end 76.511912 -204.903324)
		(stroke
			(width 0.06985)
			(type default)
		)
		(layer "In5.Cu")
	)
	(gr_line
		(start 76.511912 -204.903324)
		(end 76.662534 -204.688186)
		(stroke
			(width 0.06985)
			(type default)
		)
		(layer "In5.Cu")
	)
	(gr_line
		(start 76.693014 -54.891432)
		(end 76.722478 -54.885082)
		(stroke
			(width 0.06985)
			(type default)
		)
		(layer "In5.Cu")
	)
	(gr_line
		(start 76.722478 -54.885082)
		(end 76.751942 -54.891432)
		(stroke
			(width 0.06985)
			(type default)
		)
		(layer "In5.Cu")
	)
	(gr_line
		(start 77.056488 -204.281024)
		(end 77.765148 -204.155802)
		(stroke
			(width 0.06985)
			(type default)
		)
		(layer "In5.Cu")
	)
	(gr_line
		(start 77.079348 -204.61478)
		(end 77.29474 -204.765402)
		(stroke
			(width 0.06985)
			(type default)
		)
		(layer "In5.Cu")
	)
	(gr_line
		(start 77.29474 -204.765402)
		(end 77.70749 -204.692504)
		(stroke
			(width 0.06985)
			(type default)
		)
		(layer "In5.Cu")
	)
	(gr_line
		(start 77.70749 -204.692504)
		(end 77.858112 -204.477366)
		(stroke
			(width 0.06985)
			(type default)
		)
		(layer "In5.Cu")
	)
	(gr_line
		(start 78.423262 -57.7469)
		(end 78.452726 -57.75325)
		(stroke
			(width 0.06985)
			(type default)
		)
		(layer "In5.Cu")
	)
	(gr_line
		(start 78.452726 -57.75325)
		(end 78.48219 -57.7469)
		(stroke
			(width 0.06985)
			(type default)
		)
		(layer "In5.Cu")
	)
	(gr_line
		(start 79.433674 -55.798974)
		(end 79.463138 -55.805324)
		(stroke
			(width 0.06985)
			(type default)
		)
		(layer "In5.Cu")
	)
	(gr_line
		(start 79.463138 -55.805324)
		(end 79.492602 -55.798974)
		(stroke
			(width 0.06985)
			(type default)
		)
		(layer "In5.Cu")
	)
	(gr_arc
		(start 79.693516 -210.896454)
		(mid 79.872636 -210.584103)
		(end 79.934816 -210.22945)
		(stroke
			(width 0.06985)
			(type default)
		)
		(layer "In5.Cu")
	)
	(gr_line
		(start 79.934816 -209.098896)
		(end 79.971646 -209.046318)
		(stroke
			(width 0.06985)
			(type default)
		)
		(layer "In5.Cu")
	)
	(gr_arc
		(start 80.265016 -210.22945)
		(mid 80.3272 -210.584101)
		(end 80.506316 -210.896454)
		(stroke
			(width 0.06985)
			(type default)
		)
		(layer "In5.Cu")
	)
	(gr_line
		(start 80.98155 -207.604106)
		(end 80.99171 -207.589882)
		(stroke
			(width 0.06985)
			(type default)
		)
		(layer "In5.Cu")
	)
	(gr_line
		(start 80.99171 -207.589882)
		(end 81.005934 -207.579722)
		(stroke
			(width 0.06985)
			(type default)
		)
		(layer "In5.Cu")
	)
	(gr_line
		(start 81.407 -134.874)
		(end 81.617566 -134.663434)
		(stroke
			(width 0.0635)
			(type default)
		)
		(layer "In5.Cu")
	)
	(gr_line
		(start 81.463388 -207.25892)
		(end 82.04708 -206.849472)
		(stroke
			(width 0.06985)
			(type default)
		)
		(layer "In5.Cu")
	)
	(gr_line
		(start 81.534 -133.858)
		(end 81.617566 -133.941566)
		(stroke
			(width 0.0635)
			(type default)
		)
		(layer "In5.Cu")
	)
	(gr_line
		(start 81.6229 -207.553306)
		(end 81.881218 -207.598772)
		(stroke
			(width 0.06985)
			(type default)
		)
		(layer "In5.Cu")
	)
	(gr_line
		(start 81.881218 -207.598772)
		(end 82.224372 -207.35798)
		(stroke
			(width 0.06985)
			(type default)
		)
		(layer "In5.Cu")
	)
	(gr_line
		(start 82.224372 -207.35798)
		(end 82.269838 -207.099662)
		(stroke
			(width 0.06985)
			(type default)
		)
		(layer "In5.Cu")
	)
	(gr_line
		(start 82.418428 -206.588614)
		(end 82.431636 -206.57947)
		(stroke
			(width 0.06985)
			(type default)
		)
		(layer "In5.Cu")
	)
	(gr_line
		(start 82.457544 -206.561182)
		(end 83.04149 -206.15148)
		(stroke
			(width 0.06985)
			(type default)
		)
		(layer "In5.Cu")
	)
	(gr_line
		(start 82.465164 -206.9592)
		(end 82.613246 -206.855314)
		(stroke
			(width 0.06985)
			(type default)
		)
		(layer "In5.Cu")
	)
	(gr_line
		(start 82.616802 -206.856076)
		(end 82.87512 -206.901288)
		(stroke
			(width 0.06985)
			(type default)
		)
		(layer "In5.Cu")
	)
	(gr_line
		(start 82.87512 -206.901288)
		(end 83.218274 -206.660496)
		(stroke
			(width 0.06985)
			(type default)
		)
		(layer "In5.Cu")
	)
	(gr_arc
		(start 82.893662 -210.896454)
		(mid 83.0728 -210.584109)
		(end 83.134962 -210.22945)
		(stroke
			(width 0.06985)
			(type default)
		)
		(layer "In5.Cu")
	)
	(gr_line
		(start 82.919062 -199.087486)
		(end 82.952082 -199.081644)
		(stroke
			(width 0.06985)
			(type default)
		)
		(layer "In5.Cu")
	)
	(gr_line
		(start 82.952082 -199.081644)
		(end 82.980022 -199.062086)
		(stroke
			(width 0.06985)
			(type default)
		)
		(layer "In5.Cu")
	)
	(gr_line
		(start 83.022948 -198.068438)
		(end 83.055968 -198.062596)
		(stroke
			(width 0.06985)
			(type default)
		)
		(layer "In5.Cu")
	)
	(gr_line
		(start 83.055968 -198.062596)
		(end 83.083908 -198.043038)
		(stroke
			(width 0.06985)
			(type default)
		)
		(layer "In5.Cu")
	)
	(gr_line
		(start 83.134962 -208.98993)
		(end 83.17103 -208.938368)
		(stroke
			(width 0.06985)
			(type default)
		)
		(layer "In5.Cu")
	)
	(gr_line
		(start 83.193636 -208.90611)
		(end 83.195668 -208.903062)
		(stroke
			(width 0.06985)
			(type default)
		)
		(layer "In5.Cu")
	)
	(gr_line
		(start 83.218274 -206.660496)
		(end 83.263486 -206.402178)
		(stroke
			(width 0.06985)
			(type default)
		)
		(layer "In5.Cu")
	)
	(gr_line
		(start 83.273392 -208.792318)
		(end 83.550252 -208.39684)
		(stroke
			(width 0.06985)
			(type default)
		)
		(layer "In5.Cu")
	)
	(gr_arc
		(start 83.465162 -210.22945)
		(mid 83.52731 -210.584119)
		(end 83.706462 -210.896454)
		(stroke
			(width 0.06985)
			(type default)
		)
		(layer "In5.Cu")
	)
	(gr_line
		(start 83.55711 -208.962752)
		(end 83.81492 -208.594452)
		(stroke
			(width 0.06985)
			(type default)
		)
		(layer "In5.Cu")
	)
	(gr_line
		(start 83.568794 -208.370424)
		(end 83.976464 -207.78851)
		(stroke
			(width 0.06985)
			(type default)
		)
		(layer "In5.Cu")
	)
	(gr_line
		(start 83.818476 -208.593944)
		(end 84.076794 -208.548478)
		(stroke
			(width 0.06985)
			(type default)
		)
		(layer "In5.Cu")
	)
	(gr_line
		(start 84.076794 -208.548478)
		(end 84.317078 -208.20507)
		(stroke
			(width 0.06985)
			(type default)
		)
		(layer "In5.Cu")
	)
	(gr_line
		(start 84.264246 -207.37703)
		(end 84.674202 -206.791814)
		(stroke
			(width 0.06985)
			(type default)
		)
		(layer "In5.Cu")
	)
	(gr_line
		(start 84.271612 -207.946498)
		(end 84.317078 -208.20507)
		(stroke
			(width 0.06985)
			(type default)
		)
		(layer "In5.Cu")
	)
	(gr_line
		(start 84.51469 -207.599534)
		(end 84.773262 -207.553814)
		(stroke
			(width 0.06985)
			(type default)
		)
		(layer "In5.Cu")
	)
	(gr_line
		(start 84.547456 -194.877182)
		(end 84.580476 -194.87134)
		(stroke
			(width 0.06985)
			(type default)
		)
		(layer "In5.Cu")
	)
	(gr_line
		(start 84.57057 -201.022712)
		(end 84.60359 -201.01687)
		(stroke
			(width 0.06985)
			(type default)
		)
		(layer "In5.Cu")
	)
	(gr_line
		(start 84.580476 -194.87134)
		(end 84.608416 -194.851782)
		(stroke
			(width 0.06985)
			(type default)
		)
		(layer "In5.Cu")
	)
	(gr_line
		(start 84.60359 -201.01687)
		(end 84.63153 -200.997312)
		(stroke
			(width 0.06985)
			(type default)
		)
		(layer "In5.Cu")
	)
	(gr_line
		(start 84.773262 -207.553814)
		(end 85.013546 -207.21066)
		(stroke
			(width 0.06985)
			(type default)
		)
		(layer "In5.Cu")
	)
	(gr_line
		(start 84.96808 -206.952088)
		(end 85.013546 -207.21066)
		(stroke
			(width 0.06985)
			(type default)
		)
		(layer "In5.Cu")
	)
	(gr_line
		(start 84.98078 -199.540876)
		(end 85.0138 -199.535034)
		(stroke
			(width 0.06985)
			(type default)
		)
		(layer "In5.Cu")
	)
	(gr_line
		(start 85.0138 -199.535034)
		(end 85.04174 -199.515476)
		(stroke
			(width 0.06985)
			(type default)
		)
		(layer "In5.Cu")
	)
	(gr_line
		(start 85.05698 -203.205842)
		(end 85.09 -203.2)
		(stroke
			(width 0.06985)
			(type default)
		)
		(layer "In5.Cu")
	)
	(gr_line
		(start 85.05698 -202.062842)
		(end 85.09 -202.057)
		(stroke
			(width 0.06985)
			(type default)
		)
		(layer "In5.Cu")
	)
	(gr_line
		(start 85.09 -203.2)
		(end 85.11794 -203.180442)
		(stroke
			(width 0.06985)
			(type default)
		)
		(layer "In5.Cu")
	)
	(gr_line
		(start 85.09 -202.057)
		(end 85.11794 -202.037442)
		(stroke
			(width 0.06985)
			(type default)
		)
		(layer "In5.Cu")
	)
	(gr_line
		(start 85.476842 -205.645258)
		(end 85.487764 -205.629764)
		(stroke
			(width 0.06985)
			(type default)
		)
		(layer "In5.Cu")
	)
	(gr_line
		(start 85.487764 -205.629764)
		(end 85.503258 -205.618842)
		(stroke
			(width 0.06985)
			(type default)
		)
		(layer "In5.Cu")
	)
	(gr_arc
		(start 86.093554 -210.896454)
		(mid 86.272692 -210.584109)
		(end 86.334854 -210.22945)
		(stroke
			(width 0.06985)
			(type default)
		)
		(layer "In5.Cu")
	)
	(gr_line
		(start 86.334854 -208.01203)
		(end 86.370922 -207.960468)
		(stroke
			(width 0.06985)
			(type default)
		)
		(layer "In5.Cu")
	)
	(gr_arc
		(start 86.665054 -210.22945)
		(mid 86.727202 -210.584119)
		(end 86.906354 -210.896454)
		(stroke
			(width 0.06985)
			(type default)
		)
		(layer "In5.Cu")
	)
	(gr_line
		(start 86.779608 -77.478636)
		(end 86.988904 -77.26934)
		(stroke
			(width 0.06985)
			(type default)
		)
		(layer "In5.Cu")
	)
	(gr_line
		(start 86.779608 -76.589636)
		(end 86.988904 -76.798932)
		(stroke
			(width 0.06985)
			(type default)
		)
		(layer "In5.Cu")
	)
	(gr_line
		(start 88.29421 -205.213458)
		(end 88.305132 -205.197964)
		(stroke
			(width 0.06985)
			(type default)
		)
		(layer "In5.Cu")
	)
	(gr_line
		(start 88.305132 -205.197964)
		(end 88.320626 -205.187042)
		(stroke
			(width 0.06985)
			(type default)
		)
		(layer "In5.Cu")
	)
	(gr_arc
		(start 89.2937 -210.896454)
		(mid 89.472838 -210.584109)
		(end 89.535 -210.22945)
		(stroke
			(width 0.06985)
			(type default)
		)
		(layer "In5.Cu")
	)
	(gr_line
		(start 89.535 -207.280764)
		(end 89.57183 -207.228186)
		(stroke
			(width 0.06985)
			(type default)
		)
		(layer "In5.Cu")
	)
	(gr_arc
		(start 89.8652 -210.22945)
		(mid 89.92735 -210.584117)
		(end 90.1065 -210.896454)
		(stroke
			(width 0.06985)
			(type default)
		)
		(layer "In5.Cu")
	)
	(gr_line
		(start 91.402408 -53.267102)
		(end 91.42222 -53.263038)
		(stroke
			(width 0.06985)
			(type default)
		)
		(layer "In5.Cu")
	)
	(gr_line
		(start 91.42222 -53.263038)
		(end 91.44 -53.251608)
		(stroke
			(width 0.06985)
			(type default)
		)
		(layer "In5.Cu")
	)
	(gr_line
		(start 91.680538 -77.201776)
		(end 91.855798 -77.377036)
		(stroke
			(width 0.06985)
			(type default)
		)
		(layer "In5.Cu")
	)
	(gr_line
		(start 91.69273 -54.938422)
		(end 91.712542 -54.934358)
		(stroke
			(width 0.06985)
			(type default)
		)
		(layer "In5.Cu")
	)
	(gr_line
		(start 91.712542 -54.934358)
		(end 91.730322 -54.922928)
		(stroke
			(width 0.06985)
			(type default)
		)
		(layer "In5.Cu")
	)
	(gr_line
		(start 91.736418 -204.136752)
		(end 91.74734 -204.121258)
		(stroke
			(width 0.06985)
			(type default)
		)
		(layer "In5.Cu")
	)
	(gr_line
		(start 91.74734 -204.121258)
		(end 91.762834 -204.110336)
		(stroke
			(width 0.06985)
			(type default)
		)
		(layer "In5.Cu")
	)
	(gr_line
		(start 91.855798 -77.377036)
		(end 92.274898 -77.377036)
		(stroke
			(width 0.06985)
			(type default)
		)
		(layer "In5.Cu")
	)
	(gr_line
		(start 91.971114 -185.302652)
		(end 92.199714 -185.302652)
		(stroke
			(width 0.06985)
			(type default)
		)
		(layer "In5.Cu")
	)
	(gr_line
		(start 92.010738 -76.869036)
		(end 92.119958 -76.869036)
		(stroke
			(width 0.06985)
			(type default)
		)
		(layer "In5.Cu")
	)
	(gr_arc
		(start 92.199714 -185.302652)
		(mid 92.283709 -185.285969)
		(end 92.354908 -185.23839)
		(stroke
			(width 0.06985)
			(type default)
		)
		(layer "In5.Cu")
	)
	(gr_line
		(start 92.274898 -77.377036)
		(end 92.450158 -77.201776)
		(stroke
			(width 0.06985)
			(type default)
		)
		(layer "In5.Cu")
	)
	(gr_arc
		(start 92.493592 -210.896454)
		(mid 92.673219 -210.520694)
		(end 92.734892 -210.1088)
		(stroke
			(width 0.06985)
			(type default)
		)
		(layer "In5.Cu")
	)
	(gr_line
		(start 92.545916 -185.575448)
		(end 92.545916 -185.877454)
		(stroke
			(width 0.06985)
			(type default)
		)
		(layer "In5.Cu")
	)
	(gr_arc
		(start 92.588842 -185.471816)
		(mid 92.557093 -185.519367)
		(end 92.545916 -185.575448)
		(stroke
			(width 0.06985)
			(type default)
		)
		(layer "In5.Cu")
	)
	(gr_arc
		(start 93.065092 -210.1088)
		(mid 93.126773 -210.520691)
		(end 93.306392 -210.896454)
		(stroke
			(width 0.06985)
			(type default)
		)
		(layer "In5.Cu")
	)
	(gr_line
		(start 93.955108 -51.618134)
		(end 93.98 -51.601878)
		(stroke
			(width 0.06985)
			(type default)
		)
		(layer "In5.Cu")
	)
	(gr_line
		(start 93.98 -51.601878)
		(end 93.996256 -51.576986)
		(stroke
			(width 0.06985)
			(type default)
		)
		(layer "In5.Cu")
	)
	(gr_line
		(start 94.9833 -52.810664)
		(end 95.008192 -52.794408)
		(stroke
			(width 0.06985)
			(type default)
		)
		(layer "In5.Cu")
	)
	(gr_line
		(start 95.008192 -52.794408)
		(end 95.024448 -52.769516)
		(stroke
			(width 0.06985)
			(type default)
		)
		(layer "In5.Cu")
	)
	(gr_line
		(start 95.68688 -204.38237)
		(end 95.733108 -204.336142)
		(stroke
			(width 0.06985)
			(type default)
		)
		(layer "In5.Cu")
	)
	(gr_line
		(start 95.733108 -204.336142)
		(end 95.79737 -204.324712)
		(stroke
			(width 0.06985)
			(type default)
		)
		(layer "In5.Cu")
	)
	(gr_line
		(start 96.683068 -42.568622)
		(end 96.689418 -42.598848)
		(stroke
			(width 0.06985)
			(type default)
		)
		(layer "In5.Cu")
	)
	(gr_line
		(start 96.683068 -42.568622)
		(end 96.689418 -42.539158)
		(stroke
			(width 0.06985)
			(type default)
		)
		(layer "In5.Cu")
	)
	(gr_line
		(start 96.762062 -47.318676)
		(end 96.773492 -47.300896)
		(stroke
			(width 0.06985)
			(type default)
		)
		(layer "In5.Cu")
	)
	(gr_line
		(start 96.773492 -47.300896)
		(end 96.777556 -47.281084)
		(stroke
			(width 0.06985)
			(type default)
		)
		(layer "In5.Cu")
	)
	(gr_line
		(start 96.99371 -184.13857)
		(end 97.162366 -184.02046)
		(stroke
			(width 0.06985)
			(type default)
		)
		(layer "In5.Cu")
	)
	(gr_line
		(start 97.372932 -39.324788)
		(end 97.376996 -39.304976)
		(stroke
			(width 0.06985)
			(type default)
		)
		(layer "In5.Cu")
	)
	(gr_line
		(start 97.376996 -39.304976)
		(end 97.388426 -39.287196)
		(stroke
			(width 0.06985)
			(type default)
		)
		(layer "In5.Cu")
	)
	(gr_line
		(start 97.393506 -44.38269)
		(end 97.40011 -44.351956)
		(stroke
			(width 0.06985)
			(type default)
		)
		(layer "In5.Cu")
	)
	(gr_line
		(start 97.39376 -44.322492)
		(end 97.40011 -44.351956)
		(stroke
			(width 0.06985)
			(type default)
		)
		(layer "In5.Cu")
	)
	(gr_line
		(start 97.982786 -38.37178)
		(end 97.999042 -38.346888)
		(stroke
			(width 0.06985)
			(type default)
		)
		(layer "In5.Cu")
	)
	(gr_line
		(start 97.999042 -38.346888)
		(end 98.023934 -38.330632)
		(stroke
			(width 0.06985)
			(type default)
		)
		(layer "In5.Cu")
	)
	(gr_arc
		(start 98.093784 -210.896454)
		(mid 98.272922 -210.584109)
		(end 98.335084 -210.22945)
		(stroke
			(width 0.06985)
			(type default)
		)
		(layer "In5.Cu")
	)
	(gr_line
		(start 98.308668 -47.712376)
		(end 98.320098 -47.694596)
		(stroke
			(width 0.06985)
			(type default)
		)
		(layer "In5.Cu")
	)
	(gr_line
		(start 98.320098 -47.694596)
		(end 98.324162 -47.674784)
		(stroke
			(width 0.06985)
			(type default)
		)
		(layer "In5.Cu")
	)
	(gr_line
		(start 98.335084 -207.705452)
		(end 98.371914 -207.652874)
		(stroke
			(width 0.06985)
			(type default)
		)
		(layer "In5.Cu")
	)
	(gr_line
		(start 98.359722 -42.551604)
		(end 98.366072 -42.58183)
		(stroke
			(width 0.06985)
			(type default)
		)
		(layer "In5.Cu")
	)
	(gr_line
		(start 98.359722 -42.551604)
		(end 98.366072 -42.52214)
		(stroke
			(width 0.06985)
			(type default)
		)
		(layer "In5.Cu")
	)
	(gr_line
		(start 98.600514 -75.64374)
		(end 98.63201 -75.637136)
		(stroke
			(width 0.06985)
			(type default)
		)
		(layer "In5.Cu")
	)
	(gr_line
		(start 98.63201 -75.637136)
		(end 98.66376 -75.643994)
		(stroke
			(width 0.06985)
			(type default)
		)
		(layer "In5.Cu")
	)
	(gr_arc
		(start 98.665284 -210.22945)
		(mid 98.727433 -210.584118)
		(end 98.906584 -210.896454)
		(stroke
			(width 0.06985)
			(type default)
		)
		(layer "In5.Cu")
	)
	(gr_line
		(start 98.845116 -40.269668)
		(end 98.84918 -40.249856)
		(stroke
			(width 0.06985)
			(type default)
		)
		(layer "In5.Cu")
	)
	(gr_line
		(start 98.84918 -40.249856)
		(end 98.86061 -40.232076)
		(stroke
			(width 0.06985)
			(type default)
		)
		(layer "In5.Cu")
	)
	(gr_line
		(start 99.048824 -44.26585)
		(end 99.055428 -44.235116)
		(stroke
			(width 0.06985)
			(type default)
		)
		(layer "In5.Cu")
	)
	(gr_line
		(start 99.049078 -44.205652)
		(end 99.055428 -44.235116)
		(stroke
			(width 0.06985)
			(type default)
		)
		(layer "In5.Cu")
	)
	(gr_line
		(start 99.147122 -39.790878)
		(end 99.16414 -39.764716)
		(stroke
			(width 0.06985)
			(type default)
		)
		(layer "In5.Cu")
	)
	(gr_line
		(start 99.16414 -39.764716)
		(end 99.190302 -39.747698)
		(stroke
			(width 0.06985)
			(type default)
		)
		(layer "In5.Cu")
	)
	(gr_line
		(start 99.419918 -204.02169)
		(end 99.452938 -204.015848)
		(stroke
			(width 0.06985)
			(type default)
		)
		(layer "In5.Cu")
	)
	(gr_line
		(start 99.452938 -204.015848)
		(end 99.480878 -203.99629)
		(stroke
			(width 0.06985)
			(type default)
		)
		(layer "In5.Cu")
	)
	(gr_line
		(start 99.836478 -39.328344)
		(end 99.854258 -39.316914)
		(stroke
			(width 0.06985)
			(type default)
		)
		(layer "In5.Cu")
	)
	(gr_line
		(start 99.854258 -39.316914)
		(end 99.874578 -39.312596)
		(stroke
			(width 0.06985)
			(type default)
		)
		(layer "In5.Cu")
	)
	(gr_line
		(start 99.961954 -205.38186)
		(end 99.972876 -205.366366)
		(stroke
			(width 0.06985)
			(type default)
		)
		(layer "In5.Cu")
	)
	(gr_line
		(start 99.972876 -205.366366)
		(end 99.98837 -205.355444)
		(stroke
			(width 0.06985)
			(type default)
		)
		(layer "In5.Cu")
	)
	(gr_line
		(start 100.819966 -36.516056)
		(end 100.867718 -36.485068)
		(stroke
			(width 0.06985)
			(type default)
		)
		(layer "In5.Cu")
	)
	(gr_arc
		(start 101.293676 -210.896454)
		(mid 101.472814 -210.584109)
		(end 101.534976 -210.22945)
		(stroke
			(width 0.06985)
			(type default)
		)
		(layer "In5.Cu")
	)
	(gr_line
		(start 101.534976 -208.911952)
		(end 101.571044 -208.86039)
		(stroke
			(width 0.06985)
			(type default)
		)
		(layer "In5.Cu")
	)
	(gr_line
		(start 101.720904 -39.596314)
		(end 101.9302 -39.80561)
		(stroke
			(width 0.06985)
			(type default)
		)
		(layer "In5.Cu")
	)
	(gr_line
		(start 101.720904 -39.125906)
		(end 101.9302 -38.91661)
		(stroke
			(width 0.06985)
			(type default)
		)
		(layer "In5.Cu")
	)
	(gr_arc
		(start 101.865176 -210.22945)
		(mid 101.927325 -210.584118)
		(end 102.106476 -210.896454)
		(stroke
			(width 0.06985)
			(type default)
		)
		(layer "In5.Cu")
	)
	(gr_line
		(start 102.305104 -36.885372)
		(end 102.5144 -37.094668)
		(stroke
			(width 0.06985)
			(type default)
		)
		(layer "In5.Cu")
	)
	(gr_line
		(start 102.305104 -36.414964)
		(end 102.5144 -36.205668)
		(stroke
			(width 0.06985)
			(type default)
		)
		(layer "In5.Cu")
	)
	(gr_line
		(start 103.50119 -40.447976)
		(end 103.50119 -40.448738)
		(stroke
			(width 0.0635)
			(type default)
		)
		(layer "In5.Cu")
	)
	(gr_arc
		(start 104.493822 -210.896454)
		(mid 104.672941 -210.584103)
		(end 104.735122 -210.22945)
		(stroke
			(width 0.06985)
			(type default)
		)
		(layer "In5.Cu")
	)
	(gr_line
		(start 104.949498 -207.830166)
		(end 104.95534 -207.797146)
		(stroke
			(width 0.06985)
			(type default)
		)
		(layer "In5.Cu")
	)
	(gr_line
		(start 104.95534 -207.797146)
		(end 104.974898 -207.769206)
		(stroke
			(width 0.06985)
			(type default)
		)
		(layer "In5.Cu")
	)
	(gr_arc
		(start 105.065322 -210.22945)
		(mid 105.127468 -210.584121)
		(end 105.306622 -210.896454)
		(stroke
			(width 0.06985)
			(type default)
		)
		(layer "In5.Cu")
	)
	(gr_line
		(start 105.452418 -203.31684)
		(end 105.46334 -203.301346)
		(stroke
			(width 0.06985)
			(type default)
		)
		(layer "In5.Cu")
	)
	(gr_line
		(start 105.46334 -203.301346)
		(end 105.478834 -203.290424)
		(stroke
			(width 0.06985)
			(type default)
		)
		(layer "In5.Cu")
	)
	(gr_line
		(start 107.410504 -51.86553)
		(end 107.603798 -51.672236)
		(stroke
			(width 0.0635)
			(type default)
		)
		(layer "In5.Cu")
	)
	(gr_line
		(start 107.410504 -50.75682)
		(end 107.603798 -50.950114)
		(stroke
			(width 0.0635)
			(type default)
		)
		(layer "In5.Cu")
	)
	(gr_arc
		(start 107.693714 -210.896454)
		(mid 107.872852 -210.584109)
		(end 107.935014 -210.22945)
		(stroke
			(width 0.06985)
			(type default)
		)
		(layer "In5.Cu")
	)
	(gr_arc
		(start 108.265214 -210.22945)
		(mid 108.327398 -210.584101)
		(end 108.506514 -210.896454)
		(stroke
			(width 0.06985)
			(type default)
		)
		(layer "In5.Cu")
	)
	(gr_line
		(start 108.451904 -202.803252)
		(end 108.462826 -202.787758)
		(stroke
			(width 0.06985)
			(type default)
		)
		(layer "In5.Cu")
	)
	(gr_line
		(start 108.462826 -202.787758)
		(end 108.47832 -202.776836)
		(stroke
			(width 0.06985)
			(type default)
		)
		(layer "In5.Cu")
	)
	(gr_line
		(start 108.561632 -205.747874)
		(end 108.567474 -205.714854)
		(stroke
			(width 0.06985)
			(type default)
		)
		(layer "In5.Cu")
	)
	(gr_line
		(start 108.567474 -205.714854)
		(end 108.587032 -205.686914)
		(stroke
			(width 0.06985)
			(type default)
		)
		(layer "In5.Cu")
	)
	(gr_line
		(start 109.830108 -203.911708)
		(end 109.84103 -203.896214)
		(stroke
			(width 0.06985)
			(type default)
		)
		(layer "In5.Cu")
	)
	(gr_line
		(start 109.84103 -203.896214)
		(end 109.856524 -203.885292)
		(stroke
			(width 0.06985)
			(type default)
		)
		(layer "In5.Cu")
	)
	(gr_line
		(start 110.530894 -42.390568)
		(end 110.730792 -42.189908)
		(stroke
			(width 0.0635)
			(type default)
		)
		(layer "In5.Cu")
	)
	(gr_line
		(start 110.71479 -39.899844)
		(end 110.715044 -39.740078)
		(stroke
			(width 0.0635)
			(type default)
		)
		(layer "In5.Cu")
	)
	(gr_line
		(start 110.928658 -78.682342)
		(end 110.960154 -78.6892)
		(stroke
			(width 0.06985)
			(type default)
		)
		(layer "In5.Cu")
	)
	(gr_line
		(start 110.960154 -78.6892)
		(end 110.990634 -78.682596)
		(stroke
			(width 0.06985)
			(type default)
		)
		(layer "In5.Cu")
	)
	(gr_line
		(start 111.241332 -42.237406)
		(end 111.394494 -42.390568)
		(stroke
			(width 0.0635)
			(type default)
		)
		(layer "In5.Cu")
	)
	(gr_line
		(start 115.757706 -42.931588)
		(end 115.951 -43.124882)
		(stroke
			(width 0.0635)
			(type default)
		)
		(layer "In5.Cu")
	)
	(gr_line
		(start 115.757706 -42.209466)
		(end 115.951 -42.016172)
		(stroke
			(width 0.0635)
			(type default)
		)
		(layer "In5.Cu")
	)
	(gr_line
		(start 120.303798 -84.804758)
		(end 120.317768 -84.81822)
		(stroke
			(width 0.0635)
			(type default)
		)
		(layer "In5.Cu")
	)
	(gr_line
		(start 120.303798 -84.804504)
		(end 120.303798 -84.804758)
		(stroke
			(width 0.0635)
			(type default)
		)
		(layer "In5.Cu")
	)
	(gr_line
		(start 120.317768 -84.81822)
		(end 120.448324 -84.948776)
		(stroke
			(width 0.0635)
			(type default)
		)
		(layer "In5.Cu")
	)
	(gr_line
		(start 120.448324 -84.948776)
		(end 120.448324 -84.94903)
		(stroke
			(width 0.0635)
			(type default)
		)
		(layer "In5.Cu")
	)
	(gr_line
		(start 121.092214 -84.870798)
		(end 121.167398 -84.795614)
		(stroke
			(width 0.0635)
			(type default)
		)
		(layer "In5.Cu")
	)
	(gr_line
		(start 121.580656 -76.081128)
		(end 121.610374 -76.074778)
		(stroke
			(width 0.06985)
			(type default)
		)
		(layer "In5.Cu")
	)
	(gr_line
		(start 121.610374 -76.074778)
		(end 121.6406 -76.081128)
		(stroke
			(width 0.06985)
			(type default)
		)
		(layer "In5.Cu")
	)
	(gr_line
		(start 131.0894 -35.273234)
		(end 131.12369 -35.273234)
		(stroke
			(width 0.06985)
			(type default)
		)
		(layer "In5.Cu")
	)
	(gr_arc
		(start 131.3307 -35.480244)
		(mid 131.270083 -35.333841)
		(end 131.12369 -35.273234)
		(stroke
			(width 0.06985)
			(type default)
		)
		(layer "In5.Cu")
	)
	(gr_arc
		(start 131.86791 -35.273234)
		(mid 131.721541 -35.333865)
		(end 131.6609 -35.480244)
		(stroke
			(width 0.06985)
			(type default)
		)
		(layer "In5.Cu")
	)
	(gr_line
		(start 131.86791 -35.273234)
		(end 131.9022 -35.273234)
		(stroke
			(width 0.06985)
			(type default)
		)
		(layer "In5.Cu")
	)
	(gr_line
		(start 133.852158 -35.739832)
		(end 133.886448 -35.739832)
		(stroke
			(width 0.06985)
			(type default)
		)
		(layer "In5.Cu")
	)
	(gr_arc
		(start 134.093458 -35.946842)
		(mid 134.032844 -35.80042)
		(end 133.886448 -35.739832)
		(stroke
			(width 0.06985)
			(type default)
		)
		(layer "In5.Cu")
	)
	(gr_arc
		(start 134.630668 -35.739832)
		(mid 134.484325 -35.800478)
		(end 134.423658 -35.946842)
		(stroke
			(width 0.06985)
			(type default)
		)
		(layer "In5.Cu")
	)
	(gr_line
		(start 134.630668 -35.739832)
		(end 134.664958 -35.739832)
		(stroke
			(width 0.06985)
			(type default)
		)
		(layer "In5.Cu")
	)
	(gr_line
		(start 135.062722 -36.45916)
		(end 135.237982 -36.2839)
		(stroke
			(width 0.06985)
			(type default)
		)
		(layer "In5.Cu")
	)
	(gr_line
		(start 135.237982 -36.2839)
		(end 135.657082 -36.2839)
		(stroke
			(width 0.06985)
			(type default)
		)
		(layer "In5.Cu")
	)
	(gr_line
		(start 135.392922 -36.7919)
		(end 135.502142 -36.7919)
		(stroke
			(width 0.06985)
			(type default)
		)
		(layer "In5.Cu")
	)
	(gr_line
		(start 135.657082 -36.2839)
		(end 135.832342 -36.45916)
		(stroke
			(width 0.06985)
			(type default)
		)
		(layer "In5.Cu")
	)
	(gr_line
		(start 136.256522 -36.45916)
		(end 136.431782 -36.2839)
		(stroke
			(width 0.06985)
			(type default)
		)
		(layer "In5.Cu")
	)
	(gr_line
		(start 136.431782 -36.2839)
		(end 136.850882 -36.2839)
		(stroke
			(width 0.06985)
			(type default)
		)
		(layer "In5.Cu")
	)
	(gr_line
		(start 136.586722 -36.7919)
		(end 136.695942 -36.7919)
		(stroke
			(width 0.06985)
			(type default)
		)
		(layer "In5.Cu")
	)
	(gr_line
		(start 136.850882 -36.2839)
		(end 137.026142 -36.45916)
		(stroke
			(width 0.06985)
			(type default)
		)
		(layer "In5.Cu")
	)
	(gr_line
		(start 137.5029 -79.455772)
		(end 137.52322 -79.46009)
		(stroke
			(width 0.06985)
			(type default)
		)
		(layer "In5.Cu")
	)
	(gr_line
		(start 137.52322 -79.46009)
		(end 137.541 -79.47152)
		(stroke
			(width 0.06985)
			(type default)
		)
		(layer "In5.Cu")
	)
	(gr_line
		(start 137.5664 -34.993326)
		(end 137.60069 -34.993326)
		(stroke
			(width 0.06985)
			(type default)
		)
		(layer "In5.Cu")
	)
	(gr_line
		(start 137.575798 -66.86296)
		(end 137.765536 -66.673222)
		(stroke
			(width 0.0635)
			(type default)
		)
		(layer "In5.Cu")
	)
	(gr_arc
		(start 137.8077 -35.200336)
		(mid 137.74708 -35.053938)
		(end 137.60069 -34.993326)
		(stroke
			(width 0.06985)
			(type default)
		)
		(layer "In5.Cu")
	)
	(gr_arc
		(start 138.34491 -34.993326)
		(mid 138.198532 -35.053958)
		(end 138.1379 -35.200336)
		(stroke
			(width 0.06985)
			(type default)
		)
		(layer "In5.Cu")
	)
	(gr_line
		(start 138.34491 -34.993326)
		(end 138.3792 -34.993326)
		(stroke
			(width 0.06985)
			(type default)
		)
		(layer "In5.Cu")
	)
	(gr_line
		(start 138.487658 -66.673222)
		(end 138.677396 -66.86296)
		(stroke
			(width 0.0635)
			(type default)
		)
		(layer "In5.Cu")
	)
	(gr_line
		(start 138.493754 -210.896454)
		(end 138.545824 -210.844384)
		(stroke
			(width 0.06985)
			(type default)
		)
		(layer "In5.Cu")
	)
	(gr_arc
		(start 138.545824 -210.844384)
		(mid 138.689541 -210.626629)
		(end 138.73607 -210.369912)
		(stroke
			(width 0.06985)
			(type default)
		)
		(layer "In5.Cu")
	)
	(gr_line
		(start 138.592052 -80.154018)
		(end 138.616944 -80.170274)
		(stroke
			(width 0.06985)
			(type default)
		)
		(layer "In5.Cu")
	)
	(gr_line
		(start 138.616944 -80.170274)
		(end 138.6332 -80.19542)
		(stroke
			(width 0.06985)
			(type default)
		)
		(layer "In5.Cu")
	)
	(gr_line
		(start 138.7348 -210.314032)
		(end 138.735054 -210.32851)
		(stroke
			(width 0.06985)
			(type default)
		)
		(layer "In5.Cu")
	)
	(gr_line
		(start 138.7348 -210.314032)
		(end 138.735054 -210.313778)
		(stroke
			(width 0.06985)
			(type default)
		)
		(layer "In5.Cu")
	)
	(gr_line
		(start 138.735054 -209.983578)
		(end 138.735054 -210.313778)
		(stroke
			(width 0.06985)
			(type default)
		)
		(layer "In5.Cu")
	)
	(gr_line
		(start 138.735054 -197.449948)
		(end 138.771122 -197.398386)
		(stroke
			(width 0.06985)
			(type default)
		)
		(layer "In5.Cu")
	)
	(gr_line
		(start 138.735816 -210.362546)
		(end 138.73607 -210.369912)
		(stroke
			(width 0.06985)
			(type default)
		)
		(layer "In5.Cu")
	)
	(gr_arc
		(start 138.811 -38.9128)
		(mid 138.736605 -38.733195)
		(end 138.557 -38.6588)
		(stroke
			(width 0.06985)
			(type default)
		)
		(layer "In5.Cu")
	)
	(gr_line
		(start 139.063984 -81.465166)
		(end 139.08024 -81.490058)
		(stroke
			(width 0.06985)
			(type default)
		)
		(layer "In5.Cu")
	)
	(gr_line
		(start 139.065 -210.313778)
		(end 139.065254 -210.313778)
		(stroke
			(width 0.06985)
			(type default)
		)
		(layer "In5.Cu")
	)
	(gr_arc
		(start 139.065 -210.313778)
		(mid 139.127798 -210.629151)
		(end 139.306554 -210.896454)
		(stroke
			(width 0.06985)
			(type default)
		)
		(layer "In5.Cu")
	)
	(gr_line
		(start 139.08024 -81.490058)
		(end 139.105132 -81.506314)
		(stroke
			(width 0.06985)
			(type default)
		)
		(layer "In5.Cu")
	)
	(gr_arc
		(start 139.3698 -38.6588)
		(mid 139.208155 -38.725755)
		(end 139.1412 -38.8874)
		(stroke
			(width 0.06985)
			(type default)
		)
		(layer "In5.Cu")
	)
	(gr_line
		(start 139.391644 -40.255444)
		(end 139.439142 -40.26789)
		(stroke
			(width 0.06985)
			(type default)
		)
		(layer "In5.Cu")
	)
	(gr_line
		(start 139.69619 -36.386516)
		(end 139.74445 -36.417758)
		(stroke
			(width 0.06985)
			(type default)
		)
		(layer "In5.Cu")
	)
	(gr_line
		(start 139.74445 -36.417758)
		(end 139.753594 -36.417758)
		(stroke
			(width 0.06985)
			(type default)
		)
		(layer "In5.Cu")
	)
	(gr_line
		(start 139.906502 -36.124642)
		(end 139.906502 -36.124896)
		(stroke
			(width 0.06985)
			(type default)
		)
		(layer "In5.Cu")
	)
	(gr_line
		(start 140.070586 -82.133186)
		(end 140.088366 -82.144616)
		(stroke
			(width 0.06985)
			(type default)
		)
		(layer "In5.Cu")
	)
	(gr_line
		(start 140.088366 -82.144616)
		(end 140.108178 -82.14868)
		(stroke
			(width 0.06985)
			(type default)
		)
		(layer "In5.Cu")
	)
	(gr_line
		(start 140.251688 -37.866828)
		(end 140.2715 -37.870892)
		(stroke
			(width 0.06985)
			(type default)
		)
		(layer "In5.Cu")
	)
	(gr_line
		(start 140.2715 -37.870892)
		(end 140.28928 -37.882322)
		(stroke
			(width 0.06985)
			(type default)
		)
		(layer "In5.Cu")
	)
	(gr_line
		(start 140.846302 -40.635174)
		(end 141.520926 -40.811196)
		(stroke
			(width 0.06985)
			(type default)
		)
		(layer "In5.Cu")
	)
	(gr_line
		(start 140.894816 -40.303958)
		(end 141.108938 -40.178482)
		(stroke
			(width 0.06985)
			(type default)
		)
		(layer "In5.Cu")
	)
	(gr_line
		(start 141.108938 -40.178482)
		(end 141.514576 -40.284146)
		(stroke
			(width 0.06985)
			(type default)
		)
		(layer "In5.Cu")
	)
	(gr_line
		(start 141.367764 -38.9763)
		(end 141.948916 -39.353744)
		(stroke
			(width 0.06985)
			(type default)
		)
		(layer "In5.Cu")
	)
	(gr_line
		(start 141.514576 -40.284146)
		(end 141.640052 -40.498522)
		(stroke
			(width 0.06985)
			(type default)
		)
		(layer "In5.Cu")
	)
	(gr_line
		(start 141.5161 -38.676072)
		(end 141.75867 -38.62451)
		(stroke
			(width 0.06985)
			(type default)
		)
		(layer "In5.Cu")
	)
	(gr_line
		(start 141.559534 -37.327078)
		(end 141.579854 -37.331396)
		(stroke
			(width 0.06985)
			(type default)
		)
		(layer "In5.Cu")
	)
	(gr_line
		(start 141.579854 -37.331396)
		(end 141.597634 -37.342826)
		(stroke
			(width 0.06985)
			(type default)
		)
		(layer "In5.Cu")
	)
	(gr_line
		(start 141.6939 -210.896454)
		(end 141.728444 -210.86191)
		(stroke
			(width 0.06985)
			(type default)
		)
		(layer "In5.Cu")
	)
	(gr_arc
		(start 141.728444 -210.86191)
		(mid 141.881453 -210.632916)
		(end 141.9352 -210.3628)
		(stroke
			(width 0.06985)
			(type default)
		)
		(layer "In5.Cu")
	)
	(gr_line
		(start 141.75867 -38.62451)
		(end 142.110206 -38.852856)
		(stroke
			(width 0.06985)
			(type default)
		)
		(layer "In5.Cu")
	)
	(gr_line
		(start 141.9352 -195.83654)
		(end 141.971268 -195.784978)
		(stroke
			(width 0.06985)
			(type default)
		)
		(layer "In5.Cu")
	)
	(gr_line
		(start 142.035276 -40.603932)
		(end 142.047214 -40.60698)
		(stroke
			(width 0.06985)
			(type default)
		)
		(layer "In5.Cu")
	)
	(gr_line
		(start 142.047214 -40.60698)
		(end 142.058136 -40.614092)
		(stroke
			(width 0.06985)
			(type default)
		)
		(layer "In5.Cu")
	)
	(gr_line
		(start 142.110206 -38.852856)
		(end 142.161768 -39.095426)
		(stroke
			(width 0.06985)
			(type default)
		)
		(layer "In5.Cu")
	)
	(gr_arc
		(start 142.2654 -210.3628)
		(mid 142.319156 -210.63291)
		(end 142.472156 -210.86191)
		(stroke
			(width 0.06985)
			(type default)
		)
		(layer "In5.Cu")
	)
	(gr_line
		(start 142.368524 -39.626286)
		(end 142.950184 -40.003984)
		(stroke
			(width 0.06985)
			(type default)
		)
		(layer "In5.Cu")
	)
	(gr_line
		(start 142.472156 -210.86191)
		(end 142.5067 -210.896454)
		(stroke
			(width 0.06985)
			(type default)
		)
		(layer "In5.Cu")
	)
	(gr_line
		(start 142.51686 -41.305226)
		(end 143.09725 -41.681908)
		(stroke
			(width 0.06985)
			(type default)
		)
		(layer "In5.Cu")
	)
	(gr_line
		(start 142.517368 -39.326312)
		(end 142.759938 -39.27475)
		(stroke
			(width 0.06985)
			(type default)
		)
		(layer "In5.Cu")
	)
	(gr_line
		(start 142.664688 -41.004744)
		(end 142.907258 -40.953182)
		(stroke
			(width 0.06985)
			(type default)
		)
		(layer "In5.Cu")
	)
	(gr_line
		(start 142.759938 -39.27475)
		(end 143.111474 -39.502842)
		(stroke
			(width 0.06985)
			(type default)
		)
		(layer "In5.Cu")
	)
	(gr_line
		(start 142.907258 -40.953182)
		(end 143.258794 -41.181274)
		(stroke
			(width 0.06985)
			(type default)
		)
		(layer "In5.Cu")
	)
	(gr_line
		(start 143.111474 -39.502842)
		(end 143.163036 -39.745666)
		(stroke
			(width 0.06985)
			(type default)
		)
		(layer "In5.Cu")
	)
	(gr_line
		(start 143.248634 -36.867846)
		(end 143.275812 -36.873434)
		(stroke
			(width 0.06985)
			(type default)
		)
		(layer "In5.Cu")
	)
	(gr_line
		(start 143.258794 -41.181274)
		(end 143.31061 -41.423844)
		(stroke
			(width 0.06985)
			(type default)
		)
		(layer "In5.Cu")
	)
	(gr_line
		(start 143.275812 -36.873434)
		(end 143.298926 -36.889944)
		(stroke
			(width 0.06985)
			(type default)
		)
		(layer "In5.Cu")
	)
	(gr_line
		(start 143.516604 -41.954196)
		(end 144.09928 -42.332148)
		(stroke
			(width 0.06985)
			(type default)
		)
		(layer "In5.Cu")
	)
	(gr_line
		(start 143.66621 -41.654476)
		(end 143.90878 -41.602914)
		(stroke
			(width 0.06985)
			(type default)
		)
		(layer "In5.Cu")
	)
	(gr_line
		(start 143.90878 -41.602914)
		(end 144.260316 -41.831006)
		(stroke
			(width 0.06985)
			(type default)
		)
		(layer "In5.Cu")
	)
	(gr_line
		(start 144.260316 -41.831006)
		(end 144.312132 -42.07383)
		(stroke
			(width 0.06985)
			(type default)
		)
		(layer "In5.Cu")
	)
	(gr_line
		(start 144.893792 -210.896454)
		(end 144.94637 -210.843876)
		(stroke
			(width 0.06985)
			(type default)
		)
		(layer "In5.Cu")
	)
	(gr_arc
		(start 144.94637 -210.843876)
		(mid 145.086063 -210.63481)
		(end 145.135092 -210.3882)
		(stroke
			(width 0.06985)
			(type default)
		)
		(layer "In5.Cu")
	)
	(gr_line
		(start 145.135092 -194.477132)
		(end 145.17116 -194.42557)
		(stroke
			(width 0.06985)
			(type default)
		)
		(layer "In5.Cu")
	)
	(gr_line
		(start 145.256504 -38.701726)
		(end 145.820638 -39.106602)
		(stroke
			(width 0.06985)
			(type default)
		)
		(layer "In5.Cu")
	)
	(gr_line
		(start 145.376392 -43.161204)
		(end 145.394172 -43.172634)
		(stroke
			(width 0.06985)
			(type default)
		)
		(layer "In5.Cu")
	)
	(gr_line
		(start 145.394172 -43.172634)
		(end 145.413984 -43.176698)
		(stroke
			(width 0.06985)
			(type default)
		)
		(layer "In5.Cu")
	)
	(gr_line
		(start 145.42008 -38.409626)
		(end 145.66519 -38.369494)
		(stroke
			(width 0.06985)
			(type default)
		)
		(layer "In5.Cu")
	)
	(gr_arc
		(start 145.465292 -210.3882)
		(mid 145.514317 -210.634817)
		(end 145.654014 -210.843876)
		(stroke
			(width 0.06985)
			(type default)
		)
		(layer "In5.Cu")
	)
	(gr_line
		(start 145.654014 -210.843876)
		(end 145.706592 -210.896454)
		(stroke
			(width 0.06985)
			(type default)
		)
		(layer "In5.Cu")
	)
	(gr_line
		(start 145.66519 -38.369494)
		(end 146.00555 -38.613842)
		(stroke
			(width 0.06985)
			(type default)
		)
		(layer "In5.Cu")
	)
	(gr_line
		(start 145.801842 -187.357258)
		(end 145.812764 -187.341764)
		(stroke
			(width 0.06985)
			(type default)
		)
		(layer "In5.Cu")
	)
	(gr_line
		(start 145.812764 -187.341764)
		(end 145.828258 -187.330842)
		(stroke
			(width 0.06985)
			(type default)
		)
		(layer "In5.Cu")
	)
	(gr_line
		(start 145.9103 -34.99612)
		(end 146.045428 -35.131248)
		(stroke
			(width 0.06985)
			(type default)
		)
		(layer "In5.Cu")
	)
	(gr_line
		(start 146.00555 -38.613842)
		(end 146.045682 -38.858698)
		(stroke
			(width 0.06985)
			(type default)
		)
		(layer "In5.Cu")
	)
	(gr_arc
		(start 146.1516 -35.387534)
		(mid 146.12399 -35.248839)
		(end 146.045428 -35.131248)
		(stroke
			(width 0.06985)
			(type default)
		)
		(layer "In5.Cu")
	)
	(gr_line
		(start 146.22653 -39.39794)
		(end 146.789902 -39.802308)
		(stroke
			(width 0.06985)
			(type default)
		)
		(layer "In5.Cu")
	)
	(gr_line
		(start 146.390106 -39.10584)
		(end 146.634962 -39.065708)
		(stroke
			(width 0.06985)
			(type default)
		)
		(layer "In5.Cu")
	)
	(gr_arc
		(start 146.587972 -35.131248)
		(mid 146.509404 -35.248833)
		(end 146.4818 -35.387534)
		(stroke
			(width 0.06985)
			(type default)
		)
		(layer "In5.Cu")
	)
	(gr_line
		(start 146.587972 -35.131248)
		(end 146.7231 -34.99612)
		(stroke
			(width 0.06985)
			(type default)
		)
		(layer "In5.Cu")
	)
	(gr_line
		(start 146.634962 -39.065708)
		(end 146.975322 -39.310056)
		(stroke
			(width 0.06985)
			(type default)
		)
		(layer "In5.Cu")
	)
	(gr_line
		(start 146.975322 -39.310056)
		(end 147.015454 -39.554658)
		(stroke
			(width 0.06985)
			(type default)
		)
		(layer "In5.Cu")
	)
	(gr_line
		(start 147.04822 -42.665142)
		(end 147.066 -42.676572)
		(stroke
			(width 0.06985)
			(type default)
		)
		(layer "In5.Cu")
	)
	(gr_line
		(start 147.066 -42.676572)
		(end 147.085812 -42.680636)
		(stroke
			(width 0.06985)
			(type default)
		)
		(layer "In5.Cu")
	)
	(gr_line
		(start 147.071842 -188.500258)
		(end 147.082764 -188.484764)
		(stroke
			(width 0.06985)
			(type default)
		)
		(layer "In5.Cu")
	)
	(gr_line
		(start 147.082764 -188.484764)
		(end 147.098258 -188.473842)
		(stroke
			(width 0.06985)
			(type default)
		)
		(layer "In5.Cu")
	)
	(gr_line
		(start 147.309078 -40.17518)
		(end 147.332192 -40.19169)
		(stroke
			(width 0.06985)
			(type default)
		)
		(layer "In5.Cu")
	)
	(gr_line
		(start 147.332192 -40.19169)
		(end 147.334224 -40.192198)
		(stroke
			(width 0.06985)
			(type default)
		)
		(layer "In5.Cu")
	)
	(gr_line
		(start 147.334224 -40.192198)
		(end 147.360386 -40.197786)
		(stroke
			(width 0.06985)
			(type default)
		)
		(layer "In5.Cu")
	)
	(gr_line
		(start 147.818094 -37.235892)
		(end 147.835874 -37.247322)
		(stroke
			(width 0.06985)
			(type default)
		)
		(layer "In5.Cu")
	)
	(gr_line
		(start 147.835874 -37.247322)
		(end 147.855686 -37.251386)
		(stroke
			(width 0.06985)
			(type default)
		)
		(layer "In5.Cu")
	)
	(gr_line
		(start 147.91817 -41.841674)
		(end 147.93595 -41.853104)
		(stroke
			(width 0.06985)
			(type default)
		)
		(layer "In5.Cu")
	)
	(gr_line
		(start 147.93595 -41.853104)
		(end 147.95627 -41.857422)
		(stroke
			(width 0.06985)
			(type default)
		)
		(layer "In5.Cu")
	)
	(gr_arc
		(start 148.093684 -210.896454)
		(mid 148.272311 -210.62912)
		(end 148.334984 -210.313778)
		(stroke
			(width 0.06985)
			(type default)
		)
		(layer "In5.Cu")
	)
	(gr_line
		(start 148.334984 -210.313778)
		(end 148.336 -210.312762)
		(stroke
			(width 0.06985)
			(type default)
		)
		(layer "In5.Cu")
	)
	(gr_line
		(start 148.336 -210.28787)
		(end 148.336 -210.312762)
		(stroke
			(width 0.06985)
			(type default)
		)
		(layer "In5.Cu")
	)
	(gr_line
		(start 148.336 -193.914776)
		(end 148.372068 -193.863214)
		(stroke
			(width 0.06985)
			(type default)
		)
		(layer "In5.Cu")
	)
	(gr_line
		(start 148.341842 -189.897258)
		(end 148.352764 -189.881764)
		(stroke
			(width 0.06985)
			(type default)
		)
		(layer "In5.Cu")
	)
	(gr_line
		(start 148.352764 -189.881764)
		(end 148.368258 -189.870842)
		(stroke
			(width 0.06985)
			(type default)
		)
		(layer "In5.Cu")
	)
	(gr_line
		(start 148.444966 -41.961308)
		(end 149.122892 -42.105326)
		(stroke
			(width 0.06985)
			(type default)
		)
		(layer "In5.Cu")
	)
	(gr_line
		(start 148.477224 -41.62806)
		(end 148.68525 -41.492932)
		(stroke
			(width 0.06985)
			(type default)
		)
		(layer "In5.Cu")
	)
	(gr_line
		(start 148.665184 -210.313778)
		(end 148.6662 -210.312762)
		(stroke
			(width 0.06985)
			(type default)
		)
		(layer "In5.Cu")
	)
	(gr_arc
		(start 148.665184 -210.313778)
		(mid 148.727848 -210.629132)
		(end 148.906484 -210.896454)
		(stroke
			(width 0.06985)
			(type default)
		)
		(layer "In5.Cu")
	)
	(gr_line
		(start 148.68525 -41.492932)
		(end 149.095206 -41.580308)
		(stroke
			(width 0.06985)
			(type default)
		)
		(layer "In5.Cu")
	)
	(gr_arc
		(start 148.7678 -35.4838)
		(mid 148.69669 -35.208103)
		(end 148.5011 -35.0012)
		(stroke
			(width 0.06985)
			(type default)
		)
		(layer "In5.Cu")
	)
	(gr_line
		(start 149.095206 -41.580308)
		(end 149.230334 -41.788334)
		(stroke
			(width 0.06985)
			(type default)
		)
		(layer "In5.Cu")
	)
	(gr_arc
		(start 149.3139 -35.0012)
		(mid 149.154464 -35.219462)
		(end 149.098 -35.4838)
		(stroke
			(width 0.06985)
			(type default)
		)
		(layer "In5.Cu")
	)
	(gr_line
		(start 149.577298 -37.6174)
		(end 149.606762 -37.62375)
		(stroke
			(width 0.06985)
			(type default)
		)
		(layer "In5.Cu")
	)
	(gr_line
		(start 149.606762 -37.62375)
		(end 149.636226 -37.6174)
		(stroke
			(width 0.06985)
			(type default)
		)
		(layer "In5.Cu")
	)
	(gr_line
		(start 149.611588 -42.20972)
		(end 150.291546 -42.354246)
		(stroke
			(width 0.06985)
			(type default)
		)
		(layer "In5.Cu")
	)
	(gr_line
		(start 149.644862 -41.876472)
		(end 149.852888 -41.741344)
		(stroke
			(width 0.06985)
			(type default)
		)
		(layer "In5.Cu")
	)
	(gr_line
		(start 149.651212 -81.57083)
		(end 149.826472 -81.74609)
		(stroke
			(width 0.06985)
			(type default)
		)
		(layer "In5.Cu")
	)
	(gr_line
		(start 149.826472 -81.74609)
		(end 150.245572 -81.74609)
		(stroke
			(width 0.06985)
			(type default)
		)
		(layer "In5.Cu")
	)
	(gr_line
		(start 149.852888 -41.741344)
		(end 150.262844 -41.82872)
		(stroke
			(width 0.06985)
			(type default)
		)
		(layer "In5.Cu")
	)
	(gr_line
		(start 149.981412 -81.23809)
		(end 150.090632 -81.23809)
		(stroke
			(width 0.06985)
			(type default)
		)
		(layer "In5.Cu")
	)
	(gr_line
		(start 150.245572 -81.74609)
		(end 150.420832 -81.57083)
		(stroke
			(width 0.06985)
			(type default)
		)
		(layer "In5.Cu")
	)
	(gr_line
		(start 150.262844 -41.82872)
		(end 150.397972 -42.036746)
		(stroke
			(width 0.06985)
			(type default)
		)
		(layer "In5.Cu")
	)
	(gr_line
		(start 150.779226 -42.458132)
		(end 151.459184 -42.602658)
		(stroke
			(width 0.06985)
			(type default)
		)
		(layer "In5.Cu")
	)
	(gr_line
		(start 150.8125 -42.124884)
		(end 151.020526 -41.989756)
		(stroke
			(width 0.06985)
			(type default)
		)
		(layer "In5.Cu")
	)
	(gr_line
		(start 150.845012 -81.57083)
		(end 151.020272 -81.74609)
		(stroke
			(width 0.06985)
			(type default)
		)
		(layer "In5.Cu")
	)
	(gr_line
		(start 150.881842 -190.278258)
		(end 150.892764 -190.262764)
		(stroke
			(width 0.06985)
			(type default)
		)
		(layer "In5.Cu")
	)
	(gr_line
		(start 150.892764 -190.262764)
		(end 150.908258 -190.251842)
		(stroke
			(width 0.06985)
			(type default)
		)
		(layer "In5.Cu")
	)
	(gr_line
		(start 151.020272 -81.74609)
		(end 151.439372 -81.74609)
		(stroke
			(width 0.06985)
			(type default)
		)
		(layer "In5.Cu")
	)
	(gr_line
		(start 151.020526 -41.989756)
		(end 151.430482 -42.077132)
		(stroke
			(width 0.06985)
			(type default)
		)
		(layer "In5.Cu")
	)
	(gr_line
		(start 151.043894 -36.980114)
		(end 151.074374 -36.973764)
		(stroke
			(width 0.06985)
			(type default)
		)
		(layer "In5.Cu")
	)
	(gr_line
		(start 151.074374 -36.973764)
		(end 151.103838 -36.980114)
		(stroke
			(width 0.06985)
			(type default)
		)
		(layer "In5.Cu")
	)
	(gr_line
		(start 151.1554 -39.257224)
		(end 151.164036 -39.278814)
		(stroke
			(width 0.06985)
			(type default)
		)
		(layer "In5.Cu")
	)
	(gr_arc
		(start 151.1554 -38.500304)
		(mid 151.090606 -38.26117)
		(end 150.9141 -38.0873)
		(stroke
			(width 0.06985)
			(type default)
		)
		(layer "In5.Cu")
	)
	(gr_line
		(start 151.175212 -81.23809)
		(end 151.284432 -81.23809)
		(stroke
			(width 0.06985)
			(type default)
		)
		(layer "In5.Cu")
	)
	(gr_arc
		(start 151.29383 -210.896454)
		(mid 151.472408 -210.629105)
		(end 151.53513 -210.313778)
		(stroke
			(width 0.06985)
			(type default)
		)
		(layer "In5.Cu")
	)
	(gr_line
		(start 151.2951 -36.538662)
		(end 151.97582 -36.683442)
		(stroke
			(width 0.06985)
			(type default)
		)
		(layer "In5.Cu")
	)
	(gr_line
		(start 151.299164 -39.615618)
		(end 151.321262 -39.670482)
		(stroke
			(width 0.06985)
			(type default)
		)
		(layer "In5.Cu")
	)
	(gr_line
		(start 151.321262 -39.670482)
		(end 151.37003 -39.704772)
		(stroke
			(width 0.06985)
			(type default)
		)
		(layer "In5.Cu")
	)
	(gr_line
		(start 151.327866 -36.205414)
		(end 151.535892 -36.070286)
		(stroke
			(width 0.06985)
			(type default)
		)
		(layer "In5.Cu")
	)
	(gr_line
		(start 151.430482 -42.077132)
		(end 151.56561 -42.285158)
		(stroke
			(width 0.06985)
			(type default)
		)
		(layer "In5.Cu")
	)
	(gr_line
		(start 151.439372 -81.74609)
		(end 151.614632 -81.57083)
		(stroke
			(width 0.06985)
			(type default)
		)
		(layer "In5.Cu")
	)
	(gr_line
		(start 151.53513 -205.562708)
		(end 151.571198 -205.511146)
		(stroke
			(width 0.06985)
			(type default)
		)
		(layer "In5.Cu")
	)
	(gr_line
		(start 151.535892 -36.070286)
		(end 151.945848 -36.157408)
		(stroke
			(width 0.06985)
			(type default)
		)
		(layer "In5.Cu")
	)
	(gr_arc
		(start 151.7269 -38.0873)
		(mid 151.55039 -38.261156)
		(end 151.4856 -38.500304)
		(stroke
			(width 0.06985)
			(type default)
		)
		(layer "In5.Cu")
	)
	(gr_arc
		(start 151.86533 -210.313778)
		(mid 151.928051 -210.6291)
		(end 152.10663 -210.896454)
		(stroke
			(width 0.06985)
			(type default)
		)
		(layer "In5.Cu")
	)
	(gr_line
		(start 151.945848 -36.157408)
		(end 152.080976 -36.365434)
		(stroke
			(width 0.06985)
			(type default)
		)
		(layer "In5.Cu")
	)
	(gr_line
		(start 151.946864 -42.706544)
		(end 152.626822 -42.85107)
		(stroke
			(width 0.06985)
			(type default)
		)
		(layer "In5.Cu")
	)
	(gr_line
		(start 151.980138 -42.373296)
		(end 152.188164 -42.238168)
		(stroke
			(width 0.06985)
			(type default)
		)
		(layer "In5.Cu")
	)
	(gr_line
		(start 152.038812 -81.57083)
		(end 152.214072 -81.74609)
		(stroke
			(width 0.06985)
			(type default)
		)
		(layer "In5.Cu")
	)
	(gr_line
		(start 152.058624 -40.187118)
		(end 152.081484 -40.20312)
		(stroke
			(width 0.06985)
			(type default)
		)
		(layer "In5.Cu")
	)
	(gr_line
		(start 152.081484 -40.20312)
		(end 152.108662 -40.208962)
		(stroke
			(width 0.06985)
			(type default)
		)
		(layer "In5.Cu")
	)
	(gr_line
		(start 152.167082 -37.20592)
		(end 152.201372 -37.213032)
		(stroke
			(width 0.06985)
			(type default)
		)
		(layer "In5.Cu")
	)
	(gr_line
		(start 152.188164 -42.238168)
		(end 152.59812 -42.325544)
		(stroke
			(width 0.06985)
			(type default)
		)
		(layer "In5.Cu")
	)
	(gr_line
		(start 152.201372 -37.213032)
		(end 152.230074 -37.234876)
		(stroke
			(width 0.06985)
			(type default)
		)
		(layer "In5.Cu")
	)
	(gr_line
		(start 152.214072 -81.74609)
		(end 152.633172 -81.74609)
		(stroke
			(width 0.06985)
			(type default)
		)
		(layer "In5.Cu")
	)
	(gr_line
		(start 152.369012 -81.23809)
		(end 152.478232 -81.23809)
		(stroke
			(width 0.06985)
			(type default)
		)
		(layer "In5.Cu")
	)
	(gr_line
		(start 152.472898 -36.451286)
		(end 152.49271 -36.45535)
		(stroke
			(width 0.06985)
			(type default)
		)
		(layer "In5.Cu")
	)
	(gr_line
		(start 152.49271 -36.45535)
		(end 152.51049 -36.46678)
		(stroke
			(width 0.06985)
			(type default)
		)
		(layer "In5.Cu")
	)
	(gr_line
		(start 152.59812 -42.325544)
		(end 152.733248 -42.53357)
		(stroke
			(width 0.06985)
			(type default)
		)
		(layer "In5.Cu")
	)
	(gr_line
		(start 152.633172 -81.74609)
		(end 152.808432 -81.57083)
		(stroke
			(width 0.06985)
			(type default)
		)
		(layer "In5.Cu")
	)
	(gr_line
		(start 152.7175 -34.99612)
		(end 152.850088 -35.128708)
		(stroke
			(width 0.06985)
			(type default)
		)
		(layer "In5.Cu")
	)
	(gr_arc
		(start 152.9588 -35.39109)
		(mid 152.930528 -35.24909)
		(end 152.850088 -35.128708)
		(stroke
			(width 0.06985)
			(type default)
		)
		(layer "In5.Cu")
	)
	(gr_line
		(start 153.094436 -36.09213)
		(end 153.114756 -36.17214)
		(stroke
			(width 0.06985)
			(type default)
		)
		(layer "In5.Cu")
	)
	(gr_line
		(start 153.114756 -36.17214)
		(end 153.18232 -36.219384)
		(stroke
			(width 0.06985)
			(type default)
		)
		(layer "In5.Cu")
	)
	(gr_arc
		(start 153.397712 -35.128708)
		(mid 153.317231 -35.249078)
		(end 153.289 -35.39109)
		(stroke
			(width 0.06985)
			(type default)
		)
		(layer "In5.Cu")
	)
	(gr_line
		(start 153.397712 -35.128708)
		(end 153.5303 -34.99612)
		(stroke
			(width 0.06985)
			(type default)
		)
		(layer "In5.Cu")
	)
	(gr_line
		(start 153.935176 -38.95344)
		(end 153.961084 -38.973252)
		(stroke
			(width 0.06985)
			(type default)
		)
		(layer "In5.Cu")
	)
	(gr_line
		(start 153.961084 -38.973252)
		(end 153.993342 -38.980364)
		(stroke
			(width 0.06985)
			(type default)
		)
		(layer "In5.Cu")
	)
	(gr_line
		(start 154.037538 -36.817808)
		(end 154.065478 -36.837366)
		(stroke
			(width 0.06985)
			(type default)
		)
		(layer "In5.Cu")
	)
	(gr_line
		(start 154.065478 -36.837366)
		(end 154.098498 -36.843208)
		(stroke
			(width 0.06985)
			(type default)
		)
		(layer "In5.Cu")
	)
	(gr_arc
		(start 154.493722 -210.896454)
		(mid 154.672349 -210.62912)
		(end 154.735022 -210.313778)
		(stroke
			(width 0.06985)
			(type default)
		)
		(layer "In5.Cu")
	)
	(gr_line
		(start 154.682444 -38.269926)
		(end 154.700224 -38.281356)
		(stroke
			(width 0.06985)
			(type default)
		)
		(layer "In5.Cu")
	)
	(gr_line
		(start 154.700224 -38.281356)
		(end 154.720036 -38.28542)
		(stroke
			(width 0.06985)
			(type default)
		)
		(layer "In5.Cu")
	)
	(gr_arc
		(start 155.065222 -210.313778)
		(mid 155.127889 -210.62913)
		(end 155.306522 -210.896454)
		(stroke
			(width 0.06985)
			(type default)
		)
		(layer "In5.Cu")
	)
	(gr_line
		(start 155.593288 -36.771072)
		(end 155.656788 -36.782248)
		(stroke
			(width 0.06985)
			(type default)
		)
		(layer "In5.Cu")
	)
	(gr_line
		(start 155.690824 -41.634156)
		(end 155.718002 -41.639998)
		(stroke
			(width 0.06985)
			(type default)
		)
		(layer "In5.Cu")
	)
	(gr_line
		(start 155.718002 -41.639998)
		(end 155.740608 -41.656)
		(stroke
			(width 0.06985)
			(type default)
		)
		(layer "In5.Cu")
	)
	(gr_line
		(start 156.045662 -37.638228)
		(end 156.101796 -37.650166)
		(stroke
			(width 0.06985)
			(type default)
		)
		(layer "In5.Cu")
	)
	(gr_line
		(start 156.091636 -40.719248)
		(end 156.118814 -40.72509)
		(stroke
			(width 0.06985)
			(type default)
		)
		(layer "In5.Cu")
	)
	(gr_line
		(start 156.118814 -40.72509)
		(end 156.14142 -40.741092)
		(stroke
			(width 0.06985)
			(type default)
		)
		(layer "In5.Cu")
	)
	(gr_line
		(start 156.759148 -42.783506)
		(end 156.781754 -42.799508)
		(stroke
			(width 0.06985)
			(type default)
		)
		(layer "In5.Cu")
	)
	(gr_line
		(start 156.781754 -42.799508)
		(end 156.808932 -42.80535)
		(stroke
			(width 0.06985)
			(type default)
		)
		(layer "In5.Cu")
	)
	(gr_line
		(start 157.160214 -41.868852)
		(end 157.18282 -41.884854)
		(stroke
			(width 0.06985)
			(type default)
		)
		(layer "In5.Cu")
	)
	(gr_line
		(start 157.18282 -41.884854)
		(end 157.209998 -41.890696)
		(stroke
			(width 0.06985)
			(type default)
		)
		(layer "In5.Cu")
	)
	(gr_arc
		(start 157.693868 -210.896454)
		(mid 157.872459 -210.629108)
		(end 157.935168 -210.313778)
		(stroke
			(width 0.06985)
			(type default)
		)
		(layer "In5.Cu")
	)
	(gr_line
		(start 157.935168 -207.61579)
		(end 157.971236 -207.564228)
		(stroke
			(width 0.06985)
			(type default)
		)
		(layer "In5.Cu")
	)
	(gr_line
		(start 157.961584 -39.518844)
		(end 157.979872 -39.522908)
		(stroke
			(width 0.06985)
			(type default)
		)
		(layer "In5.Cu")
	)
	(gr_line
		(start 157.979872 -39.522908)
		(end 157.995874 -39.533322)
		(stroke
			(width 0.06985)
			(type default)
		)
		(layer "In5.Cu")
	)
	(gr_line
		(start 158.056326 -38.657276)
		(end 158.076138 -38.66134)
		(stroke
			(width 0.06985)
			(type default)
		)
		(layer "In5.Cu")
	)
	(gr_line
		(start 158.076138 -38.66134)
		(end 158.093918 -38.67277)
		(stroke
			(width 0.06985)
			(type default)
		)
		(layer "In5.Cu")
	)
	(gr_line
		(start 158.141416 -141.725904)
		(end 158.15691 -141.714982)
		(stroke
			(width 0.06985)
			(type default)
		)
		(layer "In5.Cu")
	)
	(gr_line
		(start 158.15691 -141.714982)
		(end 158.167832 -141.699488)
		(stroke
			(width 0.06985)
			(type default)
		)
		(layer "In5.Cu")
	)
	(gr_arc
		(start 158.265368 -210.313778)
		(mid 158.328089 -210.6291)
		(end 158.506668 -210.896454)
		(stroke
			(width 0.06985)
			(type default)
		)
		(layer "In5.Cu")
	)
	(gr_line
		(start 158.547816 -37.832538)
		(end 158.567628 -37.836602)
		(stroke
			(width 0.06985)
			(type default)
		)
		(layer "In5.Cu")
	)
	(gr_line
		(start 158.567628 -37.836602)
		(end 158.585408 -37.848032)
		(stroke
			(width 0.06985)
			(type default)
		)
		(layer "In5.Cu")
	)
	(gr_line
		(start 158.655004 -35.02152)
		(end 158.808166 -35.174682)
		(stroke
			(width 0.06985)
			(type default)
		)
		(layer "In5.Cu")
	)
	(gr_arc
		(start 158.896304 -35.387534)
		(mid 158.873425 -35.272332)
		(end 158.808166 -35.174682)
		(stroke
			(width 0.06985)
			(type default)
		)
		(layer "In5.Cu")
	)
	(gr_line
		(start 159.04591 -142.730982)
		(end 159.061404 -142.72006)
		(stroke
			(width 0.06985)
			(type default)
		)
		(layer "In5.Cu")
	)
	(gr_line
		(start 159.061404 -142.72006)
		(end 159.072326 -142.704566)
		(stroke
			(width 0.06985)
			(type default)
		)
		(layer "In5.Cu")
	)
	(gr_arc
		(start 159.314642 -35.174682)
		(mid 159.249389 -35.272339)
		(end 159.226504 -35.387534)
		(stroke
			(width 0.06985)
			(type default)
		)
		(layer "In5.Cu")
	)
	(gr_line
		(start 159.314642 -35.174682)
		(end 159.467804 -35.02152)
		(stroke
			(width 0.06985)
			(type default)
		)
		(layer "In5.Cu")
	)
	(gr_arc
		(start 160.89376 -210.896454)
		(mid 161.072331 -210.629103)
		(end 161.13506 -210.313778)
		(stroke
			(width 0.06985)
			(type default)
		)
		(layer "In5.Cu")
	)
	(gr_line
		(start 160.89376 -41.809162)
		(end 160.91154 -41.820592)
		(stroke
			(width 0.06985)
			(type default)
		)
		(layer "In5.Cu")
	)
	(gr_line
		(start 160.91154 -41.820592)
		(end 160.93186 -41.82491)
		(stroke
			(width 0.06985)
			(type default)
		)
		(layer "In5.Cu")
	)
	(gr_line
		(start 161.195258 -41.080944)
		(end 161.213038 -41.092374)
		(stroke
			(width 0.06985)
			(type default)
		)
		(layer "In5.Cu")
	)
	(gr_line
		(start 161.213038 -41.092374)
		(end 161.233358 -41.096692)
		(stroke
			(width 0.06985)
			(type default)
		)
		(layer "In5.Cu")
	)
	(gr_line
		(start 161.2773 -35.02152)
		(end 161.430462 -35.174682)
		(stroke
			(width 0.06985)
			(type default)
		)
		(layer "In5.Cu")
	)
	(gr_line
		(start 161.402776 -202.663298)
		(end 161.413698 -202.647804)
		(stroke
			(width 0.06985)
			(type default)
		)
		(layer "In5.Cu")
	)
	(gr_line
		(start 161.413698 -202.647804)
		(end 161.429192 -202.636882)
		(stroke
			(width 0.06985)
			(type default)
		)
		(layer "In5.Cu")
	)
	(gr_line
		(start 161.424874 -144.134332)
		(end 161.440368 -144.12341)
		(stroke
			(width 0.06985)
			(type default)
		)
		(layer "In5.Cu")
	)
	(gr_line
		(start 161.440368 -144.12341)
		(end 161.45129 -144.107916)
		(stroke
			(width 0.06985)
			(type default)
		)
		(layer "In5.Cu")
	)
	(gr_arc
		(start 161.46526 -210.313778)
		(mid 161.527981 -210.6291)
		(end 161.70656 -210.896454)
		(stroke
			(width 0.06985)
			(type default)
		)
		(layer "In5.Cu")
	)
	(gr_arc
		(start 161.5186 -35.387534)
		(mid 161.495689 -35.27235)
		(end 161.430462 -35.174682)
		(stroke
			(width 0.06985)
			(type default)
		)
		(layer "In5.Cu")
	)
	(gr_arc
		(start 161.936938 -35.174682)
		(mid 161.871708 -35.272347)
		(end 161.8488 -35.387534)
		(stroke
			(width 0.06985)
			(type default)
		)
		(layer "In5.Cu")
	)
	(gr_line
		(start 161.936938 -35.174682)
		(end 162.0901 -35.02152)
		(stroke
			(width 0.06985)
			(type default)
		)
		(layer "In5.Cu")
	)
	(gr_line
		(start 161.999676 -40.459406)
		(end 162.017456 -40.470836)
		(stroke
			(width 0.06985)
			(type default)
		)
		(layer "In5.Cu")
	)
	(gr_line
		(start 162.017456 -40.470836)
		(end 162.038538 -40.475408)
		(stroke
			(width 0.06985)
			(type default)
		)
		(layer "In5.Cu")
	)
	(gr_arc
		(start 162.0266 -38.395148)
		(mid 161.961263 -38.168376)
		(end 161.7853 -38.0111)
		(stroke
			(width 0.06985)
			(type default)
		)
		(layer "In5.Cu")
	)
	(gr_line
		(start 162.349942 -117.155468)
		(end 162.364166 -117.145308)
		(stroke
			(width 0.06985)
			(type default)
		)
		(layer "In5.Cu")
	)
	(gr_line
		(start 162.364166 -117.145308)
		(end 162.374326 -117.131084)
		(stroke
			(width 0.06985)
			(type default)
		)
		(layer "In5.Cu")
	)
	(gr_line
		(start 162.46475 -145.303494)
		(end 162.480244 -145.292572)
		(stroke
			(width 0.06985)
			(type default)
		)
		(layer "In5.Cu")
	)
	(gr_line
		(start 162.480244 -145.292572)
		(end 162.491166 -145.277078)
		(stroke
			(width 0.06985)
			(type default)
		)
		(layer "In5.Cu")
	)
	(gr_line
		(start 162.521138 -39.492428)
		(end 162.549078 -39.515288)
		(stroke
			(width 0.06985)
			(type default)
		)
		(layer "In5.Cu")
	)
	(gr_line
		(start 162.549078 -39.515288)
		(end 162.584638 -39.52367)
		(stroke
			(width 0.06985)
			(type default)
		)
		(layer "In5.Cu")
	)
	(gr_arc
		(start 162.5981 -38.0111)
		(mid 162.422108 -38.168358)
		(end 162.3568 -38.395148)
		(stroke
			(width 0.06985)
			(type default)
		)
		(layer "In5.Cu")
	)
	(gr_arc
		(start 162.941 -82.243676)
		(mid 162.878263 -81.928356)
		(end 162.6997 -81.661)
		(stroke
			(width 0.06985)
			(type default)
		)
		(layer "In5.Cu")
	)
	(gr_line
		(start 163.338764 -39.70147)
		(end 163.37026 -39.708836)
		(stroke
			(width 0.06985)
			(type default)
		)
		(layer "In5.Cu")
	)
	(gr_line
		(start 163.37026 -39.708836)
		(end 163.402264 -39.702486)
		(stroke
			(width 0.06985)
			(type default)
		)
		(layer "In5.Cu")
	)
	(gr_line
		(start 163.392612 -133.333998)
		(end 163.438078 -133.59257)
		(stroke
			(width 0.06985)
			(type default)
		)
		(layer "In5.Cu")
	)
	(gr_line
		(start 163.392612 -133.333998)
		(end 163.632896 -132.99059)
		(stroke
			(width 0.06985)
			(type default)
		)
		(layer "In5.Cu")
	)
	(gr_line
		(start 163.424616 -46.153578)
		(end 163.45408 -46.159928)
		(stroke
			(width 0.06985)
			(type default)
		)
		(layer "In5.Cu")
	)
	(gr_line
		(start 163.45408 -46.159928)
		(end 163.483544 -46.153578)
		(stroke
			(width 0.06985)
			(type default)
		)
		(layer "In5.Cu")
	)
	(gr_line
		(start 163.455604 -40.762682)
		(end 163.480242 -40.767)
		(stroke
			(width 0.06985)
			(type default)
		)
		(layer "In5.Cu")
	)
	(gr_line
		(start 163.46932 -41.552368)
		(end 163.493958 -41.556686)
		(stroke
			(width 0.06985)
			(type default)
		)
		(layer "In5.Cu")
	)
	(gr_line
		(start 163.480242 -40.767)
		(end 163.504626 -40.76192)
		(stroke
			(width 0.06985)
			(type default)
		)
		(layer "In5.Cu")
	)
	(gr_line
		(start 163.483036 -42.3418)
		(end 163.507674 -42.346118)
		(stroke
			(width 0.06985)
			(type default)
		)
		(layer "In5.Cu")
	)
	(gr_line
		(start 163.493958 -41.556686)
		(end 163.518342 -41.551606)
		(stroke
			(width 0.06985)
			(type default)
		)
		(layer "In5.Cu")
	)
	(gr_line
		(start 163.507674 -42.346118)
		(end 163.532058 -42.341038)
		(stroke
			(width 0.06985)
			(type default)
		)
		(layer "In5.Cu")
	)
	(gr_arc
		(start 163.5125 -81.661)
		(mid 163.333927 -81.928348)
		(end 163.2712 -82.243676)
		(stroke
			(width 0.06985)
			(type default)
		)
		(layer "In5.Cu")
	)
	(gr_line
		(start 163.548822 -43.240452)
		(end 163.579302 -43.246802)
		(stroke
			(width 0.06985)
			(type default)
		)
		(layer "In5.Cu")
	)
	(gr_line
		(start 163.579302 -43.246802)
		(end 163.608766 -43.240452)
		(stroke
			(width 0.06985)
			(type default)
		)
		(layer "In5.Cu")
	)
	(gr_line
		(start 163.59759 -47.042324)
		(end 163.627054 -47.048674)
		(stroke
			(width 0.06985)
			(type default)
		)
		(layer "In5.Cu")
	)
	(gr_line
		(start 163.627054 -47.048674)
		(end 163.656518 -47.042324)
		(stroke
			(width 0.06985)
			(type default)
		)
		(layer "In5.Cu")
	)
	(gr_line
		(start 163.632896 -132.99059)
		(end 163.891214 -132.945124)
		(stroke
			(width 0.06985)
			(type default)
		)
		(layer "In5.Cu")
	)
	(gr_line
		(start 163.677092 -44.267882)
		(end 163.70681 -44.274232)
		(stroke
			(width 0.06985)
			(type default)
		)
		(layer "In5.Cu")
	)
	(gr_line
		(start 163.70681 -44.274232)
		(end 163.73729 -44.267882)
		(stroke
			(width 0.06985)
			(type default)
		)
		(layer "In5.Cu")
	)
	(gr_line
		(start 163.731448 -133.75386)
		(end 164.141912 -133.167628)
		(stroke
			(width 0.06985)
			(type default)
		)
		(layer "In5.Cu")
	)
	(gr_line
		(start 163.786058 -45.225208)
		(end 163.816538 -45.231558)
		(stroke
			(width 0.06985)
			(type default)
		)
		(layer "In5.Cu")
	)
	(gr_line
		(start 163.814506 -145.552922)
		(end 163.83 -145.542)
		(stroke
			(width 0.06985)
			(type default)
		)
		(layer "In5.Cu")
	)
	(gr_line
		(start 163.816538 -45.231558)
		(end 163.846002 -45.225208)
		(stroke
			(width 0.06985)
			(type default)
		)
		(layer "In5.Cu")
	)
	(gr_line
		(start 163.83 -145.542)
		(end 163.840922 -145.526506)
		(stroke
			(width 0.06985)
			(type default)
		)
		(layer "In5.Cu")
	)
	(gr_line
		(start 164.351208 -146.557746)
		(end 164.366702 -146.546824)
		(stroke
			(width 0.06985)
			(type default)
		)
		(layer "In5.Cu")
	)
	(gr_line
		(start 164.366702 -146.546824)
		(end 164.377624 -146.53133)
		(stroke
			(width 0.06985)
			(type default)
		)
		(layer "In5.Cu")
	)
	(gr_line
		(start 164.597588 -174.591726)
		(end 164.613082 -174.580804)
		(stroke
			(width 0.06985)
			(type default)
		)
		(layer "In5.Cu")
	)
	(gr_line
		(start 164.613082 -174.580804)
		(end 164.624004 -174.56531)
		(stroke
			(width 0.06985)
			(type default)
		)
		(layer "In5.Cu")
	)
	(gr_arc
		(start 164.659564 -83.2104)
		(mid 164.671674 -83.209918)
		(end 164.683694 -83.208368)
		(stroke
			(width 0.06985)
			(type default)
		)
		(layer "In5.Cu")
	)
	(gr_line
		(start 164.92347 -87.854028)
		(end 164.935408 -87.87003)
		(stroke
			(width 0.06985)
			(type default)
		)
		(layer "In5.Cu")
	)
	(gr_line
		(start 164.935408 -87.87003)
		(end 164.952172 -87.880952)
		(stroke
			(width 0.06985)
			(type default)
		)
		(layer "In5.Cu")
	)
	(gr_line
		(start 164.939726 -176.384458)
		(end 164.95522 -176.373536)
		(stroke
			(width 0.06985)
			(type default)
		)
		(layer "In5.Cu")
	)
	(gr_line
		(start 164.95522 -176.373536)
		(end 164.966142 -176.358042)
		(stroke
			(width 0.06985)
			(type default)
		)
		(layer "In5.Cu")
	)
	(gr_line
		(start 165.180518 -147.120102)
		(end 165.196012 -147.10918)
		(stroke
			(width 0.06985)
			(type default)
		)
		(layer "In5.Cu")
	)
	(gr_line
		(start 165.196012 -147.10918)
		(end 165.206934 -147.093686)
		(stroke
			(width 0.06985)
			(type default)
		)
		(layer "In5.Cu")
	)
	(gr_line
		(start 165.351206 -148.917914)
		(end 165.3667 -148.906992)
		(stroke
			(width 0.06985)
			(type default)
		)
		(layer "In5.Cu")
	)
	(gr_line
		(start 165.3667 -148.906992)
		(end 165.377622 -148.891498)
		(stroke
			(width 0.06985)
			(type default)
		)
		(layer "In5.Cu")
	)
	(gr_line
		(start 165.48735 -178.287426)
		(end 165.502844 -178.276504)
		(stroke
			(width 0.06985)
			(type default)
		)
		(layer "In5.Cu")
	)
	(gr_line
		(start 165.502844 -178.276504)
		(end 165.513766 -178.26101)
		(stroke
			(width 0.06985)
			(type default)
		)
		(layer "In5.Cu")
	)
	(gr_line
		(start 165.61435 -180.358034)
		(end 165.629844 -180.347112)
		(stroke
			(width 0.06985)
			(type default)
		)
		(layer "In5.Cu")
	)
	(gr_line
		(start 165.629844 -180.347112)
		(end 165.640766 -180.331618)
		(stroke
			(width 0.06985)
			(type default)
		)
		(layer "In5.Cu")
	)
	(gr_line
		(start 166.053262 -149.620732)
		(end 166.068756 -149.60981)
		(stroke
			(width 0.06985)
			(type default)
		)
		(layer "In5.Cu")
	)
	(gr_line
		(start 166.068756 -149.60981)
		(end 166.079678 -149.594316)
		(stroke
			(width 0.06985)
			(type default)
		)
		(layer "In5.Cu")
	)
	(gr_line
		(start 166.19093 -39.146988)
		(end 166.218616 -39.141654)
		(stroke
			(width 0.06985)
			(type default)
		)
		(layer "In5.Cu")
	)
	(gr_line
		(start 166.218616 -39.141654)
		(end 166.242238 -39.125144)
		(stroke
			(width 0.06985)
			(type default)
		)
		(layer "In5.Cu")
	)
	(gr_arc
		(start 166.493698 -210.896454)
		(mid 166.672325 -210.62912)
		(end 166.734998 -210.313778)
		(stroke
			(width 0.06985)
			(type default)
		)
		(layer "In5.Cu")
	)
	(gr_arc
		(start 166.520622 -37.2872)
		(mid 166.542216 -37.285561)
		(end 166.563294 -37.280596)
		(stroke
			(width 0.06985)
			(type default)
		)
		(layer "In5.Cu")
	)
	(gr_line
		(start 166.734998 -209.332576)
		(end 166.771066 -209.281014)
		(stroke
			(width 0.06985)
			(type default)
		)
		(layer "In5.Cu")
	)
	(gr_line
		(start 166.74465 -40.07358)
		(end 166.770812 -40.067992)
		(stroke
			(width 0.06985)
			(type default)
		)
		(layer "In5.Cu")
	)
	(gr_line
		(start 166.770812 -40.067992)
		(end 166.792656 -40.052752)
		(stroke
			(width 0.06985)
			(type default)
		)
		(layer "In5.Cu")
	)
	(gr_line
		(start 166.96563 -89.18829)
		(end 167.013128 -89.219278)
		(stroke
			(width 0.06985)
			(type default)
		)
		(layer "In5.Cu")
	)
	(gr_line
		(start 166.989506 -199.146922)
		(end 167.005 -199.136)
		(stroke
			(width 0.06985)
			(type default)
		)
		(layer "In5.Cu")
	)
	(gr_line
		(start 166.989506 -150.505922)
		(end 167.005 -150.495)
		(stroke
			(width 0.06985)
			(type default)
		)
		(layer "In5.Cu")
	)
	(gr_line
		(start 167.005 -199.136)
		(end 167.015922 -199.120506)
		(stroke
			(width 0.06985)
			(type default)
		)
		(layer "In5.Cu")
	)
	(gr_line
		(start 167.005 -150.495)
		(end 167.015922 -150.479506)
		(stroke
			(width 0.06985)
			(type default)
		)
		(layer "In5.Cu")
	)
	(gr_arc
		(start 167.065198 -210.313778)
		(mid 167.127863 -210.629132)
		(end 167.306498 -210.896454)
		(stroke
			(width 0.06985)
			(type default)
		)
		(layer "In5.Cu")
	)
	(gr_arc
		(start 167.463724 -36.991544)
		(mid 167.483091 -36.983678)
		(end 167.501062 -36.973002)
		(stroke
			(width 0.06985)
			(type default)
		)
		(layer "In5.Cu")
	)
	(gr_line
		(start 167.53078 -89.287604)
		(end 167.701976 -89.4588)
		(stroke
			(width 0.06985)
			(type default)
		)
		(layer "In5.Cu")
	)
	(gr_line
		(start 167.53078 -88.817196)
		(end 167.701976 -88.646)
		(stroke
			(width 0.06985)
			(type default)
		)
		(layer "In5.Cu")
	)
	(gr_line
		(start 167.624506 -151.394922)
		(end 167.64 -151.384)
		(stroke
			(width 0.06985)
			(type default)
		)
		(layer "In5.Cu")
	)
	(gr_line
		(start 167.64 -151.384)
		(end 167.650922 -151.368506)
		(stroke
			(width 0.06985)
			(type default)
		)
		(layer "In5.Cu")
	)
	(gr_line
		(start 167.679116 -40.667178)
		(end 167.698928 -40.663114)
		(stroke
			(width 0.06985)
			(type default)
		)
		(layer "In5.Cu")
	)
	(gr_line
		(start 167.698928 -40.663114)
		(end 167.716708 -40.651684)
		(stroke
			(width 0.06985)
			(type default)
		)
		(layer "In5.Cu")
	)
	(gr_line
		(start 168.20769 -35.035998)
		(end 168.234868 -35.031172)
		(stroke
			(width 0.06985)
			(type default)
		)
		(layer "In5.Cu")
	)
	(gr_line
		(start 168.234868 -35.031172)
		(end 168.257982 -35.015932)
		(stroke
			(width 0.06985)
			(type default)
		)
		(layer "In5.Cu")
	)
	(gr_line
		(start 168.463214 -34.485834)
		(end 168.514522 -34.24301)
		(stroke
			(width 0.06985)
			(type default)
		)
		(layer "In5.Cu")
	)
	(gr_line
		(start 168.514522 -34.24301)
		(end 168.866058 -34.01441)
		(stroke
			(width 0.06985)
			(type default)
		)
		(layer "In5.Cu")
	)
	(gr_line
		(start 168.640506 -201.572876)
		(end 168.656 -201.561954)
		(stroke
			(width 0.06985)
			(type default)
		)
		(layer "In5.Cu")
	)
	(gr_line
		(start 168.656 -201.561954)
		(end 168.666922 -201.54646)
		(stroke
			(width 0.06985)
			(type default)
		)
		(layer "In5.Cu")
	)
	(gr_line
		(start 168.675304 -34.74466)
		(end 169.258234 -34.365438)
		(stroke
			(width 0.06985)
			(type default)
		)
		(layer "In5.Cu")
	)
	(gr_line
		(start 168.866058 -34.01441)
		(end 169.108628 -34.065972)
		(stroke
			(width 0.06985)
			(type default)
		)
		(layer "In5.Cu")
	)
	(gr_line
		(start 168.905682 -41.199054)
		(end 168.931844 -41.193466)
		(stroke
			(width 0.06985)
			(type default)
		)
		(layer "In5.Cu")
	)
	(gr_line
		(start 168.931844 -41.193466)
		(end 168.953688 -41.178226)
		(stroke
			(width 0.06985)
			(type default)
		)
		(layer "In5.Cu")
	)
	(gr_line
		(start 169.07256 -42.079164)
		(end 169.092372 -42.0751)
		(stroke
			(width 0.06985)
			(type default)
		)
		(layer "In5.Cu")
	)
	(gr_line
		(start 169.092372 -42.0751)
		(end 169.110152 -42.06367)
		(stroke
			(width 0.06985)
			(type default)
		)
		(layer "In5.Cu")
	)
	(gr_line
		(start 169.111676 -82.092292)
		(end 169.15511 -82.084672)
		(stroke
			(width 0.06985)
			(type default)
		)
		(layer "In5.Cu")
	)
	(gr_line
		(start 169.15511 -82.084672)
		(end 169.198544 -82.092292)
		(stroke
			(width 0.06985)
			(type default)
		)
		(layer "In5.Cu")
	)
	(gr_arc
		(start 169.17924 -82.424524)
		(mid 169.15511 -82.422425)
		(end 169.13098 -82.424524)
		(stroke
			(width 0.06985)
			(type default)
		)
		(layer "In5.Cu")
	)
	(gr_line
		(start 169.463974 -33.834832)
		(end 169.515282 -33.592262)
		(stroke
			(width 0.06985)
			(type default)
		)
		(layer "In5.Cu")
	)
	(gr_line
		(start 169.515282 -33.592262)
		(end 169.866818 -33.363662)
		(stroke
			(width 0.06985)
			(type default)
		)
		(layer "In5.Cu")
	)
	(gr_line
		(start 169.633646 -154.875484)
		(end 169.64914 -154.864562)
		(stroke
			(width 0.06985)
			(type default)
		)
		(layer "In5.Cu")
	)
	(gr_line
		(start 169.64914 -154.864562)
		(end 169.660062 -154.849068)
		(stroke
			(width 0.06985)
			(type default)
		)
		(layer "In5.Cu")
	)
	(gr_line
		(start 169.675302 -34.094674)
		(end 170.261026 -33.713674)
		(stroke
			(width 0.06985)
			(type default)
		)
		(layer "In5.Cu")
	)
	(gr_line
		(start 169.69359 -210.896454)
		(end 169.800016 -210.790028)
		(stroke
			(width 0.06985)
			(type default)
		)
		(layer "In5.Cu")
	)
	(gr_arc
		(start 169.800016 -210.790028)
		(mid 169.878988 -210.684243)
		(end 169.92473 -210.560412)
		(stroke
			(width 0.06985)
			(type default)
		)
		(layer "In5.Cu")
	)
	(gr_line
		(start 169.866818 -33.363662)
		(end 170.109388 -33.41497)
		(stroke
			(width 0.06985)
			(type default)
		)
		(layer "In5.Cu")
	)
	(gr_line
		(start 169.920666 -42.956734)
		(end 169.940986 -42.952416)
		(stroke
			(width 0.06985)
			(type default)
		)
		(layer "In5.Cu")
	)
	(gr_arc
		(start 169.92473 -210.560412)
		(mid 169.932324 -210.512672)
		(end 169.93489 -210.4644)
		(stroke
			(width 0.06985)
			(type default)
		)
		(layer "In5.Cu")
	)
	(gr_line
		(start 169.93489 -207.685386)
		(end 169.970958 -207.633824)
		(stroke
			(width 0.06985)
			(type default)
		)
		(layer "In5.Cu")
	)
	(gr_line
		(start 169.940986 -42.952416)
		(end 169.958766 -42.940986)
		(stroke
			(width 0.06985)
			(type default)
		)
		(layer "In5.Cu")
	)
	(gr_line
		(start 170.26255 -156.553154)
		(end 170.278044 -156.542232)
		(stroke
			(width 0.06985)
			(type default)
		)
		(layer "In5.Cu")
	)
	(gr_arc
		(start 170.26509 -210.4644)
		(mid 170.265797 -210.491751)
		(end 170.268138 -210.51901)
		(stroke
			(width 0.06985)
			(type default)
		)
		(layer "In5.Cu")
	)
	(gr_arc
		(start 170.268138 -210.51901)
		(mid 170.311263 -210.665601)
		(end 170.399964 -210.790028)
		(stroke
			(width 0.06985)
			(type default)
		)
		(layer "In5.Cu")
	)
	(gr_line
		(start 170.278044 -156.542232)
		(end 170.288966 -156.526738)
		(stroke
			(width 0.06985)
			(type default)
		)
		(layer "In5.Cu")
	)
	(gr_line
		(start 170.377612 -43.836844)
		(end 170.397424 -43.83278)
		(stroke
			(width 0.06985)
			(type default)
		)
		(layer "In5.Cu")
	)
	(gr_line
		(start 170.397424 -43.83278)
		(end 170.415204 -43.82135)
		(stroke
			(width 0.06985)
			(type default)
		)
		(layer "In5.Cu")
	)
	(gr_line
		(start 170.399964 -210.790028)
		(end 170.50639 -210.896454)
		(stroke
			(width 0.06985)
			(type default)
		)
		(layer "In5.Cu")
	)
	(gr_line
		(start 170.464734 -33.184084)
		(end 170.516042 -32.94126)
		(stroke
			(width 0.06985)
			(type default)
		)
		(layer "In5.Cu")
	)
	(gr_line
		(start 170.516042 -32.94126)
		(end 170.867578 -32.712914)
		(stroke
			(width 0.06985)
			(type default)
		)
		(layer "In5.Cu")
	)
	(gr_line
		(start 170.677078 -33.44291)
		(end 171.260262 -33.063688)
		(stroke
			(width 0.06985)
			(type default)
		)
		(layer "In5.Cu")
	)
	(gr_line
		(start 170.867578 -32.712914)
		(end 171.110148 -32.764222)
		(stroke
			(width 0.06985)
			(type default)
		)
		(layer "In5.Cu")
	)
	(gr_line
		(start 170.935904 -157.85973)
		(end 170.951398 -157.848808)
		(stroke
			(width 0.06985)
			(type default)
		)
		(layer "In5.Cu")
	)
	(gr_line
		(start 170.951398 -157.848808)
		(end 170.96232 -157.833314)
		(stroke
			(width 0.06985)
			(type default)
		)
		(layer "In5.Cu")
	)
	(gr_line
		(start 171.195238 -44.51477)
		(end 171.21505 -44.510706)
		(stroke
			(width 0.06985)
			(type default)
		)
		(layer "In5.Cu")
	)
	(gr_line
		(start 171.21505 -44.510706)
		(end 171.23283 -44.499276)
		(stroke
			(width 0.06985)
			(type default)
		)
		(layer "In5.Cu")
	)
	(gr_line
		(start 171.455842 -45.383958)
		(end 171.536868 -45.366686)
		(stroke
			(width 0.06985)
			(type default)
		)
		(layer "In5.Cu")
	)
	(gr_line
		(start 171.536868 -45.366686)
		(end 171.567856 -45.31868)
		(stroke
			(width 0.06985)
			(type default)
		)
		(layer "In5.Cu")
	)
	(gr_line
		(start 171.64685 -41.450768)
		(end 171.670472 -41.435528)
		(stroke
			(width 0.06985)
			(type default)
		)
		(layer "In5.Cu")
	)
	(gr_line
		(start 171.670472 -41.435528)
		(end 171.69765 -41.430702)
		(stroke
			(width 0.06985)
			(type default)
		)
		(layer "In5.Cu")
	)
	(gr_line
		(start 172.118528 -158.619444)
		(end 172.134022 -158.608522)
		(stroke
			(width 0.06985)
			(type default)
		)
		(layer "In5.Cu")
	)
	(gr_line
		(start 172.134022 -158.608522)
		(end 172.144944 -158.593028)
		(stroke
			(width 0.06985)
			(type default)
		)
		(layer "In5.Cu")
	)
	(gr_line
		(start 172.470572 -42.092626)
		(end 172.494194 -42.077386)
		(stroke
			(width 0.06985)
			(type default)
		)
		(layer "In5.Cu")
	)
	(gr_line
		(start 172.494194 -42.077386)
		(end 172.521372 -42.07256)
		(stroke
			(width 0.06985)
			(type default)
		)
		(layer "In5.Cu")
	)
	(gr_line
		(start 172.584618 -160.367726)
		(end 172.600112 -160.356804)
		(stroke
			(width 0.06985)
			(type default)
		)
		(layer "In5.Cu")
	)
	(gr_line
		(start 172.600112 -160.356804)
		(end 172.611034 -160.34131)
		(stroke
			(width 0.06985)
			(type default)
		)
		(layer "In5.Cu")
	)
	(gr_line
		(start 172.646594 -188.644022)
		(end 172.662088 -188.6331)
		(stroke
			(width 0.06985)
			(type default)
		)
		(layer "In5.Cu")
	)
	(gr_line
		(start 172.662088 -188.6331)
		(end 172.67301 -188.617606)
		(stroke
			(width 0.06985)
			(type default)
		)
		(layer "In5.Cu")
	)
	(gr_line
		(start 172.7454 -96.194372)
		(end 172.954696 -96.403668)
		(stroke
			(width 0.06985)
			(type default)
		)
		(layer "In5.Cu")
	)
	(gr_arc
		(start 172.893736 -210.896454)
		(mid 173.084744 -210.610591)
		(end 173.1518 -210.273392)
		(stroke
			(width 0.06985)
			(type default)
		)
		(layer "In5.Cu")
	)
	(gr_line
		(start 173.1518 -207.798162)
		(end 173.18863 -207.745584)
		(stroke
			(width 0.06985)
			(type default)
		)
		(layer "In5.Cu")
	)
	(gr_line
		(start 173.26991 -32.530542)
		(end 173.29785 -32.510984)
		(stroke
			(width 0.06985)
			(type default)
		)
		(layer "In5.Cu")
	)
	(gr_line
		(start 173.29785 -32.510984)
		(end 173.33087 -32.505142)
		(stroke
			(width 0.06985)
			(type default)
		)
		(layer "In5.Cu")
	)
	(gr_line
		(start 173.33468 -42.740072)
		(end 173.358302 -42.724832)
		(stroke
			(width 0.06985)
			(type default)
		)
		(layer "In5.Cu")
	)
	(gr_line
		(start 173.358302 -42.724832)
		(end 173.38548 -42.720006)
		(stroke
			(width 0.06985)
			(type default)
		)
		(layer "In5.Cu")
	)
	(gr_line
		(start 173.358556 -31.304992)
		(end 173.38167 -31.289752)
		(stroke
			(width 0.06985)
			(type default)
		)
		(layer "In5.Cu")
	)
	(gr_line
		(start 173.38167 -31.289752)
		(end 173.409102 -31.284926)
		(stroke
			(width 0.06985)
			(type default)
		)
		(layer "In5.Cu")
	)
	(gr_line
		(start 173.425104 -96.403668)
		(end 173.6344 -96.194372)
		(stroke
			(width 0.06985)
			(type default)
		)
		(layer "In5.Cu")
	)
	(gr_arc
		(start 173.482 -210.354418)
		(mid 173.54035 -210.647776)
		(end 173.706536 -210.896454)
		(stroke
			(width 0.06985)
			(type default)
		)
		(layer "In5.Cu")
	)
	(gr_line
		(start 173.567344 -38.774878)
		(end 173.585124 -38.763448)
		(stroke
			(width 0.06985)
			(type default)
		)
		(layer "In5.Cu")
	)
	(gr_line
		(start 173.585124 -38.763448)
		(end 173.604936 -38.759384)
		(stroke
			(width 0.06985)
			(type default)
		)
		(layer "In5.Cu")
	)
	(gr_line
		(start 173.712632 -32.435546)
		(end 173.854872 -32.232346)
		(stroke
			(width 0.06985)
			(type default)
		)
		(layer "In5.Cu")
	)
	(gr_line
		(start 173.734984 -43.513248)
		(end 173.757844 -43.498516)
		(stroke
			(width 0.06985)
			(type default)
		)
		(layer "In5.Cu")
	)
	(gr_line
		(start 173.757844 -43.498516)
		(end 173.784768 -43.49369)
		(stroke
			(width 0.06985)
			(type default)
		)
		(layer "In5.Cu")
	)
	(gr_line
		(start 173.80712 -32.756856)
		(end 174.49292 -32.635952)
		(stroke
			(width 0.06985)
			(type default)
		)
		(layer "In5.Cu")
	)
	(gr_line
		(start 173.808898 -33.423606)
		(end 173.836838 -33.404048)
		(stroke
			(width 0.06985)
			(type default)
		)
		(layer "In5.Cu")
	)
	(gr_line
		(start 173.836838 -33.404048)
		(end 173.869858 -33.398206)
		(stroke
			(width 0.06985)
			(type default)
		)
		(layer "In5.Cu")
	)
	(gr_line
		(start 173.854872 -32.232346)
		(end 174.267622 -32.159448)
		(stroke
			(width 0.06985)
			(type default)
		)
		(layer "In5.Cu")
	)
	(gr_line
		(start 174.267622 -32.159448)
		(end 174.470822 -32.301942)
		(stroke
			(width 0.06985)
			(type default)
		)
		(layer "In5.Cu")
	)
	(gr_line
		(start 174.354998 -34.354008)
		(end 174.382938 -34.33445)
		(stroke
			(width 0.06985)
			(type default)
		)
		(layer "In5.Cu")
	)
	(gr_line
		(start 174.382938 -34.33445)
		(end 174.415958 -34.328608)
		(stroke
			(width 0.06985)
			(type default)
		)
		(layer "In5.Cu")
	)
	(gr_line
		(start 174.888398 -32.228282)
		(end 175.030384 -32.025082)
		(stroke
			(width 0.06985)
			(type default)
		)
		(layer "In5.Cu")
	)
	(gr_line
		(start 174.982632 -32.549592)
		(end 175.668686 -32.428688)
		(stroke
			(width 0.06985)
			(type default)
		)
		(layer "In5.Cu")
	)
	(gr_line
		(start 174.990506 -35.250882)
		(end 175.018446 -35.231324)
		(stroke
			(width 0.06985)
			(type default)
		)
		(layer "In5.Cu")
	)
	(gr_line
		(start 175.018446 -35.231324)
		(end 175.051466 -35.225482)
		(stroke
			(width 0.06985)
			(type default)
		)
		(layer "In5.Cu")
	)
	(gr_line
		(start 175.030384 -32.025082)
		(end 175.443134 -31.952184)
		(stroke
			(width 0.06985)
			(type default)
		)
		(layer "In5.Cu")
	)
	(gr_line
		(start 175.443134 -31.952184)
		(end 175.646588 -32.094678)
		(stroke
			(width 0.06985)
			(type default)
		)
		(layer "In5.Cu")
	)
	(gr_line
		(start 175.557434 -36.150804)
		(end 175.585374 -36.131246)
		(stroke
			(width 0.06985)
			(type default)
		)
		(layer "In5.Cu")
	)
	(gr_line
		(start 175.585374 -36.131246)
		(end 175.618394 -36.125404)
		(stroke
			(width 0.06985)
			(type default)
		)
		(layer "In5.Cu")
	)
	(gr_line
		(start 176.063656 -32.021018)
		(end 176.20615 -31.817818)
		(stroke
			(width 0.06985)
			(type default)
		)
		(layer "In5.Cu")
	)
	(gr_line
		(start 176.093628 -210.896454)
		(end 176.186084 -210.803744)
		(stroke
			(width 0.06985)
			(type default)
		)
		(layer "In5.Cu")
	)
	(gr_line
		(start 176.158144 -32.342328)
		(end 176.845468 -32.22117)
		(stroke
			(width 0.06985)
			(type default)
		)
		(layer "In5.Cu")
	)
	(gr_arc
		(start 176.186084 -210.803744)
		(mid 176.290183 -210.648062)
		(end 176.3268 -210.4644)
		(stroke
			(width 0.06985)
			(type default)
		)
		(layer "In5.Cu")
	)
	(gr_line
		(start 176.20615 -31.817818)
		(end 176.6189 -31.74492)
		(stroke
			(width 0.06985)
			(type default)
		)
		(layer "In5.Cu")
	)
	(gr_line
		(start 176.3268 -204.77734)
		(end 176.362868 -204.725778)
		(stroke
			(width 0.06985)
			(type default)
		)
		(layer "In5.Cu")
	)
	(gr_line
		(start 176.6189 -31.74492)
		(end 176.822354 -31.887414)
		(stroke
			(width 0.06985)
			(type default)
		)
		(layer "In5.Cu")
	)
	(gr_arc
		(start 176.657 -210.4644)
		(mid 176.690482 -210.633196)
		(end 176.786032 -210.776312)
		(stroke
			(width 0.06985)
			(type default)
		)
		(layer "In5.Cu")
	)
	(gr_line
		(start 176.786032 -210.776312)
		(end 176.906428 -210.896454)
		(stroke
			(width 0.06985)
			(type default)
		)
		(layer "In5.Cu")
	)
	(gr_line
		(start 177.239422 -31.813754)
		(end 177.381916 -31.610554)
		(stroke
			(width 0.06985)
			(type default)
		)
		(layer "In5.Cu")
	)
	(gr_line
		(start 177.332386 -32.135572)
		(end 178.02098 -32.01416)
		(stroke
			(width 0.06985)
			(type default)
		)
		(layer "In5.Cu")
	)
	(gr_line
		(start 177.381916 -31.610554)
		(end 177.794666 -31.53791)
		(stroke
			(width 0.06985)
			(type default)
		)
		(layer "In5.Cu")
	)
	(gr_line
		(start 177.794666 -31.53791)
		(end 177.99812 -31.68015)
		(stroke
			(width 0.06985)
			(type default)
		)
		(layer "In5.Cu")
	)
	(gr_line
		(start 178.139598 -84.004404)
		(end 178.158394 -84.007706)
		(stroke
			(width 0.06985)
			(type default)
		)
		(layer "In5.Cu")
	)
	(gr_line
		(start 178.158394 -84.007706)
		(end 178.17719 -84.004404)
		(stroke
			(width 0.06985)
			(type default)
		)
		(layer "In5.Cu")
	)
	(gr_line
		(start 178.825144 -40.1701)
		(end 178.975766 -39.954708)
		(stroke
			(width 0.06985)
			(type default)
		)
		(layer "In5.Cu")
	)
	(gr_line
		(start 178.919124 -40.49141)
		(end 179.62499 -40.366696)
		(stroke
			(width 0.06985)
			(type default)
		)
		(layer "In5.Cu")
	)
	(gr_line
		(start 178.975766 -39.954708)
		(end 179.388516 -39.882064)
		(stroke
			(width 0.06985)
			(type default)
		)
		(layer "In5.Cu")
	)
	(gr_line
		(start 179.300632 -30.24632)
		(end 179.319428 -30.243018)
		(stroke
			(width 0.06985)
			(type default)
		)
		(layer "In5.Cu")
	)
	(gr_line
		(start 179.319428 -30.243018)
		(end 179.338224 -30.24632)
		(stroke
			(width 0.06985)
			(type default)
		)
		(layer "In5.Cu")
	)
	(gr_line
		(start 179.388516 -39.882064)
		(end 179.6034 -40.032686)
		(stroke
			(width 0.06985)
			(type default)
		)
		(layer "In5.Cu")
	)
	(gr_line
		(start 179.97551 -31.333948)
		(end 179.993798 -31.330646)
		(stroke
			(width 0.06985)
			(type default)
		)
		(layer "In5.Cu")
	)
	(gr_line
		(start 179.993798 -31.330646)
		(end 180.013356 -31.333948)
		(stroke
			(width 0.06985)
			(type default)
		)
		(layer "In5.Cu")
	)
	(gr_line
		(start 180.020722 -39.958772)
		(end 180.171344 -39.743634)
		(stroke
			(width 0.06985)
			(type default)
		)
		(layer "In5.Cu")
	)
	(gr_line
		(start 180.078126 -32.303212)
		(end 180.09616 -32.300164)
		(stroke
			(width 0.06985)
			(type default)
		)
		(layer "In5.Cu")
	)
	(gr_line
		(start 180.09616 -32.299656)
		(end 180.09616 -32.300164)
		(stroke
			(width 0.06985)
			(type default)
		)
		(layer "In5.Cu")
	)
	(gr_line
		(start 180.09616 -32.299656)
		(end 180.115464 -32.303212)
		(stroke
			(width 0.06985)
			(type default)
		)
		(layer "In5.Cu")
	)
	(gr_line
		(start 180.11521 -40.280082)
		(end 180.821584 -40.155368)
		(stroke
			(width 0.06985)
			(type default)
		)
		(layer "In5.Cu")
	)
	(gr_line
		(start 180.130704 -34.330132)
		(end 180.1495 -34.32683)
		(stroke
			(width 0.06985)
			(type default)
		)
		(layer "In5.Cu")
	)
	(gr_line
		(start 180.130704 -33.321244)
		(end 180.1495 -33.317942)
		(stroke
			(width 0.06985)
			(type default)
		)
		(layer "In5.Cu")
	)
	(gr_line
		(start 180.1495 -34.32683)
		(end 180.168296 -34.330132)
		(stroke
			(width 0.06985)
			(type default)
		)
		(layer "In5.Cu")
	)
	(gr_line
		(start 180.1495 -33.317942)
		(end 180.168296 -33.321244)
		(stroke
			(width 0.06985)
			(type default)
		)
		(layer "In5.Cu")
	)
	(gr_line
		(start 180.171344 -39.743634)
		(end 180.584094 -39.670736)
		(stroke
			(width 0.06985)
			(type default)
		)
		(layer "In5.Cu")
	)
	(gr_line
		(start 180.37302 -35.287204)
		(end 180.391816 -35.283902)
		(stroke
			(width 0.06985)
			(type default)
		)
		(layer "In5.Cu")
	)
	(gr_line
		(start 180.391816 -35.283902)
		(end 180.410612 -35.287204)
		(stroke
			(width 0.06985)
			(type default)
		)
		(layer "In5.Cu")
	)
	(gr_line
		(start 180.584094 -39.670736)
		(end 180.799232 -39.821358)
		(stroke
			(width 0.06985)
			(type default)
		)
		(layer "In5.Cu")
	)
	(gr_line
		(start 181.2163 -39.747698)
		(end 181.366922 -39.53256)
		(stroke
			(width 0.06985)
			(type default)
		)
		(layer "In5.Cu")
	)
	(gr_line
		(start 181.310788 -40.069008)
		(end 182.017162 -39.944294)
		(stroke
			(width 0.06985)
			(type default)
		)
		(layer "In5.Cu")
	)
	(gr_arc
		(start 181.33568 -13.6906)
		(mid 181.373621 -13.782199)
		(end 181.46522 -13.82014)
		(stroke
			(width 0.2)
			(type default)
		)
		(layer "In5.Cu")
	)
	(gr_line
		(start 181.33568 -12.2936)
		(end 181.33568 -13.6906)
		(stroke
			(width 0.2)
			(type default)
		)
		(layer "In5.Cu")
	)
	(gr_line
		(start 181.366922 -39.53256)
		(end 181.779672 -39.459662)
		(stroke
			(width 0.06985)
			(type default)
		)
		(layer "In5.Cu")
	)
	(gr_line
		(start 181.46522 -13.82014)
		(end 182.68442 -13.82014)
		(stroke
			(width 0.2)
			(type default)
		)
		(layer "In5.Cu")
	)
	(gr_arc
		(start 181.46522 -12.16406)
		(mid 181.373621 -12.202001)
		(end 181.33568 -12.2936)
		(stroke
			(width 0.2)
			(type default)
		)
		(layer "In5.Cu")
	)
	(gr_line
		(start 181.623716 -9.707372)
		(end 181.784752 -9.707372)
		(stroke
			(width 0.0635)
			(type default)
		)
		(layer "In5.Cu")
	)
	(gr_line
		(start 181.779672 -39.459662)
		(end 181.995064 -39.610284)
		(stroke
			(width 0.06985)
			(type default)
		)
		(layer "In5.Cu")
	)
	(gr_line
		(start 181.82082 -12.16406)
		(end 181.46522 -12.16406)
		(stroke
			(width 0.2)
			(type default)
		)
		(layer "In5.Cu")
	)
	(gr_arc
		(start 181.838854 -12.16533)
		(mid 181.829859 -12.164384)
		(end 181.82082 -12.16406)
		(stroke
			(width 0.2)
			(type default)
		)
		(layer "In5.Cu")
	)
	(gr_line
		(start 182.310786 -12.16533)
		(end 181.838854 -12.16533)
		(stroke
			(width 0.2)
			(type default)
		)
		(layer "In5.Cu")
	)
	(gr_arc
		(start 182.32882 -12.16406)
		(mid 182.31978 -12.164376)
		(end 182.310786 -12.16533)
		(stroke
			(width 0.2)
			(type default)
		)
		(layer "In5.Cu")
	)
	(gr_line
		(start 182.412386 -39.536624)
		(end 182.562754 -39.321486)
		(stroke
			(width 0.06985)
			(type default)
		)
		(layer "In5.Cu")
	)
	(gr_line
		(start 182.50662 -39.857934)
		(end 183.212994 -39.73322)
		(stroke
			(width 0.06985)
			(type default)
		)
		(layer "In5.Cu")
	)
	(gr_line
		(start 182.562754 -39.321486)
		(end 182.97525 -39.248588)
		(stroke
			(width 0.06985)
			(type default)
		)
		(layer "In5.Cu")
	)
	(gr_arc
		(start 182.68442 -13.82014)
		(mid 182.776019 -13.782199)
		(end 182.81396 -13.6906)
		(stroke
			(width 0.2)
			(type default)
		)
		(layer "In5.Cu")
	)
	(gr_line
		(start 182.68442 -12.16406)
		(end 182.32882 -12.16406)
		(stroke
			(width 0.2)
			(type default)
		)
		(layer "In5.Cu")
	)
	(gr_line
		(start 182.81396 -13.6906)
		(end 182.81396 -12.2936)
		(stroke
			(width 0.2)
			(type default)
		)
		(layer "In5.Cu")
	)
	(gr_arc
		(start 182.81396 -12.2936)
		(mid 182.776019 -12.202001)
		(end 182.68442 -12.16406)
		(stroke
			(width 0.2)
			(type default)
		)
		(layer "In5.Cu")
	)
	(gr_line
		(start 182.836312 -32.166814)
		(end 182.855362 -32.170116)
		(stroke
			(width 0.06985)
			(type default)
		)
		(layer "In5.Cu")
	)
	(gr_line
		(start 182.855362 -32.170116)
		(end 182.874412 -32.166814)
		(stroke
			(width 0.06985)
			(type default)
		)
		(layer "In5.Cu")
	)
	(gr_line
		(start 182.97525 -39.248588)
		(end 183.190642 -39.39921)
		(stroke
			(width 0.06985)
			(type default)
		)
		(layer "In5.Cu")
	)
	(gr_arc
		(start 183.0832 -28.9941)
		(mid 183.252402 -29.170526)
		(end 183.488076 -29.2354)
		(stroke
			(width 0.06985)
			(type default)
		)
		(layer "In5.Cu")
	)
	(gr_arc
		(start 183.0832 -25.9461)
		(mid 183.252402 -26.122526)
		(end 183.488076 -26.1874)
		(stroke
			(width 0.06985)
			(type default)
		)
		(layer "In5.Cu")
	)
	(gr_line
		(start 183.0832 -24.4729)
		(end 183.189626 -24.36622)
		(stroke
			(width 0.06985)
			(type default)
		)
		(layer "In5.Cu")
	)
	(gr_line
		(start 183.0832 -23.6601)
		(end 183.189626 -23.76678)
		(stroke
			(width 0.06985)
			(type default)
		)
		(layer "In5.Cu")
	)
	(gr_arc
		(start 183.0832 -19.8501)
		(mid 183.09892 -19.929008)
		(end 183.143652 -19.995896)
		(stroke
			(width 0.06985)
			(type default)
		)
		(layer "In5.Cu")
	)
	(gr_arc
		(start 183.131714 -20.545806)
		(mid 183.095794 -20.599523)
		(end 183.0832 -20.6629)
		(stroke
			(width 0.06985)
			(type default)
		)
		(layer "In5.Cu")
	)
	(gr_line
		(start 183.134508 -33.167828)
		(end 183.135016 -33.170368)
		(stroke
			(width 0.06985)
			(type default)
		)
		(layer "In5.Cu")
	)
	(gr_line
		(start 183.135016 -33.170368)
		(end 183.152288 -33.16732)
		(stroke
			(width 0.06985)
			(type default)
		)
		(layer "In5.Cu")
	)
	(gr_arc
		(start 183.143652 -19.995896)
		(mid 183.259031 -20.072952)
		(end 183.395112 -20.100036)
		(stroke
			(width 0.06985)
			(type default)
		)
		(layer "In5.Cu")
	)
	(gr_line
		(start 183.147716 -31.25343)
		(end 183.166512 -31.256732)
		(stroke
			(width 0.06985)
			(type default)
		)
		(layer "In5.Cu")
	)
	(gr_line
		(start 183.153304 -34.182812)
		(end 183.1721 -34.186114)
		(stroke
			(width 0.06985)
			(type default)
		)
		(layer "In5.Cu")
	)
	(gr_line
		(start 183.166512 -31.256732)
		(end 183.185308 -31.25343)
		(stroke
			(width 0.06985)
			(type default)
		)
		(layer "In5.Cu")
	)
	(gr_line
		(start 183.1721 -34.186114)
		(end 183.190896 -34.182812)
		(stroke
			(width 0.06985)
			(type default)
		)
		(layer "In5.Cu")
	)
	(gr_arc
		(start 183.189626 -23.76678)
		(mid 183.338924 -23.866445)
		(end 183.515 -23.9014)
		(stroke
			(width 0.06985)
			(type default)
		)
		(layer "In5.Cu")
	)
	(gr_line
		(start 183.216804 -35.20313)
		(end 183.2356 -35.206432)
		(stroke
			(width 0.06985)
			(type default)
		)
		(layer "In5.Cu")
	)
	(gr_line
		(start 183.2356 -35.206432)
		(end 183.254396 -35.20313)
		(stroke
			(width 0.06985)
			(type default)
		)
		(layer "In5.Cu")
	)
	(gr_line
		(start 183.268874 -36.126674)
		(end 183.28767 -36.129976)
		(stroke
			(width 0.06985)
			(type default)
		)
		(layer "In5.Cu")
	)
	(gr_line
		(start 183.28767 -36.129976)
		(end 183.306466 -36.126674)
		(stroke
			(width 0.06985)
			(type default)
		)
		(layer "In5.Cu")
	)
	(gr_arc
		(start 183.383936 -26.5176)
		(mid 183.191172 -26.585403)
		(end 183.0832 -26.7589)
		(stroke
			(width 0.06985)
			(type default)
		)
		(layer "In5.Cu")
	)
	(gr_arc
		(start 183.410606 -20.430236)
		(mid 183.259652 -20.460252)
		(end 183.131714 -20.545806)
		(stroke
			(width 0.06985)
			(type default)
		)
		(layer "In5.Cu")
	)
	(gr_arc
		(start 183.488076 -29.5656)
		(mid 183.2524 -29.630481)
		(end 183.0832 -29.8069)
		(stroke
			(width 0.06985)
			(type default)
		)
		(layer "In5.Cu")
	)
	(gr_arc
		(start 183.515 -24.2316)
		(mid 183.33892 -24.266543)
		(end 183.189626 -24.36622)
		(stroke
			(width 0.06985)
			(type default)
		)
		(layer "In5.Cu")
	)
	(gr_arc
		(start 184.093612 -210.896454)
		(mid 184.272193 -210.629106)
		(end 184.334912 -210.313778)
		(stroke
			(width 0.06985)
			(type default)
		)
		(layer "In5.Cu")
	)
	(gr_line
		(start 184.2008 -26.5176)
		(end 184.264046 -26.461974)
		(stroke
			(width 0.06985)
			(type default)
		)
		(layer "In5.Cu")
	)
	(gr_line
		(start 184.481216 -23.801324)
		(end 184.493154 -23.74519)
		(stroke
			(width 0.06985)
			(type default)
		)
		(layer "In5.Cu")
	)
	(gr_line
		(start 184.542938 -21.92274)
		(end 184.563004 -21.828506)
		(stroke
			(width 0.06985)
			(type default)
		)
		(layer "In5.Cu")
	)
	(gr_line
		(start 184.563004 -21.828506)
		(end 184.64403 -21.775674)
		(stroke
			(width 0.06985)
			(type default)
		)
		(layer "In5.Cu")
	)
	(gr_arc
		(start 184.665112 -210.313778)
		(mid 184.727833 -210.6291)
		(end 184.906412 -210.896454)
		(stroke
			(width 0.06985)
			(type default)
		)
		(layer "In5.Cu")
	)
	(gr_line
		(start 184.774078 -29.142436)
		(end 184.792874 -29.139134)
		(stroke
			(width 0.06985)
			(type default)
		)
		(layer "In5.Cu")
	)
	(gr_line
		(start 184.792874 -29.139134)
		(end 184.81167 -29.142436)
		(stroke
			(width 0.06985)
			(type default)
		)
		(layer "In5.Cu")
	)
	(gr_line
		(start 184.82691 -25.966674)
		(end 184.85485 -25.94229)
		(stroke
			(width 0.06985)
			(type default)
		)
		(layer "In5.Cu")
	)
	(gr_line
		(start 184.85485 -25.94229)
		(end 184.869074 -25.907238)
		(stroke
			(width 0.06985)
			(type default)
		)
		(layer "In5.Cu")
	)
	(gr_line
		(start 185.114692 -24.417274)
		(end 185.146442 -24.33828)
		(stroke
			(width 0.06985)
			(type default)
		)
		(layer "In5.Cu")
	)
	(gr_line
		(start 185.146442 -24.33828)
		(end 185.223658 -24.30018)
		(stroke
			(width 0.06985)
			(type default)
		)
		(layer "In5.Cu")
	)
	(gr_line
		(start 185.349896 -21.316696)
		(end 185.431684 -21.26361)
		(stroke
			(width 0.06985)
			(type default)
		)
		(layer "In5.Cu")
	)
	(gr_line
		(start 185.431684 -21.26361)
		(end 185.470038 -21.271738)
		(stroke
			(width 0.06985)
			(type default)
		)
		(layer "In5.Cu")
	)
	(gr_line
		(start 185.470038 -21.271738)
		(end 185.52668 -21.283676)
		(stroke
			(width 0.06985)
			(type default)
		)
		(layer "In5.Cu")
	)
	(gr_line
		(start 185.551318 -31.359602)
		(end 185.570368 -31.3563)
		(stroke
			(width 0.06985)
			(type default)
		)
		(layer "In5.Cu")
	)
	(gr_line
		(start 185.570368 -31.3563)
		(end 185.589164 -31.359602)
		(stroke
			(width 0.06985)
			(type default)
		)
		(layer "In5.Cu")
	)
	(gr_line
		(start 185.73115 -32.377126)
		(end 185.749946 -32.373824)
		(stroke
			(width 0.06985)
			(type default)
		)
		(layer "In5.Cu")
	)
	(gr_line
		(start 185.749946 -32.373824)
		(end 185.768996 -32.377126)
		(stroke
			(width 0.06985)
			(type default)
		)
		(layer "In5.Cu")
	)
	(gr_line
		(start 185.773314 -36.172648)
		(end 185.802778 -36.166298)
		(stroke
			(width 0.06985)
			(type default)
		)
		(layer "In5.Cu")
	)
	(gr_line
		(start 185.795158 -33.3883)
		(end 185.813954 -33.384998)
		(stroke
			(width 0.06985)
			(type default)
		)
		(layer "In5.Cu")
	)
	(gr_line
		(start 185.802778 -36.166298)
		(end 185.832242 -36.172648)
		(stroke
			(width 0.06985)
			(type default)
		)
		(layer "In5.Cu")
	)
	(gr_line
		(start 185.813954 -33.384998)
		(end 185.83275 -33.3883)
		(stroke
			(width 0.06985)
			(type default)
		)
		(layer "In5.Cu")
	)
	(gr_line
		(start 185.845704 -34.41065)
		(end 185.8645 -34.407348)
		(stroke
			(width 0.06985)
			(type default)
		)
		(layer "In5.Cu")
	)
	(gr_line
		(start 185.8645 -34.407348)
		(end 185.883296 -34.41065)
		(stroke
			(width 0.06985)
			(type default)
		)
		(layer "In5.Cu")
	)
	(gr_line
		(start 185.871104 -35.33902)
		(end 185.8899 -35.335718)
		(stroke
			(width 0.06985)
			(type default)
		)
		(layer "In5.Cu")
	)
	(gr_line
		(start 185.8899 -35.335718)
		(end 185.908696 -35.33902)
		(stroke
			(width 0.06985)
			(type default)
		)
		(layer "In5.Cu")
	)
	(gr_arc
		(start 186.055 -24.998934)
		(mid 186.223479 -25.162728)
		(end 186.450732 -25.222454)
		(stroke
			(width 0.06985)
			(type default)
		)
		(layer "In5.Cu")
	)
	(gr_line
		(start 186.153552 -30.394402)
		(end 186.172602 -30.3911)
		(stroke
			(width 0.06985)
			(type default)
		)
		(layer "In5.Cu")
	)
	(gr_line
		(start 186.172602 -30.3911)
		(end 186.191398 -30.394402)
		(stroke
			(width 0.06985)
			(type default)
		)
		(layer "In5.Cu")
	)
	(gr_line
		(start 186.186826 -195.297806)
		(end 186.192668 -195.264786)
		(stroke
			(width 0.06985)
			(type default)
		)
		(layer "In5.Cu")
	)
	(gr_line
		(start 186.192668 -195.264786)
		(end 186.212226 -195.236846)
		(stroke
			(width 0.06985)
			(type default)
		)
		(layer "In5.Cu")
	)
	(gr_arc
		(start 186.450732 -25.552654)
		(mid 186.214229 -25.623182)
		(end 186.055 -25.811734)
		(stroke
			(width 0.06985)
			(type default)
		)
		(layer "In5.Cu")
	)
	(gr_line
		(start 186.73953 -23.552404)
		(end 186.806332 -23.519384)
		(stroke
			(width 0.06985)
			(type default)
		)
		(layer "In5.Cu")
	)
	(gr_line
		(start 186.806332 -23.519384)
		(end 186.879484 -23.534878)
		(stroke
			(width 0.06985)
			(type default)
		)
		(layer "In5.Cu")
	)
	(gr_line
		(start 187.032138 -31.94939)
		(end 187.050934 -31.952692)
		(stroke
			(width 0.06985)
			(type default)
		)
		(layer "In5.Cu")
	)
	(gr_line
		(start 187.050934 -31.952692)
		(end 187.070492 -31.94939)
		(stroke
			(width 0.06985)
			(type default)
		)
		(layer "In5.Cu")
	)
	(gr_line
		(start 187.058554 -32.93999)
		(end 187.07735 -32.943292)
		(stroke
			(width 0.06985)
			(type default)
		)
		(layer "In5.Cu")
	)
	(gr_line
		(start 187.07735 -32.943292)
		(end 187.096146 -32.93999)
		(stroke
			(width 0.06985)
			(type default)
		)
		(layer "In5.Cu")
	)
	(gr_arc
		(start 187.293758 -210.896454)
		(mid 187.47233 -210.629103)
		(end 187.535058 -210.313778)
		(stroke
			(width 0.06985)
			(type default)
		)
		(layer "In5.Cu")
	)
	(gr_line
		(start 187.380372 -29.930598)
		(end 187.399168 -29.9339)
		(stroke
			(width 0.06985)
			(type default)
		)
		(layer "In5.Cu")
	)
	(gr_line
		(start 187.399168 -29.9339)
		(end 187.417964 -29.930598)
		(stroke
			(width 0.06985)
			(type default)
		)
		(layer "In5.Cu")
	)
	(gr_line
		(start 187.45581 -30.952948)
		(end 187.474606 -30.95625)
		(stroke
			(width 0.06985)
			(type default)
		)
		(layer "In5.Cu")
	)
	(gr_line
		(start 187.474606 -30.95625)
		(end 187.493656 -30.952948)
		(stroke
			(width 0.06985)
			(type default)
		)
		(layer "In5.Cu")
	)
	(gr_line
		(start 187.522612 -82.356452)
		(end 187.555632 -82.35061)
		(stroke
			(width 0.06985)
			(type default)
		)
		(layer "In5.Cu")
	)
	(gr_line
		(start 187.555632 -82.35061)
		(end 187.583572 -82.331052)
		(stroke
			(width 0.06985)
			(type default)
		)
		(layer "In5.Cu")
	)
	(gr_line
		(start 187.745878 -25.222454)
		(end 187.785248 -25.24506)
		(stroke
			(width 0.06985)
			(type default)
		)
		(layer "In5.Cu")
	)
	(gr_arc
		(start 187.865258 -210.313778)
		(mid 187.927979 -210.6291)
		(end 188.106558 -210.896454)
		(stroke
			(width 0.06985)
			(type default)
		)
		(layer "In5.Cu")
	)
	(gr_line
		(start 187.897262 -21.78431)
		(end 187.99175 -21.80463)
		(stroke
			(width 0.06985)
			(type default)
		)
		(layer "In5.Cu")
	)
	(gr_line
		(start 187.99175 -21.80463)
		(end 188.044582 -21.88591)
		(stroke
			(width 0.06985)
			(type default)
		)
		(layer "In5.Cu")
	)
	(gr_line
		(start 188.22035 -23.82012)
		(end 188.240162 -23.824184)
		(stroke
			(width 0.06985)
			(type default)
		)
		(layer "In5.Cu")
	)
	(gr_line
		(start 188.240162 -23.824184)
		(end 188.257942 -23.835614)
		(stroke
			(width 0.06985)
			(type default)
		)
		(layer "In5.Cu")
	)
	(gr_line
		(start 188.41466 -23.060914)
		(end 188.430662 -23.085552)
		(stroke
			(width 0.06985)
			(type default)
		)
		(layer "In5.Cu")
	)
	(gr_line
		(start 188.430662 -23.085806)
		(end 188.456316 -23.102316)
		(stroke
			(width 0.06985)
			(type default)
		)
		(layer "In5.Cu")
	)
	(gr_line
		(start 188.430662 -23.085552)
		(end 188.430662 -23.085806)
		(stroke
			(width 0.06985)
			(type default)
		)
		(layer "In5.Cu")
	)
	(gr_line
		(start 188.449204 -35.198304)
		(end 188.468 -35.201606)
		(stroke
			(width 0.06985)
			(type default)
		)
		(layer "In5.Cu")
	)
	(gr_line
		(start 188.449204 -34.185352)
		(end 188.468 -34.188654)
		(stroke
			(width 0.06985)
			(type default)
		)
		(layer "In5.Cu")
	)
	(gr_line
		(start 188.468 -35.201606)
		(end 188.486796 -35.198304)
		(stroke
			(width 0.06985)
			(type default)
		)
		(layer "In5.Cu")
	)
	(gr_line
		(start 188.468 -34.188654)
		(end 188.486796 -34.185352)
		(stroke
			(width 0.06985)
			(type default)
		)
		(layer "In5.Cu")
	)
	(gr_line
		(start 188.703712 -36.16706)
		(end 188.722508 -36.170362)
		(stroke
			(width 0.06985)
			(type default)
		)
		(layer "In5.Cu")
	)
	(gr_line
		(start 188.722508 -36.170362)
		(end 188.741304 -36.16706)
		(stroke
			(width 0.06985)
			(type default)
		)
		(layer "In5.Cu")
	)
	(gr_line
		(start 189.394084 -24.967946)
		(end 189.412626 -24.979884)
		(stroke
			(width 0.06985)
			(type default)
		)
		(layer "In5.Cu")
	)
	(gr_line
		(start 189.412626 -24.979884)
		(end 189.433962 -24.984456)
		(stroke
			(width 0.06985)
			(type default)
		)
		(layer "In5.Cu")
	)
	(gr_line
		(start 189.644274 -23.874222)
		(end 189.662054 -23.885652)
		(stroke
			(width 0.06985)
			(type default)
		)
		(layer "In5.Cu")
	)
	(gr_line
		(start 189.662054 -23.885652)
		(end 189.681866 -23.889716)
		(stroke
			(width 0.06985)
			(type default)
		)
		(layer "In5.Cu")
	)
	(gr_line
		(start 189.760606 -26.743914)
		(end 189.775084 -26.752042)
		(stroke
			(width 0.06985)
			(type default)
		)
		(layer "In5.Cu")
	)
	(gr_line
		(start 189.775084 -26.752042)
		(end 189.79134 -26.75509)
		(stroke
			(width 0.06985)
			(type default)
		)
		(layer "In5.Cu")
	)
	(gr_line
		(start 189.959996 -37.387784)
		(end 189.98946 -37.394134)
		(stroke
			(width 0.06985)
			(type default)
		)
		(layer "In5.Cu")
	)
	(gr_line
		(start 189.98946 -37.394134)
		(end 190.018924 -37.387784)
		(stroke
			(width 0.06985)
			(type default)
		)
		(layer "In5.Cu")
	)
	(gr_arc
		(start 190.49365 -210.896454)
		(mid 190.672223 -210.629104)
		(end 190.73495 -210.313778)
		(stroke
			(width 0.06985)
			(type default)
		)
		(layer "In5.Cu")
	)
	(gr_line
		(start 190.543942 -80.258158)
		(end 190.559436 -80.247236)
		(stroke
			(width 0.06985)
			(type default)
		)
		(layer "In5.Cu")
	)
	(gr_line
		(start 190.555118 -24.07539)
		(end 190.584582 -24.08174)
		(stroke
			(width 0.06985)
			(type default)
		)
		(layer "In5.Cu")
	)
	(gr_line
		(start 190.559436 -80.247236)
		(end 190.570358 -80.231742)
		(stroke
			(width 0.06985)
			(type default)
		)
		(layer "In5.Cu")
	)
	(gr_line
		(start 190.584582 -24.08174)
		(end 190.614046 -24.07539)
		(stroke
			(width 0.06985)
			(type default)
		)
		(layer "In5.Cu")
	)
	(gr_line
		(start 190.612268 -190.490602)
		(end 190.61811 -190.457582)
		(stroke
			(width 0.06985)
			(type default)
		)
		(layer "In5.Cu")
	)
	(gr_line
		(start 190.61811 -190.457582)
		(end 190.637668 -190.429642)
		(stroke
			(width 0.06985)
			(type default)
		)
		(layer "In5.Cu")
	)
	(gr_arc
		(start 191.06515 -210.313778)
		(mid 191.127871 -210.6291)
		(end 191.30645 -210.896454)
		(stroke
			(width 0.06985)
			(type default)
		)
		(layer "In5.Cu")
	)
	(gr_line
		(start 191.233806 -33.363154)
		(end 191.3763 -33.1597)
		(stroke
			(width 0.06985)
			(type default)
		)
		(layer "In5.Cu")
	)
	(gr_line
		(start 191.326008 -33.684972)
		(end 192.014348 -33.56356)
		(stroke
			(width 0.06985)
			(type default)
		)
		(layer "In5.Cu")
	)
	(gr_line
		(start 191.3763 -33.1597)
		(end 191.78905 -33.087056)
		(stroke
			(width 0.06985)
			(type default)
		)
		(layer "In5.Cu")
	)
	(gr_line
		(start 191.421258 -35.359086)
		(end 191.440054 -35.355784)
		(stroke
			(width 0.06985)
			(type default)
		)
		(layer "In5.Cu")
	)
	(gr_line
		(start 191.440054 -35.355784)
		(end 191.45885 -35.359086)
		(stroke
			(width 0.06985)
			(type default)
		)
		(layer "In5.Cu")
	)
	(gr_line
		(start 191.630808 -29.187648)
		(end 191.645032 -29.185108)
		(stroke
			(width 0.06985)
			(type default)
		)
		(layer "In5.Cu")
	)
	(gr_line
		(start 191.645032 -29.185108)
		(end 191.657732 -29.177996)
		(stroke
			(width 0.06985)
			(type default)
		)
		(layer "In5.Cu")
	)
	(gr_line
		(start 191.78905 -33.087056)
		(end 191.99225 -33.229296)
		(stroke
			(width 0.06985)
			(type default)
		)
		(layer "In5.Cu")
	)
	(gr_line
		(start 191.918844 -40.299132)
		(end 191.93764 -40.29583)
		(stroke
			(width 0.06985)
			(type default)
		)
		(layer "In5.Cu")
	)
	(gr_line
		(start 191.93764 -40.29583)
		(end 191.956436 -40.299132)
		(stroke
			(width 0.06985)
			(type default)
		)
		(layer "In5.Cu")
	)
	(gr_line
		(start 191.960246 -78.246478)
		(end 191.979804 -78.218538)
		(stroke
			(width 0.06985)
			(type default)
		)
		(layer "In5.Cu")
	)
	(gr_line
		(start 191.979804 -78.218538)
		(end 191.985646 -78.185518)
		(stroke
			(width 0.06985)
			(type default)
		)
		(layer "In5.Cu")
	)
	(gr_line
		(start 192.027048 -71.491348)
		(end 192.03035 -71.510398)
		(stroke
			(width 0.06985)
			(type default)
		)
		(layer "In5.Cu")
	)
	(gr_line
		(start 192.027048 -71.491348)
		(end 192.03035 -71.472552)
		(stroke
			(width 0.06985)
			(type default)
		)
		(layer "In5.Cu")
	)
	(gr_line
		(start 192.029588 -27.157172)
		(end 192.05956 -27.162506)
		(stroke
			(width 0.06985)
			(type default)
		)
		(layer "In5.Cu")
	)
	(gr_line
		(start 192.03035 -71.510144)
		(end 192.03035 -71.510398)
		(stroke
			(width 0.06985)
			(type default)
		)
		(layer "In5.Cu")
	)
	(gr_line
		(start 192.05956 -27.162506)
		(end 192.088262 -27.155394)
		(stroke
			(width 0.06985)
			(type default)
		)
		(layer "In5.Cu")
	)
	(gr_line
		(start 192.200022 -39.398194)
		(end 192.218818 -39.394892)
		(stroke
			(width 0.06985)
			(type default)
		)
		(layer "In5.Cu")
	)
	(gr_line
		(start 192.218818 -39.394892)
		(end 192.237614 -39.398194)
		(stroke
			(width 0.06985)
			(type default)
		)
		(layer "In5.Cu")
	)
	(gr_line
		(start 192.409572 -33.15589)
		(end 192.552066 -32.952436)
		(stroke
			(width 0.06985)
			(type default)
		)
		(layer "In5.Cu")
	)
	(gr_line
		(start 192.487804 -35.87623)
		(end 193.176652 -35.997642)
		(stroke
			(width 0.06985)
			(type default)
		)
		(layer "In5.Cu")
	)
	(gr_line
		(start 192.50279 -33.477454)
		(end 193.189352 -33.356296)
		(stroke
			(width 0.06985)
			(type default)
		)
		(layer "In5.Cu")
	)
	(gr_line
		(start 192.51041 -35.541966)
		(end 192.71361 -35.399726)
		(stroke
			(width 0.06985)
			(type default)
		)
		(layer "In5.Cu")
	)
	(gr_line
		(start 192.543684 -25.645364)
		(end 192.573148 -25.651714)
		(stroke
			(width 0.06985)
			(type default)
		)
		(layer "In5.Cu")
	)
	(gr_line
		(start 192.552066 -32.952436)
		(end 192.964816 -32.879792)
		(stroke
			(width 0.06985)
			(type default)
		)
		(layer "In5.Cu")
	)
	(gr_line
		(start 192.573148 -25.651714)
		(end 192.602612 -25.645364)
		(stroke
			(width 0.06985)
			(type default)
		)
		(layer "In5.Cu")
	)
	(gr_line
		(start 192.672462 -36.521644)
		(end 192.691258 -36.518342)
		(stroke
			(width 0.06985)
			(type default)
		)
		(layer "In5.Cu")
	)
	(gr_line
		(start 192.691258 -36.518342)
		(end 192.710054 -36.521644)
		(stroke
			(width 0.06985)
			(type default)
		)
		(layer "In5.Cu")
	)
	(gr_line
		(start 192.71361 -35.399726)
		(end 193.12636 -35.47237)
		(stroke
			(width 0.06985)
			(type default)
		)
		(layer "In5.Cu")
	)
	(gr_line
		(start 192.760854 -73.788778)
		(end 192.760854 -73.789032)
		(stroke
			(width 0.06985)
			(type default)
		)
		(layer "In5.Cu")
	)
	(gr_line
		(start 192.760854 -73.788778)
		(end 192.764156 -73.769982)
		(stroke
			(width 0.06985)
			(type default)
		)
		(layer "In5.Cu")
	)
	(gr_line
		(start 192.760854 -73.751186)
		(end 192.764156 -73.769982)
		(stroke
			(width 0.06985)
			(type default)
		)
		(layer "In5.Cu")
	)
	(gr_line
		(start 192.76695 -38.498018)
		(end 192.785746 -38.494716)
		(stroke
			(width 0.06985)
			(type default)
		)
		(layer "In5.Cu")
	)
	(gr_line
		(start 192.785746 -38.494716)
		(end 192.804542 -38.498018)
		(stroke
			(width 0.06985)
			(type default)
		)
		(layer "In5.Cu")
	)
	(gr_line
		(start 192.794128 -22.057868)
		(end 192.823592 -22.064218)
		(stroke
			(width 0.06985)
			(type default)
		)
		(layer "In5.Cu")
	)
	(gr_line
		(start 192.823592 -22.064218)
		(end 192.854072 -22.057868)
		(stroke
			(width 0.06985)
			(type default)
		)
		(layer "In5.Cu")
	)
	(gr_line
		(start 192.964054 -92.004642)
		(end 192.983612 -91.976702)
		(stroke
			(width 0.06985)
			(type default)
		)
		(layer "In5.Cu")
	)
	(gr_line
		(start 192.964816 -32.879792)
		(end 193.167762 -33.022032)
		(stroke
			(width 0.06985)
			(type default)
		)
		(layer "In5.Cu")
	)
	(gr_line
		(start 192.983612 -91.976702)
		(end 192.989454 -91.943682)
		(stroke
			(width 0.06985)
			(type default)
		)
		(layer "In5.Cu")
	)
	(gr_line
		(start 193.12636 -35.47237)
		(end 193.268854 -35.675824)
		(stroke
			(width 0.06985)
			(type default)
		)
		(layer "In5.Cu")
	)
	(gr_line
		(start 193.24447 -37.626544)
		(end 193.263266 -37.623242)
		(stroke
			(width 0.06985)
			(type default)
		)
		(layer "In5.Cu")
	)
	(gr_line
		(start 193.263266 -37.623242)
		(end 193.282062 -37.626544)
		(stroke
			(width 0.06985)
			(type default)
		)
		(layer "In5.Cu")
	)
	(gr_line
		(start 193.355468 -42.987468)
		(end 193.545206 -43.177206)
		(stroke
			(width 0.0635)
			(type default)
		)
		(layer "In5.Cu")
	)
	(gr_line
		(start 193.664332 -36.083494)
		(end 194.350386 -36.204398)
		(stroke
			(width 0.06985)
			(type default)
		)
		(layer "In5.Cu")
	)
	(gr_line
		(start 193.686176 -35.74923)
		(end 193.889376 -35.60699)
		(stroke
			(width 0.06985)
			(type default)
		)
		(layer "In5.Cu")
	)
	(gr_arc
		(start 193.693796 -210.896454)
		(mid 193.872381 -210.629107)
		(end 193.935096 -210.313778)
		(stroke
			(width 0.06985)
			(type default)
		)
		(layer "In5.Cu")
	)
	(gr_line
		(start 193.889376 -35.60699)
		(end 194.301872 -35.679634)
		(stroke
			(width 0.06985)
			(type default)
		)
		(layer "In5.Cu")
	)
	(gr_line
		(start 193.949574 -188.68263)
		(end 193.955416 -188.64961)
		(stroke
			(width 0.06985)
			(type default)
		)
		(layer "In5.Cu")
	)
	(gr_line
		(start 193.955416 -188.64961)
		(end 193.974974 -188.62167)
		(stroke
			(width 0.06985)
			(type default)
		)
		(layer "In5.Cu")
	)
	(gr_line
		(start 193.979546 -27.5336)
		(end 193.9798 -27.5336)
		(stroke
			(width 0.06985)
			(type default)
		)
		(layer "In5.Cu")
	)
	(gr_line
		(start 194.023996 -23.012908)
		(end 194.05346 -23.006558)
		(stroke
			(width 0.06985)
			(type default)
		)
		(layer "In5.Cu")
	)
	(gr_line
		(start 194.05346 -23.006558)
		(end 194.082924 -23.012908)
		(stroke
			(width 0.06985)
			(type default)
		)
		(layer "In5.Cu")
	)
	(gr_arc
		(start 194.265296 -210.313778)
		(mid 194.328017 -210.6291)
		(end 194.506596 -210.896454)
		(stroke
			(width 0.06985)
			(type default)
		)
		(layer "In5.Cu")
	)
	(gr_line
		(start 194.267328 -43.177206)
		(end 194.457066 -42.987468)
		(stroke
			(width 0.0635)
			(type default)
		)
		(layer "In5.Cu")
	)
	(gr_line
		(start 194.301872 -35.679634)
		(end 194.444112 -35.882834)
		(stroke
			(width 0.06985)
			(type default)
		)
		(layer "In5.Cu")
	)
	(gr_line
		(start 194.474084 -57.61228)
		(end 194.479926 -57.57926)
		(stroke
			(width 0.06985)
			(type default)
		)
		(layer "In5.Cu")
	)
	(gr_line
		(start 194.479926 -57.57926)
		(end 194.499484 -57.55132)
		(stroke
			(width 0.06985)
			(type default)
		)
		(layer "In5.Cu")
	)
	(gr_line
		(start 194.590162 -91.979496)
		(end 194.60972 -91.951556)
		(stroke
			(width 0.06985)
			(type default)
		)
		(layer "In5.Cu")
	)
	(gr_line
		(start 194.602354 -29.364686)
		(end 194.61734 -29.361892)
		(stroke
			(width 0.06985)
			(type default)
		)
		(layer "In5.Cu")
	)
	(gr_line
		(start 194.60972 -91.951556)
		(end 194.615562 -91.918536)
		(stroke
			(width 0.06985)
			(type default)
		)
		(layer "In5.Cu")
	)
	(gr_line
		(start 194.61734 -29.361892)
		(end 194.632834 -29.364432)
		(stroke
			(width 0.06985)
			(type default)
		)
		(layer "In5.Cu")
	)
	(gr_line
		(start 194.70243 -30.265624)
		(end 194.721226 -30.262322)
		(stroke
			(width 0.06985)
			(type default)
		)
		(layer "In5.Cu")
	)
	(gr_line
		(start 194.721226 -30.262322)
		(end 194.740022 -30.265624)
		(stroke
			(width 0.06985)
			(type default)
		)
		(layer "In5.Cu")
	)
	(gr_line
		(start 194.768216 -27.318462)
		(end 194.818 -27.305)
		(stroke
			(width 0.06985)
			(type default)
		)
		(layer "In5.Cu")
	)
	(gr_line
		(start 194.793616 -31.246572)
		(end 194.812412 -31.24327)
		(stroke
			(width 0.06985)
			(type default)
		)
		(layer "In5.Cu")
	)
	(gr_line
		(start 194.812412 -31.24327)
		(end 194.831208 -31.246572)
		(stroke
			(width 0.06985)
			(type default)
		)
		(layer "In5.Cu")
	)
	(gr_line
		(start 194.818 -27.305)
		(end 194.86753 -27.319224)
		(stroke
			(width 0.06985)
			(type default)
		)
		(layer "In5.Cu")
	)
	(gr_line
		(start 195.17106 -71.376032)
		(end 195.174362 -71.395082)
		(stroke
			(width 0.06985)
			(type default)
		)
		(layer "In5.Cu")
	)
	(gr_line
		(start 195.17106 -71.376032)
		(end 195.174362 -71.357236)
		(stroke
			(width 0.06985)
			(type default)
		)
		(layer "In5.Cu")
	)
	(gr_line
		(start 195.396866 -78.291182)
		(end 195.396866 -78.291436)
		(stroke
			(width 0.06985)
			(type default)
		)
		(layer "In5.Cu")
	)
	(gr_line
		(start 195.396866 -78.291182)
		(end 195.400168 -78.272386)
		(stroke
			(width 0.06985)
			(type default)
		)
		(layer "In5.Cu")
	)
	(gr_line
		(start 195.396866 -78.25359)
		(end 195.400168 -78.272386)
		(stroke
			(width 0.06985)
			(type default)
		)
		(layer "In5.Cu")
	)
	(gr_line
		(start 195.575174 -69.083936)
		(end 195.581016 -69.050916)
		(stroke
			(width 0.06985)
			(type default)
		)
		(layer "In5.Cu")
	)
	(gr_line
		(start 195.581016 -69.050916)
		(end 195.600574 -69.022976)
		(stroke
			(width 0.06985)
			(type default)
		)
		(layer "In5.Cu")
	)
	(gr_line
		(start 195.717414 -58.570114)
		(end 195.723256 -58.537094)
		(stroke
			(width 0.06985)
			(type default)
		)
		(layer "In5.Cu")
	)
	(gr_line
		(start 195.718938 -55.810912)
		(end 195.72859 -55.796942)
		(stroke
			(width 0.06985)
			(type default)
		)
		(layer "In5.Cu")
	)
	(gr_line
		(start 195.723256 -58.537094)
		(end 195.742814 -58.509154)
		(stroke
			(width 0.06985)
			(type default)
		)
		(layer "In5.Cu")
	)
	(gr_line
		(start 195.72859 -55.796942)
		(end 195.74256 -55.787036)
		(stroke
			(width 0.06985)
			(type default)
		)
		(layer "In5.Cu")
	)
	(gr_line
		(start 196.015864 -36.497768)
		(end 196.03466 -36.50107)
		(stroke
			(width 0.06985)
			(type default)
		)
		(layer "In5.Cu")
	)
	(gr_line
		(start 196.03466 -36.50107)
		(end 196.053456 -36.497768)
		(stroke
			(width 0.06985)
			(type default)
		)
		(layer "In5.Cu")
	)
	(gr_line
		(start 196.119496 -37.457888)
		(end 196.138292 -37.46119)
		(stroke
			(width 0.06985)
			(type default)
		)
		(layer "In5.Cu")
	)
	(gr_line
		(start 196.138292 -37.46119)
		(end 196.157088 -37.457888)
		(stroke
			(width 0.06985)
			(type default)
		)
		(layer "In5.Cu")
	)
	(gr_line
		(start 196.144896 -33.51276)
		(end 196.163692 -33.509458)
		(stroke
			(width 0.06985)
			(type default)
		)
		(layer "In5.Cu")
	)
	(gr_line
		(start 196.163692 -33.509458)
		(end 196.182488 -33.51276)
		(stroke
			(width 0.06985)
			(type default)
		)
		(layer "In5.Cu")
	)
	(gr_line
		(start 196.170804 -32.494982)
		(end 196.1896 -32.49168)
		(stroke
			(width 0.06985)
			(type default)
		)
		(layer "In5.Cu")
	)
	(gr_line
		(start 196.1896 -32.49168)
		(end 196.208396 -32.494982)
		(stroke
			(width 0.06985)
			(type default)
		)
		(layer "In5.Cu")
	)
	(gr_line
		(start 196.33057 -40.455342)
		(end 196.349366 -40.458644)
		(stroke
			(width 0.06985)
			(type default)
		)
		(layer "In5.Cu")
	)
	(gr_line
		(start 196.349366 -40.458644)
		(end 196.368162 -40.455342)
		(stroke
			(width 0.06985)
			(type default)
		)
		(layer "In5.Cu")
	)
	(gr_line
		(start 196.367146 -41.41216)
		(end 196.385942 -41.415462)
		(stroke
			(width 0.06985)
			(type default)
		)
		(layer "In5.Cu")
	)
	(gr_line
		(start 196.385942 -41.415462)
		(end 196.404738 -41.41216)
		(stroke
			(width 0.06985)
			(type default)
		)
		(layer "In5.Cu")
	)
	(gr_line
		(start 196.422772 -67.848734)
		(end 196.433694 -67.83324)
		(stroke
			(width 0.06985)
			(type default)
		)
		(layer "In5.Cu")
	)
	(gr_line
		(start 196.433694 -67.83324)
		(end 196.449188 -67.822318)
		(stroke
			(width 0.06985)
			(type default)
		)
		(layer "In5.Cu")
	)
	(gr_line
		(start 196.538596 -38.536118)
		(end 196.557392 -38.53942)
		(stroke
			(width 0.06985)
			(type default)
		)
		(layer "In5.Cu")
	)
	(gr_line
		(start 196.557392 -38.53942)
		(end 196.576188 -38.536118)
		(stroke
			(width 0.06985)
			(type default)
		)
		(layer "In5.Cu")
	)
	(gr_line
		(start 196.628258 -39.507668)
		(end 196.647054 -39.51097)
		(stroke
			(width 0.06985)
			(type default)
		)
		(layer "In5.Cu")
	)
	(gr_line
		(start 196.647054 -39.51097)
		(end 196.66585 -39.507668)
		(stroke
			(width 0.06985)
			(type default)
		)
		(layer "In5.Cu")
	)
	(gr_line
		(start 196.662294 -25.68829)
		(end 196.71411 -25.675336)
		(stroke
			(width 0.06985)
			(type default)
		)
		(layer "In5.Cu")
	)
	(gr_line
		(start 196.71411 -25.675336)
		(end 196.76491 -25.691592)
		(stroke
			(width 0.06985)
			(type default)
		)
		(layer "In5.Cu")
	)
	(gr_line
		(start 196.83476 -24.40813)
		(end 196.864224 -24.40178)
		(stroke
			(width 0.06985)
			(type default)
		)
		(layer "In5.Cu")
	)
	(gr_line
		(start 196.864224 -24.40178)
		(end 196.893688 -24.40813)
		(stroke
			(width 0.06985)
			(type default)
		)
		(layer "In5.Cu")
	)
	(gr_line
		(start 196.86905 -79.140304)
		(end 196.86905 -79.140558)
		(stroke
			(width 0.06985)
			(type default)
		)
		(layer "In5.Cu")
	)
	(gr_line
		(start 196.86905 -79.140304)
		(end 196.872352 -79.121508)
		(stroke
			(width 0.06985)
			(type default)
		)
		(layer "In5.Cu")
	)
	(gr_line
		(start 196.86905 -79.102712)
		(end 196.872352 -79.121508)
		(stroke
			(width 0.06985)
			(type default)
		)
		(layer "In5.Cu")
	)
	(gr_arc
		(start 196.893688 -210.896454)
		(mid 197.072274 -210.629107)
		(end 197.134988 -210.313778)
		(stroke
			(width 0.06985)
			(type default)
		)
		(layer "In5.Cu")
	)
	(gr_line
		(start 196.911214 -205.404466)
		(end 196.914516 -205.423516)
		(stroke
			(width 0.06985)
			(type default)
		)
		(layer "In5.Cu")
	)
	(gr_line
		(start 196.911214 -205.404466)
		(end 196.914516 -205.38567)
		(stroke
			(width 0.06985)
			(type default)
		)
		(layer "In5.Cu")
	)
	(gr_line
		(start 196.976492 -56.74868)
		(end 196.986144 -56.73471)
		(stroke
			(width 0.06985)
			(type default)
		)
		(layer "In5.Cu")
	)
	(gr_line
		(start 196.986144 -56.73471)
		(end 197.000114 -56.724804)
		(stroke
			(width 0.06985)
			(type default)
		)
		(layer "In5.Cu")
	)
	(gr_line
		(start 197.047104 -187.216288)
		(end 197.052946 -187.183268)
		(stroke
			(width 0.06985)
			(type default)
		)
		(layer "In5.Cu")
	)
	(gr_line
		(start 197.052946 -187.183268)
		(end 197.072504 -187.155328)
		(stroke
			(width 0.06985)
			(type default)
		)
		(layer "In5.Cu")
	)
	(gr_line
		(start 197.153276 -28.319476)
		(end 197.21195 -28.33624)
		(stroke
			(width 0.06985)
			(type default)
		)
		(layer "In5.Cu")
	)
	(gr_line
		(start 197.21195 -28.33624)
		(end 197.268592 -28.317444)
		(stroke
			(width 0.06985)
			(type default)
		)
		(layer "In5.Cu")
	)
	(gr_arc
		(start 197.465188 -210.313778)
		(mid 197.527909 -210.6291)
		(end 197.706488 -210.896454)
		(stroke
			(width 0.06985)
			(type default)
		)
		(layer "In5.Cu")
	)
	(gr_line
		(start 197.800722 -54.346094)
		(end 197.828662 -54.326536)
		(stroke
			(width 0.06985)
			(type default)
		)
		(layer "In5.Cu")
	)
	(gr_line
		(start 197.828662 -54.326536)
		(end 197.861682 -54.320694)
		(stroke
			(width 0.06985)
			(type default)
		)
		(layer "In5.Cu")
	)
	(gr_line
		(start 198.035926 -66.711322)
		(end 198.063866 -66.691764)
		(stroke
			(width 0.06985)
			(type default)
		)
		(layer "In5.Cu")
	)
	(gr_line
		(start 198.063866 -66.691764)
		(end 198.096886 -66.685922)
		(stroke
			(width 0.06985)
			(type default)
		)
		(layer "In5.Cu")
	)
	(gr_line
		(start 198.630794 -55.583328)
		(end 198.658734 -55.56377)
		(stroke
			(width 0.06985)
			(type default)
		)
		(layer "In5.Cu")
	)
	(gr_line
		(start 198.658734 -55.56377)
		(end 198.691754 -55.557928)
		(stroke
			(width 0.06985)
			(type default)
		)
		(layer "In5.Cu")
	)
	(gr_line
		(start 198.698612 -30.37332)
		(end 198.7296 -30.3784)
		(stroke
			(width 0.06985)
			(type default)
		)
		(layer "In5.Cu")
	)
	(gr_line
		(start 198.7296 -30.3784)
		(end 198.759826 -30.370272)
		(stroke
			(width 0.06985)
			(type default)
		)
		(layer "In5.Cu")
	)
	(gr_line
		(start 198.764652 -27.479752)
		(end 198.827136 -27.459178)
		(stroke
			(width 0.06985)
			(type default)
		)
		(layer "In5.Cu")
	)
	(gr_line
		(start 198.80072 -31.322264)
		(end 198.831708 -31.327852)
		(stroke
			(width 0.06985)
			(type default)
		)
		(layer "In5.Cu")
	)
	(gr_line
		(start 198.827136 -27.459178)
		(end 198.890636 -27.479498)
		(stroke
			(width 0.06985)
			(type default)
		)
		(layer "In5.Cu")
	)
	(gr_line
		(start 198.831708 -31.327852)
		(end 198.862442 -31.319978)
		(stroke
			(width 0.06985)
			(type default)
		)
		(layer "In5.Cu")
	)
	(gr_arc
		(start 200.09358 -210.896454)
		(mid 200.272168 -210.629108)
		(end 200.33488 -210.313778)
		(stroke
			(width 0.06985)
			(type default)
		)
		(layer "In5.Cu")
	)
	(gr_line
		(start 200.186798 -30.634178)
		(end 200.237852 -30.62097)
		(stroke
			(width 0.06985)
			(type default)
		)
		(layer "In5.Cu")
	)
	(gr_line
		(start 200.237852 -30.62097)
		(end 200.288652 -30.636464)
		(stroke
			(width 0.06985)
			(type default)
		)
		(layer "In5.Cu")
	)
	(gr_line
		(start 200.380092 -29.58846)
		(end 200.435464 -29.573474)
		(stroke
			(width 0.06985)
			(type default)
		)
		(layer "In5.Cu")
	)
	(gr_line
		(start 200.425812 -22.565868)
		(end 200.445624 -22.569932)
		(stroke
			(width 0.06985)
			(type default)
		)
		(layer "In5.Cu")
	)
	(gr_line
		(start 200.435464 -29.573474)
		(end 200.490074 -29.591)
		(stroke
			(width 0.06985)
			(type default)
		)
		(layer "In5.Cu")
	)
	(gr_line
		(start 200.445624 -22.569932)
		(end 200.463404 -22.581362)
		(stroke
			(width 0.06985)
			(type default)
		)
		(layer "In5.Cu")
	)
	(gr_line
		(start 200.602088 -53.837332)
		(end 200.620884 -53.83403)
		(stroke
			(width 0.06985)
			(type default)
		)
		(layer "In5.Cu")
	)
	(gr_line
		(start 200.620884 -53.83403)
		(end 200.63968 -53.837332)
		(stroke
			(width 0.06985)
			(type default)
		)
		(layer "In5.Cu")
	)
	(gr_line
		(start 200.6346 -184.286652)
		(end 200.640442 -184.253632)
		(stroke
			(width 0.06985)
			(type default)
		)
		(layer "In5.Cu")
	)
	(gr_line
		(start 200.640442 -184.253632)
		(end 200.66 -184.225692)
		(stroke
			(width 0.06985)
			(type default)
		)
		(layer "In5.Cu")
	)
	(gr_arc
		(start 200.66508 -210.313778)
		(mid 200.727801 -210.6291)
		(end 200.90638 -210.896454)
		(stroke
			(width 0.06985)
			(type default)
		)
		(layer "In5.Cu")
	)
	(gr_line
		(start 200.837546 -197.8914)
		(end 200.840848 -197.91045)
		(stroke
			(width 0.06985)
			(type default)
		)
		(layer "In5.Cu")
	)
	(gr_line
		(start 200.837546 -197.8914)
		(end 200.840848 -197.872604)
		(stroke
			(width 0.06985)
			(type default)
		)
		(layer "In5.Cu")
	)
	(gr_line
		(start 200.895458 -40.285162)
		(end 200.914254 -40.28186)
		(stroke
			(width 0.06985)
			(type default)
		)
		(layer "In5.Cu")
	)
	(gr_line
		(start 200.914254 -40.28186)
		(end 200.93305 -40.285162)
		(stroke
			(width 0.06985)
			(type default)
		)
		(layer "In5.Cu")
	)
	(gr_line
		(start 200.943718 -35.300412)
		(end 200.962514 -35.29711)
		(stroke
			(width 0.06985)
			(type default)
		)
		(layer "In5.Cu")
	)
	(gr_line
		(start 200.962514 -35.29711)
		(end 200.98131 -35.300412)
		(stroke
			(width 0.06985)
			(type default)
		)
		(layer "In5.Cu")
	)
	(gr_line
		(start 201.030078 -39.297864)
		(end 201.048874 -39.294562)
		(stroke
			(width 0.06985)
			(type default)
		)
		(layer "In5.Cu")
	)
	(gr_line
		(start 201.048874 -39.294562)
		(end 201.06767 -39.297864)
		(stroke
			(width 0.06985)
			(type default)
		)
		(layer "In5.Cu")
	)
	(gr_line
		(start 201.195432 -55.116476)
		(end 201.214228 -55.113174)
		(stroke
			(width 0.06985)
			(type default)
		)
		(layer "In5.Cu")
	)
	(gr_line
		(start 201.214228 -55.113174)
		(end 201.233024 -55.116476)
		(stroke
			(width 0.06985)
			(type default)
		)
		(layer "In5.Cu")
	)
	(gr_line
		(start 201.243184 -36.225734)
		(end 201.26198 -36.222432)
		(stroke
			(width 0.06985)
			(type default)
		)
		(layer "In5.Cu")
	)
	(gr_line
		(start 201.26198 -36.222432)
		(end 201.280776 -36.225734)
		(stroke
			(width 0.06985)
			(type default)
		)
		(layer "In5.Cu")
	)
	(gr_line
		(start 201.276458 -38.359334)
		(end 201.295254 -38.356032)
		(stroke
			(width 0.06985)
			(type default)
		)
		(layer "In5.Cu")
	)
	(gr_line
		(start 201.295254 -38.356032)
		(end 201.31405 -38.359334)
		(stroke
			(width 0.06985)
			(type default)
		)
		(layer "In5.Cu")
	)
	(gr_line
		(start 201.313542 -37.36594)
		(end 201.332338 -37.362638)
		(stroke
			(width 0.06985)
			(type default)
		)
		(layer "In5.Cu")
	)
	(gr_line
		(start 201.332338 -37.362638)
		(end 201.351134 -37.36594)
		(stroke
			(width 0.06985)
			(type default)
		)
		(layer "In5.Cu")
	)
	(gr_line
		(start 201.629772 -23.735792)
		(end 201.662792 -23.786592)
		(stroke
			(width 0.06985)
			(type default)
		)
		(layer "In5.Cu")
	)
	(gr_line
		(start 201.662792 -23.786592)
		(end 201.757026 -23.806658)
		(stroke
			(width 0.06985)
			(type default)
		)
		(layer "In5.Cu")
	)
	(gr_line
		(start 201.840592 -23.47595)
		(end 201.859388 -23.488142)
		(stroke
			(width 0.06985)
			(type default)
		)
		(layer "In5.Cu")
	)
	(gr_line
		(start 201.926698 -202.202796)
		(end 201.926698 -202.20305)
		(stroke
			(width 0.06985)
			(type default)
		)
		(layer "In5.Cu")
	)
	(gr_line
		(start 201.926698 -202.202796)
		(end 201.93 -202.184)
		(stroke
			(width 0.06985)
			(type default)
		)
		(layer "In5.Cu")
	)
	(gr_line
		(start 201.926698 -202.165204)
		(end 201.93 -202.184)
		(stroke
			(width 0.06985)
			(type default)
		)
		(layer "In5.Cu")
	)
	(gr_line
		(start 202.890374 -66.176398)
		(end 202.923394 -66.170556)
		(stroke
			(width 0.06985)
			(type default)
		)
		(layer "In5.Cu")
	)
	(gr_line
		(start 202.923394 -66.170556)
		(end 202.951334 -66.150998)
		(stroke
			(width 0.06985)
			(type default)
		)
		(layer "In5.Cu")
	)
	(gr_arc
		(start 203.293726 -210.896454)
		(mid 203.472304 -210.629105)
		(end 203.535026 -210.313778)
		(stroke
			(width 0.06985)
			(type default)
		)
		(layer "In5.Cu")
	)
	(gr_line
		(start 203.533502 -182.596028)
		(end 203.539344 -182.563008)
		(stroke
			(width 0.06985)
			(type default)
		)
		(layer "In5.Cu")
	)
	(gr_line
		(start 203.539344 -182.563008)
		(end 203.558902 -182.535068)
		(stroke
			(width 0.06985)
			(type default)
		)
		(layer "In5.Cu")
	)
	(gr_line
		(start 203.562204 -54.688232)
		(end 203.581 -54.691534)
		(stroke
			(width 0.06985)
			(type default)
		)
		(layer "In5.Cu")
	)
	(gr_line
		(start 203.581 -54.691534)
		(end 203.600558 -54.688232)
		(stroke
			(width 0.06985)
			(type default)
		)
		(layer "In5.Cu")
	)
	(gr_line
		(start 203.64577 -197.634606)
		(end 203.649072 -197.653656)
		(stroke
			(width 0.06985)
			(type default)
		)
		(layer "In5.Cu")
	)
	(gr_line
		(start 203.64577 -197.634606)
		(end 203.649072 -197.61581)
		(stroke
			(width 0.06985)
			(type default)
		)
		(layer "In5.Cu")
	)
	(gr_line
		(start 203.664058 -32.012128)
		(end 203.70165 -32.023558)
		(stroke
			(width 0.06985)
			(type default)
		)
		(layer "In5.Cu")
	)
	(gr_line
		(start 203.70165 -32.023558)
		(end 203.740512 -32.0167)
		(stroke
			(width 0.06985)
			(type default)
		)
		(layer "In5.Cu")
	)
	(gr_line
		(start 203.742544 -30.983428)
		(end 203.786994 -30.997652)
		(stroke
			(width 0.06985)
			(type default)
		)
		(layer "In5.Cu")
	)
	(gr_line
		(start 203.786994 -30.997652)
		(end 203.832968 -30.988508)
		(stroke
			(width 0.06985)
			(type default)
		)
		(layer "In5.Cu")
	)
	(gr_arc
		(start 203.865226 -210.313778)
		(mid 203.927947 -210.6291)
		(end 204.106526 -210.896454)
		(stroke
			(width 0.06985)
			(type default)
		)
		(layer "In5.Cu")
	)
	(gr_line
		(start 203.919582 -33.184846)
		(end 203.938378 -33.188148)
		(stroke
			(width 0.06985)
			(type default)
		)
		(layer "In5.Cu")
	)
	(gr_line
		(start 203.926694 -24.267668)
		(end 203.956158 -24.274018)
		(stroke
			(width 0.06985)
			(type default)
		)
		(layer "In5.Cu")
	)
	(gr_line
		(start 203.930504 -35.214052)
		(end 203.9493 -35.217354)
		(stroke
			(width 0.06985)
			(type default)
		)
		(layer "In5.Cu")
	)
	(gr_line
		(start 203.938378 -33.188148)
		(end 203.957174 -33.184846)
		(stroke
			(width 0.06985)
			(type default)
		)
		(layer "In5.Cu")
	)
	(gr_line
		(start 203.9493 -35.217354)
		(end 203.968096 -35.214052)
		(stroke
			(width 0.06985)
			(type default)
		)
		(layer "In5.Cu")
	)
	(gr_line
		(start 203.956158 -24.274018)
		(end 203.985622 -24.267668)
		(stroke
			(width 0.06985)
			(type default)
		)
		(layer "In5.Cu")
	)
	(gr_line
		(start 203.960476 -55.933086)
		(end 203.979272 -55.936388)
		(stroke
			(width 0.06985)
			(type default)
		)
		(layer "In5.Cu")
	)
	(gr_line
		(start 203.979272 -55.936388)
		(end 203.998068 -55.933086)
		(stroke
			(width 0.06985)
			(type default)
		)
		(layer "In5.Cu")
	)
	(gr_line
		(start 203.985114 -38.165024)
		(end 204.001624 -38.168072)
		(stroke
			(width 0.06985)
			(type default)
		)
		(layer "In5.Cu")
	)
	(gr_line
		(start 203.994512 -36.16706)
		(end 204.013308 -36.170362)
		(stroke
			(width 0.06985)
			(type default)
		)
		(layer "In5.Cu")
	)
	(gr_line
		(start 204.001624 -38.168072)
		(end 204.017626 -38.165278)
		(stroke
			(width 0.06985)
			(type default)
		)
		(layer "In5.Cu")
	)
	(gr_line
		(start 204.013308 -36.170362)
		(end 204.032104 -36.16706)
		(stroke
			(width 0.06985)
			(type default)
		)
		(layer "In5.Cu")
	)
	(gr_line
		(start 204.045058 -34.211768)
		(end 204.063854 -34.21507)
		(stroke
			(width 0.06985)
			(type default)
		)
		(layer "In5.Cu")
	)
	(gr_line
		(start 204.05217 -41.170606)
		(end 204.070966 -41.173908)
		(stroke
			(width 0.06985)
			(type default)
		)
		(layer "In5.Cu")
	)
	(gr_line
		(start 204.063854 -34.21507)
		(end 204.08265 -34.211768)
		(stroke
			(width 0.06985)
			(type default)
		)
		(layer "In5.Cu")
	)
	(gr_line
		(start 204.070966 -41.173908)
		(end 204.089762 -41.170606)
		(stroke
			(width 0.06985)
			(type default)
		)
		(layer "In5.Cu")
	)
	(gr_line
		(start 204.095604 -39.185342)
		(end 204.1144 -39.188644)
		(stroke
			(width 0.06985)
			(type default)
		)
		(layer "In5.Cu")
	)
	(gr_line
		(start 204.1017 -37.058346)
		(end 204.120496 -37.061648)
		(stroke
			(width 0.06985)
			(type default)
		)
		(layer "In5.Cu")
	)
	(gr_line
		(start 204.1144 -39.188644)
		(end 204.133196 -39.185342)
		(stroke
			(width 0.06985)
			(type default)
		)
		(layer "In5.Cu")
	)
	(gr_line
		(start 204.120496 -37.061648)
		(end 204.139292 -37.058346)
		(stroke
			(width 0.06985)
			(type default)
		)
		(layer "In5.Cu")
	)
	(gr_line
		(start 204.171804 -40.180768)
		(end 204.1906 -40.18407)
		(stroke
			(width 0.06985)
			(type default)
		)
		(layer "In5.Cu")
	)
	(gr_line
		(start 204.1906 -40.18407)
		(end 204.209396 -40.180768)
		(stroke
			(width 0.06985)
			(type default)
		)
		(layer "In5.Cu")
	)
	(gr_line
		(start 204.753718 -202.052936)
		(end 204.753718 -202.05319)
		(stroke
			(width 0.06985)
			(type default)
		)
		(layer "In5.Cu")
	)
	(gr_line
		(start 204.753718 -202.052936)
		(end 204.75702 -202.03414)
		(stroke
			(width 0.06985)
			(type default)
		)
		(layer "In5.Cu")
	)
	(gr_line
		(start 204.753718 -202.015344)
		(end 204.75702 -202.03414)
		(stroke
			(width 0.06985)
			(type default)
		)
		(layer "In5.Cu")
	)
	(gr_line
		(start 204.762354 -24.102568)
		(end 204.782166 -24.098504)
		(stroke
			(width 0.06985)
			(type default)
		)
		(layer "In5.Cu")
	)
	(gr_line
		(start 204.782166 -24.098504)
		(end 204.799946 -24.087074)
		(stroke
			(width 0.06985)
			(type default)
		)
		(layer "In5.Cu")
	)
	(gr_line
		(start 205.02626 -80.52054)
		(end 205.045818 -80.4926)
		(stroke
			(width 0.06985)
			(type default)
		)
		(layer "In5.Cu")
	)
	(gr_line
		(start 205.044548 -69.7865)
		(end 205.04785 -69.80555)
		(stroke
			(width 0.06985)
			(type default)
		)
		(layer "In5.Cu")
	)
	(gr_line
		(start 205.044548 -69.7865)
		(end 205.04785 -69.767704)
		(stroke
			(width 0.06985)
			(type default)
		)
		(layer "In5.Cu")
	)
	(gr_line
		(start 205.045818 -80.4926)
		(end 205.05166 -80.45958)
		(stroke
			(width 0.06985)
			(type default)
		)
		(layer "In5.Cu")
	)
	(gr_line
		(start 205.089506 -64.653922)
		(end 205.105 -64.643)
		(stroke
			(width 0.06985)
			(type default)
		)
		(layer "In5.Cu")
	)
	(gr_line
		(start 205.105 -64.643)
		(end 205.115922 -64.627506)
		(stroke
			(width 0.06985)
			(type default)
		)
		(layer "In5.Cu")
	)
	(gr_line
		(start 205.181454 -29.84754)
		(end 205.225904 -29.861764)
		(stroke
			(width 0.06985)
			(type default)
		)
		(layer "In5.Cu")
	)
	(gr_line
		(start 205.225904 -29.861764)
		(end 205.271878 -29.85262)
		(stroke
			(width 0.06985)
			(type default)
		)
		(layer "In5.Cu")
	)
	(gr_line
		(start 205.231238 -54.40045)
		(end 205.264004 -54.394608)
		(stroke
			(width 0.06985)
			(type default)
		)
		(layer "In5.Cu")
	)
	(gr_line
		(start 205.264004 -54.394608)
		(end 205.290928 -54.375812)
		(stroke
			(width 0.06985)
			(type default)
		)
		(layer "In5.Cu")
	)
	(gr_line
		(start 205.284578 -28.767024)
		(end 205.327504 -28.78074)
		(stroke
			(width 0.06985)
			(type default)
		)
		(layer "In5.Cu")
	)
	(gr_line
		(start 205.327504 -28.78074)
		(end 205.370684 -28.772104)
		(stroke
			(width 0.06985)
			(type default)
		)
		(layer "In5.Cu")
	)
	(gr_line
		(start 205.455012 -23.661624)
		(end 205.47965 -23.645622)
		(stroke
			(width 0.06985)
			(type default)
		)
		(layer "In5.Cu")
	)
	(gr_line
		(start 205.47965 -23.645622)
		(end 205.496414 -23.619968)
		(stroke
			(width 0.06985)
			(type default)
		)
		(layer "In5.Cu")
	)
	(gr_line
		(start 205.509114 -22.633432)
		(end 205.513178 -22.61362)
		(stroke
			(width 0.06985)
			(type default)
		)
		(layer "In5.Cu")
	)
	(gr_line
		(start 205.513178 -22.61362)
		(end 205.524608 -22.59584)
		(stroke
			(width 0.06985)
			(type default)
		)
		(layer "In5.Cu")
	)
	(gr_line
		(start 205.611222 -63.920116)
		(end 205.63078 -63.892176)
		(stroke
			(width 0.06985)
			(type default)
		)
		(layer "In5.Cu")
	)
	(gr_line
		(start 205.63078 -63.892176)
		(end 205.636622 -63.859156)
		(stroke
			(width 0.06985)
			(type default)
		)
		(layer "In5.Cu")
	)
	(gr_line
		(start 205.693264 -23.316946)
		(end 205.705202 -23.298404)
		(stroke
			(width 0.06985)
			(type default)
		)
		(layer "In5.Cu")
	)
	(gr_line
		(start 205.705202 -23.298404)
		(end 205.709774 -23.277068)
		(stroke
			(width 0.06985)
			(type default)
		)
		(layer "In5.Cu")
	)
	(gr_line
		(start 205.70698 -55.631842)
		(end 205.74 -55.626)
		(stroke
			(width 0.06985)
			(type default)
		)
		(layer "In5.Cu")
	)
	(gr_line
		(start 205.730602 -22.278594)
		(end 205.746858 -22.253702)
		(stroke
			(width 0.06985)
			(type default)
		)
		(layer "In5.Cu")
	)
	(gr_line
		(start 205.74 -55.626)
		(end 205.76794 -55.606442)
		(stroke
			(width 0.06985)
			(type default)
		)
		(layer "In5.Cu")
	)
	(gr_line
		(start 205.746858 -22.253702)
		(end 205.771496 -22.2377)
		(stroke
			(width 0.06985)
			(type default)
		)
		(layer "In5.Cu")
	)
	(gr_line
		(start 205.77556 -197.294246)
		(end 205.778862 -197.313296)
		(stroke
			(width 0.06985)
			(type default)
		)
		(layer "In5.Cu")
	)
	(gr_line
		(start 205.77556 -197.294246)
		(end 205.778862 -197.27545)
		(stroke
			(width 0.06985)
			(type default)
		)
		(layer "In5.Cu")
	)
	(gr_line
		(start 205.871318 -80.669384)
		(end 205.890876 -80.641444)
		(stroke
			(width 0.06985)
			(type default)
		)
		(layer "In5.Cu")
	)
	(gr_line
		(start 205.890876 -80.641444)
		(end 205.896718 -80.608424)
		(stroke
			(width 0.06985)
			(type default)
		)
		(layer "In5.Cu")
	)
	(gr_line
		(start 205.913228 -69.977)
		(end 205.91653 -69.99605)
		(stroke
			(width 0.06985)
			(type default)
		)
		(layer "In5.Cu")
	)
	(gr_line
		(start 205.913228 -69.977)
		(end 205.91653 -69.958204)
		(stroke
			(width 0.06985)
			(type default)
		)
		(layer "In5.Cu")
	)
	(gr_line
		(start 206.048102 -53.845714)
		(end 206.063596 -53.834792)
		(stroke
			(width 0.06985)
			(type default)
		)
		(layer "In5.Cu")
	)
	(gr_line
		(start 206.063596 -53.834792)
		(end 206.074518 -53.819298)
		(stroke
			(width 0.06985)
			(type default)
		)
		(layer "In5.Cu")
	)
	(gr_line
		(start 206.153512 -74.210164)
		(end 206.153512 -74.210418)
		(stroke
			(width 0.06985)
			(type default)
		)
		(layer "In5.Cu")
	)
	(gr_line
		(start 206.153512 -74.210164)
		(end 206.156814 -74.191368)
		(stroke
			(width 0.06985)
			(type default)
		)
		(layer "In5.Cu")
	)
	(gr_line
		(start 206.153512 -74.172572)
		(end 206.156814 -74.191368)
		(stroke
			(width 0.06985)
			(type default)
		)
		(layer "In5.Cu")
	)
	(gr_line
		(start 206.344774 -21.865336)
		(end 206.362554 -21.853906)
		(stroke
			(width 0.06985)
			(type default)
		)
		(layer "In5.Cu")
	)
	(gr_line
		(start 206.362554 -21.853906)
		(end 206.382366 -21.849842)
		(stroke
			(width 0.06985)
			(type default)
		)
		(layer "In5.Cu")
	)
	(gr_line
		(start 206.42072 -57.518046)
		(end 206.426562 -57.485026)
		(stroke
			(width 0.06985)
			(type default)
		)
		(layer "In5.Cu")
	)
	(gr_line
		(start 206.426562 -57.485026)
		(end 206.44612 -57.457086)
		(stroke
			(width 0.06985)
			(type default)
		)
		(layer "In5.Cu")
	)
	(gr_arc
		(start 206.493618 -210.896454)
		(mid 206.672198 -210.629105)
		(end 206.734918 -210.313778)
		(stroke
			(width 0.06985)
			(type default)
		)
		(layer "In5.Cu")
	)
	(gr_line
		(start 206.68869 -180.377846)
		(end 206.694532 -180.344826)
		(stroke
			(width 0.06985)
			(type default)
		)
		(layer "In5.Cu")
	)
	(gr_line
		(start 206.694532 -180.344826)
		(end 206.71409 -180.316886)
		(stroke
			(width 0.06985)
			(type default)
		)
		(layer "In5.Cu")
	)
	(gr_line
		(start 207.006698 -74.313796)
		(end 207.006698 -74.31405)
		(stroke
			(width 0.06985)
			(type default)
		)
		(layer "In5.Cu")
	)
	(gr_line
		(start 207.006698 -74.313796)
		(end 207.01 -74.295)
		(stroke
			(width 0.06985)
			(type default)
		)
		(layer "In5.Cu")
	)
	(gr_line
		(start 207.006698 -74.276204)
		(end 207.01 -74.295)
		(stroke
			(width 0.06985)
			(type default)
		)
		(layer "In5.Cu")
	)
	(gr_arc
		(start 207.065118 -210.313778)
		(mid 207.127839 -210.6291)
		(end 207.306418 -210.896454)
		(stroke
			(width 0.06985)
			(type default)
		)
		(layer "In5.Cu")
	)
	(gr_line
		(start 207.117696 -54.661562)
		(end 207.13319 -54.65064)
		(stroke
			(width 0.06985)
			(type default)
		)
		(layer "In5.Cu")
	)
	(gr_line
		(start 207.13319 -54.65064)
		(end 207.144112 -54.635146)
		(stroke
			(width 0.06985)
			(type default)
		)
		(layer "In5.Cu")
	)
	(gr_line
		(start 207.154272 -57.82183)
		(end 207.160114 -57.78881)
		(stroke
			(width 0.06985)
			(type default)
		)
		(layer "In5.Cu")
	)
	(gr_line
		(start 207.160114 -57.78881)
		(end 207.179672 -57.76087)
		(stroke
			(width 0.06985)
			(type default)
		)
		(layer "In5.Cu")
	)
	(gr_line
		(start 207.359758 -26.172414)
		(end 207.389222 -26.178764)
		(stroke
			(width 0.06985)
			(type default)
		)
		(layer "In5.Cu")
	)
	(gr_line
		(start 207.389222 -26.178764)
		(end 207.419702 -26.172414)
		(stroke
			(width 0.06985)
			(type default)
		)
		(layer "In5.Cu")
	)
	(gr_line
		(start 207.4164 -21.629624)
		(end 207.44688 -21.623274)
		(stroke
			(width 0.06985)
			(type default)
		)
		(layer "In5.Cu")
	)
	(gr_line
		(start 207.44688 -21.623274)
		(end 207.47736 -21.629624)
		(stroke
			(width 0.06985)
			(type default)
		)
		(layer "In5.Cu")
	)
	(gr_line
		(start 207.51038 -27.002232)
		(end 207.539844 -27.008582)
		(stroke
			(width 0.06985)
			(type default)
		)
		(layer "In5.Cu")
	)
	(gr_line
		(start 207.539844 -27.008582)
		(end 207.569308 -27.002232)
		(stroke
			(width 0.06985)
			(type default)
		)
		(layer "In5.Cu")
	)
	(gr_line
		(start 207.641698 -206.012796)
		(end 207.641698 -206.01305)
		(stroke
			(width 0.06985)
			(type default)
		)
		(layer "In5.Cu")
	)
	(gr_line
		(start 207.641698 -206.012796)
		(end 207.645 -205.994)
		(stroke
			(width 0.06985)
			(type default)
		)
		(layer "In5.Cu")
	)
	(gr_line
		(start 207.641698 -205.975204)
		(end 207.645 -205.994)
		(stroke
			(width 0.06985)
			(type default)
		)
		(layer "In5.Cu")
	)
	(gr_line
		(start 207.999076 -58.146442)
		(end 208.004918 -58.113422)
		(stroke
			(width 0.06985)
			(type default)
		)
		(layer "In5.Cu")
	)
	(gr_line
		(start 208.004918 -58.113422)
		(end 208.024476 -58.085482)
		(stroke
			(width 0.06985)
			(type default)
		)
		(layer "In5.Cu")
	)
	(gr_line
		(start 208.139284 -21.770594)
		(end 208.15935 -21.774912)
		(stroke
			(width 0.06985)
			(type default)
		)
		(layer "In5.Cu")
	)
	(gr_line
		(start 208.15935 -21.774912)
		(end 208.176622 -21.786088)
		(stroke
			(width 0.06985)
			(type default)
		)
		(layer "In5.Cu")
	)
	(gr_line
		(start 208.595976 -22.05736)
		(end 208.620868 -22.073616)
		(stroke
			(width 0.06985)
			(type default)
		)
		(layer "In5.Cu")
	)
	(gr_line
		(start 208.620868 -22.073616)
		(end 208.637124 -22.098508)
		(stroke
			(width 0.06985)
			(type default)
		)
		(layer "In5.Cu")
	)
	(gr_line
		(start 208.640172 -190.906654)
		(end 208.643474 -190.925704)
		(stroke
			(width 0.06985)
			(type default)
		)
		(layer "In5.Cu")
	)
	(gr_line
		(start 208.640172 -190.906654)
		(end 208.643474 -190.887858)
		(stroke
			(width 0.06985)
			(type default)
		)
		(layer "In5.Cu")
	)
	(gr_line
		(start 208.758028 -79.20101)
		(end 208.777586 -79.17307)
		(stroke
			(width 0.06985)
			(type default)
		)
		(layer "In5.Cu")
	)
	(gr_line
		(start 208.777586 -79.17307)
		(end 208.783428 -79.14005)
		(stroke
			(width 0.06985)
			(type default)
		)
		(layer "In5.Cu")
	)
	(gr_line
		(start 208.825338 -23.54834)
		(end 208.829656 -23.56866)
		(stroke
			(width 0.06985)
			(type default)
		)
		(layer "In5.Cu")
	)
	(gr_line
		(start 208.829656 -23.56866)
		(end 208.841086 -23.58644)
		(stroke
			(width 0.06985)
			(type default)
		)
		(layer "In5.Cu")
	)
	(gr_line
		(start 208.922112 -179.44973)
		(end 208.927954 -179.41671)
		(stroke
			(width 0.06985)
			(type default)
		)
		(layer "In5.Cu")
	)
	(gr_line
		(start 208.927954 -179.41671)
		(end 208.947512 -179.38877)
		(stroke
			(width 0.06985)
			(type default)
		)
		(layer "In5.Cu")
	)
	(gr_line
		(start 208.949544 -22.578822)
		(end 208.960974 -22.596348)
		(stroke
			(width 0.06985)
			(type default)
		)
		(layer "In5.Cu")
	)
	(gr_line
		(start 208.960974 -22.596348)
		(end 208.965292 -22.616668)
		(stroke
			(width 0.06985)
			(type default)
		)
		(layer "In5.Cu")
	)
	(gr_line
		(start 209.075782 -48.956214)
		(end 209.086704 -48.94072)
		(stroke
			(width 0.06985)
			(type default)
		)
		(layer "In5.Cu")
	)
	(gr_line
		(start 209.086704 -48.94072)
		(end 209.102198 -48.929798)
		(stroke
			(width 0.06985)
			(type default)
		)
		(layer "In5.Cu")
	)
	(gr_line
		(start 209.09661 -23.979886)
		(end 209.112866 -24.004778)
		(stroke
			(width 0.06985)
			(type default)
		)
		(layer "In5.Cu")
	)
	(gr_line
		(start 209.112866 -24.004778)
		(end 209.137504 -24.02078)
		(stroke
			(width 0.06985)
			(type default)
		)
		(layer "In5.Cu")
	)
	(gr_line
		(start 209.573114 -80.213708)
		(end 209.592672 -80.185768)
		(stroke
			(width 0.06985)
			(type default)
		)
		(layer "In5.Cu")
	)
	(gr_line
		(start 209.592672 -80.185768)
		(end 209.598514 -80.152748)
		(stroke
			(width 0.06985)
			(type default)
		)
		(layer "In5.Cu")
	)
	(gr_line
		(start 209.85861 -24.489156)
		(end 209.87639 -24.500586)
		(stroke
			(width 0.06985)
			(type default)
		)
		(layer "In5.Cu")
	)
	(gr_line
		(start 209.87639 -24.500586)
		(end 209.896202 -24.50465)
		(stroke
			(width 0.06985)
			(type default)
		)
		(layer "In5.Cu")
	)
	(gr_line
		(start 210.196938 -49.69891)
		(end 210.210146 -49.680114)
		(stroke
			(width 0.06985)
			(type default)
		)
		(layer "In5.Cu")
	)
	(gr_line
		(start 210.206336 -81.08696)
		(end 210.225894 -81.05902)
		(stroke
			(width 0.06985)
			(type default)
		)
		(layer "In5.Cu")
	)
	(gr_line
		(start 210.210146 -49.680114)
		(end 210.229196 -49.667414)
		(stroke
			(width 0.06985)
			(type default)
		)
		(layer "In5.Cu")
	)
	(gr_line
		(start 210.225894 -81.05902)
		(end 210.231736 -81.026)
		(stroke
			(width 0.06985)
			(type default)
		)
		(layer "In5.Cu")
	)
	(gr_line
		(start 210.289394 -181.554628)
		(end 210.295236 -181.521608)
		(stroke
			(width 0.06985)
			(type default)
		)
		(layer "In5.Cu")
	)
	(gr_line
		(start 210.295236 -181.521608)
		(end 210.314032 -181.494684)
		(stroke
			(width 0.06985)
			(type default)
		)
		(layer "In5.Cu")
	)
	(gr_line
		(start 210.374992 -191.287654)
		(end 210.378294 -191.306704)
		(stroke
			(width 0.06985)
			(type default)
		)
		(layer "In5.Cu")
	)
	(gr_line
		(start 210.374992 -191.287654)
		(end 210.378294 -191.268858)
		(stroke
			(width 0.06985)
			(type default)
		)
		(layer "In5.Cu")
	)
	(gr_line
		(start 210.407504 -24.613362)
		(end 210.436968 -24.619712)
		(stroke
			(width 0.06985)
			(type default)
		)
		(layer "In5.Cu")
	)
	(gr_line
		(start 210.436968 -24.619712)
		(end 210.466432 -24.613362)
		(stroke
			(width 0.06985)
			(type default)
		)
		(layer "In5.Cu")
	)
	(gr_line
		(start 210.834478 -30.429962)
		(end 210.853274 -30.42666)
		(stroke
			(width 0.06985)
			(type default)
		)
		(layer "In5.Cu")
	)
	(gr_line
		(start 210.853274 -30.42666)
		(end 210.87207 -30.429962)
		(stroke
			(width 0.06985)
			(type default)
		)
		(layer "In5.Cu")
	)
	(gr_line
		(start 211.083398 -50.834036)
		(end 211.096352 -50.815748)
		(stroke
			(width 0.06985)
			(type default)
		)
		(layer "In5.Cu")
	)
	(gr_line
		(start 211.096352 -50.815748)
		(end 211.114894 -50.803048)
		(stroke
			(width 0.06985)
			(type default)
		)
		(layer "In5.Cu")
	)
	(gr_line
		(start 211.130134 -31.5849)
		(end 211.14893 -31.581598)
		(stroke
			(width 0.06985)
			(type default)
		)
		(layer "In5.Cu")
	)
	(gr_line
		(start 211.14893 -31.581598)
		(end 211.167726 -31.5849)
		(stroke
			(width 0.06985)
			(type default)
		)
		(layer "In5.Cu")
	)
	(gr_line
		(start 211.220304 -33.60039)
		(end 211.2391 -33.597088)
		(stroke
			(width 0.06985)
			(type default)
		)
		(layer "In5.Cu")
	)
	(gr_line
		(start 211.23275 -32.615886)
		(end 211.251546 -32.612584)
		(stroke
			(width 0.06985)
			(type default)
		)
		(layer "In5.Cu")
	)
	(gr_line
		(start 211.2391 -33.597088)
		(end 211.257896 -33.60039)
		(stroke
			(width 0.06985)
			(type default)
		)
		(layer "In5.Cu")
	)
	(gr_line
		(start 211.251546 -32.612584)
		(end 211.270342 -32.615886)
		(stroke
			(width 0.06985)
			(type default)
		)
		(layer "In5.Cu")
	)
	(gr_line
		(start 211.278978 -35.463988)
		(end 211.297774 -35.460686)
		(stroke
			(width 0.06985)
			(type default)
		)
		(layer "In5.Cu")
	)
	(gr_line
		(start 211.297774 -35.460686)
		(end 211.31657 -35.463988)
		(stroke
			(width 0.06985)
			(type default)
		)
		(layer "In5.Cu")
	)
	(gr_line
		(start 211.365592 -206.364078)
		(end 211.371434 -206.397098)
		(stroke
			(width 0.06985)
			(type default)
		)
		(layer "In5.Cu")
	)
	(gr_line
		(start 211.371434 -206.397098)
		(end 211.390992 -206.425038)
		(stroke
			(width 0.06985)
			(type default)
		)
		(layer "In5.Cu")
	)
	(gr_line
		(start 211.47532 -81.016856)
		(end 211.494878 -80.988916)
		(stroke
			(width 0.06985)
			(type default)
		)
		(layer "In5.Cu")
	)
	(gr_line
		(start 211.494878 -80.988916)
		(end 211.50072 -80.955896)
		(stroke
			(width 0.06985)
			(type default)
		)
		(layer "In5.Cu")
	)
	(gr_line
		(start 211.498688 -39.528496)
		(end 211.517484 -39.525194)
		(stroke
			(width 0.06985)
			(type default)
		)
		(layer "In5.Cu")
	)
	(gr_line
		(start 211.517484 -39.525194)
		(end 211.53628 -39.528496)
		(stroke
			(width 0.06985)
			(type default)
		)
		(layer "In5.Cu")
	)
	(gr_line
		(start 211.53628 -51.538886)
		(end 211.547202 -51.523392)
		(stroke
			(width 0.06985)
			(type default)
		)
		(layer "In5.Cu")
	)
	(gr_line
		(start 211.53755 -36.512246)
		(end 211.553552 -36.509452)
		(stroke
			(width 0.06985)
			(type default)
		)
		(layer "In5.Cu")
	)
	(gr_line
		(start 211.537804 -34.508186)
		(end 211.5566 -34.504884)
		(stroke
			(width 0.06985)
			(type default)
		)
		(layer "In5.Cu")
	)
	(gr_line
		(start 211.547202 -51.523392)
		(end 211.562696 -51.51247)
		(stroke
			(width 0.06985)
			(type default)
		)
		(layer "In5.Cu")
	)
	(gr_line
		(start 211.553552 -36.509452)
		(end 211.570062 -36.5125)
		(stroke
			(width 0.06985)
			(type default)
		)
		(layer "In5.Cu")
	)
	(gr_line
		(start 211.5566 -34.504884)
		(end 211.575396 -34.508186)
		(stroke
			(width 0.06985)
			(type default)
		)
		(layer "In5.Cu")
	)
	(gr_line
		(start 211.702396 -37.514784)
		(end 211.721192 -37.511482)
		(stroke
			(width 0.06985)
			(type default)
		)
		(layer "In5.Cu")
	)
	(gr_line
		(start 211.721192 -37.511482)
		(end 211.739988 -37.514784)
		(stroke
			(width 0.06985)
			(type default)
		)
		(layer "In5.Cu")
	)
	(gr_line
		(start 211.868004 -38.49497)
		(end 211.8868 -38.491668)
		(stroke
			(width 0.06985)
			(type default)
		)
		(layer "In5.Cu")
	)
	(gr_line
		(start 211.8868 -38.491668)
		(end 211.905596 -38.49497)
		(stroke
			(width 0.06985)
			(type default)
		)
		(layer "In5.Cu")
	)
	(gr_line
		(start 211.965032 -182.270908)
		(end 211.970874 -182.237888)
		(stroke
			(width 0.06985)
			(type default)
		)
		(layer "In5.Cu")
	)
	(gr_line
		(start 211.970874 -182.237888)
		(end 211.98967 -182.210964)
		(stroke
			(width 0.06985)
			(type default)
		)
		(layer "In5.Cu")
	)
	(gr_line
		(start 212.122766 -52.231544)
		(end 212.133688 -52.21605)
		(stroke
			(width 0.06985)
			(type default)
		)
		(layer "In5.Cu")
	)
	(gr_line
		(start 212.133688 -52.21605)
		(end 212.149182 -52.205128)
		(stroke
			(width 0.06985)
			(type default)
		)
		(layer "In5.Cu")
	)
	(gr_line
		(start 212.526372 -203.487528)
		(end 212.532214 -203.520548)
		(stroke
			(width 0.06985)
			(type default)
		)
		(layer "In5.Cu")
	)
	(gr_line
		(start 212.532214 -203.520548)
		(end 212.551772 -203.548488)
		(stroke
			(width 0.06985)
			(type default)
		)
		(layer "In5.Cu")
	)
	(gr_line
		(start 212.69833 -81.309972)
		(end 212.717888 -81.282032)
		(stroke
			(width 0.06985)
			(type default)
		)
		(layer "In5.Cu")
	)
	(gr_line
		(start 212.717888 -81.281778)
		(end 212.717888 -81.282032)
		(stroke
			(width 0.06985)
			(type default)
		)
		(layer "In5.Cu")
	)
	(gr_line
		(start 212.717888 -81.281778)
		(end 212.72373 -81.248758)
		(stroke
			(width 0.06985)
			(type default)
		)
		(layer "In5.Cu")
	)
	(gr_line
		(start 212.88883 -53.955442)
		(end 212.894672 -53.922422)
		(stroke
			(width 0.06985)
			(type default)
		)
		(layer "In5.Cu")
	)
	(gr_arc
		(start 212.893656 -210.896454)
		(mid 213.072228 -210.629103)
		(end 213.134956 -210.313778)
		(stroke
			(width 0.06985)
			(type default)
		)
		(layer "In5.Cu")
	)
	(gr_line
		(start 212.894672 -53.922422)
		(end 212.91423 -53.894482)
		(stroke
			(width 0.06985)
			(type default)
		)
		(layer "In5.Cu")
	)
	(gr_line
		(start 213.051898 -40.130984)
		(end 213.733634 -40.25138)
		(stroke
			(width 0.06985)
			(type default)
		)
		(layer "In5.Cu")
	)
	(gr_line
		(start 213.070948 -39.79672)
		(end 213.273894 -39.65448)
		(stroke
			(width 0.06985)
			(type default)
		)
		(layer "In5.Cu")
	)
	(gr_line
		(start 213.273894 -39.65448)
		(end 213.686644 -39.727124)
		(stroke
			(width 0.06985)
			(type default)
		)
		(layer "In5.Cu")
	)
	(gr_line
		(start 213.428326 -208.758536)
		(end 213.465156 -208.811114)
		(stroke
			(width 0.06985)
			(type default)
		)
		(layer "In5.Cu")
	)
	(gr_arc
		(start 213.465156 -210.313778)
		(mid 213.527877 -210.6291)
		(end 213.706456 -210.896454)
		(stroke
			(width 0.06985)
			(type default)
		)
		(layer "In5.Cu")
	)
	(gr_line
		(start 213.665562 -81.63433)
		(end 213.68512 -81.60639)
		(stroke
			(width 0.06985)
			(type default)
		)
		(layer "In5.Cu")
	)
	(gr_line
		(start 213.665816 -55.183278)
		(end 213.671658 -55.150258)
		(stroke
			(width 0.06985)
			(type default)
		)
		(layer "In5.Cu")
	)
	(gr_line
		(start 213.671658 -55.150258)
		(end 213.691216 -55.122318)
		(stroke
			(width 0.06985)
			(type default)
		)
		(layer "In5.Cu")
	)
	(gr_line
		(start 213.68512 -81.60639)
		(end 213.690962 -81.57337)
		(stroke
			(width 0.06985)
			(type default)
		)
		(layer "In5.Cu")
	)
	(gr_line
		(start 213.686644 -39.727124)
		(end 213.828884 -39.930324)
		(stroke
			(width 0.06985)
			(type default)
		)
		(layer "In5.Cu")
	)
	(gr_line
		(start 213.875366 -52.521866)
		(end 213.886288 -52.506372)
		(stroke
			(width 0.06985)
			(type default)
		)
		(layer "In5.Cu")
	)
	(gr_line
		(start 213.886288 -52.506372)
		(end 213.901782 -52.49545)
		(stroke
			(width 0.06985)
			(type default)
		)
		(layer "In5.Cu")
	)
	(gr_line
		(start 214.183722 -56.710072)
		(end 214.189564 -56.677052)
		(stroke
			(width 0.06985)
			(type default)
		)
		(layer "In5.Cu")
	)
	(gr_line
		(start 214.189564 -56.677052)
		(end 214.209122 -56.649112)
		(stroke
			(width 0.06985)
			(type default)
		)
		(layer "In5.Cu")
	)
	(gr_line
		(start 214.227156 -40.338248)
		(end 214.909146 -40.458644)
		(stroke
			(width 0.06985)
			(type default)
		)
		(layer "In5.Cu")
	)
	(gr_line
		(start 214.24646 -40.003984)
		(end 214.44966 -39.861744)
		(stroke
			(width 0.06985)
			(type default)
		)
		(layer "In5.Cu")
	)
	(gr_line
		(start 214.44966 -39.861744)
		(end 214.86241 -39.934388)
		(stroke
			(width 0.06985)
			(type default)
		)
		(layer "In5.Cu")
	)
	(gr_line
		(start 214.5284 -82.624676)
		(end 214.547958 -82.596736)
		(stroke
			(width 0.06985)
			(type default)
		)
		(layer "In5.Cu")
	)
	(gr_line
		(start 214.547958 -82.596736)
		(end 214.5538 -82.563716)
		(stroke
			(width 0.06985)
			(type default)
		)
		(layer "In5.Cu")
	)
	(gr_line
		(start 214.86241 -39.934388)
		(end 215.004396 -40.137588)
		(stroke
			(width 0.06985)
			(type default)
		)
		(layer "In5.Cu")
	)
	(gr_line
		(start 214.86622 -44.894246)
		(end 214.89416 -44.874688)
		(stroke
			(width 0.06985)
			(type default)
		)
		(layer "In5.Cu")
	)
	(gr_line
		(start 214.89416 -44.874688)
		(end 214.92718 -44.868846)
		(stroke
			(width 0.06985)
			(type default)
		)
		(layer "In5.Cu")
	)
	(gr_line
		(start 215.023954 -48.146208)
		(end 215.050878 -48.12792)
		(stroke
			(width 0.06985)
			(type default)
		)
		(layer "In5.Cu")
	)
	(gr_line
		(start 215.050878 -48.12792)
		(end 215.05164 -48.127666)
		(stroke
			(width 0.06985)
			(type default)
		)
		(layer "In5.Cu")
	)
	(gr_line
		(start 215.05164 -48.12792)
		(end 215.081866 -48.122586)
		(stroke
			(width 0.06985)
			(type default)
		)
		(layer "In5.Cu")
	)
	(gr_line
		(start 215.05164 -48.127666)
		(end 215.05164 -48.12792)
		(stroke
			(width 0.06985)
			(type default)
		)
		(layer "In5.Cu")
	)
	(gr_line
		(start 215.087708 -25.065736)
		(end 215.115394 -25.059894)
		(stroke
			(width 0.06985)
			(type default)
		)
		(layer "In5.Cu")
	)
	(gr_line
		(start 215.095074 -49.039018)
		(end 215.123014 -49.01946)
		(stroke
			(width 0.06985)
			(type default)
		)
		(layer "In5.Cu")
	)
	(gr_line
		(start 215.115394 -25.059894)
		(end 215.143334 -25.065482)
		(stroke
			(width 0.06985)
			(type default)
		)
		(layer "In5.Cu")
	)
	(gr_line
		(start 215.123014 -49.01946)
		(end 215.156034 -49.013618)
		(stroke
			(width 0.06985)
			(type default)
		)
		(layer "In5.Cu")
	)
	(gr_line
		(start 215.1507 -53.03774)
		(end 215.161622 -53.022246)
		(stroke
			(width 0.06985)
			(type default)
		)
		(layer "In5.Cu")
	)
	(gr_line
		(start 215.161622 -53.022246)
		(end 215.177116 -53.011324)
		(stroke
			(width 0.06985)
			(type default)
		)
		(layer "In5.Cu")
	)
	(gr_line
		(start 215.265762 -28.364942)
		(end 215.2904 -28.359862)
		(stroke
			(width 0.06985)
			(type default)
		)
		(layer "In5.Cu")
	)
	(gr_line
		(start 215.2904 -28.359862)
		(end 215.315038 -28.364942)
		(stroke
			(width 0.06985)
			(type default)
		)
		(layer "In5.Cu")
	)
	(gr_line
		(start 215.389206 -24.139652)
		(end 215.41359 -24.134572)
		(stroke
			(width 0.06985)
			(type default)
		)
		(layer "In5.Cu")
	)
	(gr_line
		(start 215.401652 -56.92775)
		(end 215.407494 -56.89473)
		(stroke
			(width 0.06985)
			(type default)
		)
		(layer "In5.Cu")
	)
	(gr_line
		(start 215.407494 -56.89473)
		(end 215.427052 -56.86679)
		(stroke
			(width 0.06985)
			(type default)
		)
		(layer "In5.Cu")
	)
	(gr_line
		(start 215.41359 -24.134572)
		(end 215.438228 -24.13889)
		(stroke
			(width 0.06985)
			(type default)
		)
		(layer "In5.Cu")
	)
	(gr_line
		(start 215.460326 -23.21433)
		(end 215.48471 -23.20925)
		(stroke
			(width 0.06985)
			(type default)
		)
		(layer "In5.Cu")
	)
	(gr_line
		(start 215.48471 -23.20925)
		(end 215.509348 -23.213568)
		(stroke
			(width 0.06985)
			(type default)
		)
		(layer "In5.Cu")
	)
	(gr_line
		(start 215.63965 -27.44216)
		(end 215.664288 -27.43708)
		(stroke
			(width 0.06985)
			(type default)
		)
		(layer "In5.Cu")
	)
	(gr_line
		(start 215.65108 -26.379678)
		(end 215.675718 -26.374598)
		(stroke
			(width 0.06985)
			(type default)
		)
		(layer "In5.Cu")
	)
	(gr_line
		(start 215.664288 -27.43708)
		(end 215.688926 -27.44216)
		(stroke
			(width 0.06985)
			(type default)
		)
		(layer "In5.Cu")
	)
	(gr_line
		(start 215.664796 -49.743614)
		(end 215.690958 -49.725326)
		(stroke
			(width 0.06985)
			(type default)
		)
		(layer "In5.Cu")
	)
	(gr_line
		(start 215.675718 -26.374598)
		(end 215.700356 -26.379678)
		(stroke
			(width 0.06985)
			(type default)
		)
		(layer "In5.Cu")
	)
	(gr_line
		(start 215.690958 -49.725072)
		(end 215.690958 -49.725326)
		(stroke
			(width 0.06985)
			(type default)
		)
		(layer "In5.Cu")
	)
	(gr_line
		(start 215.690958 -49.725072)
		(end 215.723978 -49.71923)
		(stroke
			(width 0.06985)
			(type default)
		)
		(layer "In5.Cu")
	)
	(gr_line
		(start 215.817196 -54.352444)
		(end 215.828118 -54.33695)
		(stroke
			(width 0.06985)
			(type default)
		)
		(layer "In5.Cu")
	)
	(gr_line
		(start 215.828118 -54.33695)
		(end 215.843612 -54.326028)
		(stroke
			(width 0.06985)
			(type default)
		)
		(layer "In5.Cu")
	)
	(gr_line
		(start 215.933274 -82.41411)
		(end 215.952832 -82.38617)
		(stroke
			(width 0.06985)
			(type default)
		)
		(layer "In5.Cu")
	)
	(gr_line
		(start 215.952832 -82.38617)
		(end 215.958674 -82.35315)
		(stroke
			(width 0.06985)
			(type default)
		)
		(layer "In5.Cu")
	)
	(gr_arc
		(start 216.093548 -210.896454)
		(mid 216.272175 -210.62912)
		(end 216.334848 -210.313778)
		(stroke
			(width 0.06985)
			(type default)
		)
		(layer "In5.Cu")
	)
	(gr_line
		(start 216.218262 -50.87366)
		(end 216.246202 -50.854102)
		(stroke
			(width 0.06985)
			(type default)
		)
		(layer "In5.Cu")
	)
	(gr_line
		(start 216.246202 -50.854102)
		(end 216.279222 -50.84826)
		(stroke
			(width 0.06985)
			(type default)
		)
		(layer "In5.Cu")
	)
	(gr_line
		(start 216.264236 -45.666914)
		(end 216.30767 -45.638212)
		(stroke
			(width 0.06985)
			(type default)
		)
		(layer "In5.Cu")
	)
	(gr_line
		(start 216.279984 -52.239164)
		(end 216.307924 -52.219606)
		(stroke
			(width 0.06985)
			(type default)
		)
		(layer "In5.Cu")
	)
	(gr_line
		(start 216.30767 -45.638212)
		(end 216.359994 -45.63618)
		(stroke
			(width 0.06985)
			(type default)
		)
		(layer "In5.Cu")
	)
	(gr_line
		(start 216.307924 -52.219606)
		(end 216.340944 -52.213764)
		(stroke
			(width 0.06985)
			(type default)
		)
		(layer "In5.Cu")
	)
	(gr_line
		(start 216.502742 -87.950802)
		(end 216.5223 -87.922862)
		(stroke
			(width 0.06985)
			(type default)
		)
		(layer "In5.Cu")
	)
	(gr_line
		(start 216.5223 -87.922862)
		(end 216.528142 -87.889842)
		(stroke
			(width 0.06985)
			(type default)
		)
		(layer "In5.Cu")
	)
	(gr_line
		(start 216.596468 -57.382918)
		(end 216.60231 -57.349898)
		(stroke
			(width 0.06985)
			(type default)
		)
		(layer "In5.Cu")
	)
	(gr_line
		(start 216.597484 -55.195216)
		(end 216.608406 -55.179722)
		(stroke
			(width 0.06985)
			(type default)
		)
		(layer "In5.Cu")
	)
	(gr_line
		(start 216.60231 -57.349898)
		(end 216.621868 -57.321958)
		(stroke
			(width 0.06985)
			(type default)
		)
		(layer "In5.Cu")
	)
	(gr_line
		(start 216.608406 -55.179722)
		(end 216.6239 -55.1688)
		(stroke
			(width 0.06985)
			(type default)
		)
		(layer "In5.Cu")
	)
	(gr_line
		(start 216.628218 -208.794096)
		(end 216.665048 -208.846674)
		(stroke
			(width 0.06985)
			(type default)
		)
		(layer "In5.Cu")
	)
	(gr_arc
		(start 216.665048 -210.313778)
		(mid 216.727716 -210.629129)
		(end 216.906348 -210.896454)
		(stroke
			(width 0.06985)
			(type default)
		)
		(layer "In5.Cu")
	)
	(gr_line
		(start 217.112596 -48.09998)
		(end 217.145616 -48.094138)
		(stroke
			(width 0.06985)
			(type default)
		)
		(layer "In5.Cu")
	)
	(gr_line
		(start 217.145616 -48.094138)
		(end 217.173556 -48.07458)
		(stroke
			(width 0.06985)
			(type default)
		)
		(layer "In5.Cu")
	)
	(gr_line
		(start 217.255852 -89.450926)
		(end 217.27541 -89.422986)
		(stroke
			(width 0.06985)
			(type default)
		)
		(layer "In5.Cu")
	)
	(gr_line
		(start 217.27541 -89.422986)
		(end 217.281252 -89.389966)
		(stroke
			(width 0.06985)
			(type default)
		)
		(layer "In5.Cu")
	)
	(gr_line
		(start 217.395044 -31.915862)
		(end 217.411554 -31.91891)
		(stroke
			(width 0.06985)
			(type default)
		)
		(layer "In5.Cu")
	)
	(gr_line
		(start 217.411554 -31.91891)
		(end 217.42781 -31.915862)
		(stroke
			(width 0.06985)
			(type default)
		)
		(layer "In5.Cu")
	)
	(gr_line
		(start 217.508328 -58.02122)
		(end 217.51417 -57.9882)
		(stroke
			(width 0.06985)
			(type default)
		)
		(layer "In5.Cu")
	)
	(gr_line
		(start 217.51417 -57.9882)
		(end 217.533728 -57.96026)
		(stroke
			(width 0.06985)
			(type default)
		)
		(layer "In5.Cu")
	)
	(gr_line
		(start 217.629994 -53.075078)
		(end 217.657934 -53.05552)
		(stroke
			(width 0.06985)
			(type default)
		)
		(layer "In5.Cu")
	)
	(gr_line
		(start 217.657934 -53.05552)
		(end 217.690954 -53.049678)
		(stroke
			(width 0.06985)
			(type default)
		)
		(layer "In5.Cu")
	)
	(gr_line
		(start 217.678 -55.813706)
		(end 217.688922 -55.798212)
		(stroke
			(width 0.06985)
			(type default)
		)
		(layer "In5.Cu")
	)
	(gr_line
		(start 217.688922 -55.798212)
		(end 217.704416 -55.78729)
		(stroke
			(width 0.06985)
			(type default)
		)
		(layer "In5.Cu")
	)
	(gr_line
		(start 217.710004 -48.899064)
		(end 217.743024 -48.893222)
		(stroke
			(width 0.06985)
			(type default)
		)
		(layer "In5.Cu")
	)
	(gr_line
		(start 217.743024 -48.893222)
		(end 217.770964 -48.873664)
		(stroke
			(width 0.06985)
			(type default)
		)
		(layer "In5.Cu")
	)
	(gr_line
		(start 217.922602 -48.36414)
		(end 217.950542 -48.344582)
		(stroke
			(width 0.06985)
			(type default)
		)
		(layer "In5.Cu")
	)
	(gr_line
		(start 217.950542 -48.344582)
		(end 217.983562 -48.33874)
		(stroke
			(width 0.06985)
			(type default)
		)
		(layer "In5.Cu")
	)
	(gr_line
		(start 218.011502 -61.049662)
		(end 218.136978 -60.339478)
		(stroke
			(width 0.06985)
			(type default)
		)
		(layer "In5.Cu")
	)
	(gr_line
		(start 218.013026 -47.083726)
		(end 218.040966 -47.064168)
		(stroke
			(width 0.06985)
			(type default)
		)
		(layer "In5.Cu")
	)
	(gr_line
		(start 218.040966 -47.064168)
		(end 218.073986 -47.058326)
		(stroke
			(width 0.06985)
			(type default)
		)
		(layer "In5.Cu")
	)
	(gr_line
		(start 218.21394 -54.055518)
		(end 218.24188 -54.03596)
		(stroke
			(width 0.06985)
			(type default)
		)
		(layer "In5.Cu")
	)
	(gr_line
		(start 218.216988 -33.162748)
		(end 218.236038 -33.16605)
		(stroke
			(width 0.06985)
			(type default)
		)
		(layer "In5.Cu")
	)
	(gr_line
		(start 218.223084 -59.851798)
		(end 218.347798 -59.144154)
		(stroke
			(width 0.06985)
			(type default)
		)
		(layer "In5.Cu")
	)
	(gr_line
		(start 218.236038 -33.16605)
		(end 218.254834 -33.162748)
		(stroke
			(width 0.06985)
			(type default)
		)
		(layer "In5.Cu")
	)
	(gr_line
		(start 218.24188 -54.03596)
		(end 218.2749 -54.030118)
		(stroke
			(width 0.06985)
			(type default)
		)
		(layer "In5.Cu")
	)
	(gr_line
		(start 218.281504 -34.18713)
		(end 218.3003 -34.190432)
		(stroke
			(width 0.06985)
			(type default)
		)
		(layer "In5.Cu")
	)
	(gr_line
		(start 218.3003 -34.190432)
		(end 218.31935 -34.18713)
		(stroke
			(width 0.06985)
			(type default)
		)
		(layer "In5.Cu")
	)
	(gr_line
		(start 218.318334 -27.239722)
		(end 218.342972 -27.244802)
		(stroke
			(width 0.06985)
			(type default)
		)
		(layer "In5.Cu")
	)
	(gr_line
		(start 218.33332 -61.14034)
		(end 218.548966 -60.989464)
		(stroke
			(width 0.06985)
			(type default)
		)
		(layer "In5.Cu")
	)
	(gr_line
		(start 218.342972 -27.244802)
		(end 218.36761 -27.239722)
		(stroke
			(width 0.06985)
			(type default)
		)
		(layer "In5.Cu")
	)
	(gr_line
		(start 218.387676 -24.055832)
		(end 218.406726 -24.059134)
		(stroke
			(width 0.06985)
			(type default)
		)
		(layer "In5.Cu")
	)
	(gr_line
		(start 218.406726 -24.059134)
		(end 218.425522 -24.055832)
		(stroke
			(width 0.06985)
			(type default)
		)
		(layer "In5.Cu")
	)
	(gr_line
		(start 218.40825 -56.711342)
		(end 218.419172 -56.695848)
		(stroke
			(width 0.06985)
			(type default)
		)
		(layer "In5.Cu")
	)
	(gr_line
		(start 218.417648 -90.060018)
		(end 218.437206 -90.032078)
		(stroke
			(width 0.06985)
			(type default)
		)
		(layer "In5.Cu")
	)
	(gr_line
		(start 218.419172 -56.695848)
		(end 218.434666 -56.684926)
		(stroke
			(width 0.06985)
			(type default)
		)
		(layer "In5.Cu")
	)
	(gr_line
		(start 218.437206 -90.032078)
		(end 218.443048 -89.999058)
		(stroke
			(width 0.06985)
			(type default)
		)
		(layer "In5.Cu")
	)
	(gr_line
		(start 218.440762 -29.326586)
		(end 218.4654 -29.331666)
		(stroke
			(width 0.06985)
			(type default)
		)
		(layer "In5.Cu")
	)
	(gr_line
		(start 218.440762 -28.329128)
		(end 218.4654 -28.334208)
		(stroke
			(width 0.06985)
			(type default)
		)
		(layer "In5.Cu")
	)
	(gr_line
		(start 218.461844 -58.498232)
		(end 218.467686 -58.465212)
		(stroke
			(width 0.06985)
			(type default)
		)
		(layer "In5.Cu")
	)
	(gr_line
		(start 218.4654 -29.331666)
		(end 218.490038 -29.326586)
		(stroke
			(width 0.06985)
			(type default)
		)
		(layer "In5.Cu")
	)
	(gr_line
		(start 218.4654 -28.334208)
		(end 218.490038 -28.329128)
		(stroke
			(width 0.06985)
			(type default)
		)
		(layer "In5.Cu")
	)
	(gr_line
		(start 218.467686 -58.465212)
		(end 218.487244 -58.437272)
		(stroke
			(width 0.06985)
			(type default)
		)
		(layer "In5.Cu")
	)
	(gr_line
		(start 218.470988 -60.361322)
		(end 218.621864 -60.576714)
		(stroke
			(width 0.06985)
			(type default)
		)
		(layer "In5.Cu")
	)
	(gr_line
		(start 218.473274 -26.068782)
		(end 218.497404 -26.073608)
		(stroke
			(width 0.06985)
			(type default)
		)
		(layer "In5.Cu")
	)
	(gr_line
		(start 218.497404 -35.211766)
		(end 218.5162 -35.215068)
		(stroke
			(width 0.06985)
			(type default)
		)
		(layer "In5.Cu")
	)
	(gr_line
		(start 218.497404 -26.073608)
		(end 218.522042 -26.068528)
		(stroke
			(width 0.06985)
			(type default)
		)
		(layer "In5.Cu")
	)
	(gr_line
		(start 218.5162 -35.215068)
		(end 218.534996 -35.211766)
		(stroke
			(width 0.06985)
			(type default)
		)
		(layer "In5.Cu")
	)
	(gr_line
		(start 218.544394 -59.944762)
		(end 218.759786 -59.793886)
		(stroke
			(width 0.06985)
			(type default)
		)
		(layer "In5.Cu")
	)
	(gr_line
		(start 218.548966 -60.989464)
		(end 218.621864 -60.576714)
		(stroke
			(width 0.06985)
			(type default)
		)
		(layer "In5.Cu")
	)
	(gr_line
		(start 218.644216 -25.039574)
		(end 218.665298 -25.043384)
		(stroke
			(width 0.06985)
			(type default)
		)
		(layer "In5.Cu")
	)
	(gr_line
		(start 218.665298 -25.043384)
		(end 218.686126 -25.039066)
		(stroke
			(width 0.06985)
			(type default)
		)
		(layer "In5.Cu")
	)
	(gr_line
		(start 218.681808 -59.165998)
		(end 218.832684 -59.381136)
		(stroke
			(width 0.06985)
			(type default)
		)
		(layer "In5.Cu")
	)
	(gr_line
		(start 218.759786 -59.793886)
		(end 218.832684 -59.381136)
		(stroke
			(width 0.06985)
			(type default)
		)
		(layer "In5.Cu")
	)
	(gr_line
		(start 218.835478 -54.995318)
		(end 218.863418 -54.97576)
		(stroke
			(width 0.06985)
			(type default)
		)
		(layer "In5.Cu")
	)
	(gr_line
		(start 218.863418 -54.97576)
		(end 218.896438 -54.969918)
		(stroke
			(width 0.06985)
			(type default)
		)
		(layer "In5.Cu")
	)
	(gr_line
		(start 218.969336 -57.748932)
		(end 218.980258 -57.733438)
		(stroke
			(width 0.06985)
			(type default)
		)
		(layer "In5.Cu")
	)
	(gr_line
		(start 218.980258 -57.733438)
		(end 218.995752 -57.722516)
		(stroke
			(width 0.06985)
			(type default)
		)
		(layer "In5.Cu")
	)
	(gr_line
		(start 219.202254 -62.054232)
		(end 219.326968 -61.346588)
		(stroke
			(width 0.06985)
			(type default)
		)
		(layer "In5.Cu")
	)
	(gr_line
		(start 219.21216 -47.192946)
		(end 219.24518 -47.187104)
		(stroke
			(width 0.06985)
			(type default)
		)
		(layer "In5.Cu")
	)
	(gr_line
		(start 219.24518 -47.187104)
		(end 219.27312 -47.167546)
		(stroke
			(width 0.06985)
			(type default)
		)
		(layer "In5.Cu")
	)
	(gr_line
		(start 219.401898 -31.56839)
		(end 219.434918 -31.562548)
		(stroke
			(width 0.06985)
			(type default)
		)
		(layer "In5.Cu")
	)
	(gr_line
		(start 219.413074 -60.859162)
		(end 219.537788 -60.152026)
		(stroke
			(width 0.06985)
			(type default)
		)
		(layer "In5.Cu")
	)
	(gr_line
		(start 219.434918 -31.562548)
		(end 219.462858 -31.54299)
		(stroke
			(width 0.06985)
			(type default)
		)
		(layer "In5.Cu")
	)
	(gr_line
		(start 219.502482 -55.937404)
		(end 219.530422 -55.917846)
		(stroke
			(width 0.06985)
			(type default)
		)
		(layer "In5.Cu")
	)
	(gr_line
		(start 219.523818 -62.147704)
		(end 219.738956 -61.997336)
		(stroke
			(width 0.06985)
			(type default)
		)
		(layer "In5.Cu")
	)
	(gr_line
		(start 219.530422 -55.917846)
		(end 219.563442 -55.912004)
		(stroke
			(width 0.06985)
			(type default)
		)
		(layer "In5.Cu")
	)
	(gr_line
		(start 219.599764 -32.925766)
		(end 219.632784 -32.919924)
		(stroke
			(width 0.06985)
			(type default)
		)
		(layer "In5.Cu")
	)
	(gr_line
		(start 219.632784 -32.919924)
		(end 219.660724 -32.900366)
		(stroke
			(width 0.06985)
			(type default)
		)
		(layer "In5.Cu")
	)
	(gr_line
		(start 219.660978 -61.369194)
		(end 219.8116 -61.584586)
		(stroke
			(width 0.06985)
			(type default)
		)
		(layer "In5.Cu")
	)
	(gr_line
		(start 219.72905 -59.0677)
		(end 219.734892 -59.03468)
		(stroke
			(width 0.06985)
			(type default)
		)
		(layer "In5.Cu")
	)
	(gr_line
		(start 219.734638 -60.952126)
		(end 219.949776 -60.801504)
		(stroke
			(width 0.06985)
			(type default)
		)
		(layer "In5.Cu")
	)
	(gr_line
		(start 219.734892 -59.03468)
		(end 219.75445 -59.00674)
		(stroke
			(width 0.06985)
			(type default)
		)
		(layer "In5.Cu")
	)
	(gr_line
		(start 219.738956 -61.997336)
		(end 219.8116 -61.584586)
		(stroke
			(width 0.06985)
			(type default)
		)
		(layer "In5.Cu")
	)
	(gr_line
		(start 219.79382 -45.841412)
		(end 219.883482 -45.83811)
		(stroke
			(width 0.06985)
			(type default)
		)
		(layer "In5.Cu")
	)
	(gr_line
		(start 219.818204 -34.650172)
		(end 219.837 -34.64687)
		(stroke
			(width 0.06985)
			(type default)
		)
		(layer "In5.Cu")
	)
	(gr_line
		(start 219.818204 -33.58769)
		(end 219.837254 -33.584388)
		(stroke
			(width 0.06985)
			(type default)
		)
		(layer "In5.Cu")
	)
	(gr_line
		(start 219.837 -34.64687)
		(end 219.855796 -34.650172)
		(stroke
			(width 0.06985)
			(type default)
		)
		(layer "In5.Cu")
	)
	(gr_line
		(start 219.837254 -33.584388)
		(end 219.85605 -33.58769)
		(stroke
			(width 0.06985)
			(type default)
		)
		(layer "In5.Cu")
	)
	(gr_line
		(start 219.871798 -60.17387)
		(end 220.02242 -60.388754)
		(stroke
			(width 0.06985)
			(type default)
		)
		(layer "In5.Cu")
	)
	(gr_line
		(start 219.949776 -60.801504)
		(end 220.02242 -60.388754)
		(stroke
			(width 0.06985)
			(type default)
		)
		(layer "In5.Cu")
	)
	(gr_line
		(start 220.11259 -56.94045)
		(end 220.14053 -56.920892)
		(stroke
			(width 0.06985)
			(type default)
		)
		(layer "In5.Cu")
	)
	(gr_line
		(start 220.14053 -56.920892)
		(end 220.173804 -56.91505)
		(stroke
			(width 0.06985)
			(type default)
		)
		(layer "In5.Cu")
	)
	(gr_line
		(start 220.159834 -65.390522)
		(end 220.284548 -64.683132)
		(stroke
			(width 0.06985)
			(type default)
		)
		(layer "In5.Cu")
	)
	(gr_line
		(start 220.260926 -58.28411)
		(end 220.270578 -58.27014)
		(stroke
			(width 0.06985)
			(type default)
		)
		(layer "In5.Cu")
	)
	(gr_line
		(start 220.270578 -58.27014)
		(end 220.285056 -58.25998)
		(stroke
			(width 0.06985)
			(type default)
		)
		(layer "In5.Cu")
	)
	(gr_line
		(start 220.283786 -32.467042)
		(end 220.289628 -32.466026)
		(stroke
			(width 0.06985)
			(type default)
		)
		(layer "In5.Cu")
	)
	(gr_line
		(start 220.289628 -32.466026)
		(end 220.302836 -32.452818)
		(stroke
			(width 0.06985)
			(type default)
		)
		(layer "In5.Cu")
	)
	(gr_line
		(start 220.371162 -64.19342)
		(end 220.495368 -63.488062)
		(stroke
			(width 0.06985)
			(type default)
		)
		(layer "In5.Cu")
	)
	(gr_line
		(start 220.481144 -65.484248)
		(end 220.696536 -65.333626)
		(stroke
			(width 0.06985)
			(type default)
		)
		(layer "In5.Cu")
	)
	(gr_line
		(start 220.618558 -64.705738)
		(end 220.76918 -64.920876)
		(stroke
			(width 0.06985)
			(type default)
		)
		(layer "In5.Cu")
	)
	(gr_line
		(start 220.691964 -64.28867)
		(end 220.907356 -64.138048)
		(stroke
			(width 0.06985)
			(type default)
		)
		(layer "In5.Cu")
	)
	(gr_line
		(start 220.696536 -65.333626)
		(end 220.76918 -64.920876)
		(stroke
			(width 0.06985)
			(type default)
		)
		(layer "In5.Cu")
	)
	(gr_line
		(start 220.744542 -57.938162)
		(end 220.772482 -57.918604)
		(stroke
			(width 0.06985)
			(type default)
		)
		(layer "In5.Cu")
	)
	(gr_line
		(start 220.772482 -57.918604)
		(end 220.805502 -57.912762)
		(stroke
			(width 0.06985)
			(type default)
		)
		(layer "In5.Cu")
	)
	(gr_line
		(start 220.779086 -45.709586)
		(end 220.807788 -45.68952)
		(stroke
			(width 0.06985)
			(type default)
		)
		(layer "In5.Cu")
	)
	(gr_line
		(start 220.807788 -45.68952)
		(end 220.842078 -45.683424)
		(stroke
			(width 0.06985)
			(type default)
		)
		(layer "In5.Cu")
	)
	(gr_line
		(start 220.825568 -31.46298)
		(end 220.839792 -31.448756)
		(stroke
			(width 0.06985)
			(type default)
		)
		(layer "In5.Cu")
	)
	(gr_line
		(start 220.829378 -63.509906)
		(end 220.98 -63.725298)
		(stroke
			(width 0.06985)
			(type default)
		)
		(layer "In5.Cu")
	)
	(gr_line
		(start 220.84792 -67.264534)
		(end 220.8911 -67.019424)
		(stroke
			(width 0.06985)
			(type default)
		)
		(layer "In5.Cu")
	)
	(gr_line
		(start 220.8911 -67.019424)
		(end 220.90507 -66.939922)
		(stroke
			(width 0.06985)
			(type default)
		)
		(layer "In5.Cu")
	)
	(gr_line
		(start 220.907356 -64.138048)
		(end 220.98 -63.725298)
		(stroke
			(width 0.06985)
			(type default)
		)
		(layer "In5.Cu")
	)
	(gr_arc
		(start 220.99778 -66.761868)
		(mid 220.937708 -66.843752)
		(end 220.90507 -66.939922)
		(stroke
			(width 0.06985)
			(type default)
		)
		(layer "In5.Cu")
	)
	(gr_line
		(start 221.13494 -59.86145)
		(end 221.140782 -59.82843)
		(stroke
			(width 0.06985)
			(type default)
		)
		(layer "In5.Cu")
	)
	(gr_line
		(start 221.140782 -59.82843)
		(end 221.16034 -59.80049)
		(stroke
			(width 0.06985)
			(type default)
		)
		(layer "In5.Cu")
	)
	(gr_line
		(start 221.245684 -45.671232)
		(end 221.344998 -45.671232)
		(stroke
			(width 0.06985)
			(type default)
		)
		(layer "In5.Cu")
	)
	(gr_line
		(start 221.285562 -40.165274)
		(end 221.310962 -40.165274)
		(stroke
			(width 0.0508)
			(type default)
		)
		(layer "In5.Cu")
	)
	(gr_line
		(start 221.285562 -39.835074)
		(end 221.310962 -39.835074)
		(stroke
			(width 0.0508)
			(type default)
		)
		(layer "In5.Cu")
	)
	(gr_line
		(start 221.285562 -36.165282)
		(end 221.310962 -36.165282)
		(stroke
			(width 0.0508)
			(type default)
		)
		(layer "In5.Cu")
	)
	(gr_line
		(start 221.285562 -35.835082)
		(end 221.31782 -35.86734)
		(stroke
			(width 0.0508)
			(type default)
		)
		(layer "In5.Cu")
	)
	(gr_line
		(start 221.308168 -88.380824)
		(end 221.327726 -88.352884)
		(stroke
			(width 0.06985)
			(type default)
		)
		(layer "In5.Cu")
	)
	(gr_line
		(start 221.310962 -40.165274)
		(end 221.33052 -40.145716)
		(stroke
			(width 0.0508)
			(type default)
		)
		(layer "In5.Cu")
	)
	(gr_line
		(start 221.310962 -39.835074)
		(end 221.33052 -39.854632)
		(stroke
			(width 0.0508)
			(type default)
		)
		(layer "In5.Cu")
	)
	(gr_line
		(start 221.310962 -36.165282)
		(end 221.31782 -36.158424)
		(stroke
			(width 0.0508)
			(type default)
		)
		(layer "In5.Cu")
	)
	(gr_line
		(start 221.319598 -36.156646)
		(end 221.374462 -36.101782)
		(stroke
			(width 0.0508)
			(type default)
		)
		(layer "In5.Cu")
	)
	(gr_line
		(start 221.319598 -35.869118)
		(end 221.349062 -35.898582)
		(stroke
			(width 0.0508)
			(type default)
		)
		(layer "In5.Cu")
	)
	(gr_line
		(start 221.327726 -88.352884)
		(end 221.333568 -88.319864)
		(stroke
			(width 0.06985)
			(type default)
		)
		(layer "In5.Cu")
	)
	(gr_line
		(start 221.332298 -40.143938)
		(end 221.374462 -40.101774)
		(stroke
			(width 0.0508)
			(type default)
		)
		(layer "In5.Cu")
	)
	(gr_line
		(start 221.332298 -39.85641)
		(end 221.342712 -39.866824)
		(stroke
			(width 0.0508)
			(type default)
		)
		(layer "In5.Cu")
	)
	(gr_arc
		(start 221.342712 -39.866824)
		(mid 221.377908 -39.890341)
		(end 221.41942 -39.898574)
		(stroke
			(width 0.0508)
			(type default)
		)
		(layer "In5.Cu")
	)
	(gr_line
		(start 221.344998 -45.671232)
		(end 221.480634 -45.671232)
		(stroke
			(width 0.0508)
			(type default)
		)
		(layer "In5.Cu")
	)
	(gr_arc
		(start 221.367604 -66.859404)
		(mid 221.241536 -67.099008)
		(end 221.166944 -67.359276)
		(stroke
			(width 0.06985)
			(type default)
		)
		(layer "In5.Cu")
	)
	(gr_line
		(start 221.387924 -38.1889)
		(end 221.400624 -38.1889)
		(stroke
			(width 0.0508)
			(type default)
		)
		(layer "In5.Cu")
	)
	(gr_line
		(start 221.400624 -38.1889)
		(end 221.413324 -38.1762)
		(stroke
			(width 0.0508)
			(type default)
		)
		(layer "In5.Cu")
	)
	(gr_line
		(start 221.413324 -38.153848)
		(end 221.413324 -38.1762)
		(stroke
			(width 0.0508)
			(type default)
		)
		(layer "In5.Cu")
	)
	(gr_line
		(start 221.413324 -38.153848)
		(end 221.439232 -38.12794)
		(stroke
			(width 0.0508)
			(type default)
		)
		(layer "In5.Cu")
	)
	(gr_line
		(start 221.4372 -37.8587)
		(end 221.4626 -37.8587)
		(stroke
			(width 0.0508)
			(type default)
		)
		(layer "In5.Cu")
	)
	(gr_line
		(start 221.4626 -30.16504)
		(end 221.488 -30.16504)
		(stroke
			(width 0.0508)
			(type default)
		)
		(layer "In5.Cu")
	)
	(gr_line
		(start 221.4626 -29.83484)
		(end 221.488 -29.83484)
		(stroke
			(width 0.0508)
			(type default)
		)
		(layer "In5.Cu")
	)
	(gr_line
		(start 221.480634 -45.671232)
		(end 221.493588 -45.684186)
		(stroke
			(width 0.0508)
			(type default)
		)
		(layer "In5.Cu")
	)
	(gr_line
		(start 221.488 -30.16504)
		(end 221.507558 -30.145482)
		(stroke
			(width 0.0508)
			(type default)
		)
		(layer "In5.Cu")
	)
	(gr_line
		(start 221.488 -29.83484)
		(end 221.507558 -29.854398)
		(stroke
			(width 0.0508)
			(type default)
		)
		(layer "In5.Cu")
	)
	(gr_line
		(start 221.493588 -45.684186)
		(end 221.733618 -45.72635)
		(stroke
			(width 0.0508)
			(type default)
		)
		(layer "In5.Cu")
	)
	(gr_line
		(start 221.509336 -30.143704)
		(end 221.51975 -30.13329)
		(stroke
			(width 0.0508)
			(type default)
		)
		(layer "In5.Cu")
	)
	(gr_line
		(start 221.509336 -29.856176)
		(end 221.51975 -29.86659)
		(stroke
			(width 0.0508)
			(type default)
		)
		(layer "In5.Cu")
	)
	(gr_arc
		(start 221.512384 -45.93209)
		(mid 221.421791 -45.95011)
		(end 221.344998 -46.001432)
		(stroke
			(width 0.0508)
			(type default)
		)
		(layer "In5.Cu")
	)
	(gr_line
		(start 221.512384 -45.93209)
		(end 221.611698 -45.93209)
		(stroke
			(width 0.0508)
			(type default)
		)
		(layer "In5.Cu")
	)
	(gr_line
		(start 221.5134 -37.16528)
		(end 221.5388 -37.16528)
		(stroke
			(width 0.0508)
			(type default)
		)
		(layer "In5.Cu")
	)
	(gr_line
		(start 221.5134 -36.83508)
		(end 221.545658 -36.867338)
		(stroke
			(width 0.0508)
			(type default)
		)
		(layer "In5.Cu")
	)
	(gr_arc
		(start 221.51975 -29.86659)
		(mid 221.554944 -29.890106)
		(end 221.596458 -29.89834)
		(stroke
			(width 0.0508)
			(type default)
		)
		(layer "In5.Cu")
	)
	(gr_line
		(start 221.538292 -48.693578)
		(end 221.557088 -48.690276)
		(stroke
			(width 0.06985)
			(type default)
		)
		(layer "In5.Cu")
	)
	(gr_line
		(start 221.5388 -37.16528)
		(end 221.545658 -37.158422)
		(stroke
			(width 0.0508)
			(type default)
		)
		(layer "In5.Cu")
	)
	(gr_line
		(start 221.541086 -57.8358)
		(end 221.6658 -57.8358)
		(stroke
			(width 0.06985)
			(type default)
		)
		(layer "In5.Cu")
	)
	(gr_line
		(start 221.547436 -37.156644)
		(end 221.6023 -37.10178)
		(stroke
			(width 0.0508)
			(type default)
		)
		(layer "In5.Cu")
	)
	(gr_line
		(start 221.547436 -36.869116)
		(end 221.5769 -36.89858)
		(stroke
			(width 0.0508)
			(type default)
		)
		(layer "In5.Cu")
	)
	(gr_line
		(start 221.557088 -48.690276)
		(end 221.575884 -48.693578)
		(stroke
			(width 0.06985)
			(type default)
		)
		(layer "In5.Cu")
	)
	(gr_line
		(start 221.5642 -35.165284)
		(end 221.5896 -35.165284)
		(stroke
			(width 0.0508)
			(type default)
		)
		(layer "In5.Cu")
	)
	(gr_line
		(start 221.5642 -34.835084)
		(end 221.5896 -34.835084)
		(stroke
			(width 0.0508)
			(type default)
		)
		(layer "In5.Cu")
	)
	(gr_line
		(start 221.5642 -34.165286)
		(end 221.5896 -34.165286)
		(stroke
			(width 0.0508)
			(type default)
		)
		(layer "In5.Cu")
	)
	(gr_line
		(start 221.5642 -33.835086)
		(end 221.5896 -33.835086)
		(stroke
			(width 0.0508)
			(type default)
		)
		(layer "In5.Cu")
	)
	(gr_line
		(start 221.577662 -56.1594)
		(end 221.7674 -56.1594)
		(stroke
			(width 0.06985)
			(type default)
		)
		(layer "In5.Cu")
	)
	(gr_line
		(start 221.5896 -41.165272)
		(end 221.615 -41.165272)
		(stroke
			(width 0.0508)
			(type default)
		)
		(layer "In5.Cu")
	)
	(gr_line
		(start 221.5896 -40.835072)
		(end 221.621858 -40.86733)
		(stroke
			(width 0.0508)
			(type default)
		)
		(layer "In5.Cu")
	)
	(gr_line
		(start 221.5896 -39.165276)
		(end 221.615 -39.165276)
		(stroke
			(width 0.0508)
			(type default)
		)
		(layer "In5.Cu")
	)
	(gr_line
		(start 221.5896 -38.835076)
		(end 221.615 -38.835076)
		(stroke
			(width 0.0508)
			(type default)
		)
		(layer "In5.Cu")
	)
	(gr_line
		(start 221.5896 -35.165284)
		(end 221.6531 -35.101784)
		(stroke
			(width 0.0508)
			(type default)
		)
		(layer "In5.Cu")
	)
	(gr_arc
		(start 221.5896 -34.835084)
		(mid 221.660002 -34.882062)
		(end 221.743016 -34.898584)
		(stroke
			(width 0.0508)
			(type default)
		)
		(layer "In5.Cu")
	)
	(gr_line
		(start 221.5896 -34.165286)
		(end 221.6531 -34.101786)
		(stroke
			(width 0.0508)
			(type default)
		)
		(layer "In5.Cu")
	)
	(gr_arc
		(start 221.5896 -33.835086)
		(mid 221.659993 -33.882098)
		(end 221.743016 -33.898586)
		(stroke
			(width 0.0508)
			(type default)
		)
		(layer "In5.Cu")
	)
	(gr_arc
		(start 221.596458 -30.10154)
		(mid 221.554946 -30.109783)
		(end 221.51975 -30.13329)
		(stroke
			(width 0.0508)
			(type default)
		)
		(layer "In5.Cu")
	)
	(gr_line
		(start 221.614238 -45.93209)
		(end 221.71533 -45.93209)
		(stroke
			(width 0.0508)
			(type default)
		)
		(layer "In5.Cu")
	)
	(gr_line
		(start 221.615 -41.165272)
		(end 221.621858 -41.158414)
		(stroke
			(width 0.0508)
			(type default)
		)
		(layer "In5.Cu")
	)
	(gr_line
		(start 221.615 -39.165276)
		(end 221.634558 -39.145718)
		(stroke
			(width 0.0508)
			(type default)
		)
		(layer "In5.Cu")
	)
	(gr_line
		(start 221.615 -38.835076)
		(end 221.634558 -38.854634)
		(stroke
			(width 0.0508)
			(type default)
		)
		(layer "In5.Cu")
	)
	(gr_line
		(start 221.622112 -52.1208)
		(end 221.6404 -52.1208)
		(stroke
			(width 0.06985)
			(type default)
		)
		(layer "In5.Cu")
	)
	(gr_line
		(start 221.623636 -41.156636)
		(end 221.6785 -41.101772)
		(stroke
			(width 0.0508)
			(type default)
		)
		(layer "In5.Cu")
	)
	(gr_line
		(start 221.623636 -40.869108)
		(end 221.6531 -40.898572)
		(stroke
			(width 0.0508)
			(type default)
		)
		(layer "In5.Cu")
	)
	(gr_arc
		(start 221.633288 -31.20644)
		(mid 221.821512 -31.173782)
		(end 221.987618 -31.07944)
		(stroke
			(width 0.06985)
			(type default)
		)
		(layer "In5.Cu")
	)
	(gr_line
		(start 221.636336 -39.14394)
		(end 221.6785 -39.101776)
		(stroke
			(width 0.0508)
			(type default)
		)
		(layer "In5.Cu")
	)
	(gr_line
		(start 221.636336 -38.856412)
		(end 221.64675 -38.866826)
		(stroke
			(width 0.0508)
			(type default)
		)
		(layer "In5.Cu")
	)
	(gr_arc
		(start 221.6404 -51.7906)
		(mid 221.754384 -51.86671)
		(end 221.888812 -51.89347)
		(stroke
			(width 0.0508)
			(type default)
		)
		(layer "In5.Cu")
	)
	(gr_arc
		(start 221.64675 -38.866826)
		(mid 221.681948 -38.890331)
		(end 221.723458 -38.898576)
		(stroke
			(width 0.0508)
			(type default)
		)
		(layer "In5.Cu")
	)
	(gr_line
		(start 221.655894 -54.1528)
		(end 221.7928 -54.1528)
		(stroke
			(width 0.06985)
			(type default)
		)
		(layer "In5.Cu")
	)
	(gr_arc
		(start 221.6658 -57.8358)
		(mid 221.729662 -57.878471)
		(end 221.804992 -57.893458)
		(stroke
			(width 0.0508)
			(type default)
		)
		(layer "In5.Cu")
	)
	(gr_line
		(start 221.674944 -54.8386)
		(end 221.7674 -54.8386)
		(stroke
			(width 0.06985)
			(type default)
		)
		(layer "In5.Cu")
	)
	(gr_line
		(start 221.685104 -53.1368)
		(end 221.742 -53.1368)
		(stroke
			(width 0.06985)
			(type default)
		)
		(layer "In5.Cu")
	)
	(gr_line
		(start 221.694756 -49.050194)
		(end 221.719648 -49.054512)
		(stroke
			(width 0.0508)
			(type default)
		)
		(layer "In5.Cu")
	)
	(gr_arc
		(start 221.698566 -52.09667)
		(mid 221.667073 -52.102934)
		(end 221.6404 -52.1208)
		(stroke
			(width 0.0508)
			(type default)
		)
		(layer "In5.Cu")
	)
	(gr_line
		(start 221.719648 -49.054512)
		(end 221.756478 -49.028604)
		(stroke
			(width 0.0508)
			(type default)
		)
		(layer "In5.Cu")
	)
	(gr_line
		(start 221.7293 -57.15)
		(end 221.8182 -57.15)
		(stroke
			(width 0.06985)
			(type default)
		)
		(layer "In5.Cu")
	)
	(gr_arc
		(start 221.742 -52.8066)
		(mid 221.838264 -52.870908)
		(end 221.951804 -52.893468)
		(stroke
			(width 0.0508)
			(type default)
		)
		(layer "In5.Cu")
	)
	(gr_line
		(start 221.75216 -48.72482)
		(end 221.821248 -48.80102)
		(stroke
			(width 0.0508)
			(type default)
		)
		(layer "In5.Cu")
	)
	(gr_line
		(start 221.7674 -55.8292)
		(end 221.7801 -55.8292)
		(stroke
			(width 0.0508)
			(type default)
		)
		(layer "In5.Cu")
	)
	(gr_arc
		(start 221.7674 -54.8386)
		(mid 221.828099 -54.879228)
		(end 221.899734 -54.893464)
		(stroke
			(width 0.0508)
			(type default)
		)
		(layer "In5.Cu")
	)
	(gr_line
		(start 221.7801 -55.8292)
		(end 221.844362 -55.893462)
		(stroke
			(width 0.0508)
			(type default)
		)
		(layer "In5.Cu")
	)
	(gr_line
		(start 221.782894 -59.487308)
		(end 221.853506 -59.386724)
		(stroke
			(width 0.06985)
			(type default)
		)
		(layer "In5.Cu")
	)
	(gr_line
		(start 221.7928 -54.1528)
		(end 221.799404 -54.145942)
		(stroke
			(width 0.0508)
			(type default)
		)
		(layer "In5.Cu")
	)
	(gr_line
		(start 221.7928 -53.8226)
		(end 221.82201 -53.85181)
		(stroke
			(width 0.0508)
			(type default)
		)
		(layer "In5.Cu")
	)
	(gr_arc
		(start 221.807786 -58.096658)
		(mid 221.717196 -58.114682)
		(end 221.6404 -58.166)
		(stroke
			(width 0.0508)
			(type default)
		)
		(layer "In5.Cu")
	)
	(gr_line
		(start 221.807786 -58.096658)
		(end 221.9325 -58.096658)
		(stroke
			(width 0.0508)
			(type default)
		)
		(layer "In5.Cu")
	)
	(gr_arc
		(start 221.8182 -56.8198)
		(mid 221.899775 -56.874307)
		(end 221.996 -56.89346)
		(stroke
			(width 0.0508)
			(type default)
		)
		(layer "In5.Cu")
	)
	(gr_line
		(start 221.821248 -48.80102)
		(end 221.843092 -48.80483)
		(stroke
			(width 0.0508)
			(type default)
		)
		(layer "In5.Cu")
	)
	(gr_arc
		(start 221.82201 -53.85181)
		(mid 221.868159 -53.882642)
		(end 221.922594 -53.893466)
		(stroke
			(width 0.0508)
			(type default)
		)
		(layer "In5.Cu")
	)
	(gr_line
		(start 221.83598 -68.852796)
		(end 221.841822 -68.819776)
		(stroke
			(width 0.06985)
			(type default)
		)
		(layer "In5.Cu")
	)
	(gr_arc
		(start 221.837758 -49.01057)
		(mid 221.795328 -49.011508)
		(end 221.756478 -49.028604)
		(stroke
			(width 0.0508)
			(type default)
		)
		(layer "In5.Cu")
	)
	(gr_arc
		(start 221.838774 -53.096668)
		(mid 221.786382 -53.107089)
		(end 221.742 -53.1368)
		(stroke
			(width 0.0508)
			(type default)
		)
		(layer "In5.Cu")
	)
	(gr_line
		(start 221.841822 -68.819776)
		(end 221.86138 -68.791836)
		(stroke
			(width 0.06985)
			(type default)
		)
		(layer "In5.Cu")
	)
	(gr_line
		(start 221.844362 -55.893462)
		(end 222.0341 -55.893462)
		(stroke
			(width 0.0508)
			(type default)
		)
		(layer "In5.Cu")
	)
	(gr_line
		(start 221.853506 -59.386724)
		(end 221.924626 -59.315604)
		(stroke
			(width 0.0508)
			(type default)
		)
		(layer "In5.Cu")
	)
	(gr_arc
		(start 221.883986 -50.075338)
		(mid 222.062281 -50.043967)
		(end 222.233236 -49.984406)
		(stroke
			(width 0.0508)
			(type default)
		)
		(layer "In5.Cu")
	)
	(gr_line
		(start 221.888812 -51.89347)
		(end 221.9071 -51.89347)
		(stroke
			(width 0.0508)
			(type default)
		)
		(layer "In5.Cu")
	)
	(gr_arc
		(start 221.918784 -56.096662)
		(mid 221.836855 -56.112986)
		(end 221.7674 -56.1594)
		(stroke
			(width 0.0508)
			(type default)
		)
		(layer "In5.Cu")
	)
	(gr_arc
		(start 221.918784 -54.096666)
		(mid 221.854188 -54.109421)
		(end 221.799404 -54.145942)
		(stroke
			(width 0.0508)
			(type default)
		)
		(layer "In5.Cu")
	)
	(gr_line
		(start 221.922594 -53.893466)
		(end 222.0595 -53.893466)
		(stroke
			(width 0.0508)
			(type default)
		)
		(layer "In5.Cu")
	)
	(gr_arc
		(start 221.941644 -55.096664)
		(mid 221.847358 -55.115419)
		(end 221.7674 -55.1688)
		(stroke
			(width 0.0508)
			(type default)
		)
		(layer "In5.Cu")
	)
	(gr_line
		(start 221.941644 -55.096664)
		(end 222.0341 -55.096664)
		(stroke
			(width 0.0508)
			(type default)
		)
		(layer "In5.Cu")
	)
	(gr_arc
		(start 221.946978 -57.09666)
		(mid 221.877288 -57.110529)
		(end 221.8182 -57.15)
		(stroke
			(width 0.0508)
			(type default)
		)
		(layer "In5.Cu")
	)
	(gr_line
		(start 221.951804 -52.893468)
		(end 222.0087 -52.893468)
		(stroke
			(width 0.0508)
			(type default)
		)
		(layer "In5.Cu")
	)
	(gr_line
		(start 221.987618 -31.07944)
		(end 222.046546 -31.030926)
		(stroke
			(width 0.06985)
			(type default)
		)
		(layer "In5.Cu")
	)
	(gr_line
		(start 221.996 -56.89346)
		(end 222.0849 -56.89346)
		(stroke
			(width 0.0508)
			(type default)
		)
		(layer "In5.Cu")
	)
	(gr_arc
		(start 222.046546 -31.030926)
		(mid 222.182595 -30.776552)
		(end 222.10014 -30.500066)
		(stroke
			(width 0.06985)
			(type default)
		)
		(layer "In5.Cu")
	)
	(gr_line
		(start 222.089472 -65.919604)
		(end 222.089472 -65.919858)
		(stroke
			(width 0.06985)
			(type default)
		)
		(layer "In5.Cu")
	)
	(gr_line
		(start 222.10014 -58.499756)
		(end 222.153226 -58.552842)
		(stroke
			(width 0.0508)
			(type default)
		)
		(layer "In5.Cu")
	)
	(gr_line
		(start 222.10014 -56.49976)
		(end 222.153226 -56.552846)
		(stroke
			(width 0.0508)
			(type default)
		)
		(layer "In5.Cu")
	)
	(gr_line
		(start 222.10014 -54.499764)
		(end 222.153226 -54.55285)
		(stroke
			(width 0.0508)
			(type default)
		)
		(layer "In5.Cu")
	)
	(gr_line
		(start 222.10014 -52.499768)
		(end 222.153226 -52.552854)
		(stroke
			(width 0.0508)
			(type default)
		)
		(layer "In5.Cu")
	)
	(gr_line
		(start 222.10014 -49.499774)
		(end 222.153226 -49.55286)
		(stroke
			(width 0.0508)
			(type default)
		)
		(layer "In5.Cu")
	)
	(gr_line
		(start 222.10014 -46.500034)
		(end 222.153226 -46.55312)
		(stroke
			(width 0.0508)
			(type default)
		)
		(layer "In5.Cu")
	)
	(gr_line
		(start 222.10014 -37.500052)
		(end 222.386652 -37.500052)
		(stroke
			(width 0.0508)
			(type default)
		)
		(layer "In5.Cu")
	)
	(gr_line
		(start 222.10014 -33.48863)
		(end 222.10014 -33.50006)
		(stroke
			(width 0.0508)
			(type default)
		)
		(layer "In5.Cu")
	)
	(gr_arc
		(start 222.153226 -58.552842)
		(mid 222.206947 -58.598193)
		(end 222.267526 -58.633868)
		(stroke
			(width 0.0508)
			(type default)
		)
		(layer "In5.Cu")
	)
	(gr_arc
		(start 222.153226 -56.552846)
		(mid 222.206947 -56.598196)
		(end 222.267526 -56.633872)
		(stroke
			(width 0.0508)
			(type default)
		)
		(layer "In5.Cu")
	)
	(gr_arc
		(start 222.153226 -54.55285)
		(mid 222.206939 -54.598214)
		(end 222.267526 -54.633876)
		(stroke
			(width 0.0508)
			(type default)
		)
		(layer "In5.Cu")
	)
	(gr_arc
		(start 222.153226 -52.552854)
		(mid 222.206939 -52.598218)
		(end 222.267526 -52.63388)
		(stroke
			(width 0.0508)
			(type default)
		)
		(layer "In5.Cu")
	)
	(gr_arc
		(start 222.153226 -49.55286)
		(mid 222.206948 -49.598209)
		(end 222.267526 -49.633886)
		(stroke
			(width 0.0508)
			(type default)
		)
		(layer "In5.Cu")
	)
	(gr_arc
		(start 222.153226 -46.55312)
		(mid 222.206952 -46.598464)
		(end 222.267526 -46.634146)
		(stroke
			(width 0.0508)
			(type default)
		)
		(layer "In5.Cu")
	)
	(gr_arc
		(start 222.171768 -33.385252)
		(mid 222.119784 -33.425739)
		(end 222.10014 -33.48863)
		(stroke
			(width 0.0508)
			(type default)
		)
		(layer "In5.Cu")
	)
	(gr_line
		(start 222.171768 -33.385252)
		(end 222.26143 -33.35147)
		(stroke
			(width 0.0508)
			(type default)
		)
		(layer "In5.Cu")
	)
	(gr_line
		(start 222.267526 -58.633868)
		(end 222.296482 -58.647838)
		(stroke
			(width 0.0508)
			(type default)
		)
		(layer "In5.Cu")
	)
	(gr_line
		(start 222.267526 -56.633872)
		(end 222.296482 -56.647842)
		(stroke
			(width 0.0508)
			(type default)
		)
		(layer "In5.Cu")
	)
	(gr_line
		(start 222.267526 -54.633876)
		(end 222.296482 -54.647846)
		(stroke
			(width 0.0508)
			(type default)
		)
		(layer "In5.Cu")
	)
	(gr_line
		(start 222.267526 -52.63388)
		(end 222.296482 -52.64785)
		(stroke
			(width 0.0508)
			(type default)
		)
		(layer "In5.Cu")
	)
	(gr_line
		(start 222.267526 -49.633886)
		(end 222.296482 -49.647856)
		(stroke
			(width 0.0508)
			(type default)
		)
		(layer "In5.Cu")
	)
	(gr_line
		(start 222.267526 -46.634146)
		(end 222.296482 -46.648116)
		(stroke
			(width 0.0508)
			(type default)
		)
		(layer "In5.Cu")
	)
	(gr_arc
		(start 222.296482 -58.647838)
		(mid 222.332623 -58.660397)
		(end 222.37065 -58.664602)
		(stroke
			(width 0.0508)
			(type default)
		)
		(layer "In5.Cu")
	)
	(gr_arc
		(start 222.296482 -56.647842)
		(mid 222.332623 -56.6604)
		(end 222.37065 -56.664606)
		(stroke
			(width 0.0508)
			(type default)
		)
		(layer "In5.Cu")
	)
	(gr_arc
		(start 222.296482 -54.647846)
		(mid 222.332626 -54.660386)
		(end 222.37065 -54.66461)
		(stroke
			(width 0.0508)
			(type default)
		)
		(layer "In5.Cu")
	)
	(gr_arc
		(start 222.296482 -52.64785)
		(mid 222.332626 -52.66039)
		(end 222.37065 -52.664614)
		(stroke
			(width 0.0508)
			(type default)
		)
		(layer "In5.Cu")
	)
	(gr_arc
		(start 222.296482 -49.647856)
		(mid 222.332623 -49.660413)
		(end 222.37065 -49.66462)
		(stroke
			(width 0.0508)
			(type default)
		)
		(layer "In5.Cu")
	)
	(gr_arc
		(start 222.296482 -46.648116)
		(mid 222.332623 -46.660676)
		(end 222.37065 -46.66488)
		(stroke
			(width 0.0508)
			(type default)
		)
		(layer "In5.Cu")
	)
	(gr_arc
		(start 222.323406 -35.4076)
		(mid 222.202584 -35.431633)
		(end 222.10014 -35.500056)
		(stroke
			(width 0.0508)
			(type default)
		)
		(layer "In5.Cu")
	)
	(gr_line
		(start 222.323406 -35.4076)
		(end 222.504 -35.4076)
		(stroke
			(width 0.0508)
			(type default)
		)
		(layer "In5.Cu")
	)
	(gr_line
		(start 222.348298 -45.834554)
		(end 222.362522 -45.837094)
		(stroke
			(width 0.0508)
			(type default)
		)
		(layer "In5.Cu")
	)
	(gr_arc
		(start 222.35795 -39.898574)
		(mid 222.440716 -39.895589)
		(end 222.52305 -39.886636)
		(stroke
			(width 0.0508)
			(type default)
		)
		(layer "In5.Cu")
	)
	(gr_line
		(start 222.362522 -45.837094)
		(end 222.374206 -45.845476)
		(stroke
			(width 0.0508)
			(type default)
		)
		(layer "In5.Cu")
	)
	(gr_line
		(start 222.37065 -58.664602)
		(end 222.44431 -58.664602)
		(stroke
			(width 0.0508)
			(type default)
		)
		(layer "In5.Cu")
	)
	(gr_arc
		(start 222.37065 -56.664606)
		(mid 222.478149 -56.64321)
		(end 222.569278 -56.58231)
		(stroke
			(width 0.0508)
			(type default)
		)
		(layer "In5.Cu")
	)
	(gr_line
		(start 222.37065 -54.66461)
		(end 222.43796 -54.66461)
		(stroke
			(width 0.0508)
			(type default)
		)
		(layer "In5.Cu")
	)
	(gr_line
		(start 222.37065 -52.664614)
		(end 222.482918 -52.664614)
		(stroke
			(width 0.0508)
			(type default)
		)
		(layer "In5.Cu")
	)
	(gr_line
		(start 222.37065 -49.66462)
		(end 222.477584 -49.66462)
		(stroke
			(width 0.0508)
			(type default)
		)
		(layer "In5.Cu")
	)
	(gr_line
		(start 222.37065 -46.66488)
		(end 222.508064 -46.66488)
		(stroke
			(width 0.0508)
			(type default)
		)
		(layer "In5.Cu")
	)
	(gr_arc
		(start 222.377 -58.893456)
		(mid 221.882344 -59.008648)
		(end 221.489524 -59.33059)
		(stroke
			(width 0.0508)
			(type default)
		)
		(layer "In5.Cu")
	)
	(gr_line
		(start 222.419164 -48.001682)
		(end 222.43034 -48.012858)
		(stroke
			(width 0.0508)
			(type default)
		)
		(layer "In5.Cu")
	)
	(gr_line
		(start 222.428562 -47.669196)
		(end 222.43288 -47.668688)
		(stroke
			(width 0.06985)
			(type default)
		)
		(layer "In5.Cu")
	)
	(gr_line
		(start 222.43034 -48.012858)
		(end 222.836232 -48.012858)
		(stroke
			(width 0.0508)
			(type default)
		)
		(layer "In5.Cu")
	)
	(gr_line
		(start 222.43288 -47.668688)
		(end 222.437198 -47.66945)
		(stroke
			(width 0.06985)
			(type default)
		)
		(layer "In5.Cu")
	)
	(gr_arc
		(start 222.43796 -54.66461)
		(mid 222.51098 -54.647593)
		(end 222.56877 -54.59984)
		(stroke
			(width 0.0508)
			(type default)
		)
		(layer "In5.Cu")
	)
	(gr_arc
		(start 222.44431 -58.664602)
		(mid 222.518951 -58.644765)
		(end 222.57385 -58.590434)
		(stroke
			(width 0.0508)
			(type default)
		)
		(layer "In5.Cu")
	)
	(gr_arc
		(start 222.4532 -59.096656)
		(mid 222.167134 -59.153556)
		(end 221.924626 -59.315604)
		(stroke
			(width 0.0508)
			(type default)
		)
		(layer "In5.Cu")
	)
	(gr_arc
		(start 222.477584 -49.66462)
		(mid 222.507496 -49.661669)
		(end 222.536258 -49.652936)
		(stroke
			(width 0.0508)
			(type default)
		)
		(layer "In5.Cu")
	)
	(gr_arc
		(start 222.482918 -52.664614)
		(mid 222.50765 -52.662178)
		(end 222.531432 -52.654962)
		(stroke
			(width 0.0508)
			(type default)
		)
		(layer "In5.Cu")
	)
	(gr_arc
		(start 222.497142 -49.186084)
		(mid 222.418154 -49.128201)
		(end 222.325438 -49.096676)
		(stroke
			(width 0.0508)
			(type default)
		)
		(layer "In5.Cu")
	)
	(gr_arc
		(start 222.498412 -37.611812)
		(mid 222.465678 -37.532786)
		(end 222.386652 -37.500052)
		(stroke
			(width 0.0508)
			(type default)
		)
		(layer "In5.Cu")
	)
	(gr_arc
		(start 222.504762 -33.37687)
		(mid 222.386096 -33.335404)
		(end 222.26143 -33.35147)
		(stroke
			(width 0.0508)
			(type default)
		)
		(layer "In5.Cu")
	)
	(gr_line
		(start 222.504762 -33.37687)
		(end 222.620078 -33.45053)
		(stroke
			(width 0.0508)
			(type default)
		)
		(layer "In5.Cu")
	)
	(gr_arc
		(start 222.508064 -46.66488)
		(mid 222.561134 -46.654314)
		(end 222.606108 -46.62424)
		(stroke
			(width 0.0508)
			(type default)
		)
		(layer "In5.Cu")
	)
	(gr_line
		(start 222.51543 -47.683166)
		(end 222.613982 -47.700438)
		(stroke
			(width 0.06985)
			(type default)
		)
		(layer "In5.Cu")
	)
	(gr_arc
		(start 222.52305 -39.886636)
		(mid 222.612003 -39.825268)
		(end 222.664274 -39.73068)
		(stroke
			(width 0.0508)
			(type default)
		)
		(layer "In5.Cu")
	)
	(gr_line
		(start 222.531432 -52.654962)
		(end 222.556578 -52.644548)
		(stroke
			(width 0.0508)
			(type default)
		)
		(layer "In5.Cu")
	)
	(gr_line
		(start 222.536258 -49.652936)
		(end 222.56496 -49.640998)
		(stroke
			(width 0.0508)
			(type default)
		)
		(layer "In5.Cu")
	)
	(gr_arc
		(start 222.556578 -52.644548)
		(mid 222.620623 -52.555154)
		(end 222.655892 -52.451)
		(stroke
			(width 0.0508)
			(type default)
		)
		(layer "In5.Cu")
	)
	(gr_arc
		(start 222.56496 -49.640998)
		(mid 222.622235 -49.56392)
		(end 222.654876 -49.473612)
		(stroke
			(width 0.0508)
			(type default)
		)
		(layer "In5.Cu")
	)
	(gr_line
		(start 222.56877 -54.59984)
		(end 222.589598 -54.572408)
		(stroke
			(width 0.0508)
			(type default)
		)
		(layer "In5.Cu")
	)
	(gr_line
		(start 222.569278 -56.58231)
		(end 222.588074 -56.563514)
		(stroke
			(width 0.0508)
			(type default)
		)
		(layer "In5.Cu")
	)
	(gr_line
		(start 222.57385 -58.590434)
		(end 222.601536 -58.530236)
		(stroke
			(width 0.0508)
			(type default)
		)
		(layer "In5.Cu")
	)
	(gr_arc
		(start 222.588074 -56.563514)
		(mid 222.627489 -56.519046)
		(end 222.656146 -56.466994)
		(stroke
			(width 0.0508)
			(type default)
		)
		(layer "In5.Cu")
	)
	(gr_arc
		(start 222.588074 -52.28844)
		(mid 222.548701 -52.240496)
		(end 222.506286 -52.195222)
		(stroke
			(width 0.0508)
			(type default)
		)
		(layer "In5.Cu")
	)
	(gr_arc
		(start 222.589598 -54.572408)
		(mid 222.63642 -54.445863)
		(end 222.59925 -54.316122)
		(stroke
			(width 0.0508)
			(type default)
		)
		(layer "In5.Cu")
	)
	(gr_arc
		(start 222.59925 -54.316122)
		(mid 222.536389 -54.232324)
		(end 222.4659 -54.154832)
		(stroke
			(width 0.0508)
			(type default)
		)
		(layer "In5.Cu")
	)
	(gr_arc
		(start 222.601536 -58.530236)
		(mid 222.623443 -58.440417)
		(end 222.610426 -58.34888)
		(stroke
			(width 0.0508)
			(type default)
		)
		(layer "In5.Cu")
	)
	(gr_arc
		(start 222.606108 -46.62424)
		(mid 222.666503 -46.558147)
		(end 222.688404 -46.471332)
		(stroke
			(width 0.0508)
			(type default)
		)
		(layer "In5.Cu")
	)
	(gr_arc
		(start 222.610426 -58.34888)
		(mid 222.545225 -58.246592)
		(end 222.4659 -58.154824)
		(stroke
			(width 0.0508)
			(type default)
		)
		(layer "In5.Cu")
	)
	(gr_line
		(start 222.612712 -58.012076)
		(end 222.612966 -58.01233)
		(stroke
			(width 0.0508)
			(type default)
		)
		(layer "In5.Cu")
	)
	(gr_line
		(start 222.612712 -54.012084)
		(end 222.612966 -54.012338)
		(stroke
			(width 0.0508)
			(type default)
		)
		(layer "In5.Cu")
	)
	(gr_arc
		(start 222.612712 -49.012094)
		(mid 222.490531 -48.928446)
		(end 222.34652 -48.893984)
		(stroke
			(width 0.0508)
			(type default)
		)
		(layer "In5.Cu")
	)
	(gr_line
		(start 222.612966 -58.01233)
		(end 222.676212 -58.075322)
		(stroke
			(width 0.0508)
			(type default)
		)
		(layer "In5.Cu")
	)
	(gr_line
		(start 222.612966 -54.012338)
		(end 222.676212 -54.07533)
		(stroke
			(width 0.0508)
			(type default)
		)
		(layer "In5.Cu")
	)
	(gr_line
		(start 222.612966 -49.012348)
		(end 222.627952 -49.027334)
		(stroke
			(width 0.0508)
			(type default)
		)
		(layer "In5.Cu")
	)
	(gr_line
		(start 222.613982 -47.700438)
		(end 222.638874 -47.704756)
		(stroke
			(width 0.0508)
			(type default)
		)
		(layer "In5.Cu")
	)
	(gr_line
		(start 222.638874 -47.704756)
		(end 222.690182 -47.778162)
		(stroke
			(width 0.0508)
			(type default)
		)
		(layer "In5.Cu")
	)
	(gr_arc
		(start 222.654876 -49.466246)
		(mid 222.63236 -49.353108)
		(end 222.568262 -49.257204)
		(stroke
			(width 0.0508)
			(type default)
		)
		(layer "In5.Cu")
	)
	(gr_line
		(start 222.654876 -49.466246)
		(end 222.654876 -49.473612)
		(stroke
			(width 0.0508)
			(type default)
		)
		(layer "In5.Cu")
	)
	(gr_arc
		(start 222.655892 -52.451)
		(mid 222.632624 -52.365277)
		(end 222.588074 -52.28844)
		(stroke
			(width 0.0508)
			(type default)
		)
		(layer "In5.Cu")
	)
	(gr_arc
		(start 222.656146 -56.466994)
		(mid 222.660695 -56.451926)
		(end 222.662242 -56.43626)
		(stroke
			(width 0.0508)
			(type default)
		)
		(layer "In5.Cu")
	)
	(gr_arc
		(start 222.662242 -56.418988)
		(mid 222.649747 -56.356305)
		(end 222.614236 -56.303164)
		(stroke
			(width 0.0508)
			(type default)
		)
		(layer "In5.Cu")
	)
	(gr_line
		(start 222.662242 -56.418988)
		(end 222.662242 -56.43626)
		(stroke
			(width 0.0508)
			(type default)
		)
		(layer "In5.Cu")
	)
	(gr_arc
		(start 222.663258 -39.579804)
		(mid 222.410369 -39.337478)
		(end 222.10014 -39.500048)
		(stroke
			(width 0.0508)
			(type default)
		)
		(layer "In5.Cu")
	)
	(gr_line
		(start 222.664274 -52.063396)
		(end 222.676212 -52.075334)
		(stroke
			(width 0.0508)
			(type default)
		)
		(layer "In5.Cu")
	)
	(gr_arc
		(start 222.664274 -39.73068)
		(mid 222.670455 -39.655197)
		(end 222.663258 -39.579804)
		(stroke
			(width 0.0508)
			(type default)
		)
		(layer "In5.Cu")
	)
	(gr_arc
		(start 222.66529 -36.034726)
		(mid 222.817204 -35.925553)
		(end 222.945452 -35.789362)
		(stroke
			(width 0.0508)
			(type default)
		)
		(layer "In5.Cu")
	)
	(gr_arc
		(start 222.688404 -46.470316)
		(mid 222.682641 -46.42516)
		(end 222.661734 -46.384718)
		(stroke
			(width 0.0508)
			(type default)
		)
		(layer "In5.Cu")
	)
	(gr_line
		(start 222.688404 -46.470316)
		(end 222.688404 -46.471332)
		(stroke
			(width 0.0508)
			(type default)
		)
		(layer "In5.Cu")
	)
	(gr_line
		(start 222.690182 -47.778162)
		(end 222.690944 -47.778416)
		(stroke
			(width 0.0508)
			(type default)
		)
		(layer "In5.Cu")
	)
	(gr_line
		(start 222.690944 -47.778416)
		(end 222.708978 -47.781464)
		(stroke
			(width 0.0508)
			(type default)
		)
		(layer "In5.Cu")
	)
	(gr_arc
		(start 222.695262 -35.69081)
		(mid 222.666673 -35.503949)
		(end 222.504 -35.4076)
		(stroke
			(width 0.0508)
			(type default)
		)
		(layer "In5.Cu")
	)
	(gr_line
		(start 222.701612 -37.601652)
		(end 222.701612 -37.611812)
		(stroke
			(width 0.0508)
			(type default)
		)
		(layer "In5.Cu")
	)
	(gr_line
		(start 222.708978 -47.781464)
		(end 222.85452 -47.807118)
		(stroke
			(width 0.0508)
			(type default)
		)
		(layer "In5.Cu")
	)
	(gr_line
		(start 222.709994 -67.58051)
		(end 222.710502 -67.579748)
		(stroke
			(width 0.06985)
			(type default)
		)
		(layer "In5.Cu")
	)
	(gr_line
		(start 222.710502 -67.579748)
		(end 222.751396 -67.579748)
		(stroke
			(width 0.0508)
			(type default)
		)
		(layer "In5.Cu")
	)
	(gr_arc
		(start 222.711264 -58.1152)
		(mid 222.694388 -58.094689)
		(end 222.676212 -58.075322)
		(stroke
			(width 0.0508)
			(type default)
		)
		(layer "In5.Cu")
	)
	(gr_line
		(start 222.711264 -58.1152)
		(end 222.786956 -58.213752)
		(stroke
			(width 0.0508)
			(type default)
		)
		(layer "In5.Cu")
	)
	(gr_line
		(start 222.711264 -54.115208)
		(end 222.786956 -54.21376)
		(stroke
			(width 0.0508)
			(type default)
		)
		(layer "In5.Cu")
	)
	(gr_line
		(start 222.711264 -52.115212)
		(end 222.786956 -52.213764)
		(stroke
			(width 0.0508)
			(type default)
		)
		(layer "In5.Cu")
	)
	(gr_arc
		(start 222.72625 -40.023288)
		(mid 222.97199 -39.803671)
		(end 223.100138 -39.500048)
		(stroke
			(width 0.0508)
			(type default)
		)
		(layer "In5.Cu")
	)
	(gr_arc
		(start 222.7326 -45.526706)
		(mid 222.777933 -45.556996)
		(end 222.831406 -45.5676)
		(stroke
			(width 0.06985)
			(type default)
		)
		(layer "In5.Cu")
	)
	(gr_line
		(start 222.753936 -67.579748)
		(end 222.78086 -67.579748)
		(stroke
			(width 0.0508)
			(type default)
		)
		(layer "In5.Cu")
	)
	(gr_line
		(start 222.786956 -58.213752)
		(end 222.823278 -58.26125)
		(stroke
			(width 0.0508)
			(type default)
		)
		(layer "In5.Cu")
	)
	(gr_line
		(start 222.786956 -54.21376)
		(end 222.849694 -54.295294)
		(stroke
			(width 0.0508)
			(type default)
		)
		(layer "In5.Cu")
	)
	(gr_line
		(start 222.786956 -52.213764)
		(end 222.82277 -52.260246)
		(stroke
			(width 0.0508)
			(type default)
		)
		(layer "In5.Cu")
	)
	(gr_arc
		(start 222.799656 -65.94856)
		(mid 222.709764 -65.96648)
		(end 222.63354 -66.017394)
		(stroke
			(width 0.06985)
			(type default)
		)
		(layer "In5.Cu")
	)
	(gr_line
		(start 222.799656 -65.94856)
		(end 222.859092 -65.94856)
		(stroke
			(width 0.06985)
			(type default)
		)
		(layer "In5.Cu")
	)
	(gr_line
		(start 222.82277 -52.260246)
		(end 222.849694 -52.295298)
		(stroke
			(width 0.0508)
			(type default)
		)
		(layer "In5.Cu")
	)
	(gr_line
		(start 222.823278 -58.26125)
		(end 222.849694 -58.295286)
		(stroke
			(width 0.0508)
			(type default)
		)
		(layer "In5.Cu")
	)
	(gr_arc
		(start 222.827088 -29.89834)
		(mid 223.068601 -29.771127)
		(end 223.100138 -29.500068)
		(stroke
			(width 0.0508)
			(type default)
		)
		(layer "In5.Cu")
	)
	(gr_arc
		(start 222.828104 -37.47516)
		(mid 222.738641 -37.512204)
		(end 222.701612 -37.601652)
		(stroke
			(width 0.0508)
			(type default)
		)
		(layer "In5.Cu")
	)
	(gr_line
		(start 222.828104 -37.47516)
		(end 223.075246 -37.47516)
		(stroke
			(width 0.0508)
			(type default)
		)
		(layer "In5.Cu")
	)
	(gr_line
		(start 222.841566 -46.284896)
		(end 222.950532 -46.426374)
		(stroke
			(width 0.0508)
			(type default)
		)
		(layer "In5.Cu")
	)
	(gr_line
		(start 222.849694 -58.295286)
		(end 222.856298 -58.303668)
		(stroke
			(width 0.0508)
			(type default)
		)
		(layer "In5.Cu")
	)
	(gr_line
		(start 222.849694 -54.295294)
		(end 222.856298 -54.303676)
		(stroke
			(width 0.0508)
			(type default)
		)
		(layer "In5.Cu")
	)
	(gr_line
		(start 222.849694 -52.295298)
		(end 222.850964 -52.297076)
		(stroke
			(width 0.0508)
			(type default)
		)
		(layer "In5.Cu")
	)
	(gr_line
		(start 222.850964 -52.297076)
		(end 222.856298 -52.30368)
		(stroke
			(width 0.0508)
			(type default)
		)
		(layer "In5.Cu")
	)
	(gr_line
		(start 222.855282 -24.890222)
		(end 222.87357 -24.88692)
		(stroke
			(width 0.06985)
			(type default)
		)
		(layer "In5.Cu")
	)
	(gr_line
		(start 222.856298 -58.303668)
		(end 222.894906 -58.35396)
		(stroke
			(width 0.0508)
			(type default)
		)
		(layer "In5.Cu")
	)
	(gr_line
		(start 222.856298 -54.303676)
		(end 222.894906 -54.353968)
		(stroke
			(width 0.0508)
			(type default)
		)
		(layer "In5.Cu")
	)
	(gr_line
		(start 222.856298 -52.30368)
		(end 222.894906 -52.353972)
		(stroke
			(width 0.0508)
			(type default)
		)
		(layer "In5.Cu")
	)
	(gr_line
		(start 222.858584 -49.257712)
		(end 223.100138 -49.499266)
		(stroke
			(width 0.0508)
			(type default)
		)
		(layer "In5.Cu")
	)
	(gr_line
		(start 222.87357 -24.88692)
		(end 222.892874 -24.890222)
		(stroke
			(width 0.06985)
			(type default)
		)
		(layer "In5.Cu")
	)
	(gr_line
		(start 222.894906 -58.35396)
		(end 222.900748 -58.36158)
		(stroke
			(width 0.0508)
			(type default)
		)
		(layer "In5.Cu")
	)
	(gr_line
		(start 222.894906 -54.353968)
		(end 222.900748 -54.361588)
		(stroke
			(width 0.0508)
			(type default)
		)
		(layer "In5.Cu")
	)
	(gr_line
		(start 222.894906 -52.353972)
		(end 222.900748 -52.361592)
		(stroke
			(width 0.0508)
			(type default)
		)
		(layer "In5.Cu")
	)
	(gr_line
		(start 222.900748 -58.36158)
		(end 222.950532 -58.426096)
		(stroke
			(width 0.0508)
			(type default)
		)
		(layer "In5.Cu")
	)
	(gr_line
		(start 222.900748 -54.361588)
		(end 222.950532 -54.426104)
		(stroke
			(width 0.0508)
			(type default)
		)
		(layer "In5.Cu")
	)
	(gr_line
		(start 222.900748 -52.361592)
		(end 222.950532 -52.426108)
		(stroke
			(width 0.0508)
			(type default)
		)
		(layer "In5.Cu")
	)
	(gr_line
		(start 222.903542 -56.304942)
		(end 223.099122 -56.500522)
		(stroke
			(width 0.0508)
			(type default)
		)
		(layer "In5.Cu")
	)
	(gr_arc
		(start 222.945452 -35.789362)
		(mid 223.035048 -35.651261)
		(end 223.100138 -35.500056)
		(stroke
			(width 0.0508)
			(type default)
		)
		(layer "In5.Cu")
	)
	(gr_arc
		(start 222.950532 -58.426096)
		(mid 223.016757 -58.480353)
		(end 223.100138 -58.499756)
		(stroke
			(width 0.0508)
			(type default)
		)
		(layer "In5.Cu")
	)
	(gr_arc
		(start 222.950532 -54.426104)
		(mid 223.016756 -54.480371)
		(end 223.100138 -54.499764)
		(stroke
			(width 0.0508)
			(type default)
		)
		(layer "In5.Cu")
	)
	(gr_arc
		(start 222.950532 -52.426108)
		(mid 223.016756 -52.480374)
		(end 223.100138 -52.499768)
		(stroke
			(width 0.0508)
			(type default)
		)
		(layer "In5.Cu")
	)
	(gr_arc
		(start 222.950532 -46.426374)
		(mid 223.016762 -46.480621)
		(end 223.100138 -46.500034)
		(stroke
			(width 0.0508)
			(type default)
		)
		(layer "In5.Cu")
	)
	(gr_line
		(start 222.957136 -67.785488)
		(end 222.957136 -67.803268)
		(stroke
			(width 0.0508)
			(type default)
		)
		(layer "In5.Cu")
	)
	(gr_line
		(start 222.957136 -67.691)
		(end 222.957136 -67.782948)
		(stroke
			(width 0.0508)
			(type default)
		)
		(layer "In5.Cu")
	)
	(gr_line
		(start 223.075246 -37.47516)
		(end 223.100138 -37.500052)
		(stroke
			(width 0.0508)
			(type default)
		)
		(layer "In5.Cu")
	)
	(gr_arc
		(start 223.09455 -66.046096)
		(mid 222.986524 -65.973904)
		(end 222.859092 -65.94856)
		(stroke
			(width 0.06985)
			(type default)
		)
		(layer "In5.Cu")
	)
	(gr_line
		(start 223.09455 -66.046096)
		(end 223.125284 -66.076576)
		(stroke
			(width 0.06985)
			(type default)
		)
		(layer "In5.Cu")
	)
	(gr_line
		(start 223.099122 -56.500522)
		(end 223.099376 -56.500522)
		(stroke
			(width 0.0508)
			(type default)
		)
		(layer "In5.Cu")
	)
	(gr_line
		(start 223.099376 -56.500522)
		(end 223.100138 -56.49976)
		(stroke
			(width 0.0508)
			(type default)
		)
		(layer "In5.Cu")
	)
	(gr_line
		(start 223.100138 -66.49974)
		(end 223.151192 -66.44894)
		(stroke
			(width 0.06985)
			(type default)
		)
		(layer "In5.Cu")
	)
	(gr_arc
		(start 223.100138 -65.499742)
		(mid 222.715783 -65.576155)
		(end 222.389954 -65.793874)
		(stroke
			(width 0.06985)
			(type default)
		)
		(layer "In5.Cu")
	)
	(gr_line
		(start 223.100138 -59.499754)
		(end 223.153224 -59.55284)
		(stroke
			(width 0.0508)
			(type default)
		)
		(layer "In5.Cu")
	)
	(gr_line
		(start 223.100138 -57.499758)
		(end 223.153224 -57.552844)
		(stroke
			(width 0.0508)
			(type default)
		)
		(layer "In5.Cu")
	)
	(gr_line
		(start 223.100138 -55.499762)
		(end 223.153224 -55.552848)
		(stroke
			(width 0.0508)
			(type default)
		)
		(layer "In5.Cu")
	)
	(gr_arc
		(start 223.100138 -53.499766)
		(mid 223.181843 -53.607324)
		(end 223.298258 -53.675788)
		(stroke
			(width 0.0508)
			(type default)
		)
		(layer "In5.Cu")
	)
	(gr_line
		(start 223.100138 -50.499772)
		(end 223.153224 -50.552858)
		(stroke
			(width 0.0508)
			(type default)
		)
		(layer "In5.Cu")
	)
	(gr_line
		(start 223.100138 -49.499266)
		(end 223.100138 -49.499774)
		(stroke
			(width 0.0508)
			(type default)
		)
		(layer "In5.Cu")
	)
	(gr_line
		(start 223.100138 -48.50003)
		(end 223.27108 -48.670972)
		(stroke
			(width 0.0508)
			(type default)
		)
		(layer "In5.Cu")
	)
	(gr_line
		(start 223.100138 -48.499776)
		(end 223.100138 -48.50003)
		(stroke
			(width 0.0508)
			(type default)
		)
		(layer "In5.Cu")
	)
	(gr_line
		(start 223.100138 -40.500046)
		(end 223.39681 -40.500046)
		(stroke
			(width 0.0508)
			(type default)
		)
		(layer "In5.Cu")
	)
	(gr_line
		(start 223.100138 -38.50005)
		(end 223.38665 -38.50005)
		(stroke
			(width 0.0508)
			(type default)
		)
		(layer "In5.Cu")
	)
	(gr_line
		(start 223.100138 -36.481004)
		(end 223.100138 -36.500054)
		(stroke
			(width 0.0508)
			(type default)
		)
		(layer "In5.Cu")
	)
	(gr_line
		(start 223.100138 -34.385758)
		(end 223.100138 -34.500058)
		(stroke
			(width 0.0508)
			(type default)
		)
		(layer "In5.Cu")
	)
	(gr_arc
		(start 223.100138 -33.50006)
		(mid 222.937133 -33.646003)
		(end 222.814896 -33.827466)
		(stroke
			(width 0.0508)
			(type default)
		)
		(layer "In5.Cu")
	)
	(gr_arc
		(start 223.100138 -30.20314)
		(mid 223.070397 -30.131259)
		(end 222.998538 -30.10154)
		(stroke
			(width 0.0508)
			(type default)
		)
		(layer "In5.Cu")
	)
	(gr_line
		(start 223.100138 -30.20314)
		(end 223.100138 -30.500066)
		(stroke
			(width 0.0508)
			(type default)
		)
		(layer "In5.Cu")
	)
	(gr_line
		(start 223.142556 -23.84425)
		(end 223.161352 -23.840948)
		(stroke
			(width 0.06985)
			(type default)
		)
		(layer "In5.Cu")
	)
	(gr_arc
		(start 223.151192 -66.44894)
		(mid 223.198603 -66.377838)
		(end 223.2152 -66.294)
		(stroke
			(width 0.06985)
			(type default)
		)
		(layer "In5.Cu")
	)
	(gr_arc
		(start 223.153224 -59.55284)
		(mid 223.206945 -59.598191)
		(end 223.267524 -59.633866)
		(stroke
			(width 0.0508)
			(type default)
		)
		(layer "In5.Cu")
	)
	(gr_arc
		(start 223.153224 -57.552844)
		(mid 223.206945 -57.598195)
		(end 223.267524 -57.63387)
		(stroke
			(width 0.0508)
			(type default)
		)
		(layer "In5.Cu")
	)
	(gr_arc
		(start 223.153224 -55.552848)
		(mid 223.206937 -55.598212)
		(end 223.267524 -55.633874)
		(stroke
			(width 0.0508)
			(type default)
		)
		(layer "In5.Cu")
	)
	(gr_arc
		(start 223.153224 -50.552858)
		(mid 223.206937 -50.598222)
		(end 223.267524 -50.633884)
		(stroke
			(width 0.0508)
			(type default)
		)
		(layer "In5.Cu")
	)
	(gr_arc
		(start 223.154494 -45.608494)
		(mid 223.109155 -45.578217)
		(end 223.055688 -45.5676)
		(stroke
			(width 0.06985)
			(type default)
		)
		(layer "In5.Cu")
	)
	(gr_line
		(start 223.161352 -23.840948)
		(end 223.180148 -23.84425)
		(stroke
			(width 0.06985)
			(type default)
		)
		(layer "In5.Cu")
	)
	(gr_arc
		(start 223.214438 -34.271458)
		(mid 223.133616 -34.304936)
		(end 223.100138 -34.385758)
		(stroke
			(width 0.0508)
			(type default)
		)
		(layer "In5.Cu")
	)
	(gr_line
		(start 223.214438 -34.271458)
		(end 223.459802 -34.271458)
		(stroke
			(width 0.0508)
			(type default)
		)
		(layer "In5.Cu")
	)
	(gr_arc
		(start 223.2152 -66.294)
		(mid 223.191847 -66.176356)
		(end 223.125284 -66.076576)
		(stroke
			(width 0.06985)
			(type default)
		)
		(layer "In5.Cu")
	)
	(gr_line
		(start 223.267524 -59.633866)
		(end 223.29648 -59.647836)
		(stroke
			(width 0.0508)
			(type default)
		)
		(layer "In5.Cu")
	)
	(gr_line
		(start 223.267524 -57.63387)
		(end 223.29648 -57.64784)
		(stroke
			(width 0.0508)
			(type default)
		)
		(layer "In5.Cu")
	)
	(gr_line
		(start 223.267524 -55.633874)
		(end 223.29648 -55.647844)
		(stroke
			(width 0.0508)
			(type default)
		)
		(layer "In5.Cu")
	)
	(gr_arc
		(start 223.267524 -50.633884)
		(mid 223.297021 -50.646147)
		(end 223.327722 -50.654966)
		(stroke
			(width 0.0508)
			(type default)
		)
		(layer "In5.Cu")
	)
	(gr_arc
		(start 223.27108 -48.670972)
		(mid 223.500916 -48.713615)
		(end 223.62287 -48.514254)
		(stroke
			(width 0.0508)
			(type default)
		)
		(layer "In5.Cu")
	)
	(gr_arc
		(start 223.28759 -45.274484)
		(mid 223.246439 -45.247051)
		(end 223.197928 -45.2374)
		(stroke
			(width 0.06985)
			(type default)
		)
		(layer "In5.Cu")
	)
	(gr_arc
		(start 223.29648 -59.647836)
		(mid 223.332621 -59.660395)
		(end 223.370648 -59.6646)
		(stroke
			(width 0.0508)
			(type default)
		)
		(layer "In5.Cu")
	)
	(gr_arc
		(start 223.29648 -57.64784)
		(mid 223.332621 -57.660399)
		(end 223.370648 -57.664604)
		(stroke
			(width 0.0508)
			(type default)
		)
		(layer "In5.Cu")
	)
	(gr_arc
		(start 223.29648 -55.647844)
		(mid 223.332624 -55.660384)
		(end 223.370648 -55.664608)
		(stroke
			(width 0.0508)
			(type default)
		)
		(layer "In5.Cu")
	)
	(gr_arc
		(start 223.298258 -53.675788)
		(mid 223.35533 -53.690609)
		(end 223.414082 -53.6956)
		(stroke
			(width 0.0508)
			(type default)
		)
		(layer "In5.Cu")
	)
	(gr_line
		(start 223.327722 -50.654966)
		(end 223.345502 -50.65903)
		(stroke
			(width 0.0508)
			(type default)
		)
		(layer "In5.Cu")
	)
	(gr_arc
		(start 223.345502 -50.65903)
		(mid 223.363435 -50.661736)
		(end 223.38157 -50.661824)
		(stroke
			(width 0.0508)
			(type default)
		)
		(layer "In5.Cu")
	)
	(gr_line
		(start 223.370648 -59.6646)
		(end 223.444308 -59.6646)
		(stroke
			(width 0.0508)
			(type default)
		)
		(layer "In5.Cu")
	)
	(gr_line
		(start 223.370648 -57.664604)
		(end 223.437958 -57.664604)
		(stroke
			(width 0.0508)
			(type default)
		)
		(layer "In5.Cu")
	)
	(gr_line
		(start 223.370648 -55.664608)
		(end 223.437958 -55.664608)
		(stroke
			(width 0.0508)
			(type default)
		)
		(layer "In5.Cu")
	)
	(gr_line
		(start 223.38157 -50.661824)
		(end 223.410526 -50.660046)
		(stroke
			(width 0.0508)
			(type default)
		)
		(layer "In5.Cu")
	)
	(gr_arc
		(start 223.38792 -36.193222)
		(mid 223.184427 -36.277511)
		(end 223.100138 -36.481004)
		(stroke
			(width 0.0508)
			(type default)
		)
		(layer "In5.Cu")
	)
	(gr_line
		(start 223.38792 -36.193222)
		(end 223.388174 -36.193222)
		(stroke
			(width 0.0508)
			(type default)
		)
		(layer "In5.Cu")
	)
	(gr_arc
		(start 223.410526 -50.660046)
		(mid 223.438996 -50.655674)
		(end 223.466152 -50.646076)
		(stroke
			(width 0.0508)
			(type default)
		)
		(layer "In5.Cu")
	)
	(gr_arc
		(start 223.414082 -53.6956)
		(mid 223.47019 -53.683995)
		(end 223.516952 -53.650896)
		(stroke
			(width 0.0508)
			(type default)
		)
		(layer "In5.Cu")
	)
	(gr_line
		(start 223.432878 -28.9814)
		(end 223.458786 -29.007308)
		(stroke
			(width 0.0508)
			(type default)
		)
		(layer "In5.Cu")
	)
	(gr_arc
		(start 223.437958 -57.664604)
		(mid 223.510966 -57.647563)
		(end 223.568768 -57.599834)
		(stroke
			(width 0.0508)
			(type default)
		)
		(layer "In5.Cu")
	)
	(gr_arc
		(start 223.437958 -55.664608)
		(mid 223.510978 -55.647591)
		(end 223.568768 -55.599838)
		(stroke
			(width 0.0508)
			(type default)
		)
		(layer "In5.Cu")
	)
	(gr_arc
		(start 223.442276 -37.10178)
		(mid 223.610683 -37.068375)
		(end 223.753426 -36.973002)
		(stroke
			(width 0.0508)
			(type default)
		)
		(layer "In5.Cu")
	)
	(gr_line
		(start 223.44253 -87.746586)
		(end 223.459802 -87.721694)
		(stroke
			(width 0.06985)
			(type default)
		)
		(layer "In5.Cu")
	)
	(gr_arc
		(start 223.444308 -59.6646)
		(mid 223.518949 -59.644763)
		(end 223.573848 -59.590432)
		(stroke
			(width 0.0508)
			(type default)
		)
		(layer "In5.Cu")
	)
	(gr_line
		(start 223.459802 -87.721694)
		(end 223.465644 -87.692484)
		(stroke
			(width 0.06985)
			(type default)
		)
		(layer "In5.Cu")
	)
	(gr_arc
		(start 223.465898 -59.154822)
		(mid 223.401449 -59.111774)
		(end 223.325436 -59.096656)
		(stroke
			(width 0.0508)
			(type default)
		)
		(layer "In5.Cu")
	)
	(gr_line
		(start 223.465898 -59.154822)
		(end 223.550226 -59.23915)
		(stroke
			(width 0.0508)
			(type default)
		)
		(layer "In5.Cu")
	)
	(gr_line
		(start 223.466152 -50.646076)
		(end 223.48698 -50.636424)
		(stroke
			(width 0.0508)
			(type default)
		)
		(layer "In5.Cu")
	)
	(gr_line
		(start 223.472502 -53.162962)
		(end 223.563434 -53.27269)
		(stroke
			(width 0.0508)
			(type default)
		)
		(layer "In5.Cu")
	)
	(gr_arc
		(start 223.48698 -50.636424)
		(mid 223.529037 -50.608988)
		(end 223.561148 -50.570384)
		(stroke
			(width 0.0508)
			(type default)
		)
		(layer "In5.Cu")
	)
	(gr_arc
		(start 223.49714 -48.186086)
		(mid 223.418152 -48.128203)
		(end 223.325436 -48.096678)
		(stroke
			(width 0.0508)
			(type default)
		)
		(layer "In5.Cu")
	)
	(gr_arc
		(start 223.49841 -40.601646)
		(mid 223.468669 -40.529771)
		(end 223.39681 -40.500046)
		(stroke
			(width 0.0508)
			(type default)
		)
		(layer "In5.Cu")
	)
	(gr_line
		(start 223.49841 -40.601646)
		(end 223.49841 -40.703246)
		(stroke
			(width 0.0508)
			(type default)
		)
		(layer "In5.Cu")
	)
	(gr_arc
		(start 223.49841 -38.61181)
		(mid 223.465683 -38.53276)
		(end 223.38665 -38.50005)
		(stroke
			(width 0.0508)
			(type default)
		)
		(layer "In5.Cu")
	)
	(gr_arc
		(start 223.502728 -29.11348)
		(mid 223.491301 -29.056034)
		(end 223.458786 -29.007308)
		(stroke
			(width 0.0508)
			(type default)
		)
		(layer "In5.Cu")
	)
	(gr_line
		(start 223.502728 -29.11348)
		(end 223.502728 -29.2481)
		(stroke
			(width 0.0508)
			(type default)
		)
		(layer "In5.Cu")
	)
	(gr_line
		(start 223.505014 -26.1874)
		(end 223.556576 -26.223468)
		(stroke
			(width 0.06985)
			(type default)
		)
		(layer "In5.Cu")
	)
	(gr_line
		(start 223.516952 -53.650896)
		(end 223.55175 -53.613304)
		(stroke
			(width 0.0508)
			(type default)
		)
		(layer "In5.Cu")
	)
	(gr_arc
		(start 223.55175 -53.613304)
		(mid 223.601766 -53.535231)
		(end 223.6216 -53.444648)
		(stroke
			(width 0.0508)
			(type default)
		)
		(layer "In5.Cu")
	)
	(gr_arc
		(start 223.55429 -58.953146)
		(mid 223.487971 -58.908902)
		(end 223.409764 -58.893456)
		(stroke
			(width 0.0508)
			(type default)
		)
		(layer "In5.Cu")
	)
	(gr_line
		(start 223.55429 -58.953146)
		(end 223.598994 -58.99785)
		(stroke
			(width 0.0508)
			(type default)
		)
		(layer "In5.Cu")
	)
	(gr_line
		(start 223.568768 -57.599834)
		(end 223.589596 -57.572402)
		(stroke
			(width 0.0508)
			(type default)
		)
		(layer "In5.Cu")
	)
	(gr_line
		(start 223.568768 -55.599838)
		(end 223.589596 -55.572406)
		(stroke
			(width 0.0508)
			(type default)
		)
		(layer "In5.Cu")
	)
	(gr_line
		(start 223.573848 -59.590432)
		(end 223.601534 -59.530234)
		(stroke
			(width 0.0508)
			(type default)
		)
		(layer "In5.Cu")
	)
	(gr_arc
		(start 223.574356 -34.318956)
		(mid 223.521812 -34.283784)
		(end 223.459802 -34.271458)
		(stroke
			(width 0.0508)
			(type default)
		)
		(layer "In5.Cu")
	)
	(gr_arc
		(start 223.578166 -64.91478)
		(mid 223.515691 -65.008366)
		(end 223.493838 -65.118742)
		(stroke
			(width 0.0508)
			(type default)
		)
		(layer "In5.Cu")
	)
	(gr_line
		(start 223.578166 -64.91478)
		(end 223.73082 -64.761872)
		(stroke
			(width 0.0508)
			(type default)
		)
		(layer "In5.Cu")
	)
	(gr_arc
		(start 223.589596 -57.572402)
		(mid 223.636515 -57.445843)
		(end 223.599248 -57.316116)
		(stroke
			(width 0.0508)
			(type default)
		)
		(layer "In5.Cu")
	)
	(gr_arc
		(start 223.589596 -55.572406)
		(mid 223.636418 -55.445861)
		(end 223.599248 -55.31612)
		(stroke
			(width 0.0508)
			(type default)
		)
		(layer "In5.Cu")
	)
	(gr_arc
		(start 223.599248 -57.316116)
		(mid 223.536392 -57.232313)
		(end 223.465898 -57.154826)
		(stroke
			(width 0.0508)
			(type default)
		)
		(layer "In5.Cu")
	)
	(gr_arc
		(start 223.599248 -55.31612)
		(mid 223.536387 -55.232322)
		(end 223.465898 -55.15483)
		(stroke
			(width 0.0508)
			(type default)
		)
		(layer "In5.Cu")
	)
	(gr_arc
		(start 223.601534 -59.530234)
		(mid 223.62344 -59.440415)
		(end 223.610424 -59.348878)
		(stroke
			(width 0.0508)
			(type default)
		)
		(layer "In5.Cu")
	)
	(gr_line
		(start 223.604582 -59.33186)
		(end 223.610424 -59.348878)
		(stroke
			(width 0.0508)
			(type default)
		)
		(layer "In5.Cu")
	)
	(gr_line
		(start 223.61271 -57.012078)
		(end 223.612964 -57.012332)
		(stroke
			(width 0.0508)
			(type default)
		)
		(layer "In5.Cu")
	)
	(gr_line
		(start 223.61271 -55.012082)
		(end 223.612964 -55.012336)
		(stroke
			(width 0.0508)
			(type default)
		)
		(layer "In5.Cu")
	)
	(gr_arc
		(start 223.61271 -48.012096)
		(mid 223.490529 -47.928448)
		(end 223.346518 -47.893986)
		(stroke
			(width 0.0508)
			(type default)
		)
		(layer "In5.Cu")
	)
	(gr_line
		(start 223.612964 -57.012332)
		(end 223.67621 -57.075324)
		(stroke
			(width 0.0508)
			(type default)
		)
		(layer "In5.Cu")
	)
	(gr_line
		(start 223.612964 -55.012336)
		(end 223.67621 -55.075328)
		(stroke
			(width 0.0508)
			(type default)
		)
		(layer "In5.Cu")
	)
	(gr_arc
		(start 223.616774 -48.397922)
		(mid 223.595093 -48.307866)
		(end 223.542606 -48.231552)
		(stroke
			(width 0.0508)
			(type default)
		)
		(layer "In5.Cu")
	)
	(gr_line
		(start 223.616774 -48.397922)
		(end 223.62287 -48.514254)
		(stroke
			(width 0.0508)
			(type default)
		)
		(layer "In5.Cu")
	)
	(gr_arc
		(start 223.6216 -53.444648)
		(mid 223.608355 -53.353306)
		(end 223.563434 -53.27269)
		(stroke
			(width 0.0508)
			(type default)
		)
		(layer "In5.Cu")
	)
	(gr_arc
		(start 223.6216 -34.433002)
		(mid 223.609323 -34.371279)
		(end 223.574356 -34.318956)
		(stroke
			(width 0.0508)
			(type default)
		)
		(layer "In5.Cu")
	)
	(gr_line
		(start 223.6216 -34.433002)
		(end 223.6216 -34.699448)
		(stroke
			(width 0.0508)
			(type default)
		)
		(layer "In5.Cu")
	)
	(gr_line
		(start 223.624648 -53.024024)
		(end 223.67621 -53.075332)
		(stroke
			(width 0.0508)
			(type default)
		)
		(layer "In5.Cu")
	)
	(gr_arc
		(start 223.675956 -36.481004)
		(mid 223.591667 -36.277511)
		(end 223.388174 -36.193222)
		(stroke
			(width 0.0508)
			(type default)
		)
		(layer "In5.Cu")
	)
	(gr_line
		(start 223.675956 -36.481004)
		(end 223.675956 -36.6649)
		(stroke
			(width 0.0508)
			(type default)
		)
		(layer "In5.Cu")
	)
	(gr_line
		(start 223.683322 -48.081438)
		(end 223.724978 -48.12157)
		(stroke
			(width 0.0508)
			(type default)
		)
		(layer "In5.Cu")
	)
	(gr_line
		(start 223.711262 -59.115198)
		(end 223.711516 -59.114944)
		(stroke
			(width 0.0508)
			(type default)
		)
		(layer "In5.Cu")
	)
	(gr_arc
		(start 223.711262 -57.115202)
		(mid 223.694386 -57.094691)
		(end 223.67621 -57.075324)
		(stroke
			(width 0.0508)
			(type default)
		)
		(layer "In5.Cu")
	)
	(gr_line
		(start 223.711262 -57.115202)
		(end 223.786954 -57.213754)
		(stroke
			(width 0.0508)
			(type default)
		)
		(layer "In5.Cu")
	)
	(gr_line
		(start 223.711262 -55.115206)
		(end 223.786954 -55.213758)
		(stroke
			(width 0.0508)
			(type default)
		)
		(layer "In5.Cu")
	)
	(gr_line
		(start 223.711262 -53.11521)
		(end 223.766634 -53.187346)
		(stroke
			(width 0.0508)
			(type default)
		)
		(layer "In5.Cu")
	)
	(gr_line
		(start 223.724978 -48.12157)
		(end 223.736408 -48.133)
		(stroke
			(width 0.0508)
			(type default)
		)
		(layer "In5.Cu")
	)
	(gr_line
		(start 223.73082 -64.761872)
		(end 223.918018 -64.575182)
		(stroke
			(width 0.0508)
			(type default)
		)
		(layer "In5.Cu")
	)
	(gr_line
		(start 223.73082 -50.140616)
		(end 223.95053 -50.426112)
		(stroke
			(width 0.0508)
			(type default)
		)
		(layer "In5.Cu")
	)
	(gr_line
		(start 223.734122 -22.784562)
		(end 223.752918 -22.78126)
		(stroke
			(width 0.06985)
			(type default)
		)
		(layer "In5.Cu")
	)
	(gr_arc
		(start 223.7486 -65.0494)
		(mid 223.710452 -65.106503)
		(end 223.697038 -65.17386)
		(stroke
			(width 0.0508)
			(type default)
		)
		(layer "In5.Cu")
	)
	(gr_line
		(start 223.752918 -22.78126)
		(end 223.771714 -22.784562)
		(stroke
			(width 0.06985)
			(type default)
		)
		(layer "In5.Cu")
	)
	(gr_line
		(start 223.753426 -36.973002)
		(end 223.784414 -36.942268)
		(stroke
			(width 0.0508)
			(type default)
		)
		(layer "In5.Cu")
	)
	(gr_arc
		(start 223.756728 -48.157892)
		(mid 223.74718 -48.144947)
		(end 223.736408 -48.133)
		(stroke
			(width 0.0508)
			(type default)
		)
		(layer "In5.Cu")
	)
	(gr_line
		(start 223.756728 -48.157892)
		(end 223.766634 -48.172624)
		(stroke
			(width 0.0508)
			(type default)
		)
		(layer "In5.Cu")
	)
	(gr_arc
		(start 223.759014 -28.985718)
		(mid 223.719769 -29.044324)
		(end 223.705928 -29.11348)
		(stroke
			(width 0.0508)
			(type default)
		)
		(layer "In5.Cu")
	)
	(gr_line
		(start 223.759014 -28.985718)
		(end 223.763078 -28.9814)
		(stroke
			(width 0.0508)
			(type default)
		)
		(layer "In5.Cu")
	)
	(gr_line
		(start 223.763078 -28.84678)
		(end 223.763078 -28.9814)
		(stroke
			(width 0.06985)
			(type default)
		)
		(layer "In5.Cu")
	)
	(gr_line
		(start 223.766634 -53.187346)
		(end 223.786954 -53.213762)
		(stroke
			(width 0.0508)
			(type default)
		)
		(layer "In5.Cu")
	)
	(gr_arc
		(start 223.784414 -36.942268)
		(mid 223.960601 -36.734244)
		(end 224.100136 -36.500054)
		(stroke
			(width 0.0508)
			(type default)
		)
		(layer "In5.Cu")
	)
	(gr_line
		(start 223.786954 -57.213754)
		(end 223.849692 -57.295288)
		(stroke
			(width 0.0508)
			(type default)
		)
		(layer "In5.Cu")
	)
	(gr_line
		(start 223.786954 -55.213758)
		(end 223.849692 -55.295292)
		(stroke
			(width 0.0508)
			(type default)
		)
		(layer "In5.Cu")
	)
	(gr_line
		(start 223.786954 -53.213762)
		(end 223.828356 -53.26761)
		(stroke
			(width 0.0508)
			(type default)
		)
		(layer "In5.Cu")
	)
	(gr_line
		(start 223.794828 -59.252104)
		(end 223.835722 -59.333384)
		(stroke
			(width 0.0508)
			(type default)
		)
		(layer "In5.Cu")
	)
	(gr_arc
		(start 223.798384 -48.232568)
		(mid 223.783963 -48.201826)
		(end 223.766634 -48.172624)
		(stroke
			(width 0.0508)
			(type default)
		)
		(layer "In5.Cu")
	)
	(gr_line
		(start 223.798384 -48.232568)
		(end 223.810322 -48.26127)
		(stroke
			(width 0.0508)
			(type default)
		)
		(layer "In5.Cu")
	)
	(gr_arc
		(start 223.810322 -48.26127)
		(mid 223.85686 -48.348209)
		(end 223.919542 -48.424338)
		(stroke
			(width 0.0508)
			(type default)
		)
		(layer "In5.Cu")
	)
	(gr_arc
		(start 223.82734 -38.47592)
		(mid 223.738427 -38.512734)
		(end 223.70161 -38.60165)
		(stroke
			(width 0.0508)
			(type default)
		)
		(layer "In5.Cu")
	)
	(gr_line
		(start 223.82734 -38.47592)
		(end 224.076006 -38.47592)
		(stroke
			(width 0.0508)
			(type default)
		)
		(layer "In5.Cu")
	)
	(gr_line
		(start 223.828356 -53.26761)
		(end 223.849692 -53.295296)
		(stroke
			(width 0.0508)
			(type default)
		)
		(layer "In5.Cu")
	)
	(gr_line
		(start 223.835722 -59.333384)
		(end 223.838262 -59.338464)
		(stroke
			(width 0.0508)
			(type default)
		)
		(layer "In5.Cu")
	)
	(gr_arc
		(start 223.838262 -59.338464)
		(mid 223.848297 -59.356748)
		(end 223.859598 -59.374278)
		(stroke
			(width 0.0508)
			(type default)
		)
		(layer "In5.Cu")
	)
	(gr_line
		(start 223.845374 -25.058116)
		(end 223.91116 -25.0698)
		(stroke
			(width 0.06985)
			(type default)
		)
		(layer "In5.Cu")
	)
	(gr_line
		(start 223.849692 -57.295288)
		(end 223.856296 -57.30367)
		(stroke
			(width 0.0508)
			(type default)
		)
		(layer "In5.Cu")
	)
	(gr_line
		(start 223.849692 -55.295292)
		(end 223.856296 -55.303674)
		(stroke
			(width 0.0508)
			(type default)
		)
		(layer "In5.Cu")
	)
	(gr_line
		(start 223.849692 -53.295296)
		(end 223.856296 -53.303678)
		(stroke
			(width 0.0508)
			(type default)
		)
		(layer "In5.Cu")
	)
	(gr_line
		(start 223.851978 -30.788356)
		(end 223.960944 -30.788356)
		(stroke
			(width 0.0508)
			(type default)
		)
		(layer "In5.Cu")
	)
	(gr_line
		(start 223.856296 -57.30367)
		(end 223.894904 -57.353962)
		(stroke
			(width 0.0508)
			(type default)
		)
		(layer "In5.Cu")
	)
	(gr_line
		(start 223.856296 -55.303674)
		(end 223.894904 -55.353966)
		(stroke
			(width 0.0508)
			(type default)
		)
		(layer "In5.Cu")
	)
	(gr_line
		(start 223.856296 -53.303678)
		(end 223.894904 -53.35397)
		(stroke
			(width 0.0508)
			(type default)
		)
		(layer "In5.Cu")
	)
	(gr_arc
		(start 223.859598 -59.374278)
		(mid 223.964469 -59.466554)
		(end 224.100136 -59.499754)
		(stroke
			(width 0.0508)
			(type default)
		)
		(layer "In5.Cu")
	)
	(gr_arc
		(start 223.871282 -64.9986)
		(mid 223.804881 -65.011784)
		(end 223.7486 -65.0494)
		(stroke
			(width 0.0508)
			(type default)
		)
		(layer "In5.Cu")
	)
	(gr_line
		(start 223.871282 -64.9986)
		(end 223.967294 -64.9986)
		(stroke
			(width 0.0508)
			(type default)
		)
		(layer "In5.Cu")
	)
	(gr_line
		(start 223.894904 -57.353962)
		(end 223.900746 -57.361582)
		(stroke
			(width 0.0508)
			(type default)
		)
		(layer "In5.Cu")
	)
	(gr_line
		(start 223.894904 -55.353966)
		(end 223.900746 -55.361586)
		(stroke
			(width 0.0508)
			(type default)
		)
		(layer "In5.Cu")
	)
	(gr_line
		(start 223.894904 -53.35397)
		(end 223.900746 -53.36159)
		(stroke
			(width 0.0508)
			(type default)
		)
		(layer "In5.Cu")
	)
	(gr_arc
		(start 223.899222 -34.700972)
		(mid 223.838141 -34.774886)
		(end 223.792034 -34.85896)
		(stroke
			(width 0.0508)
			(type default)
		)
		(layer "In5.Cu")
	)
	(gr_line
		(start 223.899222 -34.700972)
		(end 224.100136 -34.500058)
		(stroke
			(width 0.0508)
			(type default)
		)
		(layer "In5.Cu")
	)
	(gr_line
		(start 223.900746 -57.361582)
		(end 223.95053 -57.426098)
		(stroke
			(width 0.0508)
			(type default)
		)
		(layer "In5.Cu")
	)
	(gr_line
		(start 223.900746 -55.361586)
		(end 223.95053 -55.426102)
		(stroke
			(width 0.0508)
			(type default)
		)
		(layer "In5.Cu")
	)
	(gr_line
		(start 223.900746 -53.36159)
		(end 223.95053 -53.426106)
		(stroke
			(width 0.0508)
			(type default)
		)
		(layer "In5.Cu")
	)
	(gr_line
		(start 223.91116 -25.0698)
		(end 223.957642 -25.116282)
		(stroke
			(width 0.06985)
			(type default)
		)
		(layer "In5.Cu")
	)
	(gr_line
		(start 223.919542 -48.424338)
		(end 223.921828 -48.426624)
		(stroke
			(width 0.0508)
			(type default)
		)
		(layer "In5.Cu")
	)
	(gr_arc
		(start 223.921828 -48.426624)
		(mid 224.002676 -48.480771)
		(end 224.098104 -48.499776)
		(stroke
			(width 0.0508)
			(type default)
		)
		(layer "In5.Cu")
	)
	(gr_arc
		(start 223.95053 -57.426098)
		(mid 224.016755 -57.480355)
		(end 224.100136 -57.499758)
		(stroke
			(width 0.0508)
			(type default)
		)
		(layer "In5.Cu")
	)
	(gr_arc
		(start 223.95053 -55.426102)
		(mid 224.016753 -55.48037)
		(end 224.100136 -55.499762)
		(stroke
			(width 0.0508)
			(type default)
		)
		(layer "In5.Cu")
	)
	(gr_arc
		(start 223.95053 -53.426106)
		(mid 224.016754 -53.480373)
		(end 224.100136 -53.499766)
		(stroke
			(width 0.0508)
			(type default)
		)
		(layer "In5.Cu")
	)
	(gr_arc
		(start 223.95053 -50.426112)
		(mid 224.016754 -50.480377)
		(end 224.100136 -50.499772)
		(stroke
			(width 0.0508)
			(type default)
		)
		(layer "In5.Cu")
	)
	(gr_arc
		(start 223.960944 -30.788356)
		(mid 224.004926 -30.778369)
		(end 224.040192 -30.750256)
		(stroke
			(width 0.0508)
			(type default)
		)
		(layer "In5.Cu")
	)
	(gr_arc
		(start 223.986852 -31.084266)
		(mid 223.888698 -31.021855)
		(end 223.778826 -30.983682)
		(stroke
			(width 0.0508)
			(type default)
		)
		(layer "In5.Cu")
	)
	(gr_arc
		(start 224.0153 -40.500046)
		(mid 223.806305 -40.576508)
		(end 223.696022 -40.769794)
		(stroke
			(width 0.0508)
			(type default)
		)
		(layer "In5.Cu")
	)
	(gr_line
		(start 224.0153 -40.500046)
		(end 224.100136 -40.500046)
		(stroke
			(width 0.0508)
			(type default)
		)
		(layer "In5.Cu")
	)
	(gr_line
		(start 224.040192 -30.750256)
		(end 224.057972 -30.728158)
		(stroke
			(width 0.0508)
			(type default)
		)
		(layer "In5.Cu")
	)
	(gr_arc
		(start 224.057972 -30.728158)
		(mid 224.093041 -30.6638)
		(end 224.103438 -30.591252)
		(stroke
			(width 0.0508)
			(type default)
		)
		(layer "In5.Cu")
	)
	(gr_arc
		(start 224.064068 -65.038732)
		(mid 224.019679 -65.009035)
		(end 223.967294 -64.9986)
		(stroke
			(width 0.0508)
			(type default)
		)
		(layer "In5.Cu")
	)
	(gr_line
		(start 224.064068 -65.038732)
		(end 224.152968 -65.127632)
		(stroke
			(width 0.0508)
			(type default)
		)
		(layer "In5.Cu")
	)
	(gr_line
		(start 224.076006 -38.47592)
		(end 224.100136 -38.50005)
		(stroke
			(width 0.0508)
			(type default)
		)
		(layer "In5.Cu")
	)
	(gr_line
		(start 224.098104 -48.499776)
		(end 224.100136 -48.499776)
		(stroke
			(width 0.0508)
			(type default)
		)
		(layer "In5.Cu")
	)
	(gr_line
		(start 224.100136 -65.499742)
		(end 224.152968 -65.44691)
		(stroke
			(width 0.0508)
			(type default)
		)
		(layer "In5.Cu")
	)
	(gr_arc
		(start 224.100136 -64.499744)
		(mid 224.001566 -64.519338)
		(end 223.918018 -64.575182)
		(stroke
			(width 0.0508)
			(type default)
		)
		(layer "In5.Cu")
	)
	(gr_line
		(start 224.100136 -30.500066)
		(end 224.103438 -30.591252)
		(stroke
			(width 0.0508)
			(type default)
		)
		(layer "In5.Cu")
	)
	(gr_arc
		(start 224.1042 -31.504128)
		(mid 224.07431 -31.286152)
		(end 223.986852 -31.084266)
		(stroke
			(width 0.0508)
			(type default)
		)
		(layer "In5.Cu")
	)
	(gr_arc
		(start 224.152968 -65.44691)
		(mid 224.21921 -65.28728)
		(end 224.152968 -65.127632)
		(stroke
			(width 0.0508)
			(type default)
		)
		(layer "In5.Cu")
	)
	(gr_line
		(start 224.249488 -45.169836)
		(end 224.274888 -45.169836)
		(stroke
			(width 0.0508)
			(type default)
		)
		(layer "In5.Cu")
	)
	(gr_line
		(start 224.249488 -44.839636)
		(end 224.274888 -44.839636)
		(stroke
			(width 0.0508)
			(type default)
		)
		(layer "In5.Cu")
	)
	(gr_line
		(start 224.274888 -45.169836)
		(end 224.294446 -45.150278)
		(stroke
			(width 0.0508)
			(type default)
		)
		(layer "In5.Cu")
	)
	(gr_line
		(start 224.274888 -44.839636)
		(end 224.294446 -44.859194)
		(stroke
			(width 0.0508)
			(type default)
		)
		(layer "In5.Cu")
	)
	(gr_line
		(start 224.296224 -45.1485)
		(end 224.338388 -45.106336)
		(stroke
			(width 0.0508)
			(type default)
		)
		(layer "In5.Cu")
	)
	(gr_line
		(start 224.296224 -44.860972)
		(end 224.338388 -44.903136)
		(stroke
			(width 0.0508)
			(type default)
		)
		(layer "In5.Cu")
	)
	(gr_line
		(start 224.40519 -29.856176)
		(end 224.862644 -30.31363)
		(stroke
			(width 0.06985)
			(type default)
		)
		(layer "In5.Cu")
	)
	(gr_line
		(start 224.4344 -66.9798)
		(end 224.4344 -67.178936)
		(stroke
			(width 0.06985)
			(type default)
		)
		(layer "In5.Cu")
	)
	(gr_line
		(start 224.4344 -66.9798)
		(end 224.453958 -66.960242)
		(stroke
			(width 0.0508)
			(type default)
		)
		(layer "In5.Cu")
	)
	(gr_line
		(start 224.455736 -66.958464)
		(end 224.493836 -66.920364)
		(stroke
			(width 0.0508)
			(type default)
		)
		(layer "In5.Cu")
	)
	(gr_line
		(start 224.519744 -24.08047)
		(end 224.584006 -24.0919)
		(stroke
			(width 0.06985)
			(type default)
		)
		(layer "In5.Cu")
	)
	(gr_arc
		(start 224.578164 -65.914778)
		(mid 224.51572 -66.008372)
		(end 224.493836 -66.11874)
		(stroke
			(width 0.0508)
			(type default)
		)
		(layer "In5.Cu")
	)
	(gr_line
		(start 224.578164 -65.914778)
		(end 224.918016 -65.57518)
		(stroke
			(width 0.0508)
			(type default)
		)
		(layer "In5.Cu")
	)
	(gr_line
		(start 224.697036 -66.912236)
		(end 224.743264 -66.958464)
		(stroke
			(width 0.0508)
			(type default)
		)
		(layer "In5.Cu")
	)
	(gr_line
		(start 224.697036 -66.7131)
		(end 224.697036 -66.912236)
		(stroke
			(width 0.0508)
			(type default)
		)
		(layer "In5.Cu")
	)
	(gr_line
		(start 224.745042 -66.960242)
		(end 224.7646 -66.9798)
		(stroke
			(width 0.0508)
			(type default)
		)
		(layer "In5.Cu")
	)
	(gr_arc
		(start 224.748598 -66.049398)
		(mid 224.71045 -66.106501)
		(end 224.697036 -66.173858)
		(stroke
			(width 0.0508)
			(type default)
		)
		(layer "In5.Cu")
	)
	(gr_line
		(start 224.794572 -88.633046)
		(end 224.81413 -88.605106)
		(stroke
			(width 0.06985)
			(type default)
		)
		(layer "In5.Cu")
	)
	(gr_line
		(start 224.81413 -88.605106)
		(end 224.819972 -88.572086)
		(stroke
			(width 0.06985)
			(type default)
		)
		(layer "In5.Cu")
	)
	(gr_line
		(start 224.862644 -30.31363)
		(end 225.100134 -30.500066)
		(stroke
			(width 0.06985)
			(type default)
		)
		(layer "In5.Cu")
	)
	(gr_arc
		(start 224.87128 -65.998598)
		(mid 224.804879 -66.011782)
		(end 224.748598 -66.049398)
		(stroke
			(width 0.0508)
			(type default)
		)
		(layer "In5.Cu")
	)
	(gr_line
		(start 224.87128 -65.998598)
		(end 224.967292 -65.998598)
		(stroke
			(width 0.0508)
			(type default)
		)
		(layer "In5.Cu")
	)
	(gr_arc
		(start 225.064066 -66.03873)
		(mid 225.019676 -66.009034)
		(end 224.967292 -65.998598)
		(stroke
			(width 0.0508)
			(type default)
		)
		(layer "In5.Cu")
	)
	(gr_line
		(start 225.064066 -66.03873)
		(end 225.071686 -66.04635)
		(stroke
			(width 0.0508)
			(type default)
		)
		(layer "In5.Cu")
	)
	(gr_line
		(start 225.100134 -66.49974)
		(end 225.125534 -66.47434)
		(stroke
			(width 0.0508)
			(type default)
		)
		(layer "In5.Cu")
	)
	(gr_arc
		(start 225.100134 -65.499742)
		(mid 225.001572 -65.519347)
		(end 224.918016 -65.57518)
		(stroke
			(width 0.0508)
			(type default)
		)
		(layer "In5.Cu")
	)
	(gr_line
		(start 225.100134 -29.500068)
		(end 225.100134 -29.53131)
		(stroke
			(width 0.06985)
			(type default)
		)
		(layer "In5.Cu")
	)
	(gr_arc
		(start 225.125534 -66.176398)
		(mid 225.111564 -66.106007)
		(end 225.071686 -66.04635)
		(stroke
			(width 0.0508)
			(type default)
		)
		(layer "In5.Cu")
	)
	(gr_line
		(start 225.125534 -66.176398)
		(end 225.125534 -66.47434)
		(stroke
			(width 0.0508)
			(type default)
		)
		(layer "In5.Cu")
	)
	(gr_line
		(start 225.265488 -27.420062)
		(end 225.280982 -27.430984)
		(stroke
			(width 0.06985)
			(type default)
		)
		(layer "In5.Cu")
	)
	(gr_line
		(start 225.280982 -27.430984)
		(end 225.291904 -27.446478)
		(stroke
			(width 0.06985)
			(type default)
		)
		(layer "In5.Cu")
	)
	(gr_line
		(start 225.308922 -25.565862)
		(end 225.319844 -25.581356)
		(stroke
			(width 0.06985)
			(type default)
		)
		(layer "In5.Cu")
	)
	(gr_line
		(start 225.319844 -25.581356)
		(end 225.335338 -25.592278)
		(stroke
			(width 0.06985)
			(type default)
		)
		(layer "In5.Cu")
	)
	(gr_line
		(start 225.43516 -29.21)
		(end 225.49866 -29.2735)
		(stroke
			(width 0.0508)
			(type default)
		)
		(layer "In5.Cu")
	)
	(gr_line
		(start 225.43516 -29.1846)
		(end 225.43516 -29.21)
		(stroke
			(width 0.0508)
			(type default)
		)
		(layer "In5.Cu")
	)
	(gr_line
		(start 225.462084 -67.0306)
		(end 225.462084 -67.20205)
		(stroke
			(width 0.06985)
			(type default)
		)
		(layer "In5.Cu")
	)
	(gr_line
		(start 225.462084 -67.0306)
		(end 225.481642 -67.011042)
		(stroke
			(width 0.0508)
			(type default)
		)
		(layer "In5.Cu")
	)
	(gr_line
		(start 225.48342 -67.009264)
		(end 225.493834 -66.99885)
		(stroke
			(width 0.0508)
			(type default)
		)
		(layer "In5.Cu")
	)
	(gr_line
		(start 225.514916 -89.885266)
		(end 225.534474 -89.857326)
		(stroke
			(width 0.06985)
			(type default)
		)
		(layer "In5.Cu")
	)
	(gr_line
		(start 225.534474 -89.857326)
		(end 225.540316 -89.824306)
		(stroke
			(width 0.06985)
			(type default)
		)
		(layer "In5.Cu")
	)
	(gr_line
		(start 225.57359 -23.10257)
		(end 225.638106 -23.114)
		(stroke
			(width 0.06985)
			(type default)
		)
		(layer "In5.Cu")
	)
	(gr_arc
		(start 225.578162 -64.91478)
		(mid 225.515688 -65.008366)
		(end 225.493834 -65.118742)
		(stroke
			(width 0.0508)
			(type default)
		)
		(layer "In5.Cu")
	)
	(gr_line
		(start 225.578162 -64.91478)
		(end 225.759264 -64.733678)
		(stroke
			(width 0.0508)
			(type default)
		)
		(layer "In5.Cu")
	)
	(gr_line
		(start 225.697034 -66.93535)
		(end 225.770948 -67.009264)
		(stroke
			(width 0.0508)
			(type default)
		)
		(layer "In5.Cu")
	)
	(gr_line
		(start 225.697034 -66.7639)
		(end 225.697034 -66.93535)
		(stroke
			(width 0.0508)
			(type default)
		)
		(layer "In5.Cu")
	)
	(gr_line
		(start 225.711004 -28.045156)
		(end 225.730562 -28.073096)
		(stroke
			(width 0.06985)
			(type default)
		)
		(layer "In5.Cu")
	)
	(gr_line
		(start 225.730562 -28.073096)
		(end 225.736404 -28.10637)
		(stroke
			(width 0.06985)
			(type default)
		)
		(layer "In5.Cu")
	)
	(gr_arc
		(start 225.748596 -65.0494)
		(mid 225.710441 -65.106503)
		(end 225.697034 -65.17386)
		(stroke
			(width 0.0508)
			(type default)
		)
		(layer "In5.Cu")
	)
	(gr_line
		(start 225.759264 -64.733678)
		(end 225.918014 -64.575182)
		(stroke
			(width 0.0508)
			(type default)
		)
		(layer "In5.Cu")
	)
	(gr_arc
		(start 225.76536 -29.21)
		(mid 225.718382 -29.280402)
		(end 225.70186 -29.363416)
		(stroke
			(width 0.0508)
			(type default)
		)
		(layer "In5.Cu")
	)
	(gr_line
		(start 225.76536 -29.1846)
		(end 225.76536 -29.21)
		(stroke
			(width 0.0508)
			(type default)
		)
		(layer "In5.Cu")
	)
	(gr_line
		(start 225.772726 -67.011042)
		(end 225.792284 -67.0306)
		(stroke
			(width 0.0508)
			(type default)
		)
		(layer "In5.Cu")
	)
	(gr_arc
		(start 225.871278 -64.9986)
		(mid 225.804889 -65.011806)
		(end 225.748596 -65.0494)
		(stroke
			(width 0.0508)
			(type default)
		)
		(layer "In5.Cu")
	)
	(gr_arc
		(start 225.95713 -30.784292)
		(mid 226.059951 -30.7209)
		(end 226.100132 -30.607)
		(stroke
			(width 0.0508)
			(type default)
		)
		(layer "In5.Cu")
	)
	(gr_line
		(start 226.021392 -26.86177)
		(end 226.036378 -26.872438)
		(stroke
			(width 0.06985)
			(type default)
		)
		(layer "In5.Cu")
	)
	(gr_line
		(start 226.036378 -26.872438)
		(end 226.046284 -26.88717)
		(stroke
			(width 0.06985)
			(type default)
		)
		(layer "In5.Cu")
	)
	(gr_arc
		(start 226.0854 -65.151)
		(mid 226.058369 -65.101431)
		(end 226.021646 -65.058544)
		(stroke
			(width 0.0508)
			(type default)
		)
		(layer "In5.Cu")
	)
	(gr_arc
		(start 226.100132 -65.499742)
		(mid 226.123852 -65.324053)
		(end 226.0854 -65.151)
		(stroke
			(width 0.0508)
			(type default)
		)
		(layer "In5.Cu")
	)
	(gr_arc
		(start 226.100132 -64.499744)
		(mid 226.001563 -64.519339)
		(end 225.918014 -64.575182)
		(stroke
			(width 0.0508)
			(type default)
		)
		(layer "In5.Cu")
	)
	(gr_arc
		(start 226.100132 -31.204662)
		(mid 226.04993 -31.064241)
		(end 225.922078 -30.987492)
		(stroke
			(width 0.0508)
			(type default)
		)
		(layer "In5.Cu")
	)
	(gr_line
		(start 226.100132 -31.204662)
		(end 226.100132 -31.500064)
		(stroke
			(width 0.0508)
			(type default)
		)
		(layer "In5.Cu")
	)
	(gr_line
		(start 226.100132 -30.500066)
		(end 226.100132 -30.607)
		(stroke
			(width 0.0508)
			(type default)
		)
		(layer "In5.Cu")
	)
	(gr_line
		(start 226.125532 -91.698318)
		(end 226.14509 -91.670378)
		(stroke
			(width 0.06985)
			(type default)
		)
		(layer "In5.Cu")
	)
	(gr_line
		(start 226.14509 -91.670378)
		(end 226.150932 -91.637358)
		(stroke
			(width 0.06985)
			(type default)
		)
		(layer "In5.Cu")
	)
	(gr_line
		(start 226.428554 -28.95727)
		(end 226.492054 -29.02077)
		(stroke
			(width 0.0508)
			(type default)
		)
		(layer "In5.Cu")
	)
	(gr_line
		(start 226.428554 -28.93187)
		(end 226.428554 -28.95727)
		(stroke
			(width 0.0508)
			(type default)
		)
		(layer "In5.Cu")
	)
	(gr_line
		(start 226.441 -66.9798)
		(end 226.441 -67.172332)
		(stroke
			(width 0.06985)
			(type default)
		)
		(layer "In5.Cu")
	)
	(gr_line
		(start 226.441 -66.9798)
		(end 226.460558 -66.960242)
		(stroke
			(width 0.0508)
			(type default)
		)
		(layer "In5.Cu")
	)
	(gr_line
		(start 226.462336 -66.958464)
		(end 226.493832 -66.926968)
		(stroke
			(width 0.0508)
			(type default)
		)
		(layer "In5.Cu")
	)
	(gr_line
		(start 226.517962 -72.43064)
		(end 226.523042 -72.405494)
		(stroke
			(width 0.06985)
			(type default)
		)
		(layer "In5.Cu")
	)
	(gr_arc
		(start 226.57816 -65.914778)
		(mid 226.515716 -66.008372)
		(end 226.493832 -66.11874)
		(stroke
			(width 0.0508)
			(type default)
		)
		(layer "In5.Cu")
	)
	(gr_line
		(start 226.57816 -65.914778)
		(end 226.918012 -65.57518)
		(stroke
			(width 0.0508)
			(type default)
		)
		(layer "In5.Cu")
	)
	(gr_line
		(start 226.697032 -66.905632)
		(end 226.749864 -66.958464)
		(stroke
			(width 0.0508)
			(type default)
		)
		(layer "In5.Cu")
	)
	(gr_line
		(start 226.697032 -66.7131)
		(end 226.697032 -66.905632)
		(stroke
			(width 0.0508)
			(type default)
		)
		(layer "In5.Cu")
	)
	(gr_line
		(start 226.723194 -27.867356)
		(end 226.758754 -27.918918)
		(stroke
			(width 0.06985)
			(type default)
		)
		(layer "In5.Cu")
	)
	(gr_arc
		(start 226.748594 -66.049398)
		(mid 226.710447 -66.106501)
		(end 226.697032 -66.173858)
		(stroke
			(width 0.0508)
			(type default)
		)
		(layer "In5.Cu")
	)
	(gr_line
		(start 226.751642 -66.960242)
		(end 226.7712 -66.9798)
		(stroke
			(width 0.0508)
			(type default)
		)
		(layer "In5.Cu")
	)
	(gr_arc
		(start 226.758754 -28.95727)
		(mid 226.711776 -29.027672)
		(end 226.695254 -29.110686)
		(stroke
			(width 0.0508)
			(type default)
		)
		(layer "In5.Cu")
	)
	(gr_line
		(start 226.758754 -28.93187)
		(end 226.758754 -28.95727)
		(stroke
			(width 0.0508)
			(type default)
		)
		(layer "In5.Cu")
	)
	(gr_arc
		(start 226.871276 -65.998598)
		(mid 226.804876 -66.011783)
		(end 226.748594 -66.049398)
		(stroke
			(width 0.0508)
			(type default)
		)
		(layer "In5.Cu")
	)
	(gr_line
		(start 226.871276 -65.998598)
		(end 226.967288 -65.998598)
		(stroke
			(width 0.0508)
			(type default)
		)
		(layer "In5.Cu")
	)
	(gr_arc
		(start 226.924108 -29.822394)
		(mid 226.991469 -29.808995)
		(end 227.048568 -29.770832)
		(stroke
			(width 0.0508)
			(type default)
		)
		(layer "In5.Cu")
	)
	(gr_line
		(start 227.048568 -29.770832)
		(end 227.070412 -29.748988)
		(stroke
			(width 0.0508)
			(type default)
		)
		(layer "In5.Cu")
	)
	(gr_arc
		(start 227.064062 -66.03873)
		(mid 227.019672 -66.009035)
		(end 226.967288 -65.998598)
		(stroke
			(width 0.0508)
			(type default)
		)
		(layer "In5.Cu")
	)
	(gr_line
		(start 227.064062 -66.03873)
		(end 227.071682 -66.04635)
		(stroke
			(width 0.0508)
			(type default)
		)
		(layer "In5.Cu")
	)
	(gr_arc
		(start 227.064062 -30.061662)
		(mid 227.024086 -30.034965)
		(end 226.97694 -30.025594)
		(stroke
			(width 0.0508)
			(type default)
		)
		(layer "In5.Cu")
	)
	(gr_line
		(start 227.064062 -30.061662)
		(end 227.070412 -30.068012)
		(stroke
			(width 0.0508)
			(type default)
		)
		(layer "In5.Cu")
	)
	(gr_arc
		(start 227.070412 -29.748988)
		(mid 227.092395 -29.715994)
		(end 227.10013 -29.677106)
		(stroke
			(width 0.0508)
			(type default)
		)
		(layer "In5.Cu")
	)
	(gr_line
		(start 227.10013 -66.49974)
		(end 227.12553 -66.47434)
		(stroke
			(width 0.0508)
			(type default)
		)
		(layer "In5.Cu")
	)
	(gr_arc
		(start 227.10013 -65.499742)
		(mid 227.001568 -65.519347)
		(end 226.918012 -65.57518)
		(stroke
			(width 0.0508)
			(type default)
		)
		(layer "In5.Cu")
	)
	(gr_arc
		(start 227.10013 -30.139894)
		(mid 227.092381 -30.101017)
		(end 227.070412 -30.068012)
		(stroke
			(width 0.0508)
			(type default)
		)
		(layer "In5.Cu")
	)
	(gr_line
		(start 227.10013 -30.139894)
		(end 227.10013 -30.500066)
		(stroke
			(width 0.0508)
			(type default)
		)
		(layer "In5.Cu")
	)
	(gr_line
		(start 227.10013 -29.500068)
		(end 227.10013 -29.677106)
		(stroke
			(width 0.0508)
			(type default)
		)
		(layer "In5.Cu")
	)
	(gr_arc
		(start 227.12553 -66.176398)
		(mid 227.11156 -66.106007)
		(end 227.071682 -66.04635)
		(stroke
			(width 0.0508)
			(type default)
		)
		(layer "In5.Cu")
	)
	(gr_line
		(start 227.12553 -66.176398)
		(end 227.12553 -66.47434)
		(stroke
			(width 0.0508)
			(type default)
		)
		(layer "In5.Cu")
	)
	(gr_line
		(start 227.179124 -92.44584)
		(end 227.198682 -92.4179)
		(stroke
			(width 0.06985)
			(type default)
		)
		(layer "In5.Cu")
	)
	(gr_line
		(start 227.198682 -92.4179)
		(end 227.204524 -92.38488)
		(stroke
			(width 0.06985)
			(type default)
		)
		(layer "In5.Cu")
	)
	(gr_line
		(start 227.4316 -66.9544)
		(end 227.4316 -67.243198)
		(stroke
			(width 0.06985)
			(type default)
		)
		(layer "In5.Cu")
	)
	(gr_line
		(start 227.4316 -66.9544)
		(end 227.49129 -66.89471)
		(stroke
			(width 0.0508)
			(type default)
		)
		(layer "In5.Cu")
	)
	(gr_line
		(start 227.435156 -28.693618)
		(end 227.498656 -28.757118)
		(stroke
			(width 0.0508)
			(type default)
		)
		(layer "In5.Cu")
	)
	(gr_line
		(start 227.435156 -28.668218)
		(end 227.435156 -28.693618)
		(stroke
			(width 0.0508)
			(type default)
		)
		(layer "In5.Cu")
	)
	(gr_arc
		(start 227.578158 -64.91478)
		(mid 227.515685 -65.008366)
		(end 227.49383 -65.118742)
		(stroke
			(width 0.0508)
			(type default)
		)
		(layer "In5.Cu")
	)
	(gr_line
		(start 227.578158 -64.91478)
		(end 227.91801 -64.575182)
		(stroke
			(width 0.0508)
			(type default)
		)
		(layer "In5.Cu")
	)
	(gr_line
		(start 227.596954 -72.823324)
		(end 227.600764 -72.801988)
		(stroke
			(width 0.06985)
			(type default)
		)
		(layer "In5.Cu")
	)
	(gr_line
		(start 227.654612 -27.491436)
		(end 227.67417 -27.519376)
		(stroke
			(width 0.06985)
			(type default)
		)
		(layer "In5.Cu")
	)
	(gr_line
		(start 227.67417 -27.519376)
		(end 227.680012 -27.552396)
		(stroke
			(width 0.06985)
			(type default)
		)
		(layer "In5.Cu")
	)
	(gr_line
		(start 227.69703 -66.976498)
		(end 227.6983 -66.977006)
		(stroke
			(width 0.0508)
			(type default)
		)
		(layer "In5.Cu")
	)
	(gr_line
		(start 227.69703 -66.6877)
		(end 227.69703 -66.976498)
		(stroke
			(width 0.0508)
			(type default)
		)
		(layer "In5.Cu")
	)
	(gr_line
		(start 227.70084 -66.978022)
		(end 227.718112 -66.985388)
		(stroke
			(width 0.0508)
			(type default)
		)
		(layer "In5.Cu")
	)
	(gr_line
		(start 227.718112 -66.985388)
		(end 227.7618 -67.029076)
		(stroke
			(width 0.0508)
			(type default)
		)
		(layer "In5.Cu")
	)
	(gr_arc
		(start 227.748592 -65.0494)
		(mid 227.710446 -65.106503)
		(end 227.69703 -65.17386)
		(stroke
			(width 0.0508)
			(type default)
		)
		(layer "In5.Cu")
	)
	(gr_arc
		(start 227.765356 -28.693618)
		(mid 227.718378 -28.76402)
		(end 227.701856 -28.847034)
		(stroke
			(width 0.0508)
			(type default)
		)
		(layer "In5.Cu")
	)
	(gr_line
		(start 227.765356 -28.668218)
		(end 227.765356 -28.693618)
		(stroke
			(width 0.0508)
			(type default)
		)
		(layer "In5.Cu")
	)
	(gr_arc
		(start 227.871274 -64.9986)
		(mid 227.804874 -65.011786)
		(end 227.748592 -65.0494)
		(stroke
			(width 0.0508)
			(type default)
		)
		(layer "In5.Cu")
	)
	(gr_line
		(start 227.871274 -64.9986)
		(end 227.967286 -64.9986)
		(stroke
			(width 0.0508)
			(type default)
		)
		(layer "In5.Cu")
	)
	(gr_arc
		(start 227.957126 -30.784292)
		(mid 228.059947 -30.7209)
		(end 228.100128 -30.607)
		(stroke
			(width 0.0508)
			(type default)
		)
		(layer "In5.Cu")
	)
	(gr_arc
		(start 228.06406 -65.038732)
		(mid 228.019676 -65.009004)
		(end 227.967286 -64.9986)
		(stroke
			(width 0.0508)
			(type default)
		)
		(layer "In5.Cu")
	)
	(gr_line
		(start 228.06406 -65.038732)
		(end 228.07168 -65.046352)
		(stroke
			(width 0.0508)
			(type default)
		)
		(layer "In5.Cu")
	)
	(gr_line
		(start 228.100128 -65.499742)
		(end 228.125528 -65.474342)
		(stroke
			(width 0.0508)
			(type default)
		)
		(layer "In5.Cu")
	)
	(gr_arc
		(start 228.100128 -64.499744)
		(mid 228.00156 -64.51934)
		(end 227.91801 -64.575182)
		(stroke
			(width 0.0508)
			(type default)
		)
		(layer "In5.Cu")
	)
	(gr_arc
		(start 228.100128 -31.088838)
		(mid 228.070457 -31.017157)
		(end 227.998782 -30.987492)
		(stroke
			(width 0.0508)
			(type default)
		)
		(layer "In5.Cu")
	)
	(gr_line
		(start 228.100128 -31.088838)
		(end 228.100128 -31.500064)
		(stroke
			(width 0.0508)
			(type default)
		)
		(layer "In5.Cu")
	)
	(gr_line
		(start 228.100128 -30.500066)
		(end 228.100128 -30.607)
		(stroke
			(width 0.0508)
			(type default)
		)
		(layer "In5.Cu")
	)
	(gr_arc
		(start 228.125528 -65.1764)
		(mid 228.111558 -65.106009)
		(end 228.07168 -65.046352)
		(stroke
			(width 0.0508)
			(type default)
		)
		(layer "In5.Cu")
	)
	(gr_line
		(start 228.125528 -65.1764)
		(end 228.125528 -65.474342)
		(stroke
			(width 0.0508)
			(type default)
		)
		(layer "In5.Cu")
	)
	(gr_line
		(start 228.4222 -66.9544)
		(end 228.441758 -66.934842)
		(stroke
			(width 0.0508)
			(type default)
		)
		(layer "In5.Cu")
	)
	(gr_line
		(start 228.428804 -28.582112)
		(end 228.492304 -28.645612)
		(stroke
			(width 0.0508)
			(type default)
		)
		(layer "In5.Cu")
	)
	(gr_line
		(start 228.428804 -28.556712)
		(end 228.428804 -28.582112)
		(stroke
			(width 0.0508)
			(type default)
		)
		(layer "In5.Cu")
	)
	(gr_line
		(start 228.443536 -66.933064)
		(end 228.493828 -66.882772)
		(stroke
			(width 0.0508)
			(type default)
		)
		(layer "In5.Cu")
	)
	(gr_line
		(start 228.493828 -66.6877)
		(end 228.493828 -66.882772)
		(stroke
			(width 0.0508)
			(type default)
		)
		(layer "In5.Cu")
	)
	(gr_arc
		(start 228.578156 -65.914778)
		(mid 228.515682 -66.008364)
		(end 228.493828 -66.11874)
		(stroke
			(width 0.0508)
			(type default)
		)
		(layer "In5.Cu")
	)
	(gr_line
		(start 228.578156 -65.914778)
		(end 228.918008 -65.57518)
		(stroke
			(width 0.0508)
			(type default)
		)
		(layer "In5.Cu")
	)
	(gr_line
		(start 228.660452 -26.308304)
		(end 228.68001 -26.336244)
		(stroke
			(width 0.06985)
			(type default)
		)
		(layer "In5.Cu")
	)
	(gr_line
		(start 228.68001 -26.336244)
		(end 228.685852 -26.369518)
		(stroke
			(width 0.06985)
			(type default)
		)
		(layer "In5.Cu")
	)
	(gr_line
		(start 228.697028 -66.899028)
		(end 228.731064 -66.933064)
		(stroke
			(width 0.0508)
			(type default)
		)
		(layer "In5.Cu")
	)
	(gr_line
		(start 228.732842 -66.934842)
		(end 228.7524 -66.9544)
		(stroke
			(width 0.0508)
			(type default)
		)
		(layer "In5.Cu")
	)
	(gr_arc
		(start 228.74859 -66.049398)
		(mid 228.710444 -66.106501)
		(end 228.697028 -66.173858)
		(stroke
			(width 0.0508)
			(type default)
		)
		(layer "In5.Cu")
	)
	(gr_line
		(start 228.7524 -66.9544)
		(end 228.7524 -67.149472)
		(stroke
			(width 0.06985)
			(type default)
		)
		(layer "In5.Cu")
	)
	(gr_arc
		(start 228.759004 -28.582112)
		(mid 228.711998 -28.652506)
		(end 228.695504 -28.735528)
		(stroke
			(width 0.0508)
			(type default)
		)
		(layer "In5.Cu")
	)
	(gr_line
		(start 228.759004 -28.556712)
		(end 228.759004 -28.582112)
		(stroke
			(width 0.0508)
			(type default)
		)
		(layer "In5.Cu")
	)
	(gr_arc
		(start 228.871272 -65.998598)
		(mid 228.804873 -66.011785)
		(end 228.74859 -66.049398)
		(stroke
			(width 0.0508)
			(type default)
		)
		(layer "In5.Cu")
	)
	(gr_line
		(start 228.871272 -65.998598)
		(end 228.967284 -65.998598)
		(stroke
			(width 0.0508)
			(type default)
		)
		(layer "In5.Cu")
	)
	(gr_arc
		(start 228.896672 -29.7942)
		(mid 228.974607 -29.778838)
		(end 229.04069 -29.734764)
		(stroke
			(width 0.0508)
			(type default)
		)
		(layer "In5.Cu")
	)
	(gr_line
		(start 229.04069 -29.734764)
		(end 229.040944 -29.73451)
		(stroke
			(width 0.0508)
			(type default)
		)
		(layer "In5.Cu")
	)
	(gr_arc
		(start 229.040944 -29.73451)
		(mid 229.084784 -29.668626)
		(end 229.100126 -29.591)
		(stroke
			(width 0.0508)
			(type default)
		)
		(layer "In5.Cu")
	)
	(gr_arc
		(start 229.064058 -66.03873)
		(mid 229.019674 -66.009004)
		(end 228.967284 -65.998598)
		(stroke
			(width 0.0508)
			(type default)
		)
		(layer "In5.Cu")
	)
	(gr_line
		(start 229.064058 -66.03873)
		(end 229.071678 -66.04635)
		(stroke
			(width 0.0508)
			(type default)
		)
		(layer "In5.Cu")
	)
	(gr_line
		(start 229.100126 -66.49974)
		(end 229.125526 -66.47434)
		(stroke
			(width 0.0508)
			(type default)
		)
		(layer "In5.Cu")
	)
	(gr_arc
		(start 229.100126 -65.499742)
		(mid 229.001558 -65.519339)
		(end 228.918008 -65.57518)
		(stroke
			(width 0.0508)
			(type default)
		)
		(layer "In5.Cu")
	)
	(gr_arc
		(start 229.100126 -30.157674)
		(mid 229.026018 -30.042268)
		(end 228.896418 -29.9974)
		(stroke
			(width 0.0508)
			(type default)
		)
		(layer "In5.Cu")
	)
	(gr_line
		(start 229.100126 -30.157674)
		(end 229.100126 -30.500066)
		(stroke
			(width 0.0508)
			(type default)
		)
		(layer "In5.Cu")
	)
	(gr_line
		(start 229.100126 -29.500068)
		(end 229.100126 -29.591)
		(stroke
			(width 0.0508)
			(type default)
		)
		(layer "In5.Cu")
	)
	(gr_arc
		(start 229.125526 -66.176398)
		(mid 229.111556 -66.106007)
		(end 229.071678 -66.04635)
		(stroke
			(width 0.0508)
			(type default)
		)
		(layer "In5.Cu")
	)
	(gr_line
		(start 229.125526 -66.176398)
		(end 229.125526 -66.47434)
		(stroke
			(width 0.0508)
			(type default)
		)
		(layer "In5.Cu")
	)
	(gr_line
		(start 229.4382 -66.9798)
		(end 229.4382 -67.175126)
		(stroke
			(width 0.06985)
			(type default)
		)
		(layer "In5.Cu")
	)
	(gr_line
		(start 229.4382 -66.9798)
		(end 229.457758 -66.960242)
		(stroke
			(width 0.0508)
			(type default)
		)
		(layer "In5.Cu")
	)
	(gr_line
		(start 229.459536 -66.958464)
		(end 229.493826 -66.924174)
		(stroke
			(width 0.0508)
			(type default)
		)
		(layer "In5.Cu")
	)
	(gr_line
		(start 229.538276 -72.42683)
		(end 229.542086 -72.405494)
		(stroke
			(width 0.06985)
			(type default)
		)
		(layer "In5.Cu")
	)
	(gr_arc
		(start 229.578154 -64.91478)
		(mid 229.515681 -65.008366)
		(end 229.493826 -65.118742)
		(stroke
			(width 0.0508)
			(type default)
		)
		(layer "In5.Cu")
	)
	(gr_line
		(start 229.578154 -64.91478)
		(end 229.918006 -64.575182)
		(stroke
			(width 0.0508)
			(type default)
		)
		(layer "In5.Cu")
	)
	(gr_line
		(start 229.697026 -66.908426)
		(end 229.747064 -66.958464)
		(stroke
			(width 0.0508)
			(type default)
		)
		(layer "In5.Cu")
	)
	(gr_line
		(start 229.697026 -66.7131)
		(end 229.697026 -66.908426)
		(stroke
			(width 0.0508)
			(type default)
		)
		(layer "In5.Cu")
	)
	(gr_arc
		(start 229.748588 -65.0494)
		(mid 229.710443 -65.106504)
		(end 229.697026 -65.17386)
		(stroke
			(width 0.0508)
			(type default)
		)
		(layer "In5.Cu")
	)
	(gr_line
		(start 229.748842 -66.960242)
		(end 229.7684 -66.9798)
		(stroke
			(width 0.0508)
			(type default)
		)
		(layer "In5.Cu")
	)
	(gr_arc
		(start 229.87127 -64.9986)
		(mid 229.804871 -65.011788)
		(end 229.748588 -65.0494)
		(stroke
			(width 0.0508)
			(type default)
		)
		(layer "In5.Cu")
	)
	(gr_line
		(start 229.87127 -64.9986)
		(end 229.967282 -64.9986)
		(stroke
			(width 0.0508)
			(type default)
		)
		(layer "In5.Cu")
	)
	(gr_arc
		(start 230.064056 -65.038732)
		(mid 230.019672 -65.009006)
		(end 229.967282 -64.9986)
		(stroke
			(width 0.0508)
			(type default)
		)
		(layer "In5.Cu")
	)
	(gr_line
		(start 230.064056 -65.038732)
		(end 230.071676 -65.046352)
		(stroke
			(width 0.0508)
			(type default)
		)
		(layer "In5.Cu")
	)
	(gr_line
		(start 230.100124 -65.499742)
		(end 230.125524 -65.474342)
		(stroke
			(width 0.0508)
			(type default)
		)
		(layer "In5.Cu")
	)
	(gr_arc
		(start 230.100124 -64.499744)
		(mid 230.001557 -64.519341)
		(end 229.918006 -64.575182)
		(stroke
			(width 0.0508)
			(type default)
		)
		(layer "In5.Cu")
	)
	(gr_arc
		(start 230.125524 -65.1764)
		(mid 230.111554 -65.106009)
		(end 230.071676 -65.046352)
		(stroke
			(width 0.0508)
			(type default)
		)
		(layer "In5.Cu")
	)
	(gr_line
		(start 230.125524 -65.1764)
		(end 230.125524 -65.474342)
		(stroke
			(width 0.0508)
			(type default)
		)
		(layer "In5.Cu")
	)
	(gr_line
		(start 230.653336 -72.78116)
		(end 230.657654 -72.801988)
		(stroke
			(width 0.06985)
			(type default)
		)
		(layer "In5.Cu")
	)
	(gr_line
		(start 230.653844 -72.823324)
		(end 230.657654 -72.801988)
		(stroke
			(width 0.06985)
			(type default)
		)
		(layer "In5.Cu")
	)
	(gr_line
		(start 231.4194 -96.408494)
		(end 231.42448 -96.43364)
		(stroke
			(width 0.06985)
			(type default)
		)
		(layer "In5.Cu")
	)
	(gr_line
		(start 231.4194 -90.058494)
		(end 231.42448 -90.08364)
		(stroke
			(width 0.06985)
			(type default)
		)
		(layer "In5.Cu")
	)
	(gr_line
		(start 231.4194 -83.708494)
		(end 231.42448 -83.73364)
		(stroke
			(width 0.06985)
			(type default)
		)
		(layer "In5.Cu")
	)
	(gr_line
		(start 231.4194 -77.358494)
		(end 231.42448 -77.38364)
		(stroke
			(width 0.06985)
			(type default)
		)
		(layer "In5.Cu")
	)
	(gr_line
		(start 231.4194 -66.9798)
		(end 231.438958 -66.960242)
		(stroke
			(width 0.0508)
			(type default)
		)
		(layer "In5.Cu")
	)
	(gr_line
		(start 231.440736 -66.958464)
		(end 231.493822 -66.905378)
		(stroke
			(width 0.0508)
			(type default)
		)
		(layer "In5.Cu")
	)
	(gr_line
		(start 231.493822 -66.7131)
		(end 231.493822 -66.905378)
		(stroke
			(width 0.0508)
			(type default)
		)
		(layer "In5.Cu")
	)
	(gr_arc
		(start 231.57815 -65.914778)
		(mid 231.515706 -66.008372)
		(end 231.493822 -66.11874)
		(stroke
			(width 0.0508)
			(type default)
		)
		(layer "In5.Cu")
	)
	(gr_line
		(start 231.57815 -65.914778)
		(end 231.918002 -65.57518)
		(stroke
			(width 0.0508)
			(type default)
		)
		(layer "In5.Cu")
	)
	(gr_line
		(start 231.697022 -66.927222)
		(end 231.728264 -66.958464)
		(stroke
			(width 0.0508)
			(type default)
		)
		(layer "In5.Cu")
	)
	(gr_line
		(start 231.730042 -66.960242)
		(end 231.7496 -66.9798)
		(stroke
			(width 0.0508)
			(type default)
		)
		(layer "In5.Cu")
	)
	(gr_arc
		(start 231.748584 -66.049398)
		(mid 231.710429 -66.106501)
		(end 231.697022 -66.173858)
		(stroke
			(width 0.0508)
			(type default)
		)
		(layer "In5.Cu")
	)
	(gr_line
		(start 231.7496 -66.9798)
		(end 231.7496 -67.172078)
		(stroke
			(width 0.06985)
			(type default)
		)
		(layer "In5.Cu")
	)
	(gr_arc
		(start 231.871266 -65.998598)
		(mid 231.804877 -66.011804)
		(end 231.748584 -66.049398)
		(stroke
			(width 0.0508)
			(type default)
		)
		(layer "In5.Cu")
	)
	(gr_line
		(start 231.871266 -65.998598)
		(end 231.967278 -65.998598)
		(stroke
			(width 0.0508)
			(type default)
		)
		(layer "In5.Cu")
	)
	(gr_arc
		(start 232.064052 -66.03873)
		(mid 232.019652 -66.009063)
		(end 231.967278 -65.998598)
		(stroke
			(width 0.0508)
			(type default)
		)
		(layer "In5.Cu")
	)
	(gr_line
		(start 232.064052 -66.03873)
		(end 232.071672 -66.04635)
		(stroke
			(width 0.0508)
			(type default)
		)
		(layer "In5.Cu")
	)
	(gr_line
		(start 232.10012 -66.49974)
		(end 232.12552 -66.47434)
		(stroke
			(width 0.0508)
			(type default)
		)
		(layer "In5.Cu")
	)
	(gr_arc
		(start 232.10012 -65.499742)
		(mid 232.001558 -65.519347)
		(end 231.918002 -65.57518)
		(stroke
			(width 0.0508)
			(type default)
		)
		(layer "In5.Cu")
	)
	(gr_arc
		(start 232.12552 -66.176398)
		(mid 232.111522 -66.106024)
		(end 232.071672 -66.04635)
		(stroke
			(width 0.0508)
			(type default)
		)
		(layer "In5.Cu")
	)
	(gr_line
		(start 232.12552 -66.176398)
		(end 232.12552 -66.47434)
		(stroke
			(width 0.0508)
			(type default)
		)
		(layer "In5.Cu")
	)
	(gr_line
		(start 232.340404 -99.75342)
		(end 232.407714 -99.665536)
		(stroke
			(width 0.06985)
			(type default)
		)
		(layer "In5.Cu")
	)
	(gr_line
		(start 232.386124 -99.557586)
		(end 232.407714 -99.665536)
		(stroke
			(width 0.06985)
			(type default)
		)
		(layer "In5.Cu")
	)
	(gr_line
		(start 232.386124 -93.25864)
		(end 232.391204 -93.233494)
		(stroke
			(width 0.06985)
			(type default)
		)
		(layer "In5.Cu")
	)
	(gr_line
		(start 232.386124 -86.90864)
		(end 232.391204 -86.883494)
		(stroke
			(width 0.06985)
			(type default)
		)
		(layer "In5.Cu")
	)
	(gr_line
		(start 232.386124 -80.55864)
		(end 232.391204 -80.533494)
		(stroke
			(width 0.06985)
			(type default)
		)
		(layer "In5.Cu")
	)
	(gr_line
		(start 232.386124 -74.20864)
		(end 232.391204 -74.183494)
		(stroke
			(width 0.06985)
			(type default)
		)
		(layer "In5.Cu")
	)
	(gr_line
		(start 232.4354 -67.0052)
		(end 232.4354 -67.20332)
		(stroke
			(width 0.06985)
			(type default)
		)
		(layer "In5.Cu")
	)
	(gr_line
		(start 232.4354 -67.0052)
		(end 232.454958 -66.985642)
		(stroke
			(width 0.0508)
			(type default)
		)
		(layer "In5.Cu")
	)
	(gr_line
		(start 232.45572 -96.408494)
		(end 232.4608 -96.43364)
		(stroke
			(width 0.06985)
			(type default)
		)
		(layer "In5.Cu")
	)
	(gr_line
		(start 232.45572 -90.058494)
		(end 232.4608 -90.08364)
		(stroke
			(width 0.06985)
			(type default)
		)
		(layer "In5.Cu")
	)
	(gr_line
		(start 232.45572 -83.708494)
		(end 232.4608 -83.73364)
		(stroke
			(width 0.06985)
			(type default)
		)
		(layer "In5.Cu")
	)
	(gr_line
		(start 232.45572 -77.358494)
		(end 232.4608 -77.38364)
		(stroke
			(width 0.06985)
			(type default)
		)
		(layer "In5.Cu")
	)
	(gr_line
		(start 232.456736 -66.983864)
		(end 232.49382 -66.94678)
		(stroke
			(width 0.0508)
			(type default)
		)
		(layer "In5.Cu")
	)
	(gr_line
		(start 232.533444 -10.42162)
		(end 232.639616 -10.528554)
		(stroke
			(width 0.0635)
			(type default)
		)
		(layer "In5.Cu")
	)
	(gr_arc
		(start 232.578148 -64.91478)
		(mid 232.515677 -65.008367)
		(end 232.49382 -65.118742)
		(stroke
			(width 0.0508)
			(type default)
		)
		(layer "In5.Cu")
	)
	(gr_line
		(start 232.578148 -64.91478)
		(end 232.918 -64.575182)
		(stroke
			(width 0.0508)
			(type default)
		)
		(layer "In5.Cu")
	)
	(gr_line
		(start 232.69702 -66.93662)
		(end 232.744264 -66.983864)
		(stroke
			(width 0.0508)
			(type default)
		)
		(layer "In5.Cu")
	)
	(gr_line
		(start 232.69702 -66.7385)
		(end 232.69702 -66.93662)
		(stroke
			(width 0.0508)
			(type default)
		)
		(layer "In5.Cu")
	)
	(gr_line
		(start 232.746042 -66.985642)
		(end 232.7656 -67.0052)
		(stroke
			(width 0.0508)
			(type default)
		)
		(layer "In5.Cu")
	)
	(gr_arc
		(start 232.748582 -65.0494)
		(mid 232.710438 -65.106504)
		(end 232.69702 -65.17386)
		(stroke
			(width 0.0508)
			(type default)
		)
		(layer "In5.Cu")
	)
	(gr_line
		(start 232.775252 -102.783386)
		(end 232.792524 -102.758494)
		(stroke
			(width 0.06985)
			(type default)
		)
		(layer "In5.Cu")
	)
	(gr_line
		(start 232.792524 -102.758494)
		(end 232.798366 -102.729284)
		(stroke
			(width 0.06985)
			(type default)
		)
		(layer "In5.Cu")
	)
	(gr_arc
		(start 232.871264 -64.9986)
		(mid 232.804866 -65.011789)
		(end 232.748582 -65.0494)
		(stroke
			(width 0.0508)
			(type default)
		)
		(layer "In5.Cu")
	)
	(gr_line
		(start 232.871264 -64.9986)
		(end 232.967276 -64.9986)
		(stroke
			(width 0.0508)
			(type default)
		)
		(layer "In5.Cu")
	)
	(gr_arc
		(start 233.06405 -65.038732)
		(mid 233.019665 -65.009008)
		(end 232.967276 -64.9986)
		(stroke
			(width 0.0508)
			(type default)
		)
		(layer "In5.Cu")
	)
	(gr_line
		(start 233.06405 -65.038732)
		(end 233.07167 -65.046352)
		(stroke
			(width 0.0508)
			(type default)
		)
		(layer "In5.Cu")
	)
	(gr_line
		(start 233.100118 -65.499742)
		(end 233.125518 -65.474342)
		(stroke
			(width 0.0508)
			(type default)
		)
		(layer "In5.Cu")
	)
	(gr_arc
		(start 233.100118 -64.499744)
		(mid 233.001552 -64.519343)
		(end 232.918 -64.575182)
		(stroke
			(width 0.0508)
			(type default)
		)
		(layer "In5.Cu")
	)
	(gr_arc
		(start 233.125518 -65.1764)
		(mid 233.111548 -65.106009)
		(end 233.07167 -65.046352)
		(stroke
			(width 0.0508)
			(type default)
		)
		(layer "In5.Cu")
	)
	(gr_line
		(start 233.125518 -65.1764)
		(end 233.125518 -65.474342)
		(stroke
			(width 0.0508)
			(type default)
		)
		(layer "In5.Cu")
	)
	(gr_line
		(start 233.150156 -10.596372)
		(end 233.413808 -10.33272)
		(stroke
			(width 0.0635)
			(type default)
		)
		(layer "In5.Cu")
	)
	(gr_line
		(start 233.422444 -99.60864)
		(end 233.427524 -99.583494)
		(stroke
			(width 0.06985)
			(type default)
		)
		(layer "In5.Cu")
	)
	(gr_line
		(start 233.422444 -93.25864)
		(end 233.427524 -93.233494)
		(stroke
			(width 0.06985)
			(type default)
		)
		(layer "In5.Cu")
	)
	(gr_line
		(start 233.422444 -86.90864)
		(end 233.427524 -86.883494)
		(stroke
			(width 0.06985)
			(type default)
		)
		(layer "In5.Cu")
	)
	(gr_line
		(start 233.422444 -80.55864)
		(end 233.427524 -80.533494)
		(stroke
			(width 0.06985)
			(type default)
		)
		(layer "In5.Cu")
	)
	(gr_line
		(start 233.422444 -74.20864)
		(end 233.427524 -74.183494)
		(stroke
			(width 0.06985)
			(type default)
		)
		(layer "In5.Cu")
	)
	(gr_line
		(start 233.422444 -74.158856)
		(end 233.427524 -74.183494)
		(stroke
			(width 0.06985)
			(type default)
		)
		(layer "In5.Cu")
	)
	(gr_line
		(start 233.426 -66.9798)
		(end 233.445558 -66.960242)
		(stroke
			(width 0.0508)
			(type default)
		)
		(layer "In5.Cu")
	)
	(gr_line
		(start 233.447336 -66.958464)
		(end 233.493818 -66.911982)
		(stroke
			(width 0.0508)
			(type default)
		)
		(layer "In5.Cu")
	)
	(gr_line
		(start 233.465878 -96.408494)
		(end 233.470958 -96.43364)
		(stroke
			(width 0.06985)
			(type default)
		)
		(layer "In5.Cu")
	)
	(gr_line
		(start 233.465878 -90.058494)
		(end 233.470958 -90.08364)
		(stroke
			(width 0.06985)
			(type default)
		)
		(layer "In5.Cu")
	)
	(gr_line
		(start 233.465878 -83.708494)
		(end 233.470958 -83.73364)
		(stroke
			(width 0.06985)
			(type default)
		)
		(layer "In5.Cu")
	)
	(gr_line
		(start 233.465878 -77.358494)
		(end 233.470958 -77.38364)
		(stroke
			(width 0.06985)
			(type default)
		)
		(layer "In5.Cu")
	)
	(gr_line
		(start 233.493818 -66.7131)
		(end 233.493818 -66.911982)
		(stroke
			(width 0.0508)
			(type default)
		)
		(layer "In5.Cu")
	)
	(gr_line
		(start 233.510836 -104.155748)
		(end 233.528108 -104.130856)
		(stroke
			(width 0.06985)
			(type default)
		)
		(layer "In5.Cu")
	)
	(gr_line
		(start 233.528108 -104.130856)
		(end 233.53395 -104.101646)
		(stroke
			(width 0.06985)
			(type default)
		)
		(layer "In5.Cu")
	)
	(gr_arc
		(start 233.578146 -65.914778)
		(mid 233.515702 -66.008372)
		(end 233.493818 -66.11874)
		(stroke
			(width 0.0508)
			(type default)
		)
		(layer "In5.Cu")
	)
	(gr_line
		(start 233.578146 -65.914778)
		(end 233.917998 -65.57518)
		(stroke
			(width 0.0508)
			(type default)
		)
		(layer "In5.Cu")
	)
	(gr_line
		(start 233.605832 -108.803948)
		(end 233.622342 -108.780326)
		(stroke
			(width 0.06985)
			(type default)
		)
		(layer "In5.Cu")
	)
	(gr_line
		(start 233.622342 -108.780326)
		(end 233.62793 -108.752132)
		(stroke
			(width 0.06985)
			(type default)
		)
		(layer "In5.Cu")
	)
	(gr_line
		(start 233.697018 -66.920618)
		(end 233.734864 -66.958464)
		(stroke
			(width 0.0508)
			(type default)
		)
		(layer "In5.Cu")
	)
	(gr_line
		(start 233.736642 -66.960242)
		(end 233.7562 -66.9798)
		(stroke
			(width 0.0508)
			(type default)
		)
		(layer "In5.Cu")
	)
	(gr_arc
		(start 233.74858 -66.049398)
		(mid 233.710425 -66.106501)
		(end 233.697018 -66.173858)
		(stroke
			(width 0.0508)
			(type default)
		)
		(layer "In5.Cu")
	)
	(gr_line
		(start 233.7562 -66.9798)
		(end 233.7562 -67.178682)
		(stroke
			(width 0.06985)
			(type default)
		)
		(layer "In5.Cu")
	)
	(gr_arc
		(start 233.871262 -65.998598)
		(mid 233.804873 -66.011804)
		(end 233.74858 -66.049398)
		(stroke
			(width 0.0508)
			(type default)
		)
		(layer "In5.Cu")
	)
	(gr_line
		(start 233.871262 -65.998598)
		(end 233.967274 -65.998598)
		(stroke
			(width 0.0508)
			(type default)
		)
		(layer "In5.Cu")
	)
	(gr_arc
		(start 234.064048 -66.03873)
		(mid 234.019648 -66.009063)
		(end 233.967274 -65.998598)
		(stroke
			(width 0.0508)
			(type default)
		)
		(layer "In5.Cu")
	)
	(gr_line
		(start 234.064048 -66.03873)
		(end 234.071668 -66.04635)
		(stroke
			(width 0.0508)
			(type default)
		)
		(layer "In5.Cu")
	)
	(gr_line
		(start 234.100116 -66.49974)
		(end 234.125516 -66.47434)
		(stroke
			(width 0.0508)
			(type default)
		)
		(layer "In5.Cu")
	)
	(gr_arc
		(start 234.100116 -65.499742)
		(mid 234.001554 -65.519347)
		(end 233.917998 -65.57518)
		(stroke
			(width 0.0508)
			(type default)
		)
		(layer "In5.Cu")
	)
	(gr_arc
		(start 234.125516 -66.176398)
		(mid 234.111518 -66.106024)
		(end 234.071668 -66.04635)
		(stroke
			(width 0.0508)
			(type default)
		)
		(layer "In5.Cu")
	)
	(gr_line
		(start 234.125516 -66.176398)
		(end 234.125516 -66.47434)
		(stroke
			(width 0.0508)
			(type default)
		)
		(layer "In5.Cu")
	)
	(gr_line
		(start 234.4166 -66.9798)
		(end 234.436158 -66.960242)
		(stroke
			(width 0.0508)
			(type default)
		)
		(layer "In5.Cu")
	)
	(gr_line
		(start 234.432602 -99.60864)
		(end 234.437682 -99.583494)
		(stroke
			(width 0.06985)
			(type default)
		)
		(layer "In5.Cu")
	)
	(gr_line
		(start 234.432602 -93.25864)
		(end 234.437682 -93.233494)
		(stroke
			(width 0.06985)
			(type default)
		)
		(layer "In5.Cu")
	)
	(gr_line
		(start 234.432602 -86.90864)
		(end 234.437682 -86.883494)
		(stroke
			(width 0.06985)
			(type default)
		)
		(layer "In5.Cu")
	)
	(gr_line
		(start 234.432602 -80.55864)
		(end 234.437682 -80.533494)
		(stroke
			(width 0.06985)
			(type default)
		)
		(layer "In5.Cu")
	)
	(gr_line
		(start 234.432602 -74.20864)
		(end 234.437682 -74.183494)
		(stroke
			(width 0.06985)
			(type default)
		)
		(layer "In5.Cu")
	)
	(gr_line
		(start 234.432602 -74.158856)
		(end 234.437682 -74.183494)
		(stroke
			(width 0.06985)
			(type default)
		)
		(layer "In5.Cu")
	)
	(gr_line
		(start 234.437936 -66.958464)
		(end 234.493816 -66.902584)
		(stroke
			(width 0.0508)
			(type default)
		)
		(layer "In5.Cu")
	)
	(gr_line
		(start 234.47629 -96.408494)
		(end 234.48137 -96.43364)
		(stroke
			(width 0.06985)
			(type default)
		)
		(layer "In5.Cu")
	)
	(gr_line
		(start 234.47629 -90.058494)
		(end 234.48137 -90.08364)
		(stroke
			(width 0.06985)
			(type default)
		)
		(layer "In5.Cu")
	)
	(gr_line
		(start 234.47629 -83.708494)
		(end 234.48137 -83.73364)
		(stroke
			(width 0.06985)
			(type default)
		)
		(layer "In5.Cu")
	)
	(gr_line
		(start 234.47629 -77.358494)
		(end 234.48137 -77.38364)
		(stroke
			(width 0.06985)
			(type default)
		)
		(layer "In5.Cu")
	)
	(gr_line
		(start 234.493816 -66.7131)
		(end 234.493816 -66.902584)
		(stroke
			(width 0.0508)
			(type default)
		)
		(layer "In5.Cu")
	)
	(gr_arc
		(start 234.578144 -64.91478)
		(mid 234.5157 -65.008374)
		(end 234.493816 -65.118742)
		(stroke
			(width 0.0508)
			(type default)
		)
		(layer "In5.Cu")
	)
	(gr_line
		(start 234.578144 -64.91478)
		(end 234.917996 -64.575182)
		(stroke
			(width 0.0508)
			(type default)
		)
		(layer "In5.Cu")
	)
	(gr_line
		(start 234.697016 -66.930016)
		(end 234.725464 -66.958464)
		(stroke
			(width 0.0508)
			(type default)
		)
		(layer "In5.Cu")
	)
	(gr_line
		(start 234.727242 -66.960242)
		(end 234.7468 -66.9798)
		(stroke
			(width 0.0508)
			(type default)
		)
		(layer "In5.Cu")
	)
	(gr_line
		(start 234.7468 -66.9798)
		(end 234.7468 -67.169284)
		(stroke
			(width 0.06985)
			(type default)
		)
		(layer "In5.Cu")
	)
	(gr_arc
		(start 234.748578 -65.0494)
		(mid 234.710423 -65.106503)
		(end 234.697016 -65.17386)
		(stroke
			(width 0.0508)
			(type default)
		)
		(layer "In5.Cu")
	)
	(gr_arc
		(start 234.87126 -64.9986)
		(mid 234.804871 -65.011806)
		(end 234.748578 -65.0494)
		(stroke
			(width 0.0508)
			(type default)
		)
		(layer "In5.Cu")
	)
	(gr_line
		(start 234.87126 -64.9986)
		(end 234.967272 -64.9986)
		(stroke
			(width 0.0508)
			(type default)
		)
		(layer "In5.Cu")
	)
	(gr_arc
		(start 235.064046 -65.038732)
		(mid 235.019646 -65.009065)
		(end 234.967272 -64.9986)
		(stroke
			(width 0.0508)
			(type default)
		)
		(layer "In5.Cu")
	)
	(gr_line
		(start 235.064046 -65.038732)
		(end 235.071666 -65.046352)
		(stroke
			(width 0.0508)
			(type default)
		)
		(layer "In5.Cu")
	)
	(gr_line
		(start 235.100114 -65.499742)
		(end 235.125514 -65.474342)
		(stroke
			(width 0.0508)
			(type default)
		)
		(layer "In5.Cu")
	)
	(gr_arc
		(start 235.100114 -64.499744)
		(mid 235.001552 -64.519349)
		(end 234.917996 -64.575182)
		(stroke
			(width 0.0508)
			(type default)
		)
		(layer "In5.Cu")
	)
	(gr_arc
		(start 235.125514 -65.1764)
		(mid 235.111516 -65.106026)
		(end 235.071666 -65.046352)
		(stroke
			(width 0.0508)
			(type default)
		)
		(layer "In5.Cu")
	)
	(gr_line
		(start 235.125514 -65.1764)
		(end 235.125514 -65.474342)
		(stroke
			(width 0.0508)
			(type default)
		)
		(layer "In5.Cu")
	)
	(gr_line
		(start 235.402374 -111.841026)
		(end 235.421932 -111.813086)
		(stroke
			(width 0.06985)
			(type default)
		)
		(layer "In5.Cu")
	)
	(gr_line
		(start 235.4072 -66.9798)
		(end 235.426758 -66.960242)
		(stroke
			(width 0.0508)
			(type default)
		)
		(layer "In5.Cu")
	)
	(gr_line
		(start 235.421932 -111.813086)
		(end 235.427774 -111.780066)
		(stroke
			(width 0.06985)
			(type default)
		)
		(layer "In5.Cu")
	)
	(gr_line
		(start 235.428536 -66.958464)
		(end 235.493814 -66.893186)
		(stroke
			(width 0.0508)
			(type default)
		)
		(layer "In5.Cu")
	)
	(gr_line
		(start 235.443014 -99.608894)
		(end 235.448094 -99.583494)
		(stroke
			(width 0.06985)
			(type default)
		)
		(layer "In5.Cu")
	)
	(gr_line
		(start 235.443014 -99.558602)
		(end 235.448094 -99.583494)
		(stroke
			(width 0.06985)
			(type default)
		)
		(layer "In5.Cu")
	)
	(gr_line
		(start 235.443014 -93.25864)
		(end 235.448094 -93.233494)
		(stroke
			(width 0.06985)
			(type default)
		)
		(layer "In5.Cu")
	)
	(gr_line
		(start 235.443014 -86.90864)
		(end 235.448094 -86.883494)
		(stroke
			(width 0.06985)
			(type default)
		)
		(layer "In5.Cu")
	)
	(gr_line
		(start 235.443014 -80.55864)
		(end 235.448094 -80.533494)
		(stroke
			(width 0.06985)
			(type default)
		)
		(layer "In5.Cu")
	)
	(gr_line
		(start 235.443014 -74.20864)
		(end 235.448094 -74.183494)
		(stroke
			(width 0.06985)
			(type default)
		)
		(layer "In5.Cu")
	)
	(gr_line
		(start 235.443014 -74.158856)
		(end 235.448094 -74.183494)
		(stroke
			(width 0.06985)
			(type default)
		)
		(layer "In5.Cu")
	)
	(gr_line
		(start 235.483908 -102.73919)
		(end 235.48721 -102.757478)
		(stroke
			(width 0.06985)
			(type default)
		)
		(layer "In5.Cu")
	)
	(gr_line
		(start 235.483908 -102.73919)
		(end 235.48721 -102.72141)
		(stroke
			(width 0.06985)
			(type default)
		)
		(layer "In5.Cu")
	)
	(gr_line
		(start 235.486702 -96.409002)
		(end 235.491782 -96.43364)
		(stroke
			(width 0.06985)
			(type default)
		)
		(layer "In5.Cu")
	)
	(gr_line
		(start 235.486702 -96.409002)
		(end 235.491782 -96.384364)
		(stroke
			(width 0.06985)
			(type default)
		)
		(layer "In5.Cu")
	)
	(gr_line
		(start 235.486702 -90.059002)
		(end 235.491782 -90.084148)
		(stroke
			(width 0.06985)
			(type default)
		)
		(layer "In5.Cu")
	)
	(gr_line
		(start 235.486702 -90.059002)
		(end 235.491782 -90.034364)
		(stroke
			(width 0.06985)
			(type default)
		)
		(layer "In5.Cu")
	)
	(gr_line
		(start 235.486702 -83.709002)
		(end 235.491782 -83.734148)
		(stroke
			(width 0.06985)
			(type default)
		)
		(layer "In5.Cu")
	)
	(gr_line
		(start 235.486702 -83.709002)
		(end 235.491782 -83.684364)
		(stroke
			(width 0.06985)
			(type default)
		)
		(layer "In5.Cu")
	)
	(gr_line
		(start 235.486702 -77.359002)
		(end 235.491782 -77.384148)
		(stroke
			(width 0.06985)
			(type default)
		)
		(layer "In5.Cu")
	)
	(gr_line
		(start 235.486702 -77.359002)
		(end 235.491782 -77.334364)
		(stroke
			(width 0.06985)
			(type default)
		)
		(layer "In5.Cu")
	)
	(gr_line
		(start 235.493814 -66.7131)
		(end 235.493814 -66.893186)
		(stroke
			(width 0.0508)
			(type default)
		)
		(layer "In5.Cu")
	)
	(gr_arc
		(start 235.578142 -65.914778)
		(mid 235.51565 -66.008359)
		(end 235.493814 -66.11874)
		(stroke
			(width 0.0508)
			(type default)
		)
		(layer "In5.Cu")
	)
	(gr_line
		(start 235.578142 -65.914778)
		(end 235.917994 -65.57518)
		(stroke
			(width 0.0508)
			(type default)
		)
		(layer "In5.Cu")
	)
	(gr_line
		(start 235.697014 -66.939414)
		(end 235.716064 -66.958464)
		(stroke
			(width 0.0508)
			(type default)
		)
		(layer "In5.Cu")
	)
	(gr_line
		(start 235.717842 -66.960242)
		(end 235.7374 -66.9798)
		(stroke
			(width 0.0508)
			(type default)
		)
		(layer "In5.Cu")
	)
	(gr_line
		(start 235.7374 -66.9798)
		(end 235.7374 -67.159886)
		(stroke
			(width 0.06985)
			(type default)
		)
		(layer "In5.Cu")
	)
	(gr_arc
		(start 235.748576 -66.049398)
		(mid 235.710433 -66.106502)
		(end 235.697014 -66.173858)
		(stroke
			(width 0.0508)
			(type default)
		)
		(layer "In5.Cu")
	)
	(gr_line
		(start 235.841794 -114.135662)
		(end 235.859066 -114.11077)
		(stroke
			(width 0.06985)
			(type default)
		)
		(layer "In5.Cu")
	)
	(gr_line
		(start 235.859066 -114.11077)
		(end 235.864908 -114.08156)
		(stroke
			(width 0.06985)
			(type default)
		)
		(layer "In5.Cu")
	)
	(gr_arc
		(start 235.871258 -65.998598)
		(mid 235.804862 -66.011789)
		(end 235.748576 -66.049398)
		(stroke
			(width 0.0508)
			(type default)
		)
		(layer "In5.Cu")
	)
	(gr_line
		(start 235.871258 -65.998598)
		(end 235.96727 -65.998598)
		(stroke
			(width 0.0508)
			(type default)
		)
		(layer "In5.Cu")
	)
	(gr_arc
		(start 236.064044 -66.03873)
		(mid 236.019659 -66.009008)
		(end 235.96727 -65.998598)
		(stroke
			(width 0.0508)
			(type default)
		)
		(layer "In5.Cu")
	)
	(gr_line
		(start 236.064044 -66.03873)
		(end 236.071664 -66.04635)
		(stroke
			(width 0.0508)
			(type default)
		)
		(layer "In5.Cu")
	)
	(gr_line
		(start 236.100112 -66.49974)
		(end 236.125512 -66.47434)
		(stroke
			(width 0.0508)
			(type default)
		)
		(layer "In5.Cu")
	)
	(gr_arc
		(start 236.100112 -65.499742)
		(mid 236.001547 -65.519343)
		(end 235.917994 -65.57518)
		(stroke
			(width 0.0508)
			(type default)
		)
		(layer "In5.Cu")
	)
	(gr_arc
		(start 236.125512 -66.176398)
		(mid 236.111541 -66.106008)
		(end 236.071664 -66.04635)
		(stroke
			(width 0.0508)
			(type default)
		)
		(layer "In5.Cu")
	)
	(gr_line
		(start 236.125512 -66.176398)
		(end 236.125512 -66.47434)
		(stroke
			(width 0.0508)
			(type default)
		)
		(layer "In5.Cu")
	)
	(gr_line
		(start 236.4232 -67.0052)
		(end 236.442758 -66.985642)
		(stroke
			(width 0.0508)
			(type default)
		)
		(layer "In5.Cu")
	)
	(gr_line
		(start 236.444536 -66.983864)
		(end 236.493812 -66.934588)
		(stroke
			(width 0.0508)
			(type default)
		)
		(layer "In5.Cu")
	)
	(gr_line
		(start 236.452664 -74.211942)
		(end 236.457744 -74.186796)
		(stroke
			(width 0.06985)
			(type default)
		)
		(layer "In5.Cu")
	)
	(gr_line
		(start 236.452664 -74.162158)
		(end 236.457744 -74.186796)
		(stroke
			(width 0.06985)
			(type default)
		)
		(layer "In5.Cu")
	)
	(gr_line
		(start 236.45368 -86.908132)
		(end 236.45876 -86.882986)
		(stroke
			(width 0.06985)
			(type default)
		)
		(layer "In5.Cu")
	)
	(gr_line
		(start 236.45368 -80.558132)
		(end 236.45876 -80.532986)
		(stroke
			(width 0.06985)
			(type default)
		)
		(layer "In5.Cu")
	)
	(gr_line
		(start 236.453934 -99.559872)
		(end 236.45749 -99.578414)
		(stroke
			(width 0.06985)
			(type default)
		)
		(layer "In5.Cu")
	)
	(gr_line
		(start 236.453934 -93.257116)
		(end 236.45876 -93.232986)
		(stroke
			(width 0.06985)
			(type default)
		)
		(layer "In5.Cu")
	)
	(gr_line
		(start 236.453934 -93.208856)
		(end 236.45876 -93.232986)
		(stroke
			(width 0.06985)
			(type default)
		)
		(layer "In5.Cu")
	)
	(gr_line
		(start 236.453934 -86.858856)
		(end 236.45876 -86.882986)
		(stroke
			(width 0.06985)
			(type default)
		)
		(layer "In5.Cu")
	)
	(gr_line
		(start 236.453934 -80.508856)
		(end 236.45876 -80.532986)
		(stroke
			(width 0.06985)
			(type default)
		)
		(layer "In5.Cu")
	)
	(gr_line
		(start 236.454188 -105.913174)
		(end 236.458506 -105.934002)
		(stroke
			(width 0.06985)
			(type default)
		)
		(layer "In5.Cu")
	)
	(gr_line
		(start 236.454442 -99.596956)
		(end 236.45749 -99.578414)
		(stroke
			(width 0.06985)
			(type default)
		)
		(layer "In5.Cu")
	)
	(gr_line
		(start 236.454696 -105.955338)
		(end 236.458506 -105.934002)
		(stroke
			(width 0.06985)
			(type default)
		)
		(layer "In5.Cu")
	)
	(gr_line
		(start 236.493812 -66.7385)
		(end 236.493812 -66.934588)
		(stroke
			(width 0.0508)
			(type default)
		)
		(layer "In5.Cu")
	)
	(gr_line
		(start 236.522768 -102.758494)
		(end 236.527848 -102.78364)
		(stroke
			(width 0.06985)
			(type default)
		)
		(layer "In5.Cu")
	)
	(gr_line
		(start 236.522768 -96.408494)
		(end 236.527848 -96.43364)
		(stroke
			(width 0.06985)
			(type default)
		)
		(layer "In5.Cu")
	)
	(gr_line
		(start 236.522768 -90.058494)
		(end 236.527848 -90.08364)
		(stroke
			(width 0.06985)
			(type default)
		)
		(layer "In5.Cu")
	)
	(gr_line
		(start 236.522768 -83.708494)
		(end 236.527848 -83.73364)
		(stroke
			(width 0.06985)
			(type default)
		)
		(layer "In5.Cu")
	)
	(gr_line
		(start 236.522768 -77.358494)
		(end 236.527848 -77.38364)
		(stroke
			(width 0.06985)
			(type default)
		)
		(layer "In5.Cu")
	)
	(gr_arc
		(start 236.57814 -64.91478)
		(mid 236.515696 -65.008374)
		(end 236.493812 -65.118742)
		(stroke
			(width 0.0508)
			(type default)
		)
		(layer "In5.Cu")
	)
	(gr_line
		(start 236.57814 -64.91478)
		(end 236.917992 -64.575182)
		(stroke
			(width 0.0508)
			(type default)
		)
		(layer "In5.Cu")
	)
	(gr_line
		(start 236.697012 -66.948812)
		(end 236.732064 -66.983864)
		(stroke
			(width 0.0508)
			(type default)
		)
		(layer "In5.Cu")
	)
	(gr_line
		(start 236.733842 -66.985642)
		(end 236.7534 -67.0052)
		(stroke
			(width 0.0508)
			(type default)
		)
		(layer "In5.Cu")
	)
	(gr_arc
		(start 236.748574 -65.0494)
		(mid 236.710419 -65.106503)
		(end 236.697012 -65.17386)
		(stroke
			(width 0.0508)
			(type default)
		)
		(layer "In5.Cu")
	)
	(gr_line
		(start 236.7534 -67.0052)
		(end 236.7534 -67.201288)
		(stroke
			(width 0.06985)
			(type default)
		)
		(layer "In5.Cu")
	)
	(gr_arc
		(start 236.871256 -64.9986)
		(mid 236.804867 -65.011806)
		(end 236.748574 -65.0494)
		(stroke
			(width 0.0508)
			(type default)
		)
		(layer "In5.Cu")
	)
	(gr_line
		(start 236.871256 -64.9986)
		(end 236.967268 -64.9986)
		(stroke
			(width 0.0508)
			(type default)
		)
		(layer "In5.Cu")
	)
	(gr_arc
		(start 237.064042 -65.038732)
		(mid 237.019642 -65.009065)
		(end 236.967268 -64.9986)
		(stroke
			(width 0.0508)
			(type default)
		)
		(layer "In5.Cu")
	)
	(gr_line
		(start 237.064042 -65.038732)
		(end 237.071662 -65.046352)
		(stroke
			(width 0.0508)
			(type default)
		)
		(layer "In5.Cu")
	)
	(gr_line
		(start 237.10011 -65.499742)
		(end 237.12551 -65.474342)
		(stroke
			(width 0.0508)
			(type default)
		)
		(layer "In5.Cu")
	)
	(gr_arc
		(start 237.10011 -64.499744)
		(mid 237.001548 -64.519349)
		(end 236.917992 -64.575182)
		(stroke
			(width 0.0508)
			(type default)
		)
		(layer "In5.Cu")
	)
	(gr_arc
		(start 237.12551 -65.1764)
		(mid 237.111512 -65.106026)
		(end 237.071662 -65.046352)
		(stroke
			(width 0.0508)
			(type default)
		)
		(layer "In5.Cu")
	)
	(gr_line
		(start 237.12551 -65.1764)
		(end 237.12551 -65.474342)
		(stroke
			(width 0.0508)
			(type default)
		)
		(layer "In5.Cu")
	)
	(gr_line
		(start 237.4392 -67.0052)
		(end 237.4392 -67.19951)
		(stroke
			(width 0.06985)
			(type default)
		)
		(layer "In5.Cu")
	)
	(gr_line
		(start 237.4392 -67.0052)
		(end 237.458758 -66.985642)
		(stroke
			(width 0.0508)
			(type default)
		)
		(layer "In5.Cu")
	)
	(gr_line
		(start 237.460536 -66.983864)
		(end 237.49381 -66.95059)
		(stroke
			(width 0.0508)
			(type default)
		)
		(layer "In5.Cu")
	)
	(gr_line
		(start 237.489492 -105.95864)
		(end 237.494572 -105.933494)
		(stroke
			(width 0.06985)
			(type default)
		)
		(layer "In5.Cu")
	)
	(gr_line
		(start 237.489492 -99.60864)
		(end 237.494572 -99.583494)
		(stroke
			(width 0.06985)
			(type default)
		)
		(layer "In5.Cu")
	)
	(gr_line
		(start 237.489492 -93.25864)
		(end 237.494572 -93.233494)
		(stroke
			(width 0.06985)
			(type default)
		)
		(layer "In5.Cu")
	)
	(gr_line
		(start 237.489492 -86.90864)
		(end 237.494572 -86.883494)
		(stroke
			(width 0.06985)
			(type default)
		)
		(layer "In5.Cu")
	)
	(gr_line
		(start 237.489492 -80.55864)
		(end 237.494572 -80.533494)
		(stroke
			(width 0.06985)
			(type default)
		)
		(layer "In5.Cu")
	)
	(gr_line
		(start 237.489492 -74.20864)
		(end 237.494572 -74.183494)
		(stroke
			(width 0.06985)
			(type default)
		)
		(layer "In5.Cu")
	)
	(gr_line
		(start 237.489492 -74.158856)
		(end 237.494572 -74.183494)
		(stroke
			(width 0.06985)
			(type default)
		)
		(layer "In5.Cu")
	)
	(gr_line
		(start 237.559088 -109.108494)
		(end 237.564168 -109.13364)
		(stroke
			(width 0.06985)
			(type default)
		)
		(layer "In5.Cu")
	)
	(gr_line
		(start 237.559088 -102.758494)
		(end 237.564168 -102.78364)
		(stroke
			(width 0.06985)
			(type default)
		)
		(layer "In5.Cu")
	)
	(gr_line
		(start 237.559088 -96.408494)
		(end 237.564168 -96.43364)
		(stroke
			(width 0.06985)
			(type default)
		)
		(layer "In5.Cu")
	)
	(gr_line
		(start 237.559088 -90.058494)
		(end 237.564168 -90.08364)
		(stroke
			(width 0.06985)
			(type default)
		)
		(layer "In5.Cu")
	)
	(gr_line
		(start 237.559088 -83.708494)
		(end 237.564168 -83.73364)
		(stroke
			(width 0.06985)
			(type default)
		)
		(layer "In5.Cu")
	)
	(gr_line
		(start 237.559088 -77.358494)
		(end 237.564168 -77.38364)
		(stroke
			(width 0.06985)
			(type default)
		)
		(layer "In5.Cu")
	)
	(gr_arc
		(start 237.578138 -65.914778)
		(mid 237.515647 -66.00836)
		(end 237.49381 -66.11874)
		(stroke
			(width 0.0508)
			(type default)
		)
		(layer "In5.Cu")
	)
	(gr_line
		(start 237.578138 -65.914778)
		(end 237.91799 -65.57518)
		(stroke
			(width 0.0508)
			(type default)
		)
		(layer "In5.Cu")
	)
	(gr_line
		(start 237.69701 -66.93281)
		(end 237.748064 -66.983864)
		(stroke
			(width 0.0508)
			(type default)
		)
		(layer "In5.Cu")
	)
	(gr_line
		(start 237.69701 -66.7385)
		(end 237.69701 -66.93281)
		(stroke
			(width 0.0508)
			(type default)
		)
		(layer "In5.Cu")
	)
	(gr_arc
		(start 237.748572 -66.049398)
		(mid 237.710429 -66.106502)
		(end 237.69701 -66.173858)
		(stroke
			(width 0.0508)
			(type default)
		)
		(layer "In5.Cu")
	)
	(gr_line
		(start 237.749842 -66.985642)
		(end 237.7694 -67.0052)
		(stroke
			(width 0.0508)
			(type default)
		)
		(layer "In5.Cu")
	)
	(gr_line
		(start 237.752128 -116.115338)
		(end 237.7694 -116.090446)
		(stroke
			(width 0.06985)
			(type default)
		)
		(layer "In5.Cu")
	)
	(gr_line
		(start 237.7694 -116.090446)
		(end 237.775242 -116.061236)
		(stroke
			(width 0.06985)
			(type default)
		)
		(layer "In5.Cu")
	)
	(gr_arc
		(start 237.871254 -65.998598)
		(mid 237.804858 -66.011791)
		(end 237.748572 -66.049398)
		(stroke
			(width 0.0508)
			(type default)
		)
		(layer "In5.Cu")
	)
	(gr_line
		(start 237.871254 -65.998598)
		(end 237.967266 -65.998598)
		(stroke
			(width 0.0508)
			(type default)
		)
		(layer "In5.Cu")
	)
	(gr_arc
		(start 238.06404 -66.03873)
		(mid 238.019655 -66.009009)
		(end 237.967266 -65.998598)
		(stroke
			(width 0.0508)
			(type default)
		)
		(layer "In5.Cu")
	)
	(gr_line
		(start 238.06404 -66.03873)
		(end 238.07166 -66.04635)
		(stroke
			(width 0.0508)
			(type default)
		)
		(layer "In5.Cu")
	)
	(gr_line
		(start 238.100108 -66.49974)
		(end 238.125508 -66.47434)
		(stroke
			(width 0.0508)
			(type default)
		)
		(layer "In5.Cu")
	)
	(gr_arc
		(start 238.100108 -65.499742)
		(mid 238.001544 -65.519345)
		(end 237.91799 -65.57518)
		(stroke
			(width 0.0508)
			(type default)
		)
		(layer "In5.Cu")
	)
	(gr_arc
		(start 238.125508 -66.176398)
		(mid 238.111537 -66.106008)
		(end 238.07166 -66.04635)
		(stroke
			(width 0.0508)
			(type default)
		)
		(layer "In5.Cu")
	)
	(gr_line
		(start 238.125508 -66.176398)
		(end 238.125508 -66.47434)
		(stroke
			(width 0.0508)
			(type default)
		)
		(layer "In5.Cu")
	)
	(gr_line
		(start 238.4298 -67.0052)
		(end 238.449358 -66.985642)
		(stroke
			(width 0.0508)
			(type default)
		)
		(layer "In5.Cu")
	)
	(gr_line
		(start 238.451136 -66.983864)
		(end 238.493808 -66.941192)
		(stroke
			(width 0.0508)
			(type default)
		)
		(layer "In5.Cu")
	)
	(gr_line
		(start 238.493808 -66.7385)
		(end 238.493808 -66.941192)
		(stroke
			(width 0.0508)
			(type default)
		)
		(layer "In5.Cu")
	)
	(gr_line
		(start 238.525812 -112.30864)
		(end 238.530892 -112.283494)
		(stroke
			(width 0.06985)
			(type default)
		)
		(layer "In5.Cu")
	)
	(gr_line
		(start 238.525812 -105.95864)
		(end 238.530892 -105.933494)
		(stroke
			(width 0.06985)
			(type default)
		)
		(layer "In5.Cu")
	)
	(gr_line
		(start 238.525812 -99.60864)
		(end 238.530892 -99.583494)
		(stroke
			(width 0.06985)
			(type default)
		)
		(layer "In5.Cu")
	)
	(gr_line
		(start 238.525812 -93.25864)
		(end 238.530892 -93.233494)
		(stroke
			(width 0.06985)
			(type default)
		)
		(layer "In5.Cu")
	)
	(gr_line
		(start 238.525812 -86.90864)
		(end 238.530892 -86.883494)
		(stroke
			(width 0.06985)
			(type default)
		)
		(layer "In5.Cu")
	)
	(gr_line
		(start 238.525812 -80.55864)
		(end 238.530892 -80.533494)
		(stroke
			(width 0.06985)
			(type default)
		)
		(layer "In5.Cu")
	)
	(gr_line
		(start 238.525812 -74.20864)
		(end 238.530892 -74.183494)
		(stroke
			(width 0.06985)
			(type default)
		)
		(layer "In5.Cu")
	)
	(gr_line
		(start 238.525812 -74.158856)
		(end 238.530892 -74.183494)
		(stroke
			(width 0.06985)
			(type default)
		)
		(layer "In5.Cu")
	)
	(gr_line
		(start 238.569246 -109.108494)
		(end 238.574326 -109.13364)
		(stroke
			(width 0.06985)
			(type default)
		)
		(layer "In5.Cu")
	)
	(gr_line
		(start 238.569246 -102.758494)
		(end 238.574326 -102.78364)
		(stroke
			(width 0.06985)
			(type default)
		)
		(layer "In5.Cu")
	)
	(gr_line
		(start 238.569246 -96.408494)
		(end 238.574326 -96.43364)
		(stroke
			(width 0.06985)
			(type default)
		)
		(layer "In5.Cu")
	)
	(gr_line
		(start 238.569246 -90.058494)
		(end 238.574326 -90.08364)
		(stroke
			(width 0.06985)
			(type default)
		)
		(layer "In5.Cu")
	)
	(gr_line
		(start 238.569246 -83.708494)
		(end 238.574326 -83.73364)
		(stroke
			(width 0.06985)
			(type default)
		)
		(layer "In5.Cu")
	)
	(gr_line
		(start 238.569246 -77.358494)
		(end 238.574326 -77.38364)
		(stroke
			(width 0.06985)
			(type default)
		)
		(layer "In5.Cu")
	)
	(gr_arc
		(start 238.578136 -64.91478)
		(mid 238.515692 -65.008374)
		(end 238.493808 -65.118742)
		(stroke
			(width 0.0508)
			(type default)
		)
		(layer "In5.Cu")
	)
	(gr_line
		(start 238.578136 -64.91478)
		(end 238.917988 -64.575182)
		(stroke
			(width 0.0508)
			(type default)
		)
		(layer "In5.Cu")
	)
	(gr_line
		(start 238.697008 -66.942208)
		(end 238.738664 -66.983864)
		(stroke
			(width 0.0508)
			(type default)
		)
		(layer "In5.Cu")
	)
	(gr_line
		(start 238.740442 -66.985642)
		(end 238.76 -67.0052)
		(stroke
			(width 0.0508)
			(type default)
		)
		(layer "In5.Cu")
	)
	(gr_line
		(start 238.742728 -116.214144)
		(end 238.76 -116.189252)
		(stroke
			(width 0.06985)
			(type default)
		)
		(layer "In5.Cu")
	)
	(gr_arc
		(start 238.74857 -65.0494)
		(mid 238.710415 -65.106503)
		(end 238.697008 -65.17386)
		(stroke
			(width 0.0508)
			(type default)
		)
		(layer "In5.Cu")
	)
	(gr_line
		(start 238.76 -116.189252)
		(end 238.765842 -116.160042)
		(stroke
			(width 0.06985)
			(type default)
		)
		(layer "In5.Cu")
	)
	(gr_line
		(start 238.76 -67.0052)
		(end 238.76 -67.207892)
		(stroke
			(width 0.06985)
			(type default)
		)
		(layer "In5.Cu")
	)
	(gr_arc
		(start 238.871252 -64.9986)
		(mid 238.804863 -65.011806)
		(end 238.74857 -65.0494)
		(stroke
			(width 0.0508)
			(type default)
		)
		(layer "In5.Cu")
	)
	(gr_line
		(start 238.871252 -64.9986)
		(end 238.967264 -64.9986)
		(stroke
			(width 0.0508)
			(type default)
		)
		(layer "In5.Cu")
	)
	(gr_arc
		(start 239.064038 -65.038732)
		(mid 239.019638 -65.009065)
		(end 238.967264 -64.9986)
		(stroke
			(width 0.0508)
			(type default)
		)
		(layer "In5.Cu")
	)
	(gr_line
		(start 239.064038 -65.038732)
		(end 239.071658 -65.046352)
		(stroke
			(width 0.0508)
			(type default)
		)
		(layer "In5.Cu")
	)
	(gr_line
		(start 239.100106 -65.499742)
		(end 239.125506 -65.474342)
		(stroke
			(width 0.0508)
			(type default)
		)
		(layer "In5.Cu")
	)
	(gr_arc
		(start 239.100106 -64.499744)
		(mid 239.001544 -64.519349)
		(end 238.917988 -64.575182)
		(stroke
			(width 0.0508)
			(type default)
		)
		(layer "In5.Cu")
	)
	(gr_arc
		(start 239.100106 -37.203126)
		(mid 239.070358 -37.131265)
		(end 238.998506 -37.101526)
		(stroke
			(width 0.0508)
			(type default)
		)
		(layer "In5.Cu")
	)
	(gr_line
		(start 239.100106 -37.203126)
		(end 239.100106 -37.500052)
		(stroke
			(width 0.0508)
			(type default)
		)
		(layer "In5.Cu")
	)
	(gr_line
		(start 239.100106 -36.500054)
		(end 239.226344 -36.500054)
		(stroke
			(width 0.0508)
			(type default)
		)
		(layer "In5.Cu")
	)
	(gr_line
		(start 239.100106 -34.152332)
		(end 239.100106 -34.500058)
		(stroke
			(width 0.0508)
			(type default)
		)
		(layer "In5.Cu")
	)
	(gr_arc
		(start 239.100106 -33.695132)
		(mid 239.137315 -33.784912)
		(end 239.227106 -33.822132)
		(stroke
			(width 0.0508)
			(type default)
		)
		(layer "In5.Cu")
	)
	(gr_line
		(start 239.100106 -33.50006)
		(end 239.100106 -33.695132)
		(stroke
			(width 0.0508)
			(type default)
		)
		(layer "In5.Cu")
	)
	(gr_arc
		(start 239.125506 -65.1764)
		(mid 239.111508 -65.106026)
		(end 239.071658 -65.046352)
		(stroke
			(width 0.0508)
			(type default)
		)
		(layer "In5.Cu")
	)
	(gr_line
		(start 239.125506 -65.1764)
		(end 239.125506 -65.474342)
		(stroke
			(width 0.0508)
			(type default)
		)
		(layer "In5.Cu")
	)
	(gr_line
		(start 239.204246 -36.898326)
		(end 239.226344 -36.898326)
		(stroke
			(width 0.0508)
			(type default)
		)
		(layer "In5.Cu")
	)
	(gr_arc
		(start 239.226344 -36.898326)
		(mid 239.42548 -36.69919)
		(end 239.226344 -36.500054)
		(stroke
			(width 0.0508)
			(type default)
		)
		(layer "In5.Cu")
	)
	(gr_arc
		(start 239.227106 -34.025332)
		(mid 239.137311 -34.062529)
		(end 239.100106 -34.152332)
		(stroke
			(width 0.0508)
			(type default)
		)
		(layer "In5.Cu")
	)
	(gr_line
		(start 239.53597 -112.30864)
		(end 239.54105 -112.283494)
		(stroke
			(width 0.06985)
			(type default)
		)
		(layer "In5.Cu")
	)
	(gr_line
		(start 239.53597 -105.95864)
		(end 239.54105 -105.933494)
		(stroke
			(width 0.06985)
			(type default)
		)
		(layer "In5.Cu")
	)
	(gr_line
		(start 239.53597 -99.60864)
		(end 239.54105 -99.583494)
		(stroke
			(width 0.06985)
			(type default)
		)
		(layer "In5.Cu")
	)
	(gr_line
		(start 239.53597 -93.25864)
		(end 239.54105 -93.233494)
		(stroke
			(width 0.06985)
			(type default)
		)
		(layer "In5.Cu")
	)
	(gr_line
		(start 239.53597 -86.90864)
		(end 239.54105 -86.883494)
		(stroke
			(width 0.06985)
			(type default)
		)
		(layer "In5.Cu")
	)
	(gr_line
		(start 239.53597 -80.55864)
		(end 239.54105 -80.533494)
		(stroke
			(width 0.06985)
			(type default)
		)
		(layer "In5.Cu")
	)
	(gr_line
		(start 239.53597 -74.20864)
		(end 239.54105 -74.183494)
		(stroke
			(width 0.06985)
			(type default)
		)
		(layer "In5.Cu")
	)
	(gr_line
		(start 239.53597 -74.158856)
		(end 239.54105 -74.183494)
		(stroke
			(width 0.06985)
			(type default)
		)
		(layer "In5.Cu")
	)
	(gr_line
		(start 239.6998 -36.703)
		(end 239.6998 -36.7284)
		(stroke
			(width 0.0508)
			(type default)
		)
		(layer "In5.Cu")
	)
	(gr_line
		(start 239.6998 -36.703)
		(end 239.719358 -36.683442)
		(stroke
			(width 0.0508)
			(type default)
		)
		(layer "In5.Cu")
	)
	(gr_line
		(start 239.721136 -36.681664)
		(end 239.73155 -36.67125)
		(stroke
			(width 0.0508)
			(type default)
		)
		(layer "In5.Cu")
	)
	(gr_arc
		(start 239.73155 -36.67125)
		(mid 239.75505 -36.636051)
		(end 239.7633 -36.594542)
		(stroke
			(width 0.0508)
			(type default)
		)
		(layer "In5.Cu")
	)
	(gr_arc
		(start 239.9665 -36.594542)
		(mid 239.974746 -36.63605)
		(end 239.99825 -36.67125)
		(stroke
			(width 0.0508)
			(type default)
		)
		(layer "In5.Cu")
	)
	(gr_line
		(start 239.99825 -36.67125)
		(end 240.008664 -36.681664)
		(stroke
			(width 0.0508)
			(type default)
		)
		(layer "In5.Cu")
	)
	(gr_line
		(start 240.010442 -36.683442)
		(end 240.03 -36.703)
		(stroke
			(width 0.0508)
			(type default)
		)
		(layer "In5.Cu")
	)
	(gr_line
		(start 240.03 -36.703)
		(end 240.03 -36.7284)
		(stroke
			(width 0.0508)
			(type default)
		)
		(layer "In5.Cu")
	)
	(gr_line
		(start 241.427 -66.9544)
		(end 241.446558 -66.934842)
		(stroke
			(width 0.0508)
			(type default)
		)
		(layer "In5.Cu")
	)
	(gr_line
		(start 241.448336 -66.933064)
		(end 241.493548 -66.887852)
		(stroke
			(width 0.0508)
			(type default)
		)
		(layer "In5.Cu")
	)
	(gr_line
		(start 241.493548 -66.6877)
		(end 241.493548 -66.887852)
		(stroke
			(width 0.0508)
			(type default)
		)
		(layer "In5.Cu")
	)
	(gr_arc
		(start 241.577876 -64.91478)
		(mid 241.515432 -65.008374)
		(end 241.493548 -65.118742)
		(stroke
			(width 0.0508)
			(type default)
		)
		(layer "In5.Cu")
	)
	(gr_line
		(start 241.577876 -64.91478)
		(end 241.917728 -64.575182)
		(stroke
			(width 0.0508)
			(type default)
		)
		(layer "In5.Cu")
	)
	(gr_line
		(start 241.625882 -102.758494)
		(end 241.630962 -102.78364)
		(stroke
			(width 0.06985)
			(type default)
		)
		(layer "In5.Cu")
	)
	(gr_line
		(start 241.625882 -90.058494)
		(end 241.630962 -90.08364)
		(stroke
			(width 0.06985)
			(type default)
		)
		(layer "In5.Cu")
	)
	(gr_line
		(start 241.696748 -66.893948)
		(end 241.735864 -66.933064)
		(stroke
			(width 0.0508)
			(type default)
		)
		(layer "In5.Cu")
	)
	(gr_line
		(start 241.737642 -66.934842)
		(end 241.7572 -66.9544)
		(stroke
			(width 0.0508)
			(type default)
		)
		(layer "In5.Cu")
	)
	(gr_line
		(start 241.739928 -116.511324)
		(end 241.7572 -116.486432)
		(stroke
			(width 0.06985)
			(type default)
		)
		(layer "In5.Cu")
	)
	(gr_arc
		(start 241.74831 -65.0494)
		(mid 241.710155 -65.106503)
		(end 241.696748 -65.17386)
		(stroke
			(width 0.0508)
			(type default)
		)
		(layer "In5.Cu")
	)
	(gr_line
		(start 241.7572 -116.486432)
		(end 241.763042 -116.457222)
		(stroke
			(width 0.06985)
			(type default)
		)
		(layer "In5.Cu")
	)
	(gr_line
		(start 241.7572 -66.9544)
		(end 241.7572 -67.154552)
		(stroke
			(width 0.06985)
			(type default)
		)
		(layer "In5.Cu")
	)
	(gr_arc
		(start 241.870992 -64.9986)
		(mid 241.804603 -65.011806)
		(end 241.74831 -65.0494)
		(stroke
			(width 0.0508)
			(type default)
		)
		(layer "In5.Cu")
	)
	(gr_line
		(start 241.870992 -64.9986)
		(end 241.967004 -64.9986)
		(stroke
			(width 0.0508)
			(type default)
		)
		(layer "In5.Cu")
	)
	(gr_arc
		(start 242.063778 -65.038732)
		(mid 242.019378 -65.009065)
		(end 241.967004 -64.9986)
		(stroke
			(width 0.0508)
			(type default)
		)
		(layer "In5.Cu")
	)
	(gr_line
		(start 242.063778 -65.038732)
		(end 242.071398 -65.046352)
		(stroke
			(width 0.0508)
			(type default)
		)
		(layer "In5.Cu")
	)
	(gr_line
		(start 242.099846 -65.499742)
		(end 242.125246 -65.474342)
		(stroke
			(width 0.0508)
			(type default)
		)
		(layer "In5.Cu")
	)
	(gr_arc
		(start 242.099846 -64.499744)
		(mid 242.001284 -64.519349)
		(end 241.917728 -64.575182)
		(stroke
			(width 0.0508)
			(type default)
		)
		(layer "In5.Cu")
	)
	(gr_arc
		(start 242.125246 -65.1764)
		(mid 242.111248 -65.106026)
		(end 242.071398 -65.046352)
		(stroke
			(width 0.0508)
			(type default)
		)
		(layer "In5.Cu")
	)
	(gr_line
		(start 242.125246 -65.1764)
		(end 242.125246 -65.474342)
		(stroke
			(width 0.0508)
			(type default)
		)
		(layer "In5.Cu")
	)
	(gr_line
		(start 242.4176 -66.929)
		(end 242.437158 -66.909442)
		(stroke
			(width 0.0508)
			(type default)
		)
		(layer "In5.Cu")
	)
	(gr_line
		(start 242.438936 -66.907664)
		(end 242.493546 -66.853054)
		(stroke
			(width 0.0508)
			(type default)
		)
		(layer "In5.Cu")
	)
	(gr_line
		(start 242.493546 -66.6623)
		(end 242.493546 -66.853054)
		(stroke
			(width 0.0508)
			(type default)
		)
		(layer "In5.Cu")
	)
	(gr_arc
		(start 242.577874 -65.914778)
		(mid 242.51543 -66.008372)
		(end 242.493546 -66.11874)
		(stroke
			(width 0.0508)
			(type default)
		)
		(layer "In5.Cu")
	)
	(gr_line
		(start 242.577874 -65.914778)
		(end 242.917726 -65.57518)
		(stroke
			(width 0.0508)
			(type default)
		)
		(layer "In5.Cu")
	)
	(gr_line
		(start 242.636294 -102.758494)
		(end 242.641374 -102.78364)
		(stroke
			(width 0.06985)
			(type default)
		)
		(layer "In5.Cu")
	)
	(gr_line
		(start 242.636294 -90.058494)
		(end 242.641374 -90.08364)
		(stroke
			(width 0.06985)
			(type default)
		)
		(layer "In5.Cu")
	)
	(gr_line
		(start 242.696746 -66.877946)
		(end 242.726464 -66.907664)
		(stroke
			(width 0.0508)
			(type default)
		)
		(layer "In5.Cu")
	)
	(gr_line
		(start 242.728242 -66.909442)
		(end 242.7478 -66.929)
		(stroke
			(width 0.0508)
			(type default)
		)
		(layer "In5.Cu")
	)
	(gr_line
		(start 242.730528 -116.609876)
		(end 242.7478 -116.584984)
		(stroke
			(width 0.06985)
			(type default)
		)
		(layer "In5.Cu")
	)
	(gr_line
		(start 242.7478 -116.584984)
		(end 242.753642 -116.555774)
		(stroke
			(width 0.06985)
			(type default)
		)
		(layer "In5.Cu")
	)
	(gr_line
		(start 242.7478 -66.929)
		(end 242.7478 -67.119754)
		(stroke
			(width 0.06985)
			(type default)
		)
		(layer "In5.Cu")
	)
	(gr_arc
		(start 242.748308 -66.049398)
		(mid 242.710153 -66.106501)
		(end 242.696746 -66.173858)
		(stroke
			(width 0.0508)
			(type default)
		)
		(layer "In5.Cu")
	)
	(gr_arc
		(start 242.87099 -65.998598)
		(mid 242.804601 -66.011804)
		(end 242.748308 -66.049398)
		(stroke
			(width 0.0508)
			(type default)
		)
		(layer "In5.Cu")
	)
	(gr_line
		(start 242.87099 -65.998598)
		(end 242.967002 -65.998598)
		(stroke
			(width 0.0508)
			(type default)
		)
		(layer "In5.Cu")
	)
	(gr_arc
		(start 243.063776 -66.03873)
		(mid 243.019376 -66.009063)
		(end 242.967002 -65.998598)
		(stroke
			(width 0.0508)
			(type default)
		)
		(layer "In5.Cu")
	)
	(gr_line
		(start 243.063776 -66.03873)
		(end 243.071396 -66.04635)
		(stroke
			(width 0.0508)
			(type default)
		)
		(layer "In5.Cu")
	)
	(gr_line
		(start 243.099844 -66.49974)
		(end 243.125244 -66.47434)
		(stroke
			(width 0.0508)
			(type default)
		)
		(layer "In5.Cu")
	)
	(gr_arc
		(start 243.099844 -65.499742)
		(mid 243.001282 -65.519347)
		(end 242.917726 -65.57518)
		(stroke
			(width 0.0508)
			(type default)
		)
		(layer "In5.Cu")
	)
	(gr_arc
		(start 243.125244 -66.176398)
		(mid 243.111246 -66.106024)
		(end 243.071396 -66.04635)
		(stroke
			(width 0.0508)
			(type default)
		)
		(layer "In5.Cu")
	)
	(gr_line
		(start 243.125244 -66.176398)
		(end 243.125244 -66.47434)
		(stroke
			(width 0.0508)
			(type default)
		)
		(layer "In5.Cu")
	)
	(gr_line
		(start 243.227606 -109.13364)
		(end 243.232686 -109.108494)
		(stroke
			(width 0.06985)
			(type default)
		)
		(layer "In5.Cu")
	)
	(gr_line
		(start 243.227606 -96.43364)
		(end 243.232686 -96.408494)
		(stroke
			(width 0.06985)
			(type default)
		)
		(layer "In5.Cu")
	)
	(gr_line
		(start 243.227606 -83.73364)
		(end 243.232686 -83.708494)
		(stroke
			(width 0.06985)
			(type default)
		)
		(layer "In5.Cu")
	)
	(gr_line
		(start 243.227606 -83.683856)
		(end 243.232686 -83.708494)
		(stroke
			(width 0.06985)
			(type default)
		)
		(layer "In5.Cu")
	)
	(gr_line
		(start 243.4336 -67.0052)
		(end 243.4336 -67.204844)
		(stroke
			(width 0.06985)
			(type default)
		)
		(layer "In5.Cu")
	)
	(gr_line
		(start 243.4336 -67.0052)
		(end 243.453158 -66.985642)
		(stroke
			(width 0.0508)
			(type default)
		)
		(layer "In5.Cu")
	)
	(gr_line
		(start 243.454936 -66.983864)
		(end 243.493544 -66.945256)
		(stroke
			(width 0.0508)
			(type default)
		)
		(layer "In5.Cu")
	)
	(gr_arc
		(start 243.577872 -64.91478)
		(mid 243.515428 -65.008374)
		(end 243.493544 -65.118742)
		(stroke
			(width 0.0508)
			(type default)
		)
		(layer "In5.Cu")
	)
	(gr_line
		(start 243.577872 -64.91478)
		(end 243.917724 -64.575182)
		(stroke
			(width 0.0508)
			(type default)
		)
		(layer "In5.Cu")
	)
	(gr_line
		(start 243.672614 -102.758494)
		(end 243.677694 -102.78364)
		(stroke
			(width 0.06985)
			(type default)
		)
		(layer "In5.Cu")
	)
	(gr_line
		(start 243.672614 -90.058494)
		(end 243.677694 -90.08364)
		(stroke
			(width 0.06985)
			(type default)
		)
		(layer "In5.Cu")
	)
	(gr_line
		(start 243.696744 -66.938144)
		(end 243.742464 -66.983864)
		(stroke
			(width 0.0508)
			(type default)
		)
		(layer "In5.Cu")
	)
	(gr_line
		(start 243.696744 -66.7385)
		(end 243.696744 -66.938144)
		(stroke
			(width 0.0508)
			(type default)
		)
		(layer "In5.Cu")
	)
	(gr_line
		(start 243.744242 -66.985642)
		(end 243.7638 -67.0052)
		(stroke
			(width 0.0508)
			(type default)
		)
		(layer "In5.Cu")
	)
	(gr_arc
		(start 243.748306 -65.0494)
		(mid 243.710151 -65.106503)
		(end 243.696744 -65.17386)
		(stroke
			(width 0.0508)
			(type default)
		)
		(layer "In5.Cu")
	)
	(gr_line
		(start 243.820442 -118.01094)
		(end 243.84 -117.983)
		(stroke
			(width 0.06985)
			(type default)
		)
		(layer "In5.Cu")
	)
	(gr_line
		(start 243.84 -117.983)
		(end 243.845842 -117.94998)
		(stroke
			(width 0.06985)
			(type default)
		)
		(layer "In5.Cu")
	)
	(gr_arc
		(start 243.870988 -64.9986)
		(mid 243.804599 -65.011806)
		(end 243.748306 -65.0494)
		(stroke
			(width 0.0508)
			(type default)
		)
		(layer "In5.Cu")
	)
	(gr_line
		(start 243.870988 -64.9986)
		(end 243.967 -64.9986)
		(stroke
			(width 0.0508)
			(type default)
		)
		(layer "In5.Cu")
	)
	(gr_arc
		(start 244.063774 -65.038732)
		(mid 244.019374 -65.009065)
		(end 243.967 -64.9986)
		(stroke
			(width 0.0508)
			(type default)
		)
		(layer "In5.Cu")
	)
	(gr_line
		(start 244.063774 -65.038732)
		(end 244.071394 -65.046352)
		(stroke
			(width 0.0508)
			(type default)
		)
		(layer "In5.Cu")
	)
	(gr_line
		(start 244.099842 -65.499742)
		(end 244.125242 -65.474342)
		(stroke
			(width 0.0508)
			(type default)
		)
		(layer "In5.Cu")
	)
	(gr_arc
		(start 244.099842 -64.499744)
		(mid 244.00128 -64.519349)
		(end 243.917724 -64.575182)
		(stroke
			(width 0.0508)
			(type default)
		)
		(layer "In5.Cu")
	)
	(gr_arc
		(start 244.125242 -65.1764)
		(mid 244.111244 -65.106026)
		(end 244.071394 -65.046352)
		(stroke
			(width 0.0508)
			(type default)
		)
		(layer "In5.Cu")
	)
	(gr_line
		(start 244.125242 -65.1764)
		(end 244.125242 -65.474342)
		(stroke
			(width 0.0508)
			(type default)
		)
		(layer "In5.Cu")
	)
	(gr_line
		(start 244.238018 -109.13364)
		(end 244.243098 -109.108494)
		(stroke
			(width 0.06985)
			(type default)
		)
		(layer "In5.Cu")
	)
	(gr_line
		(start 244.238018 -96.43364)
		(end 244.243098 -96.408494)
		(stroke
			(width 0.06985)
			(type default)
		)
		(layer "In5.Cu")
	)
	(gr_line
		(start 244.238018 -83.73364)
		(end 244.243098 -83.708494)
		(stroke
			(width 0.06985)
			(type default)
		)
		(layer "In5.Cu")
	)
	(gr_line
		(start 244.238018 -83.683856)
		(end 244.243098 -83.708494)
		(stroke
			(width 0.06985)
			(type default)
		)
		(layer "In5.Cu")
	)
	(gr_line
		(start 244.4242 -66.9544)
		(end 244.443758 -66.934842)
		(stroke
			(width 0.0508)
			(type default)
		)
		(layer "In5.Cu")
	)
	(gr_line
		(start 244.445536 -66.933064)
		(end 244.493542 -66.885058)
		(stroke
			(width 0.0508)
			(type default)
		)
		(layer "In5.Cu")
	)
	(gr_line
		(start 244.493542 -66.6877)
		(end 244.493542 -66.885058)
		(stroke
			(width 0.0508)
			(type default)
		)
		(layer "In5.Cu")
	)
	(gr_arc
		(start 244.57787 -65.914778)
		(mid 244.515426 -66.008372)
		(end 244.493542 -66.11874)
		(stroke
			(width 0.0508)
			(type default)
		)
		(layer "In5.Cu")
	)
	(gr_line
		(start 244.57787 -65.914778)
		(end 244.917722 -65.57518)
		(stroke
			(width 0.0508)
			(type default)
		)
		(layer "In5.Cu")
	)
	(gr_line
		(start 244.682772 -102.758494)
		(end 244.687852 -102.78364)
		(stroke
			(width 0.06985)
			(type default)
		)
		(layer "In5.Cu")
	)
	(gr_line
		(start 244.682772 -90.058494)
		(end 244.687852 -90.08364)
		(stroke
			(width 0.06985)
			(type default)
		)
		(layer "In5.Cu")
	)
	(gr_line
		(start 244.696742 -66.896742)
		(end 244.733064 -66.933064)
		(stroke
			(width 0.0508)
			(type default)
		)
		(layer "In5.Cu")
	)
	(gr_line
		(start 244.734842 -66.934842)
		(end 244.7544 -66.9544)
		(stroke
			(width 0.0508)
			(type default)
		)
		(layer "In5.Cu")
	)
	(gr_arc
		(start 244.748304 -66.049398)
		(mid 244.710149 -66.106501)
		(end 244.696742 -66.173858)
		(stroke
			(width 0.0508)
			(type default)
		)
		(layer "In5.Cu")
	)
	(gr_line
		(start 244.7544 -66.9544)
		(end 244.7544 -67.151758)
		(stroke
			(width 0.06985)
			(type default)
		)
		(layer "In5.Cu")
	)
	(gr_arc
		(start 244.870986 -65.998598)
		(mid 244.804597 -66.011804)
		(end 244.748304 -66.049398)
		(stroke
			(width 0.0508)
			(type default)
		)
		(layer "In5.Cu")
	)
	(gr_line
		(start 244.870986 -65.998598)
		(end 244.966998 -65.998598)
		(stroke
			(width 0.0508)
			(type default)
		)
		(layer "In5.Cu")
	)
	(gr_arc
		(start 245.063772 -66.03873)
		(mid 245.019372 -66.009063)
		(end 244.966998 -65.998598)
		(stroke
			(width 0.0508)
			(type default)
		)
		(layer "In5.Cu")
	)
	(gr_line
		(start 245.063772 -66.03873)
		(end 245.071392 -66.04635)
		(stroke
			(width 0.0508)
			(type default)
		)
		(layer "In5.Cu")
	)
	(gr_line
		(start 245.09984 -66.49974)
		(end 245.12524 -66.47434)
		(stroke
			(width 0.0508)
			(type default)
		)
		(layer "In5.Cu")
	)
	(gr_arc
		(start 245.09984 -65.499742)
		(mid 245.001278 -65.519347)
		(end 244.917722 -65.57518)
		(stroke
			(width 0.0508)
			(type default)
		)
		(layer "In5.Cu")
	)
	(gr_arc
		(start 245.12524 -66.176398)
		(mid 245.111242 -66.106024)
		(end 245.071392 -66.04635)
		(stroke
			(width 0.0508)
			(type default)
		)
		(layer "In5.Cu")
	)
	(gr_line
		(start 245.12524 -66.176398)
		(end 245.12524 -66.47434)
		(stroke
			(width 0.0508)
			(type default)
		)
		(layer "In5.Cu")
	)
	(gr_line
		(start 245.274338 -96.43364)
		(end 245.279418 -96.408494)
		(stroke
			(width 0.06985)
			(type default)
		)
		(layer "In5.Cu")
	)
	(gr_line
		(start 245.274338 -83.73364)
		(end 245.279418 -83.708494)
		(stroke
			(width 0.06985)
			(type default)
		)
		(layer "In5.Cu")
	)
	(gr_line
		(start 245.274338 -83.683856)
		(end 245.279418 -83.708494)
		(stroke
			(width 0.06985)
			(type default)
		)
		(layer "In5.Cu")
	)
	(gr_line
		(start 245.341648 -109.420914)
		(end 245.345966 -109.441742)
		(stroke
			(width 0.06985)
			(type default)
		)
		(layer "In5.Cu")
	)
	(gr_line
		(start 245.342156 -109.463078)
		(end 245.345966 -109.441742)
		(stroke
			(width 0.06985)
			(type default)
		)
		(layer "In5.Cu")
	)
	(gr_line
		(start 245.350792 -118.784116)
		(end 245.37035 -118.756176)
		(stroke
			(width 0.06985)
			(type default)
		)
		(layer "In5.Cu")
	)
	(gr_line
		(start 245.37035 -118.756176)
		(end 245.376192 -118.723156)
		(stroke
			(width 0.06985)
			(type default)
		)
		(layer "In5.Cu")
	)
	(gr_line
		(start 245.4148 -67.0052)
		(end 245.434358 -66.985642)
		(stroke
			(width 0.0508)
			(type default)
		)
		(layer "In5.Cu")
	)
	(gr_line
		(start 245.436136 -66.983864)
		(end 245.49354 -66.92646)
		(stroke
			(width 0.0508)
			(type default)
		)
		(layer "In5.Cu")
	)
	(gr_line
		(start 245.49354 -66.7385)
		(end 245.49354 -66.92646)
		(stroke
			(width 0.0508)
			(type default)
		)
		(layer "In5.Cu")
	)
	(gr_arc
		(start 245.577868 -64.91478)
		(mid 245.515424 -65.008374)
		(end 245.49354 -65.118742)
		(stroke
			(width 0.0508)
			(type default)
		)
		(layer "In5.Cu")
	)
	(gr_line
		(start 245.577868 -64.91478)
		(end 245.91772 -64.575182)
		(stroke
			(width 0.0508)
			(type default)
		)
		(layer "In5.Cu")
	)
	(gr_line
		(start 245.693184 -102.758494)
		(end 245.698264 -102.78364)
		(stroke
			(width 0.06985)
			(type default)
		)
		(layer "In5.Cu")
	)
	(gr_line
		(start 245.693184 -90.058494)
		(end 245.698264 -90.08364)
		(stroke
			(width 0.06985)
			(type default)
		)
		(layer "In5.Cu")
	)
	(gr_line
		(start 245.69674 -66.95694)
		(end 245.723664 -66.983864)
		(stroke
			(width 0.0508)
			(type default)
		)
		(layer "In5.Cu")
	)
	(gr_line
		(start 245.725442 -66.985642)
		(end 245.745 -67.0052)
		(stroke
			(width 0.0508)
			(type default)
		)
		(layer "In5.Cu")
	)
	(gr_line
		(start 245.745 -67.0052)
		(end 245.745 -67.19316)
		(stroke
			(width 0.06985)
			(type default)
		)
		(layer "In5.Cu")
	)
	(gr_arc
		(start 245.748302 -65.0494)
		(mid 245.710147 -65.106503)
		(end 245.69674 -65.17386)
		(stroke
			(width 0.0508)
			(type default)
		)
		(layer "In5.Cu")
	)
	(gr_arc
		(start 245.870984 -64.9986)
		(mid 245.804595 -65.011806)
		(end 245.748302 -65.0494)
		(stroke
			(width 0.0508)
			(type default)
		)
		(layer "In5.Cu")
	)
	(gr_line
		(start 245.870984 -64.9986)
		(end 245.966996 -64.9986)
		(stroke
			(width 0.0508)
			(type default)
		)
		(layer "In5.Cu")
	)
	(gr_arc
		(start 246.06377 -65.038732)
		(mid 246.01937 -65.009065)
		(end 245.966996 -64.9986)
		(stroke
			(width 0.0508)
			(type default)
		)
		(layer "In5.Cu")
	)
	(gr_line
		(start 246.06377 -65.038732)
		(end 246.07139 -65.046352)
		(stroke
			(width 0.0508)
			(type default)
		)
		(layer "In5.Cu")
	)
	(gr_line
		(start 246.099838 -65.499742)
		(end 246.125238 -65.474342)
		(stroke
			(width 0.0508)
			(type default)
		)
		(layer "In5.Cu")
	)
	(gr_arc
		(start 246.099838 -64.499744)
		(mid 246.001276 -64.519349)
		(end 245.91772 -64.575182)
		(stroke
			(width 0.0508)
			(type default)
		)
		(layer "In5.Cu")
	)
	(gr_arc
		(start 246.125238 -65.1764)
		(mid 246.11124 -65.106026)
		(end 246.07139 -65.046352)
		(stroke
			(width 0.0508)
			(type default)
		)
		(layer "In5.Cu")
	)
	(gr_line
		(start 246.125238 -65.1764)
		(end 246.125238 -65.474342)
		(stroke
			(width 0.0508)
			(type default)
		)
		(layer "In5.Cu")
	)
	(gr_line
		(start 246.284496 -96.43364)
		(end 246.289576 -96.408494)
		(stroke
			(width 0.06985)
			(type default)
		)
		(layer "In5.Cu")
	)
	(gr_line
		(start 246.284496 -83.73364)
		(end 246.289576 -83.708494)
		(stroke
			(width 0.06985)
			(type default)
		)
		(layer "In5.Cu")
	)
	(gr_line
		(start 246.284496 -83.683856)
		(end 246.289576 -83.708494)
		(stroke
			(width 0.06985)
			(type default)
		)
		(layer "In5.Cu")
	)
	(gr_line
		(start 246.360442 -119.53494)
		(end 246.38 -119.507)
		(stroke
			(width 0.06985)
			(type default)
		)
		(layer "In5.Cu")
	)
	(gr_line
		(start 246.38 -119.507)
		(end 246.385842 -119.47398)
		(stroke
			(width 0.06985)
			(type default)
		)
		(layer "In5.Cu")
	)
	(gr_line
		(start 246.4054 -66.9798)
		(end 246.424958 -66.960242)
		(stroke
			(width 0.0508)
			(type default)
		)
		(layer "In5.Cu")
	)
	(gr_line
		(start 246.426736 -66.958464)
		(end 246.493538 -66.891662)
		(stroke
			(width 0.0508)
			(type default)
		)
		(layer "In5.Cu")
	)
	(gr_line
		(start 246.493538 -66.7131)
		(end 246.493538 -66.891662)
		(stroke
			(width 0.0508)
			(type default)
		)
		(layer "In5.Cu")
	)
	(gr_arc
		(start 246.577866 -65.914778)
		(mid 246.515422 -66.008372)
		(end 246.493538 -66.11874)
		(stroke
			(width 0.0508)
			(type default)
		)
		(layer "In5.Cu")
	)
	(gr_line
		(start 246.577866 -65.914778)
		(end 246.917718 -65.57518)
		(stroke
			(width 0.0508)
			(type default)
		)
		(layer "In5.Cu")
	)
	(gr_line
		(start 246.696738 -66.940938)
		(end 246.714264 -66.958464)
		(stroke
			(width 0.0508)
			(type default)
		)
		(layer "In5.Cu")
	)
	(gr_line
		(start 246.70131 -111.20755)
		(end 246.70512 -111.186214)
		(stroke
			(width 0.06985)
			(type default)
		)
		(layer "In5.Cu")
	)
	(gr_line
		(start 246.703596 -102.758494)
		(end 246.708676 -102.78364)
		(stroke
			(width 0.06985)
			(type default)
		)
		(layer "In5.Cu")
	)
	(gr_line
		(start 246.703596 -90.058494)
		(end 246.708676 -90.08364)
		(stroke
			(width 0.06985)
			(type default)
		)
		(layer "In5.Cu")
	)
	(gr_line
		(start 246.716042 -66.960242)
		(end 246.7356 -66.9798)
		(stroke
			(width 0.0508)
			(type default)
		)
		(layer "In5.Cu")
	)
	(gr_line
		(start 246.7356 -66.9798)
		(end 246.7356 -67.158362)
		(stroke
			(width 0.06985)
			(type default)
		)
		(layer "In5.Cu")
	)
	(gr_arc
		(start 246.7483 -66.049398)
		(mid 246.710145 -66.106501)
		(end 246.696738 -66.173858)
		(stroke
			(width 0.0508)
			(type default)
		)
		(layer "In5.Cu")
	)
	(gr_arc
		(start 246.870982 -65.998598)
		(mid 246.804593 -66.011804)
		(end 246.7483 -66.049398)
		(stroke
			(width 0.0508)
			(type default)
		)
		(layer "In5.Cu")
	)
	(gr_line
		(start 246.870982 -65.998598)
		(end 246.966994 -65.998598)
		(stroke
			(width 0.0508)
			(type default)
		)
		(layer "In5.Cu")
	)
	(gr_arc
		(start 247.063768 -66.03873)
		(mid 247.019368 -66.009063)
		(end 246.966994 -65.998598)
		(stroke
			(width 0.0508)
			(type default)
		)
		(layer "In5.Cu")
	)
	(gr_line
		(start 247.063768 -66.03873)
		(end 247.071388 -66.04635)
		(stroke
			(width 0.0508)
			(type default)
		)
		(layer "In5.Cu")
	)
	(gr_line
		(start 247.099836 -66.49974)
		(end 247.125236 -66.47434)
		(stroke
			(width 0.0508)
			(type default)
		)
		(layer "In5.Cu")
	)
	(gr_arc
		(start 247.099836 -65.499742)
		(mid 247.001274 -65.519347)
		(end 246.917718 -65.57518)
		(stroke
			(width 0.0508)
			(type default)
		)
		(layer "In5.Cu")
	)
	(gr_arc
		(start 247.125236 -66.176398)
		(mid 247.111238 -66.106024)
		(end 247.071388 -66.04635)
		(stroke
			(width 0.0508)
			(type default)
		)
		(layer "In5.Cu")
	)
	(gr_line
		(start 247.125236 -66.176398)
		(end 247.125236 -66.47434)
		(stroke
			(width 0.0508)
			(type default)
		)
		(layer "In5.Cu")
	)
	(gr_line
		(start 247.294908 -96.43364)
		(end 247.299988 -96.408494)
		(stroke
			(width 0.06985)
			(type default)
		)
		(layer "In5.Cu")
	)
	(gr_line
		(start 247.294908 -83.73364)
		(end 247.299988 -83.708494)
		(stroke
			(width 0.06985)
			(type default)
		)
		(layer "In5.Cu")
	)
	(gr_line
		(start 247.4214 -66.9544)
		(end 247.440958 -66.934842)
		(stroke
			(width 0.0508)
			(type default)
		)
		(layer "In5.Cu")
	)
	(gr_line
		(start 247.442736 -66.933064)
		(end 247.493536 -66.882264)
		(stroke
			(width 0.0508)
			(type default)
		)
		(layer "In5.Cu")
	)
	(gr_line
		(start 247.49125 -120.36933)
		(end 247.510808 -120.34139)
		(stroke
			(width 0.06985)
			(type default)
		)
		(layer "In5.Cu")
	)
	(gr_line
		(start 247.493536 -66.6877)
		(end 247.493536 -66.882264)
		(stroke
			(width 0.0508)
			(type default)
		)
		(layer "In5.Cu")
	)
	(gr_line
		(start 247.510808 -120.34139)
		(end 247.51665 -120.30837)
		(stroke
			(width 0.06985)
			(type default)
		)
		(layer "In5.Cu")
	)
	(gr_line
		(start 247.523 -27.360626)
		(end 247.523 -27.467814)
		(stroke
			(width 0.0635)
			(type default)
		)
		(layer "In5.Cu")
	)
	(gr_arc
		(start 247.577864 -64.91478)
		(mid 247.51542 -65.008374)
		(end 247.493536 -65.118742)
		(stroke
			(width 0.0508)
			(type default)
		)
		(layer "In5.Cu")
	)
	(gr_line
		(start 247.577864 -64.91478)
		(end 247.917716 -64.575182)
		(stroke
			(width 0.0508)
			(type default)
		)
		(layer "In5.Cu")
	)
	(gr_line
		(start 247.65 -37.7444)
		(end 247.8786 -37.973)
		(stroke
			(width 0.0635)
			(type default)
		)
		(layer "In5.Cu")
	)
	(gr_line
		(start 247.65 -30.36697)
		(end 247.65 -37.7444)
		(stroke
			(width 0.0635)
			(type default)
		)
		(layer "In5.Cu")
	)
	(gr_line
		(start 247.65 -30.193996)
		(end 247.65 -30.36443)
		(stroke
			(width 0.0635)
			(type default)
		)
		(layer "In5.Cu")
	)
	(gr_line
		(start 247.696736 -66.899536)
		(end 247.730264 -66.933064)
		(stroke
			(width 0.0508)
			(type default)
		)
		(layer "In5.Cu")
	)
	(gr_line
		(start 247.732042 -66.934842)
		(end 247.7516 -66.9544)
		(stroke
			(width 0.0508)
			(type default)
		)
		(layer "In5.Cu")
	)
	(gr_line
		(start 247.739662 -102.758494)
		(end 247.744742 -102.78364)
		(stroke
			(width 0.06985)
			(type default)
		)
		(layer "In5.Cu")
	)
	(gr_line
		(start 247.739662 -90.058494)
		(end 247.744742 -90.08364)
		(stroke
			(width 0.06985)
			(type default)
		)
		(layer "In5.Cu")
	)
	(gr_arc
		(start 247.748298 -65.0494)
		(mid 247.710143 -65.106503)
		(end 247.696736 -65.17386)
		(stroke
			(width 0.0508)
			(type default)
		)
		(layer "In5.Cu")
	)
	(gr_line
		(start 247.7516 -66.9544)
		(end 247.7516 -67.148964)
		(stroke
			(width 0.06985)
			(type default)
		)
		(layer "In5.Cu")
	)
	(gr_line
		(start 247.781064 -111.515144)
		(end 247.785382 -111.535972)
		(stroke
			(width 0.06985)
			(type default)
		)
		(layer "In5.Cu")
	)
	(gr_line
		(start 247.781572 -111.557308)
		(end 247.785382 -111.535972)
		(stroke
			(width 0.06985)
			(type default)
		)
		(layer "In5.Cu")
	)
	(gr_line
		(start 247.840754 -26.852626)
		(end 247.840754 -26.959814)
		(stroke
			(width 0.0635)
			(type default)
		)
		(layer "In5.Cu")
	)
	(gr_arc
		(start 247.87098 -64.9986)
		(mid 247.804591 -65.011806)
		(end 247.748298 -65.0494)
		(stroke
			(width 0.0508)
			(type default)
		)
		(layer "In5.Cu")
	)
	(gr_line
		(start 247.87098 -64.9986)
		(end 247.966992 -64.9986)
		(stroke
			(width 0.0508)
			(type default)
		)
		(layer "In5.Cu")
	)
	(gr_line
		(start 247.8786 -37.973)
		(end 249.57278 -37.973)
		(stroke
			(width 0.0635)
			(type default)
		)
		(layer "In5.Cu")
	)
	(gr_line
		(start 248.031 -29.685996)
		(end 248.031 -29.85643)
		(stroke
			(width 0.0635)
			(type default)
		)
		(layer "In5.Cu")
	)
	(gr_arc
		(start 248.063766 -65.038732)
		(mid 248.019366 -65.009065)
		(end 247.966992 -64.9986)
		(stroke
			(width 0.0508)
			(type default)
		)
		(layer "In5.Cu")
	)
	(gr_line
		(start 248.063766 -65.038732)
		(end 248.071386 -65.046352)
		(stroke
			(width 0.0508)
			(type default)
		)
		(layer "In5.Cu")
	)
	(gr_line
		(start 248.099834 -65.499742)
		(end 248.125234 -65.474342)
		(stroke
			(width 0.0508)
			(type default)
		)
		(layer "In5.Cu")
	)
	(gr_arc
		(start 248.099834 -64.499744)
		(mid 248.001272 -64.519349)
		(end 247.917716 -64.575182)
		(stroke
			(width 0.0508)
			(type default)
		)
		(layer "In5.Cu")
	)
	(gr_arc
		(start 248.125234 -65.1764)
		(mid 248.111236 -65.106026)
		(end 248.071386 -65.046352)
		(stroke
			(width 0.0508)
			(type default)
		)
		(layer "In5.Cu")
	)
	(gr_line
		(start 248.125234 -65.1764)
		(end 248.125234 -65.474342)
		(stroke
			(width 0.0508)
			(type default)
		)
		(layer "In5.Cu")
	)
	(gr_line
		(start 248.30532 -96.43364)
		(end 248.3104 -96.408494)
		(stroke
			(width 0.06985)
			(type default)
		)
		(layer "In5.Cu")
	)
	(gr_line
		(start 248.30532 -83.73364)
		(end 248.3104 -83.708494)
		(stroke
			(width 0.06985)
			(type default)
		)
		(layer "In5.Cu")
	)
	(gr_line
		(start 248.30532 -83.683856)
		(end 248.3104 -83.708494)
		(stroke
			(width 0.06985)
			(type default)
		)
		(layer "In5.Cu")
	)
	(gr_line
		(start 248.370344 -30.195774)
		(end 248.506234 -30.331664)
		(stroke
			(width 0.0635)
			(type default)
		)
		(layer "In5.Cu")
	)
	(gr_line
		(start 248.412 -66.929)
		(end 248.431558 -66.909442)
		(stroke
			(width 0.0508)
			(type default)
		)
		(layer "In5.Cu")
	)
	(gr_line
		(start 248.433336 -66.907664)
		(end 248.493534 -66.847466)
		(stroke
			(width 0.0508)
			(type default)
		)
		(layer "In5.Cu")
	)
	(gr_line
		(start 248.468134 -26.721816)
		(end 248.576592 -26.830274)
		(stroke
			(width 0.0508)
			(type default)
		)
		(layer "In5.Cu")
	)
	(gr_line
		(start 248.468134 -26.614628)
		(end 248.468134 -26.721816)
		(stroke
			(width 0.0508)
			(type default)
		)
		(layer "In5.Cu")
	)
	(gr_line
		(start 248.493534 -66.6623)
		(end 248.493534 -66.847466)
		(stroke
			(width 0.0508)
			(type default)
		)
		(layer "In5.Cu")
	)
	(gr_line
		(start 248.49963 -121.21642)
		(end 248.519188 -121.18848)
		(stroke
			(width 0.06985)
			(type default)
		)
		(layer "In5.Cu")
	)
	(gr_line
		(start 248.506234 -31.7246)
		(end 248.684034 -31.9024)
		(stroke
			(width 0.0508)
			(type default)
		)
		(layer "In5.Cu")
	)
	(gr_line
		(start 248.506234 -30.331664)
		(end 248.506234 -31.7246)
		(stroke
			(width 0.0635)
			(type default)
		)
		(layer "In5.Cu")
	)
	(gr_line
		(start 248.519188 -121.18848)
		(end 248.52503 -121.15546)
		(stroke
			(width 0.06985)
			(type default)
		)
		(layer "In5.Cu")
	)
	(gr_arc
		(start 248.577862 -65.914778)
		(mid 248.515418 -66.008372)
		(end 248.493534 -66.11874)
		(stroke
			(width 0.0508)
			(type default)
		)
		(layer "In5.Cu")
	)
	(gr_line
		(start 248.577862 -65.914778)
		(end 248.917714 -65.57518)
		(stroke
			(width 0.0508)
			(type default)
		)
		(layer "In5.Cu")
	)
	(gr_line
		(start 248.57837 -26.832052)
		(end 248.620534 -26.874216)
		(stroke
			(width 0.0508)
			(type default)
		)
		(layer "In5.Cu")
	)
	(gr_line
		(start 248.620534 -28.363418)
		(end 248.620534 -28.364688)
		(stroke
			(width 0.0508)
			(type default)
		)
		(layer "In5.Cu")
	)
	(gr_line
		(start 248.684034 -31.9024)
		(end 249.076972 -31.9024)
		(stroke
			(width 0.0508)
			(type default)
		)
		(layer "In5.Cu")
	)
	(gr_line
		(start 248.696734 -66.883534)
		(end 248.720864 -66.907664)
		(stroke
			(width 0.0508)
			(type default)
		)
		(layer "In5.Cu")
	)
	(gr_line
		(start 248.706132 -28.566618)
		(end 248.706132 -28.567888)
		(stroke
			(width 0.0508)
			(type default)
		)
		(layer "In5.Cu")
	)
	(gr_line
		(start 248.722642 -66.909442)
		(end 248.7422 -66.929)
		(stroke
			(width 0.0508)
			(type default)
		)
		(layer "In5.Cu")
	)
	(gr_line
		(start 248.7422 -66.929)
		(end 248.7422 -67.114166)
		(stroke
			(width 0.06985)
			(type default)
		)
		(layer "In5.Cu")
	)
	(gr_arc
		(start 248.748296 -66.049398)
		(mid 248.710141 -66.106501)
		(end 248.696734 -66.173858)
		(stroke
			(width 0.0508)
			(type default)
		)
		(layer "In5.Cu")
	)
	(gr_line
		(start 248.750074 -102.758494)
		(end 248.755154 -102.78364)
		(stroke
			(width 0.06985)
			(type default)
		)
		(layer "In5.Cu")
	)
	(gr_line
		(start 248.750074 -90.058494)
		(end 248.755154 -90.08364)
		(stroke
			(width 0.06985)
			(type default)
		)
		(layer "In5.Cu")
	)
	(gr_line
		(start 248.823734 -26.874216)
		(end 248.865898 -26.832052)
		(stroke
			(width 0.0508)
			(type default)
		)
		(layer "In5.Cu")
	)
	(gr_line
		(start 248.867676 -26.830274)
		(end 248.976134 -26.721816)
		(stroke
			(width 0.0508)
			(type default)
		)
		(layer "In5.Cu")
	)
	(gr_arc
		(start 248.870978 -65.998598)
		(mid 248.804589 -66.011804)
		(end 248.748296 -66.049398)
		(stroke
			(width 0.0508)
			(type default)
		)
		(layer "In5.Cu")
	)
	(gr_line
		(start 248.870978 -65.998598)
		(end 248.96699 -65.998598)
		(stroke
			(width 0.0508)
			(type default)
		)
		(layer "In5.Cu")
	)
	(gr_line
		(start 248.933716 -112.226344)
		(end 248.938034 -112.247172)
		(stroke
			(width 0.06985)
			(type default)
		)
		(layer "In5.Cu")
	)
	(gr_line
		(start 248.934224 -112.268508)
		(end 248.938034 -112.247172)
		(stroke
			(width 0.06985)
			(type default)
		)
		(layer "In5.Cu")
	)
	(gr_line
		(start 248.976134 -26.696416)
		(end 248.976134 -26.721816)
		(stroke
			(width 0.0508)
			(type default)
		)
		(layer "In5.Cu")
	)
	(gr_arc
		(start 249.063764 -66.03873)
		(mid 249.019364 -66.009063)
		(end 248.96699 -65.998598)
		(stroke
			(width 0.0508)
			(type default)
		)
		(layer "In5.Cu")
	)
	(gr_line
		(start 249.063764 -66.03873)
		(end 249.071384 -66.04635)
		(stroke
			(width 0.0508)
			(type default)
		)
		(layer "In5.Cu")
	)
	(gr_line
		(start 249.071892 -5.4864)
		(end 249.141234 -5.4864)
		(stroke
			(width 0.0635)
			(type default)
		)
		(layer "In5.Cu")
	)
	(gr_line
		(start 249.076972 -31.9024)
		(end 249.501152 -32.32658)
		(stroke
			(width 0.0508)
			(type default)
		)
		(layer "In5.Cu")
	)
	(gr_line
		(start 249.099832 -66.49974)
		(end 249.125232 -66.47434)
		(stroke
			(width 0.0508)
			(type default)
		)
		(layer "In5.Cu")
	)
	(gr_arc
		(start 249.099832 -65.499742)
		(mid 249.00127 -65.519347)
		(end 248.917714 -65.57518)
		(stroke
			(width 0.0508)
			(type default)
		)
		(layer "In5.Cu")
	)
	(gr_arc
		(start 249.125232 -66.176398)
		(mid 249.111234 -66.106024)
		(end 249.071384 -66.04635)
		(stroke
			(width 0.0508)
			(type default)
		)
		(layer "In5.Cu")
	)
	(gr_line
		(start 249.125232 -66.176398)
		(end 249.125232 -66.47434)
		(stroke
			(width 0.0508)
			(type default)
		)
		(layer "In5.Cu")
	)
	(gr_line
		(start 249.341386 -96.43364)
		(end 249.346466 -96.408494)
		(stroke
			(width 0.06985)
			(type default)
		)
		(layer "In5.Cu")
	)
	(gr_line
		(start 249.341386 -83.73364)
		(end 249.346466 -83.708494)
		(stroke
			(width 0.06985)
			(type default)
		)
		(layer "In5.Cu")
	)
	(gr_line
		(start 249.341386 -83.683856)
		(end 249.346466 -83.708494)
		(stroke
			(width 0.06985)
			(type default)
		)
		(layer "In5.Cu")
	)
	(gr_line
		(start 249.463052 -122.102118)
		(end 249.483118 -122.073416)
		(stroke
			(width 0.06985)
			(type default)
		)
		(layer "In5.Cu")
	)
	(gr_line
		(start 249.483118 -122.073416)
		(end 249.48896 -122.039126)
		(stroke
			(width 0.06985)
			(type default)
		)
		(layer "In5.Cu")
	)
	(gr_line
		(start 249.501152 -32.901382)
		(end 250.09983 -33.50006)
		(stroke
			(width 0.0508)
			(type default)
		)
		(layer "In5.Cu")
	)
	(gr_line
		(start 249.501152 -32.32658)
		(end 249.501152 -32.901382)
		(stroke
			(width 0.0508)
			(type default)
		)
		(layer "In5.Cu")
	)
	(gr_line
		(start 249.57278 -37.973)
		(end 250.09983 -38.50005)
		(stroke
			(width 0.0635)
			(type default)
		)
		(layer "In5.Cu")
	)
	(gr_line
		(start 249.579892 -5.766308)
		(end 249.649234 -5.766308)
		(stroke
			(width 0.0635)
			(type default)
		)
		(layer "In5.Cu")
	)
	(gr_line
		(start 249.70613 -32.663384)
		(end 250.139708 -33.096962)
		(stroke
			(width 0.0508)
			(type default)
		)
		(layer "In5.Cu")
	)
	(gr_line
		(start 249.70613 -32.099504)
		(end 249.70613 -32.663384)
		(stroke
			(width 0.0508)
			(type default)
		)
		(layer "In5.Cu")
	)
	(gr_line
		(start 249.70613 -32.037528)
		(end 249.70613 -32.096964)
		(stroke
			(width 0.0508)
			(type default)
		)
		(layer "In5.Cu")
	)
	(gr_line
		(start 249.849894 -31.893764)
		(end 249.90933 -31.893764)
		(stroke
			(width 0.0508)
			(type default)
		)
		(layer "In5.Cu")
	)
	(gr_line
		(start 249.91187 -31.893764)
		(end 250.050554 -31.893764)
		(stroke
			(width 0.0508)
			(type default)
		)
		(layer "In5.Cu")
	)
	(gr_line
		(start 250.034806 -112.550448)
		(end 250.039124 -112.571276)
		(stroke
			(width 0.06985)
			(type default)
		)
		(layer "In5.Cu")
	)
	(gr_line
		(start 250.035314 -112.592612)
		(end 250.039124 -112.571276)
		(stroke
			(width 0.06985)
			(type default)
		)
		(layer "In5.Cu")
	)
	(gr_line
		(start 250.050554 -31.893764)
		(end 250.698 -32.54121)
		(stroke
			(width 0.0508)
			(type default)
		)
		(layer "In5.Cu")
	)
	(gr_line
		(start 250.139708 -33.096962)
		(end 250.253754 -33.096962)
		(stroke
			(width 0.0508)
			(type default)
		)
		(layer "In5.Cu")
	)
	(gr_line
		(start 250.253754 -33.096962)
		(end 250.49226 -33.335468)
		(stroke
			(width 0.0508)
			(type default)
		)
		(layer "In5.Cu")
	)
	(gr_line
		(start 250.337066 -6.729476)
		(end 250.800362 -6.26618)
		(stroke
			(width 0.0635)
			(type default)
		)
		(layer "In5.Cu")
	)
	(gr_line
		(start 250.351798 -96.43364)
		(end 250.356878 -96.408494)
		(stroke
			(width 0.06985)
			(type default)
		)
		(layer "In5.Cu")
	)
	(gr_line
		(start 250.351798 -83.73364)
		(end 250.356878 -83.708494)
		(stroke
			(width 0.06985)
			(type default)
		)
		(layer "In5.Cu")
	)
	(gr_line
		(start 250.351798 -83.683856)
		(end 250.356878 -83.708494)
		(stroke
			(width 0.06985)
			(type default)
		)
		(layer "In5.Cu")
	)
	(gr_line
		(start 250.4186 -67.090544)
		(end 250.49099 -67.018154)
		(stroke
			(width 0.0508)
			(type default)
		)
		(layer "In5.Cu")
	)
	(gr_line
		(start 250.49353 -66.89852)
		(end 250.49353 -67.015614)
		(stroke
			(width 0.0508)
			(type default)
		)
		(layer "In5.Cu")
	)
	(gr_line
		(start 250.49353 -34.893758)
		(end 251.099828 -35.500056)
		(stroke
			(width 0.0508)
			(type default)
		)
		(layer "In5.Cu")
	)
	(gr_line
		(start 250.49353 -34.30397)
		(end 250.49353 -34.893758)
		(stroke
			(width 0.0508)
			(type default)
		)
		(layer "In5.Cu")
	)
	(gr_arc
		(start 250.577858 -64.91478)
		(mid 250.515414 -65.008374)
		(end 250.49353 -65.118742)
		(stroke
			(width 0.0508)
			(type default)
		)
		(layer "In5.Cu")
	)
	(gr_line
		(start 250.577858 -64.91478)
		(end 250.91771 -64.575182)
		(stroke
			(width 0.0508)
			(type default)
		)
		(layer "In5.Cu")
	)
	(gr_line
		(start 250.698 -32.54121)
		(end 250.698 -33.130998)
		(stroke
			(width 0.0508)
			(type default)
		)
		(layer "In5.Cu")
	)
	(gr_line
		(start 250.69927 -67.017646)
		(end 250.7488 -67.055492)
		(stroke
			(width 0.0508)
			(type default)
		)
		(layer "In5.Cu")
	)
	(gr_line
		(start 250.69927 -34.0995)
		(end 251.099828 -34.500058)
		(stroke
			(width 0.0508)
			(type default)
		)
		(layer "In5.Cu")
	)
	(gr_arc
		(start 250.748292 -65.0494)
		(mid 250.710137 -65.106503)
		(end 250.69673 -65.17386)
		(stroke
			(width 0.0508)
			(type default)
		)
		(layer "In5.Cu")
	)
	(gr_line
		(start 250.7488 -67.16522)
		(end 250.7488 -67.282314)
		(stroke
			(width 0.06985)
			(type default)
		)
		(layer "In5.Cu")
	)
	(gr_line
		(start 250.7488 -67.055492)
		(end 250.7488 -67.16522)
		(stroke
			(width 0.0508)
			(type default)
		)
		(layer "In5.Cu")
	)
	(gr_line
		(start 250.800362 -5.891022)
		(end 250.800362 -6.26618)
		(stroke
			(width 0.0635)
			(type default)
		)
		(layer "In5.Cu")
	)
	(gr_line
		(start 250.800362 -5.629656)
		(end 250.800362 -5.789422)
		(stroke
			(width 0.0635)
			(type default)
		)
		(layer "In5.Cu")
	)
	(gr_arc
		(start 250.870974 -64.9986)
		(mid 250.804585 -65.011806)
		(end 250.748292 -65.0494)
		(stroke
			(width 0.0508)
			(type default)
		)
		(layer "In5.Cu")
	)
	(gr_line
		(start 250.870974 -64.9986)
		(end 250.966986 -64.9986)
		(stroke
			(width 0.0508)
			(type default)
		)
		(layer "In5.Cu")
	)
	(gr_arc
		(start 251.06376 -65.038732)
		(mid 251.01936 -65.009065)
		(end 250.966986 -64.9986)
		(stroke
			(width 0.0508)
			(type default)
		)
		(layer "In5.Cu")
	)
	(gr_line
		(start 251.06376 -65.038732)
		(end 251.07138 -65.046352)
		(stroke
			(width 0.0508)
			(type default)
		)
		(layer "In5.Cu")
	)
	(gr_line
		(start 251.099828 -65.499742)
		(end 251.125228 -65.474342)
		(stroke
			(width 0.0508)
			(type default)
		)
		(layer "In5.Cu")
	)
	(gr_arc
		(start 251.099828 -64.499744)
		(mid 251.001266 -64.519349)
		(end 250.91771 -64.575182)
		(stroke
			(width 0.0508)
			(type default)
		)
		(layer "In5.Cu")
	)
	(gr_line
		(start 251.10313 -112.84077)
		(end 251.107448 -112.861598)
		(stroke
			(width 0.06985)
			(type default)
		)
		(layer "In5.Cu")
	)
	(gr_line
		(start 251.103638 -112.882934)
		(end 251.107448 -112.861598)
		(stroke
			(width 0.06985)
			(type default)
		)
		(layer "In5.Cu")
	)
	(gr_arc
		(start 251.125228 -65.1764)
		(mid 251.11123 -65.106026)
		(end 251.07138 -65.046352)
		(stroke
			(width 0.0508)
			(type default)
		)
		(layer "In5.Cu")
	)
	(gr_line
		(start 251.125228 -65.1764)
		(end 251.125228 -65.474342)
		(stroke
			(width 0.0508)
			(type default)
		)
		(layer "In5.Cu")
	)
	(gr_line
		(start 251.427742 -28.358592)
		(end 251.463048 -28.393898)
		(stroke
			(width 0.0508)
			(type default)
		)
		(layer "In5.Cu")
	)
	(gr_line
		(start 251.4346 -67.129152)
		(end 251.4346 -67.253104)
		(stroke
			(width 0.06985)
			(type default)
		)
		(layer "In5.Cu")
	)
	(gr_line
		(start 251.4346 -67.103752)
		(end 251.4346 -67.129152)
		(stroke
			(width 0.0508)
			(type default)
		)
		(layer "In5.Cu")
	)
	(gr_line
		(start 251.4346 -67.103752)
		(end 251.493528 -67.070732)
		(stroke
			(width 0.0508)
			(type default)
		)
		(layer "In5.Cu")
	)
	(gr_line
		(start 251.464826 -28.395676)
		(end 251.494036 -28.424886)
		(stroke
			(width 0.0508)
			(type default)
		)
		(layer "In5.Cu")
	)
	(gr_line
		(start 251.494036 -28.424886)
		(end 251.494036 -28.656534)
		(stroke
			(width 0.0508)
			(type default)
		)
		(layer "In5.Cu")
	)
	(gr_arc
		(start 251.577856 -65.914778)
		(mid 251.515382 -66.008364)
		(end 251.493528 -66.11874)
		(stroke
			(width 0.0508)
			(type default)
		)
		(layer "In5.Cu")
	)
	(gr_line
		(start 251.577856 -65.914778)
		(end 251.917708 -65.57518)
		(stroke
			(width 0.0508)
			(type default)
		)
		(layer "In5.Cu")
	)
	(gr_line
		(start 251.696728 -66.862452)
		(end 251.696728 -66.986404)
		(stroke
			(width 0.0508)
			(type default)
		)
		(layer "In5.Cu")
	)
	(gr_line
		(start 251.697236 -28.45054)
		(end 251.7521 -28.395676)
		(stroke
			(width 0.0508)
			(type default)
		)
		(layer "In5.Cu")
	)
	(gr_line
		(start 251.699268 -66.988944)
		(end 251.7648 -67.054476)
		(stroke
			(width 0.0508)
			(type default)
		)
		(layer "In5.Cu")
	)
	(gr_arc
		(start 251.74829 -66.049398)
		(mid 251.710144 -66.106501)
		(end 251.696728 -66.173858)
		(stroke
			(width 0.0508)
			(type default)
		)
		(layer "In5.Cu")
	)
	(gr_line
		(start 251.753878 -28.393898)
		(end 251.757942 -28.389834)
		(stroke
			(width 0.0508)
			(type default)
		)
		(layer "In5.Cu")
	)
	(gr_line
		(start 251.757942 -28.158186)
		(end 251.757942 -28.389834)
		(stroke
			(width 0.06985)
			(type default)
		)
		(layer "In5.Cu")
	)
	(gr_line
		(start 251.769118 -22.654514)
		(end 251.789438 -22.539452)
		(stroke
			(width 0.06985)
			(type default)
		)
		(layer "In5.Cu")
	)
	(gr_line
		(start 251.779532 -122.851672)
		(end 251.79909 -122.823732)
		(stroke
			(width 0.06985)
			(type default)
		)
		(layer "In5.Cu")
	)
	(gr_line
		(start 251.789438 -22.539452)
		(end 251.891292 -22.48281)
		(stroke
			(width 0.06985)
			(type default)
		)
		(layer "In5.Cu")
	)
	(gr_line
		(start 251.79909 -122.823732)
		(end 251.804932 -122.790712)
		(stroke
			(width 0.06985)
			(type default)
		)
		(layer "In5.Cu")
	)
	(gr_line
		(start 251.849382 -30.003496)
		(end 251.998226 -30.003496)
		(stroke
			(width 0.0508)
			(type default)
		)
		(layer "In5.Cu")
	)
	(gr_arc
		(start 251.870972 -65.998598)
		(mid 251.804573 -66.011785)
		(end 251.74829 -66.049398)
		(stroke
			(width 0.0508)
			(type default)
		)
		(layer "In5.Cu")
	)
	(gr_line
		(start 251.870972 -65.998598)
		(end 251.966984 -65.998598)
		(stroke
			(width 0.0508)
			(type default)
		)
		(layer "In5.Cu")
	)
	(gr_arc
		(start 252.063758 -66.03873)
		(mid 252.019374 -66.009004)
		(end 251.966984 -65.998598)
		(stroke
			(width 0.0508)
			(type default)
		)
		(layer "In5.Cu")
	)
	(gr_line
		(start 252.063758 -66.03873)
		(end 252.071378 -66.04635)
		(stroke
			(width 0.0508)
			(type default)
		)
		(layer "In5.Cu")
	)
	(gr_line
		(start 252.099826 -66.49974)
		(end 252.125226 -66.47434)
		(stroke
			(width 0.0508)
			(type default)
		)
		(layer "In5.Cu")
	)
	(gr_arc
		(start 252.099826 -65.499742)
		(mid 252.001258 -65.519339)
		(end 251.917708 -65.57518)
		(stroke
			(width 0.0508)
			(type default)
		)
		(layer "In5.Cu")
	)
	(gr_arc
		(start 252.099826 -30.105096)
		(mid 252.070068 -30.033247)
		(end 251.998226 -30.003496)
		(stroke
			(width 0.0508)
			(type default)
		)
		(layer "In5.Cu")
	)
	(gr_line
		(start 252.099826 -30.105096)
		(end 252.099826 -30.500066)
		(stroke
			(width 0.0508)
			(type default)
		)
		(layer "In5.Cu")
	)
	(gr_arc
		(start 252.125226 -66.176398)
		(mid 252.111256 -66.106007)
		(end 252.071378 -66.04635)
		(stroke
			(width 0.0508)
			(type default)
		)
		(layer "In5.Cu")
	)
	(gr_line
		(start 252.125226 -66.176398)
		(end 252.125226 -66.47434)
		(stroke
			(width 0.0508)
			(type default)
		)
		(layer "In5.Cu")
	)
	(gr_line
		(start 252.349 -28.14574)
		(end 252.368558 -28.165298)
		(stroke
			(width 0.0508)
			(type default)
		)
		(layer "In5.Cu")
	)
	(gr_line
		(start 252.349 -28.12034)
		(end 252.349 -28.14574)
		(stroke
			(width 0.0508)
			(type default)
		)
		(layer "In5.Cu")
	)
	(gr_line
		(start 252.349 -25.535382)
		(end 252.385068 -25.48382)
		(stroke
			(width 0.06985)
			(type default)
		)
		(layer "In5.Cu")
	)
	(gr_line
		(start 252.370336 -28.167076)
		(end 252.4125 -28.20924)
		(stroke
			(width 0.0508)
			(type default)
		)
		(layer "In5.Cu")
	)
	(gr_line
		(start 252.4252 -66.9544)
		(end 252.444758 -66.934842)
		(stroke
			(width 0.0508)
			(type default)
		)
		(layer "In5.Cu")
	)
	(gr_line
		(start 252.446536 -66.933064)
		(end 252.493526 -66.886074)
		(stroke
			(width 0.0508)
			(type default)
		)
		(layer "In5.Cu")
	)
	(gr_line
		(start 252.493526 -66.6877)
		(end 252.493526 -66.886074)
		(stroke
			(width 0.0508)
			(type default)
		)
		(layer "In5.Cu")
	)
	(gr_line
		(start 252.499114 -29.064204)
		(end 252.499114 -29.096462)
		(stroke
			(width 0.0508)
			(type default)
		)
		(layer "In5.Cu")
	)
	(gr_arc
		(start 252.577854 -64.91478)
		(mid 252.51541 -65.008374)
		(end 252.493526 -65.118742)
		(stroke
			(width 0.0508)
			(type default)
		)
		(layer "In5.Cu")
	)
	(gr_line
		(start 252.577854 -64.91478)
		(end 252.917706 -64.575182)
		(stroke
			(width 0.0508)
			(type default)
		)
		(layer "In5.Cu")
	)
	(gr_line
		(start 252.6157 -28.861004)
		(end 252.6157 -28.893262)
		(stroke
			(width 0.0508)
			(type default)
		)
		(layer "In5.Cu")
	)
	(gr_line
		(start 252.6157 -28.20924)
		(end 252.657864 -28.167076)
		(stroke
			(width 0.0508)
			(type default)
		)
		(layer "In5.Cu")
	)
	(gr_line
		(start 252.659642 -28.165298)
		(end 252.6792 -28.14574)
		(stroke
			(width 0.0508)
			(type default)
		)
		(layer "In5.Cu")
	)
	(gr_line
		(start 252.6792 -28.12034)
		(end 252.6792 -28.14574)
		(stroke
			(width 0.0508)
			(type default)
		)
		(layer "In5.Cu")
	)
	(gr_line
		(start 252.696726 -66.895726)
		(end 252.734064 -66.933064)
		(stroke
			(width 0.0508)
			(type default)
		)
		(layer "In5.Cu")
	)
	(gr_line
		(start 252.735842 -66.934842)
		(end 252.7554 -66.9544)
		(stroke
			(width 0.0508)
			(type default)
		)
		(layer "In5.Cu")
	)
	(gr_arc
		(start 252.748288 -65.0494)
		(mid 252.710133 -65.106503)
		(end 252.696726 -65.17386)
		(stroke
			(width 0.0508)
			(type default)
		)
		(layer "In5.Cu")
	)
	(gr_line
		(start 252.7554 -66.9544)
		(end 252.7554 -67.152774)
		(stroke
			(width 0.06985)
			(type default)
		)
		(layer "In5.Cu")
	)
	(gr_arc
		(start 252.833378 -30.950408)
		(mid 252.972518 -30.992392)
		(end 253.104904 -30.932374)
		(stroke
			(width 0.0508)
			(type default)
		)
		(layer "In5.Cu")
	)
	(gr_arc
		(start 252.87097 -64.9986)
		(mid 252.804581 -65.011806)
		(end 252.748288 -65.0494)
		(stroke
			(width 0.0508)
			(type default)
		)
		(layer "In5.Cu")
	)
	(gr_line
		(start 252.87097 -64.9986)
		(end 252.966982 -64.9986)
		(stroke
			(width 0.0508)
			(type default)
		)
		(layer "In5.Cu")
	)
	(gr_line
		(start 252.911356 -124.344938)
		(end 252.930914 -124.316998)
		(stroke
			(width 0.06985)
			(type default)
		)
		(layer "In5.Cu")
	)
	(gr_line
		(start 252.930914 -124.316998)
		(end 252.936756 -124.283978)
		(stroke
			(width 0.06985)
			(type default)
		)
		(layer "In5.Cu")
	)
	(gr_arc
		(start 253.063756 -65.038732)
		(mid 253.019356 -65.009065)
		(end 252.966982 -64.9986)
		(stroke
			(width 0.0508)
			(type default)
		)
		(layer "In5.Cu")
	)
	(gr_line
		(start 253.063756 -65.038732)
		(end 253.098046 -65.073022)
		(stroke
			(width 0.0508)
			(type default)
		)
		(layer "In5.Cu")
	)
	(gr_arc
		(start 253.099824 -65.499742)
		(mid 253.145688 -65.431102)
		(end 253.1618 -65.350136)
		(stroke
			(width 0.0508)
			(type default)
		)
		(layer "In5.Cu")
	)
	(gr_arc
		(start 253.099824 -64.499744)
		(mid 253.001262 -64.519349)
		(end 252.917706 -64.575182)
		(stroke
			(width 0.0508)
			(type default)
		)
		(layer "In5.Cu")
	)
	(gr_line
		(start 253.099824 -30.500066)
		(end 253.168912 -30.602174)
		(stroke
			(width 0.0508)
			(type default)
		)
		(layer "In5.Cu")
	)
	(gr_line
		(start 253.104904 -30.932374)
		(end 253.105158 -30.93212)
		(stroke
			(width 0.0508)
			(type default)
		)
		(layer "In5.Cu")
	)
	(gr_arc
		(start 253.105158 -30.93212)
		(mid 253.205348 -30.780335)
		(end 253.168912 -30.602174)
		(stroke
			(width 0.0508)
			(type default)
		)
		(layer "In5.Cu")
	)
	(gr_arc
		(start 253.1618 -65.2272)
		(mid 253.145226 -65.143787)
		(end 253.098046 -65.073022)
		(stroke
			(width 0.0508)
			(type default)
		)
		(layer "In5.Cu")
	)
	(gr_line
		(start 253.1618 -65.2272)
		(end 253.1618 -65.350136)
		(stroke
			(width 0.0508)
			(type default)
		)
		(layer "In5.Cu")
	)
	(gr_line
		(start 253.2888 -29.0576)
		(end 253.308358 -29.077158)
		(stroke
			(width 0.0508)
			(type default)
		)
		(layer "In5.Cu")
	)
	(gr_line
		(start 253.2888 -29.0322)
		(end 253.2888 -29.0576)
		(stroke
			(width 0.0508)
			(type default)
		)
		(layer "In5.Cu")
	)
	(gr_line
		(start 253.2888 -26.14803)
		(end 253.324868 -26.096468)
		(stroke
			(width 0.06985)
			(type default)
		)
		(layer "In5.Cu")
	)
	(gr_line
		(start 253.310136 -29.078936)
		(end 253.3523 -29.1211)
		(stroke
			(width 0.0508)
			(type default)
		)
		(layer "In5.Cu")
	)
	(gr_line
		(start 253.4539 -66.978276)
		(end 253.4539 -67.095624)
		(stroke
			(width 0.06985)
			(type default)
		)
		(layer "In5.Cu")
	)
	(gr_line
		(start 253.4539 -66.965576)
		(end 253.4539 -66.978276)
		(stroke
			(width 0.0508)
			(type default)
		)
		(layer "In5.Cu")
	)
	(gr_line
		(start 253.4539 -66.965576)
		(end 253.493524 -66.925952)
		(stroke
			(width 0.0508)
			(type default)
		)
		(layer "In5.Cu")
	)
	(gr_line
		(start 253.5555 -29.1211)
		(end 253.597664 -29.078936)
		(stroke
			(width 0.0508)
			(type default)
		)
		(layer "In5.Cu")
	)
	(gr_arc
		(start 253.577852 -65.914778)
		(mid 253.515408 -66.008372)
		(end 253.493524 -66.11874)
		(stroke
			(width 0.0508)
			(type default)
		)
		(layer "In5.Cu")
	)
	(gr_line
		(start 253.577852 -65.914778)
		(end 253.917704 -65.57518)
		(stroke
			(width 0.0508)
			(type default)
		)
		(layer "In5.Cu")
	)
	(gr_line
		(start 253.599442 -29.077158)
		(end 253.619 -29.0576)
		(stroke
			(width 0.0508)
			(type default)
		)
		(layer "In5.Cu")
	)
	(gr_line
		(start 253.619 -29.0322)
		(end 253.619 -29.0576)
		(stroke
			(width 0.0508)
			(type default)
		)
		(layer "In5.Cu")
	)
	(gr_line
		(start 253.696724 -66.711576)
		(end 253.696724 -66.828924)
		(stroke
			(width 0.0508)
			(type default)
		)
		(layer "In5.Cu")
	)
	(gr_line
		(start 253.699264 -66.831464)
		(end 253.7841 -66.9163)
		(stroke
			(width 0.0508)
			(type default)
		)
		(layer "In5.Cu")
	)
	(gr_arc
		(start 253.748286 -66.049398)
		(mid 253.710131 -66.106501)
		(end 253.696724 -66.173858)
		(stroke
			(width 0.0508)
			(type default)
		)
		(layer "In5.Cu")
	)
	(gr_arc
		(start 253.870968 -65.998598)
		(mid 253.804579 -66.011804)
		(end 253.748286 -66.049398)
		(stroke
			(width 0.0508)
			(type default)
		)
		(layer "In5.Cu")
	)
	(gr_line
		(start 253.870968 -65.998598)
		(end 253.96698 -65.998598)
		(stroke
			(width 0.0508)
			(type default)
		)
		(layer "In5.Cu")
	)
	(gr_arc
		(start 253.90602 -30.018228)
		(mid 253.965107 -30.057697)
		(end 254.034798 -30.071568)
		(stroke
			(width 0.0508)
			(type default)
		)
		(layer "In5.Cu")
	)
	(gr_line
		(start 253.90729 -30.307534)
		(end 254.099822 -30.500066)
		(stroke
			(width 0.0508)
			(type default)
		)
		(layer "In5.Cu")
	)
	(gr_line
		(start 254.034798 -30.071568)
		(end 254.156972 -30.071568)
		(stroke
			(width 0.0508)
			(type default)
		)
		(layer "In5.Cu")
	)
	(gr_arc
		(start 254.063754 -66.03873)
		(mid 254.019354 -66.009063)
		(end 253.96698 -65.998598)
		(stroke
			(width 0.0508)
			(type default)
		)
		(layer "In5.Cu")
	)
	(gr_arc
		(start 254.099822 -66.125852)
		(mid 254.090445 -66.078709)
		(end 254.063754 -66.03873)
		(stroke
			(width 0.0508)
			(type default)
		)
		(layer "In5.Cu")
	)
	(gr_line
		(start 254.099822 -66.125852)
		(end 254.099822 -66.49974)
		(stroke
			(width 0.0508)
			(type default)
		)
		(layer "In5.Cu")
	)
	(gr_arc
		(start 254.099822 -65.499742)
		(mid 254.00126 -65.519347)
		(end 253.917704 -65.57518)
		(stroke
			(width 0.0508)
			(type default)
		)
		(layer "In5.Cu")
	)
	(gr_arc
		(start 254.156972 -30.071568)
		(mid 254.243574 -30.035722)
		(end 254.2794 -29.94914)
		(stroke
			(width 0.0508)
			(type default)
		)
		(layer "In5.Cu")
	)
	(gr_line
		(start 254.163576 -22.94255)
		(end 254.174498 -22.927056)
		(stroke
			(width 0.06985)
			(type default)
		)
		(layer "In5.Cu")
	)
	(gr_line
		(start 254.174498 -22.927056)
		(end 254.189992 -22.916134)
		(stroke
			(width 0.06985)
			(type default)
		)
		(layer "In5.Cu")
	)
	(gr_arc
		(start 254.2794 -29.679646)
		(mid 254.22682 -29.552628)
		(end 254.099822 -29.500068)
		(stroke
			(width 0.0508)
			(type default)
		)
		(layer "In5.Cu")
	)
	(gr_line
		(start 254.2794 -29.679646)
		(end 254.2794 -29.94914)
		(stroke
			(width 0.0508)
			(type default)
		)
		(layer "In5.Cu")
	)
	(gr_line
		(start 254.4318 -66.8782)
		(end 254.4318 -67.079622)
		(stroke
			(width 0.06985)
			(type default)
		)
		(layer "In5.Cu")
	)
	(gr_line
		(start 254.4318 -66.8782)
		(end 254.451358 -66.858642)
		(stroke
			(width 0.0508)
			(type default)
		)
		(layer "In5.Cu")
	)
	(gr_line
		(start 254.453136 -66.856864)
		(end 254.493522 -66.816478)
		(stroke
			(width 0.0508)
			(type default)
		)
		(layer "In5.Cu")
	)
	(gr_line
		(start 254.487172 -24.435816)
		(end 254.498094 -24.420322)
		(stroke
			(width 0.06985)
			(type default)
		)
		(layer "In5.Cu")
	)
	(gr_line
		(start 254.498094 -24.420322)
		(end 254.513588 -24.4094)
		(stroke
			(width 0.06985)
			(type default)
		)
		(layer "In5.Cu")
	)
	(gr_line
		(start 254.501396 -30.008576)
		(end 254.501396 -30.023054)
		(stroke
			(width 0.0508)
			(type default)
		)
		(layer "In5.Cu")
	)
	(gr_line
		(start 254.501396 -30.008576)
		(end 254.512572 -29.9974)
		(stroke
			(width 0.0508)
			(type default)
		)
		(layer "In5.Cu")
	)
	(gr_line
		(start 254.512572 -29.845)
		(end 254.512572 -29.9974)
		(stroke
			(width 0.0508)
			(type default)
		)
		(layer "In5.Cu")
	)
	(gr_line
		(start 254.512572 -26.722324)
		(end 254.514604 -26.720292)
		(stroke
			(width 0.06985)
			(type default)
		)
		(layer "In5.Cu")
	)
	(gr_arc
		(start 254.57785 -64.91478)
		(mid 254.515406 -65.008374)
		(end 254.493522 -65.118742)
		(stroke
			(width 0.0508)
			(type default)
		)
		(layer "In5.Cu")
	)
	(gr_line
		(start 254.57785 -64.91478)
		(end 254.917702 -64.575182)
		(stroke
			(width 0.0508)
			(type default)
		)
		(layer "In5.Cu")
	)
	(gr_line
		(start 254.630174 -26.078434)
		(end 254.636016 -26.045414)
		(stroke
			(width 0.06985)
			(type default)
		)
		(layer "In5.Cu")
	)
	(gr_line
		(start 254.636016 -26.045414)
		(end 254.655574 -26.017474)
		(stroke
			(width 0.06985)
			(type default)
		)
		(layer "In5.Cu")
	)
	(gr_line
		(start 254.66548 -31.060644)
		(end 255.09982 -31.495492)
		(stroke
			(width 0.0508)
			(type default)
		)
		(layer "In5.Cu")
	)
	(gr_line
		(start 254.696722 -66.812922)
		(end 254.740664 -66.856864)
		(stroke
			(width 0.0508)
			(type default)
		)
		(layer "In5.Cu")
	)
	(gr_line
		(start 254.696722 -66.6115)
		(end 254.696722 -66.812922)
		(stroke
			(width 0.0508)
			(type default)
		)
		(layer "In5.Cu")
	)
	(gr_line
		(start 254.742442 -66.858642)
		(end 254.762 -66.8782)
		(stroke
			(width 0.0508)
			(type default)
		)
		(layer "In5.Cu")
	)
	(gr_arc
		(start 254.748284 -65.0494)
		(mid 254.710129 -65.106503)
		(end 254.696722 -65.17386)
		(stroke
			(width 0.0508)
			(type default)
		)
		(layer "In5.Cu")
	)
	(gr_arc
		(start 254.773684 -30.061916)
		(mid 254.722574 -30.138493)
		(end 254.704596 -30.228794)
		(stroke
			(width 0.0508)
			(type default)
		)
		(layer "In5.Cu")
	)
	(gr_line
		(start 254.773684 -30.061916)
		(end 254.842772 -29.992828)
		(stroke
			(width 0.0508)
			(type default)
		)
		(layer "In5.Cu")
	)
	(gr_arc
		(start 254.78867 -30.89275)
		(mid 254.866057 -30.944425)
		(end 254.957326 -30.9626)
		(stroke
			(width 0.0508)
			(type default)
		)
		(layer "In5.Cu")
	)
	(gr_line
		(start 254.842772 -29.8323)
		(end 254.842772 -29.992828)
		(stroke
			(width 0.0508)
			(type default)
		)
		(layer "In5.Cu")
	)
	(gr_arc
		(start 254.870966 -64.9986)
		(mid 254.804577 -65.011806)
		(end 254.748284 -65.0494)
		(stroke
			(width 0.0508)
			(type default)
		)
		(layer "In5.Cu")
	)
	(gr_line
		(start 254.870966 -64.9986)
		(end 254.966978 -64.9986)
		(stroke
			(width 0.0508)
			(type default)
		)
		(layer "In5.Cu")
	)
	(gr_line
		(start 254.957326 -30.9626)
		(end 254.958088 -30.9626)
		(stroke
			(width 0.0508)
			(type default)
		)
		(layer "In5.Cu")
	)
	(gr_arc
		(start 254.958088 -30.9626)
		(mid 255.124765 -30.893565)
		(end 255.1938 -30.726888)
		(stroke
			(width 0.0508)
			(type default)
		)
		(layer "In5.Cu")
	)
	(gr_arc
		(start 255.063752 -65.038732)
		(mid 255.019352 -65.009065)
		(end 254.966978 -64.9986)
		(stroke
			(width 0.0508)
			(type default)
		)
		(layer "In5.Cu")
	)
	(gr_line
		(start 255.063752 -65.038732)
		(end 255.071372 -65.046352)
		(stroke
			(width 0.0508)
			(type default)
		)
		(layer "In5.Cu")
	)
	(gr_line
		(start 255.09982 -65.499742)
		(end 255.12522 -65.474342)
		(stroke
			(width 0.0508)
			(type default)
		)
		(layer "In5.Cu")
	)
	(gr_arc
		(start 255.09982 -64.499744)
		(mid 255.001258 -64.519349)
		(end 254.917702 -64.575182)
		(stroke
			(width 0.0508)
			(type default)
		)
		(layer "In5.Cu")
	)
	(gr_line
		(start 255.09982 -31.495492)
		(end 255.09982 -31.500064)
		(stroke
			(width 0.0508)
			(type default)
		)
		(layer "In5.Cu")
	)
	(gr_arc
		(start 255.12522 -65.1764)
		(mid 255.111222 -65.106026)
		(end 255.071372 -65.046352)
		(stroke
			(width 0.0508)
			(type default)
		)
		(layer "In5.Cu")
	)
	(gr_line
		(start 255.12522 -65.1764)
		(end 255.12522 -65.474342)
		(stroke
			(width 0.0508)
			(type default)
		)
		(layer "In5.Cu")
	)
	(gr_arc
		(start 255.1938 -30.726888)
		(mid 255.169356 -30.604135)
		(end 255.09982 -30.500066)
		(stroke
			(width 0.0508)
			(type default)
		)
		(layer "In5.Cu")
	)
	(gr_line
		(start 255.316482 -25.073356)
		(end 255.327404 -25.057862)
		(stroke
			(width 0.06985)
			(type default)
		)
		(layer "In5.Cu")
	)
	(gr_line
		(start 255.327404 -25.057862)
		(end 255.342898 -25.04694)
		(stroke
			(width 0.06985)
			(type default)
		)
		(layer "In5.Cu")
	)
	(gr_line
		(start 255.4224 -66.929)
		(end 255.441958 -66.909442)
		(stroke
			(width 0.0508)
			(type default)
		)
		(layer "In5.Cu")
	)
	(gr_line
		(start 255.443736 -66.907664)
		(end 255.49352 -66.85788)
		(stroke
			(width 0.0508)
			(type default)
		)
		(layer "In5.Cu")
	)
	(gr_line
		(start 255.49352 -66.6623)
		(end 255.49352 -66.85788)
		(stroke
			(width 0.0508)
			(type default)
		)
		(layer "In5.Cu")
	)
	(gr_arc
		(start 255.577848 -65.914778)
		(mid 255.515404 -66.008372)
		(end 255.49352 -66.11874)
		(stroke
			(width 0.0508)
			(type default)
		)
		(layer "In5.Cu")
	)
	(gr_line
		(start 255.577848 -65.914778)
		(end 255.9177 -65.57518)
		(stroke
			(width 0.0508)
			(type default)
		)
		(layer "In5.Cu")
	)
	(gr_line
		(start 255.604772 -28.23464)
		(end 255.62433 -28.254198)
		(stroke
			(width 0.0508)
			(type default)
		)
		(layer "In5.Cu")
	)
	(gr_line
		(start 255.604772 -28.20924)
		(end 255.604772 -28.23464)
		(stroke
			(width 0.0508)
			(type default)
		)
		(layer "In5.Cu")
	)
	(gr_line
		(start 255.626108 -28.255976)
		(end 255.668272 -28.29814)
		(stroke
			(width 0.0508)
			(type default)
		)
		(layer "In5.Cu")
	)
	(gr_line
		(start 255.69164 -30.091634)
		(end 255.759458 -30.159706)
		(stroke
			(width 0.0508)
			(type default)
		)
		(layer "In5.Cu")
	)
	(gr_line
		(start 255.69672 -66.87312)
		(end 255.731264 -66.907664)
		(stroke
			(width 0.0508)
			(type default)
		)
		(layer "In5.Cu")
	)
	(gr_line
		(start 255.733042 -66.909442)
		(end 255.7526 -66.929)
		(stroke
			(width 0.0508)
			(type default)
		)
		(layer "In5.Cu")
	)
	(gr_line
		(start 255.744218 -26.536396)
		(end 255.75006 -26.503884)
		(stroke
			(width 0.06985)
			(type default)
		)
		(layer "In5.Cu")
	)
	(gr_arc
		(start 255.748282 -66.049398)
		(mid 255.710127 -66.106501)
		(end 255.69672 -66.173858)
		(stroke
			(width 0.0508)
			(type default)
		)
		(layer "In5.Cu")
	)
	(gr_line
		(start 255.75006 -26.503884)
		(end 255.76911 -26.476706)
		(stroke
			(width 0.06985)
			(type default)
		)
		(layer "In5.Cu")
	)
	(gr_line
		(start 255.7526 -66.929)
		(end 255.7526 -67.12458)
		(stroke
			(width 0.06985)
			(type default)
		)
		(layer "In5.Cu")
	)
	(gr_line
		(start 255.759458 -30.159706)
		(end 256.099818 -30.500066)
		(stroke
			(width 0.0508)
			(type default)
		)
		(layer "In5.Cu")
	)
	(gr_line
		(start 255.788668 -29.892752)
		(end 255.905508 -30.009592)
		(stroke
			(width 0.0508)
			(type default)
		)
		(layer "In5.Cu")
	)
	(gr_line
		(start 255.842262 -21.759418)
		(end 255.864106 -21.744178)
		(stroke
			(width 0.06985)
			(type default)
		)
		(layer "In5.Cu")
	)
	(gr_line
		(start 255.864106 -21.744178)
		(end 255.890268 -21.73859)
		(stroke
			(width 0.06985)
			(type default)
		)
		(layer "In5.Cu")
	)
	(gr_arc
		(start 255.870964 -65.998598)
		(mid 255.804575 -66.011804)
		(end 255.748282 -66.049398)
		(stroke
			(width 0.0508)
			(type default)
		)
		(layer "In5.Cu")
	)
	(gr_line
		(start 255.870964 -65.998598)
		(end 255.966976 -65.998598)
		(stroke
			(width 0.0508)
			(type default)
		)
		(layer "In5.Cu")
	)
	(gr_line
		(start 255.871472 -28.29814)
		(end 255.913636 -28.255976)
		(stroke
			(width 0.0508)
			(type default)
		)
		(layer "In5.Cu")
	)
	(gr_arc
		(start 255.905508 -30.009592)
		(mid 256.029587 -30.034234)
		(end 256.099818 -29.929074)
		(stroke
			(width 0.0508)
			(type default)
		)
		(layer "In5.Cu")
	)
	(gr_line
		(start 255.915414 -28.254198)
		(end 255.934972 -28.23464)
		(stroke
			(width 0.0508)
			(type default)
		)
		(layer "In5.Cu")
	)
	(gr_line
		(start 255.934972 -28.20924)
		(end 255.934972 -28.23464)
		(stroke
			(width 0.0508)
			(type default)
		)
		(layer "In5.Cu")
	)
	(gr_arc
		(start 256.06375 -66.03873)
		(mid 256.01935 -66.009063)
		(end 255.966976 -65.998598)
		(stroke
			(width 0.0508)
			(type default)
		)
		(layer "In5.Cu")
	)
	(gr_line
		(start 256.06375 -66.03873)
		(end 256.07137 -66.04635)
		(stroke
			(width 0.0508)
			(type default)
		)
		(layer "In5.Cu")
	)
	(gr_line
		(start 256.099818 -66.49974)
		(end 256.125218 -66.47434)
		(stroke
			(width 0.0508)
			(type default)
		)
		(layer "In5.Cu")
	)
	(gr_arc
		(start 256.099818 -65.499742)
		(mid 256.001256 -65.519347)
		(end 255.9177 -65.57518)
		(stroke
			(width 0.0508)
			(type default)
		)
		(layer "In5.Cu")
	)
	(gr_line
		(start 256.099818 -29.500068)
		(end 256.099818 -29.929074)
		(stroke
			(width 0.0508)
			(type default)
		)
		(layer "In5.Cu")
	)
	(gr_arc
		(start 256.125218 -66.176398)
		(mid 256.11122 -66.106024)
		(end 256.07137 -66.04635)
		(stroke
			(width 0.0508)
			(type default)
		)
		(layer "In5.Cu")
	)
	(gr_line
		(start 256.125218 -66.176398)
		(end 256.125218 -66.47434)
		(stroke
			(width 0.0508)
			(type default)
		)
		(layer "In5.Cu")
	)
	(gr_line
		(start 256.395728 -25.581102)
		(end 256.40665 -25.565608)
		(stroke
			(width 0.06985)
			(type default)
		)
		(layer "In5.Cu")
	)
	(gr_line
		(start 256.40665 -25.565608)
		(end 256.422144 -25.554686)
		(stroke
			(width 0.06985)
			(type default)
		)
		(layer "In5.Cu")
	)
	(gr_line
		(start 256.413 -66.9544)
		(end 256.432558 -66.934842)
		(stroke
			(width 0.0508)
			(type default)
		)
		(layer "In5.Cu")
	)
	(gr_line
		(start 256.434336 -66.933064)
		(end 256.493518 -66.873882)
		(stroke
			(width 0.0508)
			(type default)
		)
		(layer "In5.Cu")
	)
	(gr_line
		(start 256.493518 -66.6877)
		(end 256.493518 -66.873882)
		(stroke
			(width 0.0508)
			(type default)
		)
		(layer "In5.Cu")
	)
	(gr_arc
		(start 256.577846 -64.91478)
		(mid 256.515402 -65.008374)
		(end 256.493518 -65.118742)
		(stroke
			(width 0.0508)
			(type default)
		)
		(layer "In5.Cu")
	)
	(gr_line
		(start 256.577846 -64.91478)
		(end 256.917698 -64.575182)
		(stroke
			(width 0.0508)
			(type default)
		)
		(layer "In5.Cu")
	)
	(gr_line
		(start 256.6162 -28.35402)
		(end 256.635758 -28.373578)
		(stroke
			(width 0.0508)
			(type default)
		)
		(layer "In5.Cu")
	)
	(gr_line
		(start 256.6162 -28.32862)
		(end 256.6162 -28.35402)
		(stroke
			(width 0.0508)
			(type default)
		)
		(layer "In5.Cu")
	)
	(gr_line
		(start 256.637536 -28.375356)
		(end 256.6797 -28.41752)
		(stroke
			(width 0.0508)
			(type default)
		)
		(layer "In5.Cu")
	)
	(gr_line
		(start 256.689352 -27.174444)
		(end 256.695194 -27.141424)
		(stroke
			(width 0.06985)
			(type default)
		)
		(layer "In5.Cu")
	)
	(gr_line
		(start 256.691638 -31.091632)
		(end 257.099816 -31.500064)
		(stroke
			(width 0.0508)
			(type default)
		)
		(layer "In5.Cu")
	)
	(gr_line
		(start 256.695194 -27.141424)
		(end 256.714244 -27.1145)
		(stroke
			(width 0.06985)
			(type default)
		)
		(layer "In5.Cu")
	)
	(gr_line
		(start 256.696718 -66.907918)
		(end 256.721864 -66.933064)
		(stroke
			(width 0.0508)
			(type default)
		)
		(layer "In5.Cu")
	)
	(gr_line
		(start 256.7178 -69.649848)
		(end 256.723642 -69.682868)
		(stroke
			(width 0.06985)
			(type default)
		)
		(layer "In5.Cu")
	)
	(gr_line
		(start 256.723642 -69.682868)
		(end 256.7432 -69.710808)
		(stroke
			(width 0.06985)
			(type default)
		)
		(layer "In5.Cu")
	)
	(gr_line
		(start 256.723642 -66.934842)
		(end 256.7432 -66.9544)
		(stroke
			(width 0.0508)
			(type default)
		)
		(layer "In5.Cu")
	)
	(gr_line
		(start 256.7432 -66.9544)
		(end 256.7432 -67.140582)
		(stroke
			(width 0.06985)
			(type default)
		)
		(layer "In5.Cu")
	)
	(gr_arc
		(start 256.74828 -65.0494)
		(mid 256.710125 -65.106503)
		(end 256.696718 -65.17386)
		(stroke
			(width 0.0508)
			(type default)
		)
		(layer "In5.Cu")
	)
	(gr_line
		(start 256.788666 -30.89275)
		(end 256.84226 -30.94609)
		(stroke
			(width 0.0508)
			(type default)
		)
		(layer "In5.Cu")
	)
	(gr_line
		(start 256.84226 -30.94609)
		(end 256.892044 -30.995874)
		(stroke
			(width 0.0508)
			(type default)
		)
		(layer "In5.Cu")
	)
	(gr_arc
		(start 256.870962 -64.9986)
		(mid 256.804573 -65.011806)
		(end 256.74828 -65.0494)
		(stroke
			(width 0.0508)
			(type default)
		)
		(layer "In5.Cu")
	)
	(gr_line
		(start 256.870962 -64.9986)
		(end 256.966974 -64.9986)
		(stroke
			(width 0.0508)
			(type default)
		)
		(layer "In5.Cu")
	)
	(gr_line
		(start 256.8829 -28.41752)
		(end 256.925064 -28.375356)
		(stroke
			(width 0.0508)
			(type default)
		)
		(layer "In5.Cu")
	)
	(gr_arc
		(start 256.892044 -30.995874)
		(mid 256.96672 -31.026806)
		(end 257.041396 -30.995874)
		(stroke
			(width 0.0508)
			(type default)
		)
		(layer "In5.Cu")
	)
	(gr_line
		(start 256.926842 -28.373578)
		(end 256.9464 -28.35402)
		(stroke
			(width 0.0508)
			(type default)
		)
		(layer "In5.Cu")
	)
	(gr_line
		(start 256.9464 -28.32862)
		(end 256.9464 -28.35402)
		(stroke
			(width 0.0508)
			(type default)
		)
		(layer "In5.Cu")
	)
	(gr_arc
		(start 257.041396 -30.995874)
		(mid 257.084612 -30.931196)
		(end 257.099816 -30.854904)
		(stroke
			(width 0.0508)
			(type default)
		)
		(layer "In5.Cu")
	)
	(gr_line
		(start 257.05689 -26.62555)
		(end 257.066542 -26.61158)
		(stroke
			(width 0.06985)
			(type default)
		)
		(layer "In5.Cu")
	)
	(gr_arc
		(start 257.063748 -65.038732)
		(mid 257.019348 -65.009065)
		(end 256.966974 -64.9986)
		(stroke
			(width 0.0508)
			(type default)
		)
		(layer "In5.Cu")
	)
	(gr_line
		(start 257.063748 -65.038732)
		(end 257.071368 -65.046352)
		(stroke
			(width 0.0508)
			(type default)
		)
		(layer "In5.Cu")
	)
	(gr_line
		(start 257.066542 -26.61158)
		(end 257.080512 -26.601674)
		(stroke
			(width 0.06985)
			(type default)
		)
		(layer "In5.Cu")
	)
	(gr_line
		(start 257.099816 -65.499742)
		(end 257.125216 -65.474342)
		(stroke
			(width 0.0508)
			(type default)
		)
		(layer "In5.Cu")
	)
	(gr_arc
		(start 257.099816 -64.499744)
		(mid 257.001254 -64.519349)
		(end 256.917698 -64.575182)
		(stroke
			(width 0.0508)
			(type default)
		)
		(layer "In5.Cu")
	)
	(gr_line
		(start 257.099816 -59.499754)
		(end 257.217926 -59.381644)
		(stroke
			(width 0.0508)
			(type default)
		)
		(layer "In5.Cu")
	)
	(gr_line
		(start 257.099816 -57.499758)
		(end 257.217926 -57.381648)
		(stroke
			(width 0.0508)
			(type default)
		)
		(layer "In5.Cu")
	)
	(gr_line
		(start 257.099816 -55.499762)
		(end 257.217926 -55.381652)
		(stroke
			(width 0.0508)
			(type default)
		)
		(layer "In5.Cu")
	)
	(gr_line
		(start 257.099816 -53.499766)
		(end 257.217926 -53.381656)
		(stroke
			(width 0.0508)
			(type default)
		)
		(layer "In5.Cu")
	)
	(gr_line
		(start 257.099816 -50.499772)
		(end 257.217926 -50.381662)
		(stroke
			(width 0.0508)
			(type default)
		)
		(layer "In5.Cu")
	)
	(gr_line
		(start 257.099816 -48.499776)
		(end 257.217926 -48.381666)
		(stroke
			(width 0.0508)
			(type default)
		)
		(layer "In5.Cu")
	)
	(gr_line
		(start 257.099816 -45.500036)
		(end 257.217926 -45.381926)
		(stroke
			(width 0.0508)
			(type default)
		)
		(layer "In5.Cu")
	)
	(gr_line
		(start 257.099816 -43.50004)
		(end 257.217926 -43.38193)
		(stroke
			(width 0.0508)
			(type default)
		)
		(layer "In5.Cu")
	)
	(gr_line
		(start 257.099816 -40.500046)
		(end 257.553968 -40.045894)
		(stroke
			(width 0.0508)
			(type default)
		)
		(layer "In5.Cu")
	)
	(gr_line
		(start 257.099816 -38.50005)
		(end 257.553968 -38.045898)
		(stroke
			(width 0.0508)
			(type default)
		)
		(layer "In5.Cu")
	)
	(gr_line
		(start 257.099816 -36.500054)
		(end 257.553968 -36.045902)
		(stroke
			(width 0.0508)
			(type default)
		)
		(layer "In5.Cu")
	)
	(gr_line
		(start 257.099816 -34.500058)
		(end 257.553968 -34.045906)
		(stroke
			(width 0.0508)
			(type default)
		)
		(layer "In5.Cu")
	)
	(gr_line
		(start 257.099816 -30.500066)
		(end 257.099816 -30.854904)
		(stroke
			(width 0.0508)
			(type default)
		)
		(layer "In5.Cu")
	)
	(gr_line
		(start 257.108198 -22.593046)
		(end 257.130042 -22.577806)
		(stroke
			(width 0.06985)
			(type default)
		)
		(layer "In5.Cu")
	)
	(gr_arc
		(start 257.125216 -65.1764)
		(mid 257.111218 -65.106026)
		(end 257.071368 -65.046352)
		(stroke
			(width 0.0508)
			(type default)
		)
		(layer "In5.Cu")
	)
	(gr_line
		(start 257.125216 -65.1764)
		(end 257.125216 -65.474342)
		(stroke
			(width 0.0508)
			(type default)
		)
		(layer "In5.Cu")
	)
	(gr_line
		(start 257.130042 -22.577806)
		(end 257.156204 -22.572218)
		(stroke
			(width 0.06985)
			(type default)
		)
		(layer "In5.Cu")
	)
	(gr_arc
		(start 257.276092 -59.357514)
		(mid 257.244611 -59.363802)
		(end 257.217926 -59.381644)
		(stroke
			(width 0.0508)
			(type default)
		)
		(layer "In5.Cu")
	)
	(gr_arc
		(start 257.276092 -57.357518)
		(mid 257.244611 -57.363807)
		(end 257.217926 -57.381648)
		(stroke
			(width 0.0508)
			(type default)
		)
		(layer "In5.Cu")
	)
	(gr_arc
		(start 257.276092 -55.357522)
		(mid 257.244599 -55.363786)
		(end 257.217926 -55.381652)
		(stroke
			(width 0.0508)
			(type default)
		)
		(layer "In5.Cu")
	)
	(gr_arc
		(start 257.276092 -53.357526)
		(mid 257.244612 -53.363815)
		(end 257.217926 -53.381656)
		(stroke
			(width 0.0508)
			(type default)
		)
		(layer "In5.Cu")
	)
	(gr_arc
		(start 257.276092 -50.357532)
		(mid 257.244599 -50.363796)
		(end 257.217926 -50.381662)
		(stroke
			(width 0.0508)
			(type default)
		)
		(layer "In5.Cu")
	)
	(gr_arc
		(start 257.276092 -48.357536)
		(mid 257.244599 -48.3638)
		(end 257.217926 -48.381666)
		(stroke
			(width 0.0508)
			(type default)
		)
		(layer "In5.Cu")
	)
	(gr_arc
		(start 257.276092 -45.357796)
		(mid 257.24461 -45.364083)
		(end 257.217926 -45.381926)
		(stroke
			(width 0.0508)
			(type default)
		)
		(layer "In5.Cu")
	)
	(gr_arc
		(start 257.276092 -43.3578)
		(mid 257.24461 -43.364088)
		(end 257.217926 -43.38193)
		(stroke
			(width 0.0508)
			(type default)
		)
		(layer "In5.Cu")
	)
	(gr_arc
		(start 257.325876 -59.363356)
		(mid 257.301156 -59.358967)
		(end 257.276092 -59.357514)
		(stroke
			(width 0.0508)
			(type default)
		)
		(layer "In5.Cu")
	)
	(gr_arc
		(start 257.325876 -57.36336)
		(mid 257.301157 -57.358971)
		(end 257.276092 -57.357518)
		(stroke
			(width 0.0508)
			(type default)
		)
		(layer "In5.Cu")
	)
	(gr_arc
		(start 257.325876 -55.363364)
		(mid 257.301156 -55.358977)
		(end 257.276092 -55.357522)
		(stroke
			(width 0.0508)
			(type default)
		)
		(layer "In5.Cu")
	)
	(gr_arc
		(start 257.325876 -53.363368)
		(mid 257.301157 -53.358979)
		(end 257.276092 -53.357526)
		(stroke
			(width 0.0508)
			(type default)
		)
		(layer "In5.Cu")
	)
	(gr_arc
		(start 257.325876 -50.363374)
		(mid 257.301156 -50.358987)
		(end 257.276092 -50.357532)
		(stroke
			(width 0.0508)
			(type default)
		)
		(layer "In5.Cu")
	)
	(gr_arc
		(start 257.325876 -48.363378)
		(mid 257.301156 -48.358991)
		(end 257.276092 -48.357536)
		(stroke
			(width 0.0508)
			(type default)
		)
		(layer "In5.Cu")
	)
	(gr_arc
		(start 257.325876 -45.363638)
		(mid 257.301157 -45.359247)
		(end 257.276092 -45.357796)
		(stroke
			(width 0.0508)
			(type default)
		)
		(layer "In5.Cu")
	)
	(gr_arc
		(start 257.325876 -43.363642)
		(mid 257.301157 -43.359251)
		(end 257.276092 -43.3578)
		(stroke
			(width 0.0508)
			(type default)
		)
		(layer "In5.Cu")
	)
	(gr_line
		(start 257.36677 -24.89327)
		(end 257.39471 -24.873712)
		(stroke
			(width 0.06985)
			(type default)
		)
		(layer "In5.Cu")
	)
	(gr_line
		(start 257.39471 -24.873712)
		(end 257.42773 -24.86787)
		(stroke
			(width 0.06985)
			(type default)
		)
		(layer "In5.Cu")
	)
	(gr_arc
		(start 257.396742 -59.395106)
		(mid 257.362762 -59.375988)
		(end 257.325876 -59.363356)
		(stroke
			(width 0.0508)
			(type default)
		)
		(layer "In5.Cu")
	)
	(gr_line
		(start 257.429 -66.929)
		(end 257.448558 -66.909442)
		(stroke
			(width 0.0508)
			(type default)
		)
		(layer "In5.Cu")
	)
	(gr_line
		(start 257.450336 -66.907664)
		(end 257.493516 -66.864484)
		(stroke
			(width 0.0508)
			(type default)
		)
		(layer "In5.Cu")
	)
	(gr_line
		(start 257.456178 -23.567644)
		(end 257.478022 -23.552404)
		(stroke
			(width 0.06985)
			(type default)
		)
		(layer "In5.Cu")
	)
	(gr_arc
		(start 257.472942 -59.489086)
		(mid 257.441618 -59.436603)
		(end 257.396742 -59.395106)
		(stroke
			(width 0.0508)
			(type default)
		)
		(layer "In5.Cu")
	)
	(gr_line
		(start 257.472942 -59.489086)
		(end 257.496056 -59.544712)
		(stroke
			(width 0.0508)
			(type default)
		)
		(layer "In5.Cu")
	)
	(gr_arc
		(start 257.472942 -57.48909)
		(mid 257.414536 -57.408528)
		(end 257.325876 -57.36336)
		(stroke
			(width 0.0508)
			(type default)
		)
		(layer "In5.Cu")
	)
	(gr_line
		(start 257.472942 -57.48909)
		(end 257.496056 -57.544716)
		(stroke
			(width 0.0508)
			(type default)
		)
		(layer "In5.Cu")
	)
	(gr_arc
		(start 257.472942 -55.489094)
		(mid 257.414479 -55.408619)
		(end 257.325876 -55.363364)
		(stroke
			(width 0.0508)
			(type default)
		)
		(layer "In5.Cu")
	)
	(gr_line
		(start 257.472942 -55.489094)
		(end 257.496056 -55.54472)
		(stroke
			(width 0.0508)
			(type default)
		)
		(layer "In5.Cu")
	)
	(gr_arc
		(start 257.472942 -53.489098)
		(mid 257.414537 -53.408534)
		(end 257.325876 -53.363368)
		(stroke
			(width 0.0508)
			(type default)
		)
		(layer "In5.Cu")
	)
	(gr_line
		(start 257.472942 -53.489098)
		(end 257.496056 -53.544724)
		(stroke
			(width 0.0508)
			(type default)
		)
		(layer "In5.Cu")
	)
	(gr_arc
		(start 257.472942 -50.489104)
		(mid 257.414479 -50.408629)
		(end 257.325876 -50.363374)
		(stroke
			(width 0.0508)
			(type default)
		)
		(layer "In5.Cu")
	)
	(gr_line
		(start 257.472942 -50.489104)
		(end 257.496056 -50.54473)
		(stroke
			(width 0.0508)
			(type default)
		)
		(layer "In5.Cu")
	)
	(gr_arc
		(start 257.472942 -48.489108)
		(mid 257.414479 -48.408633)
		(end 257.325876 -48.363378)
		(stroke
			(width 0.0508)
			(type default)
		)
		(layer "In5.Cu")
	)
	(gr_line
		(start 257.472942 -48.489108)
		(end 257.496056 -48.544734)
		(stroke
			(width 0.0508)
			(type default)
		)
		(layer "In5.Cu")
	)
	(gr_arc
		(start 257.472942 -45.489368)
		(mid 257.414532 -45.408814)
		(end 257.325876 -45.363638)
		(stroke
			(width 0.0508)
			(type default)
		)
		(layer "In5.Cu")
	)
	(gr_line
		(start 257.472942 -45.489368)
		(end 257.496056 -45.544994)
		(stroke
			(width 0.0508)
			(type default)
		)
		(layer "In5.Cu")
	)
	(gr_arc
		(start 257.472942 -43.489372)
		(mid 257.414532 -43.408816)
		(end 257.325876 -43.363642)
		(stroke
			(width 0.0508)
			(type default)
		)
		(layer "In5.Cu")
	)
	(gr_line
		(start 257.472942 -43.489372)
		(end 257.496056 -43.544998)
		(stroke
			(width 0.0508)
			(type default)
		)
		(layer "In5.Cu")
	)
	(gr_line
		(start 257.478022 -23.552404)
		(end 257.504184 -23.546816)
		(stroke
			(width 0.06985)
			(type default)
		)
		(layer "In5.Cu")
	)
	(gr_line
		(start 257.493516 -66.6623)
		(end 257.493516 -66.864484)
		(stroke
			(width 0.0508)
			(type default)
		)
		(layer "In5.Cu")
	)
	(gr_arc
		(start 257.513582 -59.682634)
		(mid 257.513959 -59.690419)
		(end 257.515106 -59.698128)
		(stroke
			(width 0.0508)
			(type default)
		)
		(layer "In5.Cu")
	)
	(gr_arc
		(start 257.513582 -59.63285)
		(mid 257.509167 -59.587915)
		(end 257.496056 -59.544712)
		(stroke
			(width 0.0508)
			(type default)
		)
		(layer "In5.Cu")
	)
	(gr_line
		(start 257.513582 -59.63285)
		(end 257.513582 -59.682634)
		(stroke
			(width 0.0508)
			(type default)
		)
		(layer "In5.Cu")
	)
	(gr_arc
		(start 257.513582 -57.682638)
		(mid 257.513959 -57.690423)
		(end 257.515106 -57.698132)
		(stroke
			(width 0.0508)
			(type default)
		)
		(layer "In5.Cu")
	)
	(gr_arc
		(start 257.513582 -57.632854)
		(mid 257.509149 -57.587925)
		(end 257.496056 -57.544716)
		(stroke
			(width 0.0508)
			(type default)
		)
		(layer "In5.Cu")
	)
	(gr_line
		(start 257.513582 -57.632854)
		(end 257.513582 -57.682638)
		(stroke
			(width 0.0508)
			(type default)
		)
		(layer "In5.Cu")
	)
	(gr_arc
		(start 257.513582 -55.682642)
		(mid 257.513982 -55.690424)
		(end 257.515106 -55.698136)
		(stroke
			(width 0.0508)
			(type default)
		)
		(layer "In5.Cu")
	)
	(gr_arc
		(start 257.513582 -55.632858)
		(mid 257.509158 -55.587926)
		(end 257.496056 -55.54472)
		(stroke
			(width 0.0508)
			(type default)
		)
		(layer "In5.Cu")
	)
	(gr_line
		(start 257.513582 -55.632858)
		(end 257.513582 -55.682642)
		(stroke
			(width 0.0508)
			(type default)
		)
		(layer "In5.Cu")
	)
	(gr_arc
		(start 257.513582 -53.682646)
		(mid 257.513959 -53.690431)
		(end 257.515106 -53.69814)
		(stroke
			(width 0.0508)
			(type default)
		)
		(layer "In5.Cu")
	)
	(gr_arc
		(start 257.513582 -53.632862)
		(mid 257.509151 -53.587932)
		(end 257.496056 -53.544724)
		(stroke
			(width 0.0508)
			(type default)
		)
		(layer "In5.Cu")
	)
	(gr_line
		(start 257.513582 -53.632862)
		(end 257.513582 -53.682646)
		(stroke
			(width 0.0508)
			(type default)
		)
		(layer "In5.Cu")
	)
	(gr_arc
		(start 257.513582 -50.682652)
		(mid 257.513973 -50.690436)
		(end 257.515106 -50.698146)
		(stroke
			(width 0.0508)
			(type default)
		)
		(layer "In5.Cu")
	)
	(gr_arc
		(start 257.513582 -50.632868)
		(mid 257.509158 -50.587936)
		(end 257.496056 -50.54473)
		(stroke
			(width 0.0508)
			(type default)
		)
		(layer "In5.Cu")
	)
	(gr_line
		(start 257.513582 -50.632868)
		(end 257.513582 -50.682652)
		(stroke
			(width 0.0508)
			(type default)
		)
		(layer "In5.Cu")
	)
	(gr_arc
		(start 257.513582 -48.682656)
		(mid 257.513974 -48.69044)
		(end 257.515106 -48.69815)
		(stroke
			(width 0.0508)
			(type default)
		)
		(layer "In5.Cu")
	)
	(gr_arc
		(start 257.513582 -48.632872)
		(mid 257.509158 -48.58794)
		(end 257.496056 -48.544734)
		(stroke
			(width 0.0508)
			(type default)
		)
		(layer "In5.Cu")
	)
	(gr_line
		(start 257.513582 -48.632872)
		(end 257.513582 -48.682656)
		(stroke
			(width 0.0508)
			(type default)
		)
		(layer "In5.Cu")
	)
	(gr_arc
		(start 257.513582 -45.682916)
		(mid 257.513959 -45.690701)
		(end 257.515106 -45.69841)
		(stroke
			(width 0.0508)
			(type default)
		)
		(layer "In5.Cu")
	)
	(gr_arc
		(start 257.513582 -45.633132)
		(mid 257.509164 -45.588198)
		(end 257.496056 -45.544994)
		(stroke
			(width 0.0508)
			(type default)
		)
		(layer "In5.Cu")
	)
	(gr_line
		(start 257.513582 -45.633132)
		(end 257.513582 -45.682916)
		(stroke
			(width 0.0508)
			(type default)
		)
		(layer "In5.Cu")
	)
	(gr_arc
		(start 257.513582 -43.68292)
		(mid 257.513959 -43.690705)
		(end 257.515106 -43.698414)
		(stroke
			(width 0.0508)
			(type default)
		)
		(layer "In5.Cu")
	)
	(gr_arc
		(start 257.513582 -43.633136)
		(mid 257.509165 -43.588202)
		(end 257.496056 -43.544998)
		(stroke
			(width 0.0508)
			(type default)
		)
		(layer "In5.Cu")
	)
	(gr_line
		(start 257.513582 -43.633136)
		(end 257.513582 -43.68292)
		(stroke
			(width 0.0508)
			(type default)
		)
		(layer "In5.Cu")
	)
	(gr_line
		(start 257.515106 -59.698128)
		(end 257.526536 -59.75604)
		(stroke
			(width 0.0508)
			(type default)
		)
		(layer "In5.Cu")
	)
	(gr_line
		(start 257.515106 -57.698132)
		(end 257.526536 -57.756044)
		(stroke
			(width 0.0508)
			(type default)
		)
		(layer "In5.Cu")
	)
	(gr_line
		(start 257.515106 -55.698136)
		(end 257.526536 -55.756048)
		(stroke
			(width 0.0508)
			(type default)
		)
		(layer "In5.Cu")
	)
	(gr_line
		(start 257.515106 -53.69814)
		(end 257.526536 -53.756052)
		(stroke
			(width 0.0508)
			(type default)
		)
		(layer "In5.Cu")
	)
	(gr_line
		(start 257.515106 -50.698146)
		(end 257.526536 -50.756058)
		(stroke
			(width 0.0508)
			(type default)
		)
		(layer "In5.Cu")
	)
	(gr_line
		(start 257.515106 -48.69815)
		(end 257.526536 -48.756062)
		(stroke
			(width 0.0508)
			(type default)
		)
		(layer "In5.Cu")
	)
	(gr_line
		(start 257.515106 -45.69841)
		(end 257.526536 -45.756322)
		(stroke
			(width 0.0508)
			(type default)
		)
		(layer "In5.Cu")
	)
	(gr_line
		(start 257.515106 -43.698414)
		(end 257.526536 -43.756326)
		(stroke
			(width 0.0508)
			(type default)
		)
		(layer "In5.Cu")
	)
	(gr_arc
		(start 257.577844 -65.914778)
		(mid 257.5154 -66.008372)
		(end 257.493516 -66.11874)
		(stroke
			(width 0.0508)
			(type default)
		)
		(layer "In5.Cu")
	)
	(gr_line
		(start 257.577844 -65.914778)
		(end 257.917696 -65.57518)
		(stroke
			(width 0.0508)
			(type default)
		)
		(layer "In5.Cu")
	)
	(gr_line
		(start 257.600958 -68.89623)
		(end 257.6068 -68.92925)
		(stroke
			(width 0.06985)
			(type default)
		)
		(layer "In5.Cu")
	)
	(gr_line
		(start 257.6068 -68.92925)
		(end 257.626358 -68.95719)
		(stroke
			(width 0.06985)
			(type default)
		)
		(layer "In5.Cu")
	)
	(gr_line
		(start 257.696716 -66.866516)
		(end 257.737864 -66.907664)
		(stroke
			(width 0.0508)
			(type default)
		)
		(layer "In5.Cu")
	)
	(gr_line
		(start 257.722624 -59.666378)
		(end 257.722624 -59.682634)
		(stroke
			(width 0.0508)
			(type default)
		)
		(layer "In5.Cu")
	)
	(gr_line
		(start 257.722624 -57.666382)
		(end 257.722624 -57.682638)
		(stroke
			(width 0.0508)
			(type default)
		)
		(layer "In5.Cu")
	)
	(gr_arc
		(start 257.722624 -55.682642)
		(mid 257.722615 -55.68442)
		(end 257.722624 -55.686198)
		(stroke
			(width 0.0508)
			(type default)
		)
		(layer "In5.Cu")
	)
	(gr_line
		(start 257.722624 -55.666386)
		(end 257.722624 -55.682642)
		(stroke
			(width 0.0508)
			(type default)
		)
		(layer "In5.Cu")
	)
	(gr_line
		(start 257.722624 -53.66639)
		(end 257.722624 -53.682646)
		(stroke
			(width 0.0508)
			(type default)
		)
		(layer "In5.Cu")
	)
	(gr_arc
		(start 257.722624 -50.682652)
		(mid 257.722615 -50.68443)
		(end 257.722624 -50.686208)
		(stroke
			(width 0.0508)
			(type default)
		)
		(layer "In5.Cu")
	)
	(gr_line
		(start 257.722624 -50.666396)
		(end 257.722624 -50.682652)
		(stroke
			(width 0.0508)
			(type default)
		)
		(layer "In5.Cu")
	)
	(gr_arc
		(start 257.722624 -48.682656)
		(mid 257.722615 -48.684434)
		(end 257.722624 -48.686212)
		(stroke
			(width 0.0508)
			(type default)
		)
		(layer "In5.Cu")
	)
	(gr_line
		(start 257.722624 -48.6664)
		(end 257.722624 -48.682656)
		(stroke
			(width 0.0508)
			(type default)
		)
		(layer "In5.Cu")
	)
	(gr_line
		(start 257.722624 -45.66666)
		(end 257.722624 -45.682916)
		(stroke
			(width 0.0508)
			(type default)
		)
		(layer "In5.Cu")
	)
	(gr_line
		(start 257.722624 -43.666664)
		(end 257.722624 -43.68292)
		(stroke
			(width 0.0508)
			(type default)
		)
		(layer "In5.Cu")
	)
	(gr_arc
		(start 257.724148 -59.654948)
		(mid 257.723265 -59.660647)
		(end 257.722624 -59.666378)
		(stroke
			(width 0.0508)
			(type default)
		)
		(layer "In5.Cu")
	)
	(gr_arc
		(start 257.724148 -57.654952)
		(mid 257.723265 -57.660651)
		(end 257.722624 -57.666382)
		(stroke
			(width 0.0508)
			(type default)
		)
		(layer "In5.Cu")
	)
	(gr_arc
		(start 257.724148 -55.654956)
		(mid 257.723272 -55.660656)
		(end 257.722624 -55.666386)
		(stroke
			(width 0.0508)
			(type default)
		)
		(layer "In5.Cu")
	)
	(gr_arc
		(start 257.724148 -53.65496)
		(mid 257.723265 -53.660659)
		(end 257.722624 -53.66639)
		(stroke
			(width 0.0508)
			(type default)
		)
		(layer "In5.Cu")
	)
	(gr_arc
		(start 257.724148 -50.654966)
		(mid 257.723268 -50.660665)
		(end 257.722624 -50.666396)
		(stroke
			(width 0.0508)
			(type default)
		)
		(layer "In5.Cu")
	)
	(gr_arc
		(start 257.724148 -48.65497)
		(mid 257.723268 -48.660669)
		(end 257.722624 -48.6664)
		(stroke
			(width 0.0508)
			(type default)
		)
		(layer "In5.Cu")
	)
	(gr_arc
		(start 257.724148 -45.65523)
		(mid 257.723265 -45.660929)
		(end 257.722624 -45.66666)
		(stroke
			(width 0.0508)
			(type default)
		)
		(layer "In5.Cu")
	)
	(gr_arc
		(start 257.724148 -43.655234)
		(mid 257.723265 -43.660933)
		(end 257.722624 -43.666664)
		(stroke
			(width 0.0508)
			(type default)
		)
		(layer "In5.Cu")
	)
	(gr_arc
		(start 257.735832 -59.619134)
		(mid 257.728755 -59.636639)
		(end 257.724148 -59.654948)
		(stroke
			(width 0.0508)
			(type default)
		)
		(layer "In5.Cu")
	)
	(gr_arc
		(start 257.735832 -59.618626)
		(mid 257.735832 -59.61888)
		(end 257.735832 -59.619134)
		(stroke
			(width 0.0508)
			(type default)
		)
		(layer "In5.Cu")
	)
	(gr_arc
		(start 257.735832 -57.619138)
		(mid 257.728755 -57.636643)
		(end 257.724148 -57.654952)
		(stroke
			(width 0.0508)
			(type default)
		)
		(layer "In5.Cu")
	)
	(gr_arc
		(start 257.735832 -55.619142)
		(mid 257.728783 -55.636655)
		(end 257.724148 -55.654956)
		(stroke
			(width 0.0508)
			(type default)
		)
		(layer "In5.Cu")
	)
	(gr_arc
		(start 257.735832 -53.619146)
		(mid 257.728755 -53.636651)
		(end 257.724148 -53.65496)
		(stroke
			(width 0.0508)
			(type default)
		)
		(layer "In5.Cu")
	)
	(gr_arc
		(start 257.735832 -50.619152)
		(mid 257.728784 -50.636666)
		(end 257.724148 -50.654966)
		(stroke
			(width 0.0508)
			(type default)
		)
		(layer "In5.Cu")
	)
	(gr_arc
		(start 257.735832 -48.619156)
		(mid 257.728785 -48.63667)
		(end 257.724148 -48.65497)
		(stroke
			(width 0.0508)
			(type default)
		)
		(layer "In5.Cu")
	)
	(gr_arc
		(start 257.735832 -45.619416)
		(mid 257.728755 -45.636921)
		(end 257.724148 -45.65523)
		(stroke
			(width 0.0508)
			(type default)
		)
		(layer "In5.Cu")
	)
	(gr_arc
		(start 257.735832 -43.61942)
		(mid 257.728755 -43.636925)
		(end 257.724148 -43.655234)
		(stroke
			(width 0.0508)
			(type default)
		)
		(layer "In5.Cu")
	)
	(gr_line
		(start 257.739642 -66.909442)
		(end 257.7592 -66.929)
		(stroke
			(width 0.0508)
			(type default)
		)
		(layer "In5.Cu")
	)
	(gr_arc
		(start 257.74015 -59.611006)
		(mid 257.737931 -59.614782)
		(end 257.735832 -59.618626)
		(stroke
			(width 0.0508)
			(type default)
		)
		(layer "In5.Cu")
	)
	(gr_arc
		(start 257.74015 -57.61101)
		(mid 257.737919 -57.615036)
		(end 257.735832 -57.619138)
		(stroke
			(width 0.0508)
			(type default)
		)
		(layer "In5.Cu")
	)
	(gr_arc
		(start 257.74015 -55.611014)
		(mid 257.737928 -55.615044)
		(end 257.735832 -55.619142)
		(stroke
			(width 0.0508)
			(type default)
		)
		(layer "In5.Cu")
	)
	(gr_arc
		(start 257.74015 -53.611018)
		(mid 257.737919 -53.615044)
		(end 257.735832 -53.619146)
		(stroke
			(width 0.0508)
			(type default)
		)
		(layer "In5.Cu")
	)
	(gr_arc
		(start 257.74015 -50.611024)
		(mid 257.737928 -50.615055)
		(end 257.735832 -50.619152)
		(stroke
			(width 0.0508)
			(type default)
		)
		(layer "In5.Cu")
	)
	(gr_arc
		(start 257.74015 -48.611028)
		(mid 257.737928 -48.615059)
		(end 257.735832 -48.619156)
		(stroke
			(width 0.0508)
			(type default)
		)
		(layer "In5.Cu")
	)
	(gr_arc
		(start 257.74015 -45.611288)
		(mid 257.737919 -45.615314)
		(end 257.735832 -45.619416)
		(stroke
			(width 0.0508)
			(type default)
		)
		(layer "In5.Cu")
	)
	(gr_arc
		(start 257.74015 -43.611292)
		(mid 257.737919 -43.615318)
		(end 257.735832 -43.61942)
		(stroke
			(width 0.0508)
			(type default)
		)
		(layer "In5.Cu")
	)
	(gr_arc
		(start 257.74142 -59.609228)
		(mid 257.740782 -59.610115)
		(end 257.74015 -59.611006)
		(stroke
			(width 0.0508)
			(type default)
		)
		(layer "In5.Cu")
	)
	(gr_arc
		(start 257.74142 -57.609232)
		(mid 257.740782 -57.610119)
		(end 257.74015 -57.61101)
		(stroke
			(width 0.0508)
			(type default)
		)
		(layer "In5.Cu")
	)
	(gr_arc
		(start 257.74142 -55.609236)
		(mid 257.740782 -55.610123)
		(end 257.74015 -55.611014)
		(stroke
			(width 0.0508)
			(type default)
		)
		(layer "In5.Cu")
	)
	(gr_arc
		(start 257.74142 -53.60924)
		(mid 257.740782 -53.610127)
		(end 257.74015 -53.611018)
		(stroke
			(width 0.0508)
			(type default)
		)
		(layer "In5.Cu")
	)
	(gr_arc
		(start 257.74142 -50.609246)
		(mid 257.740782 -50.610133)
		(end 257.74015 -50.611024)
		(stroke
			(width 0.0508)
			(type default)
		)
		(layer "In5.Cu")
	)
	(gr_arc
		(start 257.74142 -48.60925)
		(mid 257.740782 -48.610137)
		(end 257.74015 -48.611028)
		(stroke
			(width 0.0508)
			(type default)
		)
		(layer "In5.Cu")
	)
	(gr_arc
		(start 257.74142 -45.60951)
		(mid 257.740782 -45.610397)
		(end 257.74015 -45.611288)
		(stroke
			(width 0.0508)
			(type default)
		)
		(layer "In5.Cu")
	)
	(gr_arc
		(start 257.74142 -43.609514)
		(mid 257.740782 -43.610401)
		(end 257.74015 -43.611292)
		(stroke
			(width 0.0508)
			(type default)
		)
		(layer "In5.Cu")
	)
	(gr_arc
		(start 257.748278 -66.049398)
		(mid 257.710123 -66.106501)
		(end 257.696716 -66.173858)
		(stroke
			(width 0.0508)
			(type default)
		)
		(layer "In5.Cu")
	)
	(gr_line
		(start 257.7592 -66.929)
		(end 257.7592 -67.131184)
		(stroke
			(width 0.06985)
			(type default)
		)
		(layer "In5.Cu")
	)
	(gr_arc
		(start 257.762502 -59.582558)
		(mid 257.751139 -59.595243)
		(end 257.74142 -59.609228)
		(stroke
			(width 0.0508)
			(type default)
		)
		(layer "In5.Cu")
	)
	(gr_line
		(start 257.762502 -59.582558)
		(end 257.7846 -59.560714)
		(stroke
			(width 0.0508)
			(type default)
		)
		(layer "In5.Cu")
	)
	(gr_arc
		(start 257.762502 -57.582562)
		(mid 257.751139 -57.595247)
		(end 257.74142 -57.609232)
		(stroke
			(width 0.0508)
			(type default)
		)
		(layer "In5.Cu")
	)
	(gr_line
		(start 257.762502 -57.582562)
		(end 257.7846 -57.560718)
		(stroke
			(width 0.0508)
			(type default)
		)
		(layer "In5.Cu")
	)
	(gr_arc
		(start 257.762502 -55.582566)
		(mid 257.751146 -55.595256)
		(end 257.74142 -55.609236)
		(stroke
			(width 0.0508)
			(type default)
		)
		(layer "In5.Cu")
	)
	(gr_line
		(start 257.762502 -55.582566)
		(end 257.7846 -55.560722)
		(stroke
			(width 0.0508)
			(type default)
		)
		(layer "In5.Cu")
	)
	(gr_arc
		(start 257.762502 -53.58257)
		(mid 257.751139 -53.595255)
		(end 257.74142 -53.60924)
		(stroke
			(width 0.0508)
			(type default)
		)
		(layer "In5.Cu")
	)
	(gr_line
		(start 257.762502 -53.58257)
		(end 257.7846 -53.560726)
		(stroke
			(width 0.0508)
			(type default)
		)
		(layer "In5.Cu")
	)
	(gr_arc
		(start 257.762502 -50.582576)
		(mid 257.751139 -50.595262)
		(end 257.74142 -50.609246)
		(stroke
			(width 0.0508)
			(type default)
		)
		(layer "In5.Cu")
	)
	(gr_line
		(start 257.762502 -50.582576)
		(end 257.7846 -50.560732)
		(stroke
			(width 0.0508)
			(type default)
		)
		(layer "In5.Cu")
	)
	(gr_arc
		(start 257.762502 -48.58258)
		(mid 257.751139 -48.595266)
		(end 257.74142 -48.60925)
		(stroke
			(width 0.0508)
			(type default)
		)
		(layer "In5.Cu")
	)
	(gr_line
		(start 257.762502 -48.58258)
		(end 257.7846 -48.560736)
		(stroke
			(width 0.0508)
			(type default)
		)
		(layer "In5.Cu")
	)
	(gr_arc
		(start 257.762502 -45.58284)
		(mid 257.751139 -45.595525)
		(end 257.74142 -45.60951)
		(stroke
			(width 0.0508)
			(type default)
		)
		(layer "In5.Cu")
	)
	(gr_line
		(start 257.762502 -45.58284)
		(end 257.7846 -45.560996)
		(stroke
			(width 0.0508)
			(type default)
		)
		(layer "In5.Cu")
	)
	(gr_arc
		(start 257.762502 -43.582844)
		(mid 257.751139 -43.595529)
		(end 257.74142 -43.609514)
		(stroke
			(width 0.0508)
			(type default)
		)
		(layer "In5.Cu")
	)
	(gr_line
		(start 257.762502 -43.582844)
		(end 257.7846 -43.561)
		(stroke
			(width 0.0508)
			(type default)
		)
		(layer "In5.Cu")
	)
	(gr_arc
		(start 257.773424 -39.91864)
		(mid 257.655352 -39.967877)
		(end 257.553968 -40.045894)
		(stroke
			(width 0.0508)
			(type default)
		)
		(layer "In5.Cu")
	)
	(gr_arc
		(start 257.773424 -37.918644)
		(mid 257.655373 -37.967913)
		(end 257.553968 -38.045898)
		(stroke
			(width 0.0508)
			(type default)
		)
		(layer "In5.Cu")
	)
	(gr_arc
		(start 257.773424 -35.918648)
		(mid 257.655373 -35.967917)
		(end 257.553968 -36.045902)
		(stroke
			(width 0.0508)
			(type default)
		)
		(layer "In5.Cu")
	)
	(gr_line
		(start 257.828796 -26.077926)
		(end 257.856736 -26.058368)
		(stroke
			(width 0.06985)
			(type default)
		)
		(layer "In5.Cu")
	)
	(gr_line
		(start 257.856736 -26.058368)
		(end 257.889756 -26.052526)
		(stroke
			(width 0.06985)
			(type default)
		)
		(layer "In5.Cu")
	)
	(gr_arc
		(start 257.87096 -65.998598)
		(mid 257.804571 -66.011804)
		(end 257.748278 -66.049398)
		(stroke
			(width 0.0508)
			(type default)
		)
		(layer "In5.Cu")
	)
	(gr_line
		(start 257.87096 -65.998598)
		(end 257.966972 -65.998598)
		(stroke
			(width 0.0508)
			(type default)
		)
		(layer "In5.Cu")
	)
	(gr_arc
		(start 257.876802 -40.302434)
		(mid 257.943617 -40.451672)
		(end 258.099814 -40.500046)
		(stroke
			(width 0.0508)
			(type default)
		)
		(layer "In5.Cu")
	)
	(gr_arc
		(start 257.876802 -38.302438)
		(mid 257.943617 -38.451676)
		(end 258.099814 -38.50005)
		(stroke
			(width 0.0508)
			(type default)
		)
		(layer "In5.Cu")
	)
	(gr_line
		(start 257.876802 -38.286182)
		(end 257.876802 -38.302438)
		(stroke
			(width 0.0508)
			(type default)
		)
		(layer "In5.Cu")
	)
	(gr_arc
		(start 257.876802 -36.302442)
		(mid 257.943617 -36.45168)
		(end 258.099814 -36.500054)
		(stroke
			(width 0.0508)
			(type default)
		)
		(layer "In5.Cu")
	)
	(gr_line
		(start 257.876802 -36.274756)
		(end 257.876802 -36.302442)
		(stroke
			(width 0.0508)
			(type default)
		)
		(layer "In5.Cu")
	)
	(gr_arc
		(start 257.902202 -39.901622)
		(mid 257.83725 -39.905873)
		(end 257.773424 -39.91864)
		(stroke
			(width 0.0508)
			(type default)
		)
		(layer "In5.Cu")
	)
	(gr_arc
		(start 257.902202 -37.901626)
		(mid 257.837247 -37.90586)
		(end 257.773424 -37.918644)
		(stroke
			(width 0.0508)
			(type default)
		)
		(layer "In5.Cu")
	)
	(gr_arc
		(start 257.902202 -35.90163)
		(mid 257.837247 -35.905864)
		(end 257.773424 -35.918648)
		(stroke
			(width 0.0508)
			(type default)
		)
		(layer "In5.Cu")
	)
	(gr_arc
		(start 257.902202 -33.901634)
		(mid 257.713728 -33.939124)
		(end 257.553968 -34.045906)
		(stroke
			(width 0.0508)
			(type default)
		)
		(layer "In5.Cu")
	)
	(gr_arc
		(start 257.926586 -36.154614)
		(mid 257.889755 -36.209736)
		(end 257.876802 -36.274756)
		(stroke
			(width 0.0508)
			(type default)
		)
		(layer "In5.Cu")
	)
	(gr_line
		(start 257.931666 -59.499754)
		(end 258.099814 -59.499754)
		(stroke
			(width 0.0508)
			(type default)
		)
		(layer "In5.Cu")
	)
	(gr_line
		(start 257.931666 -57.499758)
		(end 258.099814 -57.499758)
		(stroke
			(width 0.0508)
			(type default)
		)
		(layer "In5.Cu")
	)
	(gr_arc
		(start 257.931666 -55.499762)
		(mid 257.852074 -55.515628)
		(end 257.7846 -55.560722)
		(stroke
			(width 0.0508)
			(type default)
		)
		(layer "In5.Cu")
	)
	(gr_line
		(start 257.931666 -55.499762)
		(end 258.099814 -55.499762)
		(stroke
			(width 0.0508)
			(type default)
		)
		(layer "In5.Cu")
	)
	(gr_line
		(start 257.931666 -53.499766)
		(end 258.099814 -53.499766)
		(stroke
			(width 0.0508)
			(type default)
		)
		(layer "In5.Cu")
	)
	(gr_arc
		(start 257.931666 -50.499772)
		(mid 257.852075 -50.515639)
		(end 257.7846 -50.560732)
		(stroke
			(width 0.0508)
			(type default)
		)
		(layer "In5.Cu")
	)
	(gr_line
		(start 257.931666 -50.499772)
		(end 258.099814 -50.499772)
		(stroke
			(width 0.0508)
			(type default)
		)
		(layer "In5.Cu")
	)
	(gr_arc
		(start 257.931666 -48.499776)
		(mid 257.852075 -48.515643)
		(end 257.7846 -48.560736)
		(stroke
			(width 0.0508)
			(type default)
		)
		(layer "In5.Cu")
	)
	(gr_line
		(start 257.931666 -48.499776)
		(end 258.099814 -48.499776)
		(stroke
			(width 0.0508)
			(type default)
		)
		(layer "In5.Cu")
	)
	(gr_line
		(start 257.931666 -45.500036)
		(end 258.099814 -45.500036)
		(stroke
			(width 0.0508)
			(type default)
		)
		(layer "In5.Cu")
	)
	(gr_line
		(start 257.931666 -43.50004)
		(end 258.099814 -43.50004)
		(stroke
			(width 0.0508)
			(type default)
		)
		(layer "In5.Cu")
	)
	(gr_arc
		(start 258.046728 -36.10483)
		(mid 257.9817 -36.117765)
		(end 257.926586 -36.154614)
		(stroke
			(width 0.0508)
			(type default)
		)
		(layer "In5.Cu")
	)
	(gr_arc
		(start 258.053332 -40.104822)
		(mid 257.920888 -40.164126)
		(end 257.876802 -40.302434)
		(stroke
			(width 0.0508)
			(type default)
		)
		(layer "In5.Cu")
	)
	(gr_arc
		(start 258.058158 -38.104826)
		(mid 257.92992 -38.157944)
		(end 257.876802 -38.286182)
		(stroke
			(width 0.0508)
			(type default)
		)
		(layer "In5.Cu")
	)
	(gr_arc
		(start 258.063746 -66.03873)
		(mid 258.019346 -66.009063)
		(end 257.966972 -65.998598)
		(stroke
			(width 0.0508)
			(type default)
		)
		(layer "In5.Cu")
	)
	(gr_line
		(start 258.063746 -66.03873)
		(end 258.071366 -66.04635)
		(stroke
			(width 0.0508)
			(type default)
		)
		(layer "In5.Cu")
	)
	(gr_line
		(start 258.069842 -44.092114)
		(end 258.138168 -44.092114)
		(stroke
			(width 0.0508)
			(type default)
		)
		(layer "In5.Cu")
	)
	(gr_line
		(start 258.074414 -34.500058)
		(end 258.099814 -34.500058)
		(stroke
			(width 0.0508)
			(type default)
		)
		(layer "In5.Cu")
	)
	(gr_arc
		(start 258.074414 -34.104834)
		(mid 257.876802 -34.302446)
		(end 258.074414 -34.500058)
		(stroke
			(width 0.0508)
			(type default)
		)
		(layer "In5.Cu")
	)
	(gr_line
		(start 258.092702 -29.8069)
		(end 258.099814 -29.799788)
		(stroke
			(width 0.0508)
			(type default)
		)
		(layer "In5.Cu")
	)
	(gr_line
		(start 258.099814 -66.49974)
		(end 258.125214 -66.47434)
		(stroke
			(width 0.0508)
			(type default)
		)
		(layer "In5.Cu")
	)
	(gr_arc
		(start 258.099814 -65.499742)
		(mid 258.001252 -65.519347)
		(end 257.917696 -65.57518)
		(stroke
			(width 0.0508)
			(type default)
		)
		(layer "In5.Cu")
	)
	(gr_line
		(start 258.099814 -46.500034)
		(end 258.341368 -46.741334)
		(stroke
			(width 0.06985)
			(type default)
		)
		(layer "In5.Cu")
	)
	(gr_arc
		(start 258.099814 -39.500048)
		(mid 258.222014 -39.475762)
		(end 258.32562 -39.406576)
		(stroke
			(width 0.06985)
			(type default)
		)
		(layer "In5.Cu")
	)
	(gr_arc
		(start 258.099814 -37.500052)
		(mid 258.222011 -37.475763)
		(end 258.32562 -37.40658)
		(stroke
			(width 0.06985)
			(type default)
		)
		(layer "In5.Cu")
	)
	(gr_line
		(start 258.099814 -35.500056)
		(end 258.45643 -35.14344)
		(stroke
			(width 0.0508)
			(type default)
		)
		(layer "In5.Cu")
	)
	(gr_arc
		(start 258.099814 -33.50006)
		(mid 258.293926 -33.461449)
		(end 258.458462 -33.35147)
		(stroke
			(width 0.0508)
			(type default)
		)
		(layer "In5.Cu")
	)
	(gr_arc
		(start 258.099814 -30.456886)
		(mid 258.018845 -30.207302)
		(end 257.806952 -30.052518)
		(stroke
			(width 0.0508)
			(type default)
		)
		(layer "In5.Cu")
	)
	(gr_line
		(start 258.099814 -30.456886)
		(end 258.099814 -30.500066)
		(stroke
			(width 0.0508)
			(type default)
		)
		(layer "In5.Cu")
	)
	(gr_arc
		(start 258.099814 -29.799788)
		(mid 258.161963 -29.649928)
		(end 258.099814 -29.500068)
		(stroke
			(width 0.0508)
			(type default)
		)
		(layer "In5.Cu")
	)
	(gr_arc
		(start 258.125214 -66.176398)
		(mid 258.111216 -66.106024)
		(end 258.071366 -66.04635)
		(stroke
			(width 0.0508)
			(type default)
		)
		(layer "In5.Cu")
	)
	(gr_line
		(start 258.125214 -66.176398)
		(end 258.125214 -66.47434)
		(stroke
			(width 0.0508)
			(type default)
		)
		(layer "In5.Cu")
	)
	(gr_line
		(start 258.2164 -43.8912)
		(end 258.341368 -43.8912)
		(stroke
			(width 0.0508)
			(type default)
		)
		(layer "In5.Cu")
	)
	(gr_arc
		(start 258.308856 -58.58637)
		(mid 258.212954 -58.522269)
		(end 258.099814 -58.499756)
		(stroke
			(width 0.0508)
			(type default)
		)
		(layer "In5.Cu")
	)
	(gr_line
		(start 258.308856 -58.58637)
		(end 258.828286 -59.106054)
		(stroke
			(width 0.0508)
			(type default)
		)
		(layer "In5.Cu")
	)
	(gr_arc
		(start 258.308856 -56.586374)
		(mid 258.212954 -56.522272)
		(end 258.099814 -56.49976)
		(stroke
			(width 0.0508)
			(type default)
		)
		(layer "In5.Cu")
	)
	(gr_line
		(start 258.308856 -56.586374)
		(end 258.828286 -57.106058)
		(stroke
			(width 0.0508)
			(type default)
		)
		(layer "In5.Cu")
	)
	(gr_arc
		(start 258.308856 -54.586378)
		(mid 258.212954 -54.522275)
		(end 258.099814 -54.499764)
		(stroke
			(width 0.0508)
			(type default)
		)
		(layer "In5.Cu")
	)
	(gr_line
		(start 258.308856 -54.586378)
		(end 258.828286 -55.106062)
		(stroke
			(width 0.0508)
			(type default)
		)
		(layer "In5.Cu")
	)
	(gr_arc
		(start 258.308856 -52.586382)
		(mid 258.212954 -52.522278)
		(end 258.099814 -52.499768)
		(stroke
			(width 0.0508)
			(type default)
		)
		(layer "In5.Cu")
	)
	(gr_line
		(start 258.308856 -52.586382)
		(end 258.828286 -53.106066)
		(stroke
			(width 0.0508)
			(type default)
		)
		(layer "In5.Cu")
	)
	(gr_arc
		(start 258.308856 -49.586388)
		(mid 258.212947 -49.522303)
		(end 258.099814 -49.499774)
		(stroke
			(width 0.0508)
			(type default)
		)
		(layer "In5.Cu")
	)
	(gr_line
		(start 258.308856 -49.586388)
		(end 258.828286 -50.106072)
		(stroke
			(width 0.0508)
			(type default)
		)
		(layer "In5.Cu")
	)
	(gr_arc
		(start 258.308856 -44.586652)
		(mid 258.212953 -44.522555)
		(end 258.099814 -44.500038)
		(stroke
			(width 0.0508)
			(type default)
		)
		(layer "In5.Cu")
	)
	(gr_line
		(start 258.308856 -44.586652)
		(end 258.828286 -45.106336)
		(stroke
			(width 0.0508)
			(type default)
		)
		(layer "In5.Cu")
	)
	(gr_arc
		(start 258.308856 -42.586656)
		(mid 258.212947 -42.522571)
		(end 258.099814 -42.500042)
		(stroke
			(width 0.0508)
			(type default)
		)
		(layer "In5.Cu")
	)
	(gr_line
		(start 258.308856 -42.586656)
		(end 258.704334 -42.982134)
		(stroke
			(width 0.0508)
			(type default)
		)
		(layer "In5.Cu")
	)
	(gr_line
		(start 258.32562 -39.406576)
		(end 258.366514 -39.365682)
		(stroke
			(width 0.06985)
			(type default)
		)
		(layer "In5.Cu")
	)
	(gr_line
		(start 258.32562 -37.40658)
		(end 258.366514 -37.365686)
		(stroke
			(width 0.06985)
			(type default)
		)
		(layer "In5.Cu")
	)
	(gr_arc
		(start 258.366514 -39.365682)
		(mid 258.416913 -39.290287)
		(end 258.434586 -39.201344)
		(stroke
			(width 0.06985)
			(type default)
		)
		(layer "In5.Cu")
	)
	(gr_arc
		(start 258.366514 -37.365686)
		(mid 258.416894 -37.290287)
		(end 258.434586 -37.201348)
		(stroke
			(width 0.06985)
			(type default)
		)
		(layer "In5.Cu")
	)
	(gr_line
		(start 258.434586 -39.109396)
		(end 258.43484 -39.109396)
		(stroke
			(width 0.06985)
			(type default)
		)
		(layer "In5.Cu")
	)
	(gr_line
		(start 258.434586 -37.1094)
		(end 258.43484 -37.1094)
		(stroke
			(width 0.06985)
			(type default)
		)
		(layer "In5.Cu")
	)
	(gr_arc
		(start 258.43484 -46.967394)
		(mid 258.410587 -46.845067)
		(end 258.341368 -46.741334)
		(stroke
			(width 0.06985)
			(type default)
		)
		(layer "In5.Cu")
	)
	(gr_line
		(start 258.43484 -46.967394)
		(end 258.43484 -46.98365)
		(stroke
			(width 0.06985)
			(type default)
		)
		(layer "In5.Cu")
	)
	(gr_line
		(start 258.45643 -35.14344)
		(end 258.890008 -34.957258)
		(stroke
			(width 0.0508)
			(type default)
		)
		(layer "In5.Cu")
	)
	(gr_line
		(start 258.458462 -33.35147)
		(end 258.817364 -32.992568)
		(stroke
			(width 0.0508)
			(type default)
		)
		(layer "In5.Cu")
	)
	(gr_line
		(start 258.5085 -28.6258)
		(end 258.572 -28.6258)
		(stroke
			(width 0.0508)
			(type default)
		)
		(layer "In5.Cu")
	)
	(gr_line
		(start 258.57454 -28.62834)
		(end 258.699 -28.7528)
		(stroke
			(width 0.0508)
			(type default)
		)
		(layer "In5.Cu")
	)
	(gr_line
		(start 258.699 -28.7528)
		(end 258.793996 -28.7528)
		(stroke
			(width 0.0508)
			(type default)
		)
		(layer "In5.Cu")
	)
	(gr_line
		(start 258.7117 -42.9895)
		(end 258.828032 -43.106086)
		(stroke
			(width 0.0508)
			(type default)
		)
		(layer "In5.Cu")
	)
	(gr_arc
		(start 258.764786 -39.163752)
		(mid 258.790204 -39.291584)
		(end 258.862576 -39.399972)
		(stroke
			(width 0.06985)
			(type default)
		)
		(layer "In5.Cu")
	)
	(gr_line
		(start 258.764786 -39.124128)
		(end 258.764786 -39.163752)
		(stroke
			(width 0.06985)
			(type default)
		)
		(layer "In5.Cu")
	)
	(gr_arc
		(start 258.764786 -37.163756)
		(mid 258.790205 -37.291587)
		(end 258.862576 -37.399976)
		(stroke
			(width 0.06985)
			(type default)
		)
		(layer "In5.Cu")
	)
	(gr_line
		(start 258.764786 -37.124132)
		(end 258.764786 -37.163756)
		(stroke
			(width 0.06985)
			(type default)
		)
		(layer "In5.Cu")
	)
	(gr_line
		(start 258.7752 -28.4226)
		(end 258.8387 -28.4226)
		(stroke
			(width 0.06985)
			(type default)
		)
		(layer "In5.Cu")
	)
	(gr_line
		(start 258.847844 -18.400014)
		(end 258.865624 -18.388584)
		(stroke
			(width 0.06985)
			(type default)
		)
		(layer "In5.Cu")
	)
	(gr_line
		(start 258.858766 -46.74108)
		(end 259.099812 -46.500034)
		(stroke
			(width 0.06985)
			(type default)
		)
		(layer "In5.Cu")
	)
	(gr_line
		(start 258.862576 -39.399972)
		(end 258.865624 -39.40302)
		(stroke
			(width 0.06985)
			(type default)
		)
		(layer "In5.Cu")
	)
	(gr_line
		(start 258.862576 -37.399976)
		(end 258.865624 -37.403024)
		(stroke
			(width 0.06985)
			(type default)
		)
		(layer "In5.Cu")
	)
	(gr_arc
		(start 258.865624 -39.40302)
		(mid 258.973062 -39.474845)
		(end 259.099812 -39.500048)
		(stroke
			(width 0.06985)
			(type default)
		)
		(layer "In5.Cu")
	)
	(gr_arc
		(start 258.865624 -37.403024)
		(mid 258.973062 -37.474848)
		(end 259.099812 -37.500052)
		(stroke
			(width 0.06985)
			(type default)
		)
		(layer "In5.Cu")
	)
	(gr_line
		(start 258.865624 -18.388584)
		(end 258.885436 -18.38452)
		(stroke
			(width 0.06985)
			(type default)
		)
		(layer "In5.Cu")
	)
	(gr_arc
		(start 258.9022 -35.302444)
		(mid 258.960079 -35.442177)
		(end 259.099812 -35.500056)
		(stroke
			(width 0.0508)
			(type default)
		)
		(layer "In5.Cu")
	)
	(gr_line
		(start 258.9022 -35.300158)
		(end 258.9022 -35.302444)
		(stroke
			(width 0.0508)
			(type default)
		)
		(layer "In5.Cu")
	)
	(gr_arc
		(start 258.9276 -58.824114)
		(mid 258.944769 -58.910429)
		(end 258.99364 -58.983626)
		(stroke
			(width 0.0508)
			(type default)
		)
		(layer "In5.Cu")
	)
	(gr_arc
		(start 258.9276 -56.824118)
		(mid 258.944769 -56.910433)
		(end 258.99364 -56.98363)
		(stroke
			(width 0.0508)
			(type default)
		)
		(layer "In5.Cu")
	)
	(gr_arc
		(start 258.9276 -54.824122)
		(mid 258.944769 -54.910437)
		(end 258.99364 -54.983634)
		(stroke
			(width 0.0508)
			(type default)
		)
		(layer "In5.Cu")
	)
	(gr_arc
		(start 258.9276 -52.824126)
		(mid 258.944769 -52.910441)
		(end 258.99364 -52.983638)
		(stroke
			(width 0.0508)
			(type default)
		)
		(layer "In5.Cu")
	)
	(gr_arc
		(start 258.9276 -49.824132)
		(mid 258.944769 -49.910447)
		(end 258.99364 -49.983644)
		(stroke
			(width 0.0508)
			(type default)
		)
		(layer "In5.Cu")
	)
	(gr_arc
		(start 258.9276 -44.824396)
		(mid 258.944769 -44.910711)
		(end 258.99364 -44.983908)
		(stroke
			(width 0.0508)
			(type default)
		)
		(layer "In5.Cu")
	)
	(gr_arc
		(start 258.9276 -42.8244)
		(mid 258.944745 -42.910728)
		(end 258.99364 -42.983912)
		(stroke
			(width 0.0508)
			(type default)
		)
		(layer "In5.Cu")
	)
	(gr_arc
		(start 258.998466 -35.13201)
		(mid 258.927999 -35.203291)
		(end 258.9022 -35.300158)
		(stroke
			(width 0.0508)
			(type default)
		)
		(layer "In5.Cu")
	)
	(gr_line
		(start 259.00888 -34.90595)
		(end 259.013198 -34.901632)
		(stroke
			(width 0.0508)
			(type default)
		)
		(layer "In5.Cu")
	)
	(gr_arc
		(start 259.035296 -58.564526)
		(mid 258.955633 -58.683611)
		(end 258.9276 -58.824114)
		(stroke
			(width 0.0508)
			(type default)
		)
		(layer "In5.Cu")
	)
	(gr_line
		(start 259.035296 -58.564526)
		(end 259.099812 -58.499756)
		(stroke
			(width 0.0508)
			(type default)
		)
		(layer "In5.Cu")
	)
	(gr_arc
		(start 259.035296 -56.56453)
		(mid 258.955633 -56.683615)
		(end 258.9276 -56.824118)
		(stroke
			(width 0.0508)
			(type default)
		)
		(layer "In5.Cu")
	)
	(gr_line
		(start 259.035296 -56.56453)
		(end 259.099812 -56.49976)
		(stroke
			(width 0.0508)
			(type default)
		)
		(layer "In5.Cu")
	)
	(gr_arc
		(start 259.035296 -54.564534)
		(mid 258.955633 -54.683619)
		(end 258.9276 -54.824122)
		(stroke
			(width 0.0508)
			(type default)
		)
		(layer "In5.Cu")
	)
	(gr_line
		(start 259.035296 -54.564534)
		(end 259.099812 -54.499764)
		(stroke
			(width 0.0508)
			(type default)
		)
		(layer "In5.Cu")
	)
	(gr_arc
		(start 259.035296 -52.564538)
		(mid 258.955633 -52.683623)
		(end 258.9276 -52.824126)
		(stroke
			(width 0.0508)
			(type default)
		)
		(layer "In5.Cu")
	)
	(gr_line
		(start 259.035296 -52.564538)
		(end 259.099812 -52.499768)
		(stroke
			(width 0.0508)
			(type default)
		)
		(layer "In5.Cu")
	)
	(gr_arc
		(start 259.035296 -49.564544)
		(mid 258.955633 -49.683629)
		(end 258.9276 -49.824132)
		(stroke
			(width 0.0508)
			(type default)
		)
		(layer "In5.Cu")
	)
	(gr_line
		(start 259.035296 -49.564544)
		(end 259.099812 -49.499774)
		(stroke
			(width 0.0508)
			(type default)
		)
		(layer "In5.Cu")
	)
	(gr_arc
		(start 259.035296 -44.564808)
		(mid 258.955633 -44.683893)
		(end 258.9276 -44.824396)
		(stroke
			(width 0.0508)
			(type default)
		)
		(layer "In5.Cu")
	)
	(gr_line
		(start 259.035296 -44.564808)
		(end 259.099812 -44.500038)
		(stroke
			(width 0.0508)
			(type default)
		)
		(layer "In5.Cu")
	)
	(gr_arc
		(start 259.035296 -42.564812)
		(mid 258.955621 -42.683895)
		(end 258.9276 -42.8244)
		(stroke
			(width 0.0508)
			(type default)
		)
		(layer "In5.Cu")
	)
	(gr_line
		(start 259.035296 -42.564812)
		(end 259.099812 -42.500042)
		(stroke
			(width 0.0508)
			(type default)
		)
		(layer "In5.Cu")
	)
	(gr_arc
		(start 259.03682 -32.901636)
		(mid 258.918047 -32.925279)
		(end 258.817364 -32.992568)
		(stroke
			(width 0.0508)
			(type default)
		)
		(layer "In5.Cu")
	)
	(gr_line
		(start 259.074412 -33.50006)
		(end 259.099812 -33.50006)
		(stroke
			(width 0.0508)
			(type default)
		)
		(layer "In5.Cu")
	)
	(gr_arc
		(start 259.074412 -33.104836)
		(mid 258.8768 -33.302448)
		(end 259.074412 -33.50006)
		(stroke
			(width 0.0508)
			(type default)
		)
		(layer "In5.Cu")
	)
	(gr_line
		(start 259.081016 -34.104834)
		(end 259.199634 -34.104834)
		(stroke
			(width 0.0508)
			(type default)
		)
		(layer "In5.Cu")
	)
	(gr_line
		(start 259.099812 -30.500066)
		(end 259.271008 -30.671262)
		(stroke
			(width 0.06985)
			(type default)
		)
		(layer "In5.Cu")
	)
	(gr_line
		(start 259.176774 -40.668448)
		(end 259.217668 -40.709342)
		(stroke
			(width 0.0508)
			(type default)
		)
		(layer "In5.Cu")
	)
	(gr_line
		(start 259.178552 -40.379142)
		(end 259.5372 -40.379142)
		(stroke
			(width 0.0508)
			(type default)
		)
		(layer "In5.Cu")
	)
	(gr_line
		(start 259.217668 -40.709342)
		(end 259.5372 -40.709342)
		(stroke
			(width 0.0508)
			(type default)
		)
		(layer "In5.Cu")
	)
	(gr_line
		(start 259.284216 -33.901888)
		(end 259.402834 -33.901888)
		(stroke
			(width 0.0508)
			(type default)
		)
		(layer "In5.Cu")
	)
	(gr_line
		(start 259.285994 -34.191194)
		(end 259.326888 -34.232088)
		(stroke
			(width 0.0508)
			(type default)
		)
		(layer "In5.Cu")
	)
	(gr_line
		(start 259.326888 -34.232088)
		(end 259.469382 -34.232088)
		(stroke
			(width 0.0508)
			(type default)
		)
		(layer "In5.Cu")
	)
	(gr_line
		(start 259.405374 -33.901888)
		(end 259.4864 -33.901888)
		(stroke
			(width 0.0508)
			(type default)
		)
		(layer "In5.Cu")
	)
	(gr_line
		(start 259.4483 -44.0944)
		(end 259.556504 -44.0944)
		(stroke
			(width 0.0508)
			(type default)
		)
		(layer "In5.Cu")
	)
	(gr_line
		(start 259.4737 -58.091832)
		(end 259.576062 -58.091832)
		(stroke
			(width 0.0508)
			(type default)
		)
		(layer "In5.Cu")
	)
	(gr_line
		(start 259.4737 -56.091836)
		(end 259.52577 -56.091836)
		(stroke
			(width 0.0508)
			(type default)
		)
		(layer "In5.Cu")
	)
	(gr_line
		(start 259.4737 -54.09184)
		(end 259.550916 -54.09184)
		(stroke
			(width 0.0508)
			(type default)
		)
		(layer "In5.Cu")
	)
	(gr_line
		(start 259.4737 -51.091846)
		(end 259.525516 -51.091846)
		(stroke
			(width 0.0508)
			(type default)
		)
		(layer "In5.Cu")
	)
	(gr_line
		(start 259.4737 -49.09185)
		(end 259.549138 -49.09185)
		(stroke
			(width 0.0508)
			(type default)
		)
		(layer "In5.Cu")
	)
	(gr_line
		(start 259.4737 -46.09211)
		(end 259.574284 -46.09211)
		(stroke
			(width 0.0508)
			(type default)
		)
		(layer "In5.Cu")
	)
	(gr_arc
		(start 259.491988 -59.101482)
		(mid 259.579567 -59.084062)
		(end 259.653786 -59.034426)
		(stroke
			(width 0.0508)
			(type default)
		)
		(layer "In5.Cu")
	)
	(gr_arc
		(start 259.514594 -57.101486)
		(mid 259.550679 -57.099215)
		(end 259.586222 -57.092596)
		(stroke
			(width 0.0508)
			(type default)
		)
		(layer "In5.Cu")
	)
	(gr_arc
		(start 259.514594 -55.10149)
		(mid 259.550679 -55.099219)
		(end 259.586222 -55.0926)
		(stroke
			(width 0.0508)
			(type default)
		)
		(layer "In5.Cu")
	)
	(gr_arc
		(start 259.514594 -53.101494)
		(mid 259.550679 -53.099223)
		(end 259.586222 -53.092604)
		(stroke
			(width 0.0508)
			(type default)
		)
		(layer "In5.Cu")
	)
	(gr_arc
		(start 259.514594 -50.1015)
		(mid 259.550679 -50.099229)
		(end 259.586222 -50.09261)
		(stroke
			(width 0.0508)
			(type default)
		)
		(layer "In5.Cu")
	)
	(gr_arc
		(start 259.514594 -45.101764)
		(mid 259.550679 -45.099493)
		(end 259.586222 -45.092874)
		(stroke
			(width 0.0508)
			(type default)
		)
		(layer "In5.Cu")
	)
	(gr_arc
		(start 259.514594 -43.101768)
		(mid 259.550674 -43.099471)
		(end 259.586222 -43.092878)
		(stroke
			(width 0.0508)
			(type default)
		)
		(layer "In5.Cu")
	)
	(gr_line
		(start 259.53974 -33.104836)
		(end 259.558536 -33.104836)
		(stroke
			(width 0.0508)
			(type default)
		)
		(layer "In5.Cu")
	)
	(gr_arc
		(start 259.586222 -57.092596)
		(mid 259.661861 -57.062714)
		(end 259.726684 -57.013602)
		(stroke
			(width 0.0508)
			(type default)
		)
		(layer "In5.Cu")
	)
	(gr_arc
		(start 259.586222 -55.0926)
		(mid 259.661861 -55.062718)
		(end 259.726684 -55.013606)
		(stroke
			(width 0.0508)
			(type default)
		)
		(layer "In5.Cu")
	)
	(gr_arc
		(start 259.586222 -53.092604)
		(mid 259.661861 -53.062722)
		(end 259.726684 -53.01361)
		(stroke
			(width 0.0508)
			(type default)
		)
		(layer "In5.Cu")
	)
	(gr_arc
		(start 259.586222 -50.09261)
		(mid 259.661861 -50.062728)
		(end 259.726684 -50.013616)
		(stroke
			(width 0.0508)
			(type default)
		)
		(layer "In5.Cu")
	)
	(gr_arc
		(start 259.586222 -45.092874)
		(mid 259.661861 -45.062992)
		(end 259.726684 -45.01388)
		(stroke
			(width 0.0508)
			(type default)
		)
		(layer "In5.Cu")
	)
	(gr_arc
		(start 259.586222 -43.092878)
		(mid 259.661848 -43.062977)
		(end 259.726684 -43.013884)
		(stroke
			(width 0.0508)
			(type default)
		)
		(layer "In5.Cu")
	)
	(gr_arc
		(start 259.592318 -43.8912)
		(mid 259.658707 -43.877994)
		(end 259.715 -43.8404)
		(stroke
			(width 0.0508)
			(type default)
		)
		(layer "In5.Cu")
	)
	(gr_line
		(start 259.595366 -59.888628)
		(end 259.777738 -59.888628)
		(stroke
			(width 0.0508)
			(type default)
		)
		(layer "In5.Cu")
	)
	(gr_arc
		(start 259.607304 -36.171632)
		(mid 259.533159 -36.122216)
		(end 259.44576 -36.10483)
		(stroke
			(width 0.0508)
			(type default)
		)
		(layer "In5.Cu")
	)
	(gr_line
		(start 259.607304 -36.171632)
		(end 259.67436 -36.238688)
		(stroke
			(width 0.0508)
			(type default)
		)
		(layer "In5.Cu")
	)
	(gr_arc
		(start 259.623306 -57.888632)
		(mid 259.686681 -57.876026)
		(end 259.7404 -57.840118)
		(stroke
			(width 0.0508)
			(type default)
		)
		(layer "In5.Cu")
	)
	(gr_arc
		(start 259.623306 -55.888636)
		(mid 259.686682 -55.87603)
		(end 259.7404 -55.840122)
		(stroke
			(width 0.0508)
			(type default)
		)
		(layer "In5.Cu")
	)
	(gr_arc
		(start 259.623306 -53.88864)
		(mid 259.686681 -53.876034)
		(end 259.7404 -53.840126)
		(stroke
			(width 0.0508)
			(type default)
		)
		(layer "In5.Cu")
	)
	(gr_arc
		(start 259.623306 -50.888646)
		(mid 259.686682 -50.87604)
		(end 259.7404 -50.840132)
		(stroke
			(width 0.0508)
			(type default)
		)
		(layer "In5.Cu")
	)
	(gr_arc
		(start 259.623306 -48.88865)
		(mid 259.686683 -48.876044)
		(end 259.7404 -48.840136)
		(stroke
			(width 0.0508)
			(type default)
		)
		(layer "In5.Cu")
	)
	(gr_arc
		(start 259.623306 -45.88891)
		(mid 259.686681 -45.876304)
		(end 259.7404 -45.840396)
		(stroke
			(width 0.0508)
			(type default)
		)
		(layer "In5.Cu")
	)
	(gr_line
		(start 259.6515 -35.90163)
		(end 259.835142 -35.90163)
		(stroke
			(width 0.0508)
			(type default)
		)
		(layer "In5.Cu")
	)
	(gr_line
		(start 259.653786 -59.034426)
		(end 259.747258 -58.940954)
		(stroke
			(width 0.0508)
			(type default)
		)
		(layer "In5.Cu")
	)
	(gr_line
		(start 259.67436 -36.238688)
		(end 259.8674 -36.238688)
		(stroke
			(width 0.0508)
			(type default)
		)
		(layer "In5.Cu")
	)
	(gr_arc
		(start 259.682742 -38.179248)
		(mid 259.600365 -38.124142)
		(end 259.503164 -38.104826)
		(stroke
			(width 0.0508)
			(type default)
		)
		(layer "In5.Cu")
	)
	(gr_line
		(start 259.682742 -38.179248)
		(end 259.73532 -38.231826)
		(stroke
			(width 0.0508)
			(type default)
		)
		(layer "In5.Cu")
	)
	(gr_line
		(start 259.708904 -37.901626)
		(end 259.770626 -37.901626)
		(stroke
			(width 0.0508)
			(type default)
		)
		(layer "In5.Cu")
	)
	(gr_line
		(start 259.715 -43.8404)
		(end 259.823204 -43.8404)
		(stroke
			(width 0.06985)
			(type default)
		)
		(layer "In5.Cu")
	)
	(gr_line
		(start 259.720334 -57.304686)
		(end 259.725922 -57.304686)
		(stroke
			(width 0.0508)
			(type default)
		)
		(layer "In5.Cu")
	)
	(gr_line
		(start 259.720334 -55.30469)
		(end 259.725922 -55.30469)
		(stroke
			(width 0.0508)
			(type default)
		)
		(layer "In5.Cu")
	)
	(gr_line
		(start 259.720334 -53.304694)
		(end 259.725922 -53.304694)
		(stroke
			(width 0.0508)
			(type default)
		)
		(layer "In5.Cu")
	)
	(gr_line
		(start 259.720334 -50.3047)
		(end 259.725922 -50.3047)
		(stroke
			(width 0.0508)
			(type default)
		)
		(layer "In5.Cu")
	)
	(gr_line
		(start 259.720334 -45.304964)
		(end 259.725922 -45.304964)
		(stroke
			(width 0.0508)
			(type default)
		)
		(layer "In5.Cu")
	)
	(gr_line
		(start 259.720334 -43.304968)
		(end 259.725922 -43.304968)
		(stroke
			(width 0.0508)
			(type default)
		)
		(layer "In5.Cu")
	)
	(gr_arc
		(start 259.725922 -50.3047)
		(mid 259.88923 -50.272236)
		(end 260.027674 -50.179732)
		(stroke
			(width 0.0508)
			(type default)
		)
		(layer "In5.Cu")
	)
	(gr_arc
		(start 259.725922 -43.304968)
		(mid 259.889229 -43.272502)
		(end 260.027674 -43.18)
		(stroke
			(width 0.0508)
			(type default)
		)
		(layer "In5.Cu")
	)
	(gr_line
		(start 259.726684 -57.013602)
		(end 259.890768 -56.849518)
		(stroke
			(width 0.0508)
			(type default)
		)
		(layer "In5.Cu")
	)
	(gr_line
		(start 259.726684 -55.013606)
		(end 259.890768 -54.849522)
		(stroke
			(width 0.0508)
			(type default)
		)
		(layer "In5.Cu")
	)
	(gr_line
		(start 259.726684 -53.01361)
		(end 259.890768 -52.849526)
		(stroke
			(width 0.0508)
			(type default)
		)
		(layer "In5.Cu")
	)
	(gr_line
		(start 259.726684 -50.013616)
		(end 259.890768 -49.849532)
		(stroke
			(width 0.0508)
			(type default)
		)
		(layer "In5.Cu")
	)
	(gr_line
		(start 259.726684 -45.01388)
		(end 259.890768 -44.849796)
		(stroke
			(width 0.0508)
			(type default)
		)
		(layer "In5.Cu")
	)
	(gr_line
		(start 259.726684 -43.013884)
		(end 259.890768 -42.8498)
		(stroke
			(width 0.0508)
			(type default)
		)
		(layer "In5.Cu")
	)
	(gr_arc
		(start 259.7404 -60.170314)
		(mid 259.569349 -60.111696)
		(end 259.389626 -60.091828)
		(stroke
			(width 0.0508)
			(type default)
		)
		(layer "In5.Cu")
	)
	(gr_line
		(start 259.7404 -60.170314)
		(end 259.888736 -60.2742)
		(stroke
			(width 0.06985)
			(type default)
		)
		(layer "In5.Cu")
	)
	(gr_arc
		(start 259.7404 -58.170318)
		(mid 259.66712 -58.112467)
		(end 259.576062 -58.091832)
		(stroke
			(width 0.0508)
			(type default)
		)
		(layer "In5.Cu")
	)
	(gr_line
		(start 259.7404 -57.840118)
		(end 259.842762 -57.840118)
		(stroke
			(width 0.06985)
			(type default)
		)
		(layer "In5.Cu")
	)
	(gr_arc
		(start 259.7404 -56.170322)
		(mid 259.640034 -56.112078)
		(end 259.52577 -56.091836)
		(stroke
			(width 0.0508)
			(type default)
		)
		(layer "In5.Cu")
	)
	(gr_line
		(start 259.7404 -55.840122)
		(end 259.79247 -55.840122)
		(stroke
			(width 0.06985)
			(type default)
		)
		(layer "In5.Cu")
	)
	(gr_arc
		(start 259.7404 -54.170326)
		(mid 259.653466 -54.11223)
		(end 259.550916 -54.09184)
		(stroke
			(width 0.0508)
			(type default)
		)
		(layer "In5.Cu")
	)
	(gr_line
		(start 259.7404 -53.840126)
		(end 259.817616 -53.840126)
		(stroke
			(width 0.06985)
			(type default)
		)
		(layer "In5.Cu")
	)
	(gr_arc
		(start 259.7404 -51.170332)
		(mid 259.639896 -51.112098)
		(end 259.525516 -51.091846)
		(stroke
			(width 0.0508)
			(type default)
		)
		(layer "In5.Cu")
	)
	(gr_line
		(start 259.7404 -50.840132)
		(end 259.792216 -50.840132)
		(stroke
			(width 0.06985)
			(type default)
		)
		(layer "In5.Cu")
	)
	(gr_arc
		(start 259.7404 -49.170336)
		(mid 259.652508 -49.112235)
		(end 259.549138 -49.09185)
		(stroke
			(width 0.0508)
			(type default)
		)
		(layer "In5.Cu")
	)
	(gr_line
		(start 259.7404 -48.840136)
		(end 259.815838 -48.840136)
		(stroke
			(width 0.06985)
			(type default)
		)
		(layer "In5.Cu")
	)
	(gr_arc
		(start 259.7404 -46.170596)
		(mid 259.666149 -46.112713)
		(end 259.574284 -46.09211)
		(stroke
			(width 0.0508)
			(type default)
		)
		(layer "In5.Cu")
	)
	(gr_line
		(start 259.7404 -45.840396)
		(end 259.840984 -45.840396)
		(stroke
			(width 0.06985)
			(type default)
		)
		(layer "In5.Cu")
	)
	(gr_arc
		(start 259.7404 -44.1706)
		(mid 259.656039 -44.114182)
		(end 259.556504 -44.0944)
		(stroke
			(width 0.0508)
			(type default)
		)
		(layer "In5.Cu")
	)
	(gr_line
		(start 259.741416 -30.671262)
		(end 259.912612 -30.500066)
		(stroke
			(width 0.06985)
			(type default)
		)
		(layer "In5.Cu")
	)
	(gr_line
		(start 259.74294 -33.001712)
		(end 259.761736 -33.001712)
		(stroke
			(width 0.0508)
			(type default)
		)
		(layer "In5.Cu")
	)
	(gr_line
		(start 259.808726 -59.249818)
		(end 259.839968 -59.229244)
		(stroke
			(width 0.0508)
			(type default)
		)
		(layer "In5.Cu")
	)
	(gr_line
		(start 259.835142 -35.90163)
		(end 259.842 -35.908488)
		(stroke
			(width 0.0508)
			(type default)
		)
		(layer "In5.Cu")
	)
	(gr_arc
		(start 259.892292 -59.219338)
		(mid 259.865138 -59.219052)
		(end 259.839968 -59.229244)
		(stroke
			(width 0.0508)
			(type default)
		)
		(layer "In5.Cu")
	)
	(gr_arc
		(start 259.892292 -59.219338)
		(mid 259.916005 -59.219575)
		(end 259.938012 -59.210702)
		(stroke
			(width 0.0508)
			(type default)
		)
		(layer "In5.Cu")
	)
	(gr_line
		(start 259.938012 -59.210702)
		(end 259.945378 -59.205114)
		(stroke
			(width 0.06985)
			(type default)
		)
		(layer "In5.Cu")
	)
	(gr_line
		(start 259.987288 -35.107372)
		(end 260.119622 -35.239706)
		(stroke
			(width 0.0508)
			(type default)
		)
		(layer "In5.Cu")
	)
	(gr_arc
		(start 260.11124 -60.026804)
		(mid 259.958236 -59.924541)
		(end 259.777738 -59.888628)
		(stroke
			(width 0.0508)
			(type default)
		)
		(layer "In5.Cu")
	)
	(gr_line
		(start 260.119622 -35.239706)
		(end 260.274562 -35.239706)
		(stroke
			(width 0.0508)
			(type default)
		)
		(layer "In5.Cu")
	)
	(gr_line
		(start 260.190488 -34.901632)
		(end 260.266688 -34.901632)
		(stroke
			(width 0.0508)
			(type default)
		)
		(layer "In5.Cu")
	)
	(gr_line
		(start 260.233922 -33.204912)
		(end 260.276086 -33.247076)
		(stroke
			(width 0.0508)
			(type default)
		)
		(layer "In5.Cu")
	)
	(gr_line
		(start 260.233922 -33.001712)
		(end 260.276086 -32.959548)
		(stroke
			(width 0.0508)
			(type default)
		)
		(layer "In5.Cu")
	)
	(gr_line
		(start 260.266688 -34.901632)
		(end 260.274562 -34.909506)
		(stroke
			(width 0.0508)
			(type default)
		)
		(layer "In5.Cu")
	)
	(gr_line
		(start 260.277864 -33.248854)
		(end 260.297422 -33.268412)
		(stroke
			(width 0.0508)
			(type default)
		)
		(layer "In5.Cu")
	)
	(gr_line
		(start 260.277864 -32.95777)
		(end 260.297422 -32.938212)
		(stroke
			(width 0.0508)
			(type default)
		)
		(layer "In5.Cu")
	)
	(gr_line
		(start 260.297422 -33.268412)
		(end 260.322822 -33.268412)
		(stroke
			(width 0.0508)
			(type default)
		)
		(layer "In5.Cu")
	)
	(gr_line
		(start 260.297422 -32.938212)
		(end 260.322822 -32.938212)
		(stroke
			(width 0.0508)
			(type default)
		)
		(layer "In5.Cu")
	)
	(gr_line
		(start 260.363716 -21.890736)
		(end 260.39318 -21.884386)
		(stroke
			(width 0.06985)
			(type default)
		)
		(layer "In5.Cu")
	)
	(gr_line
		(start 260.39318 -21.884386)
		(end 260.422644 -21.890736)
		(stroke
			(width 0.06985)
			(type default)
		)
		(layer "In5.Cu")
	)
	(gr_line
		(start 260.491986 -22.911816)
		(end 260.52145 -22.905466)
		(stroke
			(width 0.06985)
			(type default)
		)
		(layer "In5.Cu")
	)
	(gr_line
		(start 260.52145 -22.905466)
		(end 260.550914 -22.911816)
		(stroke
			(width 0.06985)
			(type default)
		)
		(layer "In5.Cu")
	)
	(gr_line
		(start 260.737604 -25.550368)
		(end 260.7564 -25.547066)
		(stroke
			(width 0.06985)
			(type default)
		)
		(layer "In5.Cu")
	)
	(gr_line
		(start 260.743446 -20.70735)
		(end 261.42696 -20.562062)
		(stroke
			(width 0.06985)
			(type default)
		)
		(layer "In5.Cu")
	)
	(gr_line
		(start 260.7564 -25.547066)
		(end 260.775196 -25.550368)
		(stroke
			(width 0.06985)
			(type default)
		)
		(layer "In5.Cu")
	)
	(gr_line
		(start 260.777736 -21.040344)
		(end 260.986016 -21.175472)
		(stroke
			(width 0.06985)
			(type default)
		)
		(layer "In5.Cu")
	)
	(gr_line
		(start 260.986016 -21.175472)
		(end 261.395972 -21.08835)
		(stroke
			(width 0.06985)
			(type default)
		)
		(layer "In5.Cu")
	)
	(gr_line
		(start 261.34314 -24.177752)
		(end 261.364476 -24.173942)
		(stroke
			(width 0.06985)
			(type default)
		)
		(layer "In5.Cu")
	)
	(gr_line
		(start 261.364476 -24.173942)
		(end 261.366 -24.174196)
		(stroke
			(width 0.06985)
			(type default)
		)
		(layer "In5.Cu")
	)
	(gr_line
		(start 261.366 -24.174196)
		(end 261.385558 -24.17826)
		(stroke
			(width 0.06985)
			(type default)
		)
		(layer "In5.Cu")
	)
	(gr_line
		(start 261.395972 -21.08835)
		(end 261.5311 -20.88007)
		(stroke
			(width 0.06985)
			(type default)
		)
		(layer "In5.Cu")
	)
	(gr_line
		(start 261.83336 -58.962544)
		(end 261.86638 -58.968386)
		(stroke
			(width 0.06985)
			(type default)
		)
		(layer "In5.Cu")
	)
	(gr_line
		(start 261.86638 -58.968386)
		(end 261.89432 -58.987944)
		(stroke
			(width 0.06985)
			(type default)
		)
		(layer "In5.Cu")
	)
	(gr_line
		(start 261.9121 -20.459192)
		(end 262.593074 -20.314412)
		(stroke
			(width 0.06985)
			(type default)
		)
		(layer "In5.Cu")
	)
	(gr_line
		(start 261.945374 -20.792186)
		(end 262.153654 -20.927314)
		(stroke
			(width 0.06985)
			(type default)
		)
		(layer "In5.Cu")
	)
	(gr_line
		(start 262.153654 -20.927314)
		(end 262.56361 -20.840192)
		(stroke
			(width 0.06985)
			(type default)
		)
		(layer "In5.Cu")
	)
	(gr_line
		(start 262.56361 -20.840192)
		(end 262.698738 -20.631912)
		(stroke
			(width 0.06985)
			(type default)
		)
		(layer "In5.Cu")
	)
	(gr_line
		(start 262.871204 -55.629302)
		(end 262.89 -55.626)
		(stroke
			(width 0.06985)
			(type default)
		)
		(layer "In5.Cu")
	)
	(gr_line
		(start 262.89 -55.626)
		(end 262.908796 -55.629302)
		(stroke
			(width 0.06985)
			(type default)
		)
		(layer "In5.Cu")
	)
	(gr_line
		(start 262.985504 -58.192924)
		(end 263.018524 -58.198766)
		(stroke
			(width 0.06985)
			(type default)
		)
		(layer "In5.Cu")
	)
	(gr_line
		(start 263.018524 -58.198766)
		(end 263.046464 -58.218324)
		(stroke
			(width 0.06985)
			(type default)
		)
		(layer "In5.Cu")
	)
	(gr_line
		(start 263.0805 -20.21078)
		(end 263.76122 -20.066)
		(stroke
			(width 0.06985)
			(type default)
		)
		(layer "In5.Cu")
	)
	(gr_line
		(start 263.113266 -20.544028)
		(end 263.321292 -20.679156)
		(stroke
			(width 0.06985)
			(type default)
		)
		(layer "In5.Cu")
	)
	(gr_line
		(start 263.288526 -190.754254)
		(end 263.291828 -190.773304)
		(stroke
			(width 0.06985)
			(type default)
		)
		(layer "In5.Cu")
	)
	(gr_line
		(start 263.288526 -190.754254)
		(end 263.291828 -190.735458)
		(stroke
			(width 0.06985)
			(type default)
		)
		(layer "In5.Cu")
	)
	(gr_line
		(start 263.321292 -20.679156)
		(end 263.731248 -20.592034)
		(stroke
			(width 0.06985)
			(type default)
		)
		(layer "In5.Cu")
	)
	(gr_line
		(start 263.395714 -30.828996)
		(end 264.078212 -30.7086)
		(stroke
			(width 0.06985)
			(type default)
		)
		(layer "In5.Cu")
	)
	(gr_line
		(start 263.416034 -31.16326)
		(end 263.619234 -31.3055)
		(stroke
			(width 0.06985)
			(type default)
		)
		(layer "In5.Cu")
	)
	(gr_line
		(start 263.50341 -57.333134)
		(end 263.53643 -57.338976)
		(stroke
			(width 0.06985)
			(type default)
		)
		(layer "In5.Cu")
	)
	(gr_line
		(start 263.506204 -53.470302)
		(end 263.525 -53.467)
		(stroke
			(width 0.06985)
			(type default)
		)
		(layer "In5.Cu")
	)
	(gr_line
		(start 263.50722 -54.365144)
		(end 263.526016 -54.361842)
		(stroke
			(width 0.06985)
			(type default)
		)
		(layer "In5.Cu")
	)
	(gr_line
		(start 263.51611 -62.411102)
		(end 263.531604 -62.422024)
		(stroke
			(width 0.06985)
			(type default)
		)
		(layer "In5.Cu")
	)
	(gr_line
		(start 263.525 -53.467)
		(end 263.543796 -53.470302)
		(stroke
			(width 0.06985)
			(type default)
		)
		(layer "In5.Cu")
	)
	(gr_line
		(start 263.526016 -54.361842)
		(end 263.544812 -54.365144)
		(stroke
			(width 0.06985)
			(type default)
		)
		(layer "In5.Cu")
	)
	(gr_line
		(start 263.531604 -62.422024)
		(end 263.542526 -62.437518)
		(stroke
			(width 0.06985)
			(type default)
		)
		(layer "In5.Cu")
	)
	(gr_line
		(start 263.535668 -45.255688)
		(end 263.554464 -45.252386)
		(stroke
			(width 0.06985)
			(type default)
		)
		(layer "In5.Cu")
	)
	(gr_line
		(start 263.53643 -57.338976)
		(end 263.56437 -57.358534)
		(stroke
			(width 0.06985)
			(type default)
		)
		(layer "In5.Cu")
	)
	(gr_line
		(start 263.551924 -44.331382)
		(end 263.57072 -44.32808)
		(stroke
			(width 0.06985)
			(type default)
		)
		(layer "In5.Cu")
	)
	(gr_line
		(start 263.554464 -45.252386)
		(end 263.57326 -45.255688)
		(stroke
			(width 0.06985)
			(type default)
		)
		(layer "In5.Cu")
	)
	(gr_line
		(start 263.57072 -44.32808)
		(end 263.589516 -44.331382)
		(stroke
			(width 0.06985)
			(type default)
		)
		(layer "In5.Cu")
	)
	(gr_line
		(start 263.576816 -43.248072)
		(end 263.595612 -43.24477)
		(stroke
			(width 0.06985)
			(type default)
		)
		(layer "In5.Cu")
	)
	(gr_line
		(start 263.595612 -43.24477)
		(end 263.614408 -43.248072)
		(stroke
			(width 0.06985)
			(type default)
		)
		(layer "In5.Cu")
	)
	(gr_line
		(start 263.619234 -31.3055)
		(end 264.031984 -31.232602)
		(stroke
			(width 0.06985)
			(type default)
		)
		(layer "In5.Cu")
	)
	(gr_line
		(start 263.621012 -22.90826)
		(end 263.650476 -22.91461)
		(stroke
			(width 0.06985)
			(type default)
		)
		(layer "In5.Cu")
	)
	(gr_line
		(start 263.635236 -52.342542)
		(end 263.654032 -52.33924)
		(stroke
			(width 0.06985)
			(type default)
		)
		(layer "In5.Cu")
	)
	(gr_line
		(start 263.650476 -22.91461)
		(end 263.67994 -22.90826)
		(stroke
			(width 0.06985)
			(type default)
		)
		(layer "In5.Cu")
	)
	(gr_line
		(start 263.653016 -42.313352)
		(end 263.671812 -42.31005)
		(stroke
			(width 0.06985)
			(type default)
		)
		(layer "In5.Cu")
	)
	(gr_line
		(start 263.654032 -52.33924)
		(end 263.672828 -52.342542)
		(stroke
			(width 0.06985)
			(type default)
		)
		(layer "In5.Cu")
	)
	(gr_line
		(start 263.671812 -42.31005)
		(end 263.690608 -42.313352)
		(stroke
			(width 0.06985)
			(type default)
		)
		(layer "In5.Cu")
	)
	(gr_line
		(start 263.731248 -20.592034)
		(end 263.866376 -20.384008)
		(stroke
			(width 0.06985)
			(type default)
		)
		(layer "In5.Cu")
	)
	(gr_line
		(start 263.90473 -23.96236)
		(end 263.934194 -23.96871)
		(stroke
			(width 0.06985)
			(type default)
		)
		(layer "In5.Cu")
	)
	(gr_line
		(start 263.934194 -23.96871)
		(end 263.963658 -23.96236)
		(stroke
			(width 0.06985)
			(type default)
		)
		(layer "In5.Cu")
	)
	(gr_line
		(start 264.031984 -31.232602)
		(end 264.174224 -31.029402)
		(stroke
			(width 0.06985)
			(type default)
		)
		(layer "In5.Cu")
	)
	(gr_line
		(start 264.058146 -60.503054)
		(end 264.07364 -60.513976)
		(stroke
			(width 0.06985)
			(type default)
		)
		(layer "In5.Cu")
	)
	(gr_line
		(start 264.07364 -60.513976)
		(end 264.084562 -60.52947)
		(stroke
			(width 0.06985)
			(type default)
		)
		(layer "In5.Cu")
	)
	(gr_line
		(start 264.175748 -49.221136)
		(end 264.194544 -49.217834)
		(stroke
			(width 0.06985)
			(type default)
		)
		(layer "In5.Cu")
	)
	(gr_line
		(start 264.194544 -49.217834)
		(end 264.21334 -49.221136)
		(stroke
			(width 0.06985)
			(type default)
		)
		(layer "In5.Cu")
	)
	(gr_line
		(start 264.218928 -55.860188)
		(end 264.251948 -55.86603)
		(stroke
			(width 0.06985)
			(type default)
		)
		(layer "In5.Cu")
	)
	(gr_line
		(start 264.2235 -79.817976)
		(end 264.243058 -79.845916)
		(stroke
			(width 0.06985)
			(type default)
		)
		(layer "In5.Cu")
	)
	(gr_line
		(start 264.243058 -79.845916)
		(end 264.2489 -79.878936)
		(stroke
			(width 0.06985)
			(type default)
		)
		(layer "In5.Cu")
	)
	(gr_line
		(start 264.24763 -19.962622)
		(end 264.27811 -19.956272)
		(stroke
			(width 0.06985)
			(type default)
		)
		(layer "In5.Cu")
	)
	(gr_line
		(start 264.251948 -55.86603)
		(end 264.279888 -55.885588)
		(stroke
			(width 0.06985)
			(type default)
		)
		(layer "In5.Cu")
	)
	(gr_line
		(start 264.27811 -19.956272)
		(end 264.307574 -19.962622)
		(stroke
			(width 0.06985)
			(type default)
		)
		(layer "In5.Cu")
	)
	(gr_line
		(start 264.324084 -54.502558)
		(end 264.357104 -54.5084)
		(stroke
			(width 0.06985)
			(type default)
		)
		(layer "In5.Cu")
	)
	(gr_line
		(start 264.357104 -54.5084)
		(end 264.385044 -54.527958)
		(stroke
			(width 0.06985)
			(type default)
		)
		(layer "In5.Cu")
	)
	(gr_line
		(start 264.407904 -48.101504)
		(end 264.4267 -48.098202)
		(stroke
			(width 0.06985)
			(type default)
		)
		(layer "In5.Cu")
	)
	(gr_line
		(start 264.41654 0.645414)
		(end 264.6934 0.645414)
		(stroke
			(width 0.0635)
			(type default)
		)
		(layer "In5.Cu")
	)
	(gr_line
		(start 264.4267 -48.098202)
		(end 264.445496 -48.101504)
		(stroke
			(width 0.06985)
			(type default)
		)
		(layer "In5.Cu")
	)
	(gr_line
		(start 264.493756 -210.896454)
		(end 264.611866 -210.778344)
		(stroke
			(width 0.06985)
			(type default)
		)
		(layer "In5.Cu")
	)
	(gr_line
		(start 264.516362 -25.14092)
		(end 264.541 -25.146)
		(stroke
			(width 0.06985)
			(type default)
		)
		(layer "In5.Cu")
	)
	(gr_line
		(start 264.541 -25.146)
		(end 264.565638 -25.14092)
		(stroke
			(width 0.06985)
			(type default)
		)
		(layer "In5.Cu")
	)
	(gr_line
		(start 264.572242 -30.621732)
		(end 265.252962 -30.50159)
		(stroke
			(width 0.06985)
			(type default)
		)
		(layer "In5.Cu")
	)
	(gr_line
		(start 264.5918 -30.955742)
		(end 264.795 -31.097982)
		(stroke
			(width 0.06985)
			(type default)
		)
		(layer "In5.Cu")
	)
	(gr_arc
		(start 264.611866 -210.778344)
		(mid 264.728626 -210.603666)
		(end 264.7696 -210.397598)
		(stroke
			(width 0.06985)
			(type default)
		)
		(layer "In5.Cu")
	)
	(gr_line
		(start 264.65276 -26.56967)
		(end 264.671556 -26.572972)
		(stroke
			(width 0.06985)
			(type default)
		)
		(layer "In5.Cu")
	)
	(gr_line
		(start 264.671556 -26.572972)
		(end 264.690352 -26.56967)
		(stroke
			(width 0.06985)
			(type default)
		)
		(layer "In5.Cu")
	)
	(gr_line
		(start 264.755376 -50.399188)
		(end 264.840466 -50.389028)
		(stroke
			(width 0.06985)
			(type default)
		)
		(layer "In5.Cu")
	)
	(gr_line
		(start 264.7696 -207.876902)
		(end 264.805668 -207.82534)
		(stroke
			(width 0.06985)
			(type default)
		)
		(layer "In5.Cu")
	)
	(gr_line
		(start 264.795 -31.097982)
		(end 265.20775 -31.025338)
		(stroke
			(width 0.06985)
			(type default)
		)
		(layer "In5.Cu")
	)
	(gr_line
		(start 264.832338 -53.697632)
		(end 264.865358 -53.703474)
		(stroke
			(width 0.06985)
			(type default)
		)
		(layer "In5.Cu")
	)
	(gr_line
		(start 264.840466 -50.389028)
		(end 264.860532 -50.402998)
		(stroke
			(width 0.06985)
			(type default)
		)
		(layer "In5.Cu")
	)
	(gr_line
		(start 264.860532 -50.402998)
		(end 264.884408 -50.419762)
		(stroke
			(width 0.06985)
			(type default)
		)
		(layer "In5.Cu")
	)
	(gr_line
		(start 264.865358 -53.703474)
		(end 264.893298 -53.723032)
		(stroke
			(width 0.06985)
			(type default)
		)
		(layer "In5.Cu")
	)
	(gr_line
		(start 264.884408 -50.419762)
		(end 264.91057 -50.43805)
		(stroke
			(width 0.06985)
			(type default)
		)
		(layer "In5.Cu")
	)
	(gr_line
		(start 264.92454 0.157988)
		(end 265.2014 0.157988)
		(stroke
			(width 0.0635)
			(type default)
		)
		(layer "In5.Cu")
	)
	(gr_line
		(start 264.943082 -0.6477)
		(end 265.196828 -0.6477)
		(stroke
			(width 0.0635)
			(type default)
		)
		(layer "In5.Cu")
	)
	(gr_line
		(start 265.03122 -190.613538)
		(end 265.034522 -190.632588)
		(stroke
			(width 0.06985)
			(type default)
		)
		(layer "In5.Cu")
	)
	(gr_line
		(start 265.03122 -190.613538)
		(end 265.034522 -190.594742)
		(stroke
			(width 0.06985)
			(type default)
		)
		(layer "In5.Cu")
	)
	(gr_arc
		(start 265.0998 -210.397344)
		(mid 265.153531 -210.667467)
		(end 265.306556 -210.896454)
		(stroke
			(width 0.06985)
			(type default)
		)
		(layer "In5.Cu")
	)
	(gr_line
		(start 265.20775 -31.025338)
		(end 265.34999 -30.822138)
		(stroke
			(width 0.06985)
			(type default)
		)
		(layer "In5.Cu")
	)
	(gr_line
		(start 265.432794 -59.889136)
		(end 265.448288 -59.900058)
		(stroke
			(width 0.06985)
			(type default)
		)
		(layer "In5.Cu")
	)
	(gr_line
		(start 265.448288 -59.900058)
		(end 265.45921 -59.915552)
		(stroke
			(width 0.06985)
			(type default)
		)
		(layer "In5.Cu")
	)
	(gr_line
		(start 265.451082 -1.112012)
		(end 265.840718 -1.112012)
		(stroke
			(width 0.0635)
			(type default)
		)
		(layer "In5.Cu")
	)
	(gr_line
		(start 265.572748 -207.305402)
		(end 265.592306 -207.277462)
		(stroke
			(width 0.06985)
			(type default)
		)
		(layer "In5.Cu")
	)
	(gr_line
		(start 265.592306 -207.277462)
		(end 265.598148 -207.244442)
		(stroke
			(width 0.06985)
			(type default)
		)
		(layer "In5.Cu")
	)
	(gr_line
		(start 265.673586 -52.695348)
		(end 265.706606 -52.70119)
		(stroke
			(width 0.06985)
			(type default)
		)
		(layer "In5.Cu")
	)
	(gr_line
		(start 265.69543 -49.482502)
		(end 265.72845 -49.488344)
		(stroke
			(width 0.06985)
			(type default)
		)
		(layer "In5.Cu")
	)
	(gr_line
		(start 265.706606 -52.70119)
		(end 265.734546 -52.720748)
		(stroke
			(width 0.06985)
			(type default)
		)
		(layer "In5.Cu")
	)
	(gr_line
		(start 265.72845 -49.488344)
		(end 265.75639 -49.507902)
		(stroke
			(width 0.06985)
			(type default)
		)
		(layer "In5.Cu")
	)
	(gr_line
		(start 265.913616 -80.216756)
		(end 265.933174 -80.244696)
		(stroke
			(width 0.06985)
			(type default)
		)
		(layer "In5.Cu")
	)
	(gr_line
		(start 265.933174 -80.244696)
		(end 265.939016 -80.277716)
		(stroke
			(width 0.06985)
			(type default)
		)
		(layer "In5.Cu")
	)
	(gr_line
		(start 266.03198 -48.381158)
		(end 266.065 -48.387)
		(stroke
			(width 0.06985)
			(type default)
		)
		(layer "In5.Cu")
	)
	(gr_line
		(start 266.045442 -66.01206)
		(end 266.065 -66.04)
		(stroke
			(width 0.06985)
			(type default)
		)
		(layer "In5.Cu")
	)
	(gr_line
		(start 266.061698 -204.615796)
		(end 266.061698 -204.61605)
		(stroke
			(width 0.06985)
			(type default)
		)
		(layer "In5.Cu")
	)
	(gr_line
		(start 266.061698 -204.615796)
		(end 266.065 -204.597)
		(stroke
			(width 0.06985)
			(type default)
		)
		(layer "In5.Cu")
	)
	(gr_line
		(start 266.061698 -204.578204)
		(end 266.065 -204.597)
		(stroke
			(width 0.06985)
			(type default)
		)
		(layer "In5.Cu")
	)
	(gr_line
		(start 266.065 -66.04)
		(end 266.070842 -66.07302)
		(stroke
			(width 0.06985)
			(type default)
		)
		(layer "In5.Cu")
	)
	(gr_line
		(start 266.065 -48.387)
		(end 266.09294 -48.406558)
		(stroke
			(width 0.06985)
			(type default)
		)
		(layer "In5.Cu")
	)
	(gr_line
		(start 266.0904 0.157988)
		(end 266.36726 0.157988)
		(stroke
			(width 0.0635)
			(type default)
		)
		(layer "In5.Cu")
	)
	(gr_line
		(start 266.094972 -0.6477)
		(end 266.348718 -0.6477)
		(stroke
			(width 0.0635)
			(type default)
		)
		(layer "In5.Cu")
	)
	(gr_line
		(start 266.25423 -59.241944)
		(end 266.269724 -59.252866)
		(stroke
			(width 0.06985)
			(type default)
		)
		(layer "In5.Cu")
	)
	(gr_line
		(start 266.269724 -59.252866)
		(end 266.280646 -59.26836)
		(stroke
			(width 0.06985)
			(type default)
		)
		(layer "In5.Cu")
	)
	(gr_line
		(start 266.5984 0.645414)
		(end 266.87526 0.645414)
		(stroke
			(width 0.0635)
			(type default)
		)
		(layer "In5.Cu")
	)
	(gr_line
		(start 266.752832 -45.816266)
		(end 266.785852 -45.822108)
		(stroke
			(width 0.06985)
			(type default)
		)
		(layer "In5.Cu")
	)
	(gr_line
		(start 266.785852 -45.822108)
		(end 266.813792 -45.841666)
		(stroke
			(width 0.06985)
			(type default)
		)
		(layer "In5.Cu")
	)
	(gr_line
		(start 266.842494 -39.74846)
		(end 266.86129 -39.745158)
		(stroke
			(width 0.06985)
			(type default)
		)
		(layer "In5.Cu")
	)
	(gr_line
		(start 266.86129 -39.745158)
		(end 266.880086 -39.74846)
		(stroke
			(width 0.06985)
			(type default)
		)
		(layer "In5.Cu")
	)
	(gr_line
		(start 266.959842 -57.761886)
		(end 266.975336 -57.772808)
		(stroke
			(width 0.06985)
			(type default)
		)
		(layer "In5.Cu")
	)
	(gr_line
		(start 266.975336 -57.772808)
		(end 266.986258 -57.788302)
		(stroke
			(width 0.06985)
			(type default)
		)
		(layer "In5.Cu")
	)
	(gr_line
		(start 267.036804 -37.442902)
		(end 267.0556 -37.4396)
		(stroke
			(width 0.06985)
			(type default)
		)
		(layer "In5.Cu")
	)
	(gr_line
		(start 267.0556 -37.4396)
		(end 267.074396 -37.442902)
		(stroke
			(width 0.06985)
			(type default)
		)
		(layer "In5.Cu")
	)
	(gr_line
		(start 267.075158 -38.608762)
		(end 267.093954 -38.60546)
		(stroke
			(width 0.06985)
			(type default)
		)
		(layer "In5.Cu")
	)
	(gr_line
		(start 267.093954 -38.60546)
		(end 267.11275 -38.608762)
		(stroke
			(width 0.06985)
			(type default)
		)
		(layer "In5.Cu")
	)
	(gr_line
		(start 267.23086 -36.45408)
		(end 267.24991 -36.450778)
		(stroke
			(width 0.06985)
			(type default)
		)
		(layer "In5.Cu")
	)
	(gr_line
		(start 267.24991 -36.450778)
		(end 267.268198 -36.45408)
		(stroke
			(width 0.06985)
			(type default)
		)
		(layer "In5.Cu")
	)
	(gr_line
		(start 267.507466 -35.322256)
		(end 267.526262 -35.318954)
		(stroke
			(width 0.06985)
			(type default)
		)
		(layer "In5.Cu")
	)
	(gr_line
		(start 267.526262 -35.318954)
		(end 267.545058 -35.322256)
		(stroke
			(width 0.06985)
			(type default)
		)
		(layer "In5.Cu")
	)
	(gr_line
		(start 267.630402 -65.593722)
		(end 267.64996 -65.621662)
		(stroke
			(width 0.06985)
			(type default)
		)
		(layer "In5.Cu")
	)
	(gr_line
		(start 267.634466 -208.28)
		(end 267.637768 -208.29905)
		(stroke
			(width 0.06985)
			(type default)
		)
		(layer "In5.Cu")
	)
	(gr_line
		(start 267.634466 -208.28)
		(end 267.637768 -208.261204)
		(stroke
			(width 0.06985)
			(type default)
		)
		(layer "In5.Cu")
	)
	(gr_line
		(start 267.64996 -65.621662)
		(end 267.655802 -65.654682)
		(stroke
			(width 0.06985)
			(type default)
		)
		(layer "In5.Cu")
	)
	(gr_line
		(start 267.689838 -31.857696)
		(end 267.708634 -31.854394)
		(stroke
			(width 0.06985)
			(type default)
		)
		(layer "In5.Cu")
	)
	(gr_line
		(start 267.693648 -210.896454)
		(end 267.835888 -210.75396)
		(stroke
			(width 0.06985)
			(type default)
		)
		(layer "In5.Cu")
	)
	(gr_line
		(start 267.708634 -31.854394)
		(end 267.72743 -31.857696)
		(stroke
			(width 0.06985)
			(type default)
		)
		(layer "In5.Cu")
	)
	(gr_line
		(start 267.773912 -16.832834)
		(end 267.793724 -16.82877)
		(stroke
			(width 0.06985)
			(type default)
		)
		(layer "In5.Cu")
	)
	(gr_line
		(start 267.790422 -34.104326)
		(end 267.806424 -34.101786)
		(stroke
			(width 0.06985)
			(type default)
		)
		(layer "In5.Cu")
	)
	(gr_line
		(start 267.793724 -16.82877)
		(end 267.811504 -16.81734)
		(stroke
			(width 0.06985)
			(type default)
		)
		(layer "In5.Cu")
	)
	(gr_line
		(start 267.806424 -34.101786)
		(end 267.822426 -34.10458)
		(stroke
			(width 0.06985)
			(type default)
		)
		(layer "In5.Cu")
	)
	(gr_arc
		(start 267.835888 -210.75396)
		(mid 267.909154 -210.644427)
		(end 267.934948 -210.5152)
		(stroke
			(width 0.06985)
			(type default)
		)
		(layer "In5.Cu")
	)
	(gr_line
		(start 267.839698 -32.871156)
		(end 267.858494 -32.867854)
		(stroke
			(width 0.06985)
			(type default)
		)
		(layer "In5.Cu")
	)
	(gr_line
		(start 267.858494 -32.867854)
		(end 267.87729 -32.871156)
		(stroke
			(width 0.06985)
			(type default)
		)
		(layer "In5.Cu")
	)
	(gr_line
		(start 267.977112 -45.105066)
		(end 268.010132 -45.110908)
		(stroke
			(width 0.06985)
			(type default)
		)
		(layer "In5.Cu")
	)
	(gr_line
		(start 267.98524 -44.018708)
		(end 268.01826 -44.02455)
		(stroke
			(width 0.06985)
			(type default)
		)
		(layer "In5.Cu")
	)
	(gr_line
		(start 267.997686 -21.08454)
		(end 268.02715 -21.09089)
		(stroke
			(width 0.06985)
			(type default)
		)
		(layer "In5.Cu")
	)
	(gr_line
		(start 268.010132 -45.110908)
		(end 268.038072 -45.130466)
		(stroke
			(width 0.06985)
			(type default)
		)
		(layer "In5.Cu")
	)
	(gr_line
		(start 268.01826 -44.02455)
		(end 268.0462 -44.044108)
		(stroke
			(width 0.06985)
			(type default)
		)
		(layer "In5.Cu")
	)
	(gr_line
		(start 268.02715 -21.09089)
		(end 268.05763 -21.08454)
		(stroke
			(width 0.06985)
			(type default)
		)
		(layer "In5.Cu")
	)
	(gr_line
		(start 268.073124 -30.004004)
		(end 268.09192 -30.000702)
		(stroke
			(width 0.06985)
			(type default)
		)
		(layer "In5.Cu")
	)
	(gr_line
		(start 268.09192 -30.000702)
		(end 268.110716 -30.004004)
		(stroke
			(width 0.06985)
			(type default)
		)
		(layer "In5.Cu")
	)
	(gr_line
		(start 268.222476 -206.84871)
		(end 268.222476 -206.848964)
		(stroke
			(width 0.06985)
			(type default)
		)
		(layer "In5.Cu")
	)
	(gr_line
		(start 268.222476 -206.84871)
		(end 268.225778 -206.829914)
		(stroke
			(width 0.06985)
			(type default)
		)
		(layer "In5.Cu")
	)
	(gr_line
		(start 268.222476 -206.811118)
		(end 268.225778 -206.829914)
		(stroke
			(width 0.06985)
			(type default)
		)
		(layer "In5.Cu")
	)
	(gr_arc
		(start 268.265148 -210.5152)
		(mid 268.290946 -210.644424)
		(end 268.364208 -210.75396)
		(stroke
			(width 0.06985)
			(type default)
		)
		(layer "In5.Cu")
	)
	(gr_line
		(start 268.364208 -210.75396)
		(end 268.506448 -210.896454)
		(stroke
			(width 0.06985)
			(type default)
		)
		(layer "In5.Cu")
	)
	(gr_line
		(start 268.416278 -57.35066)
		(end 268.431772 -57.361582)
		(stroke
			(width 0.06985)
			(type default)
		)
		(layer "In5.Cu")
	)
	(gr_line
		(start 268.431772 -57.361582)
		(end 268.442694 -57.377076)
		(stroke
			(width 0.06985)
			(type default)
		)
		(layer "In5.Cu")
	)
	(gr_arc
		(start 268.478 -13.843)
		(mid 268.625756 -13.981057)
		(end 268.821662 -14.031214)
		(stroke
			(width 0.06985)
			(type default)
		)
		(layer "In5.Cu")
	)
	(gr_line
		(start 268.57198 -43.174158)
		(end 268.605 -43.18)
		(stroke
			(width 0.06985)
			(type default)
		)
		(layer "In5.Cu")
	)
	(gr_line
		(start 268.605 -43.18)
		(end 268.63294 -43.199558)
		(stroke
			(width 0.06985)
			(type default)
		)
		(layer "In5.Cu")
	)
	(gr_arc
		(start 268.772386 -14.361414)
		(mid 268.564233 -14.447643)
		(end 268.478 -14.6558)
		(stroke
			(width 0.06985)
			(type default)
		)
		(layer "In5.Cu")
	)
	(gr_line
		(start 268.831822 -23.978616)
		(end 268.850618 -23.975314)
		(stroke
			(width 0.06985)
			(type default)
		)
		(layer "In5.Cu")
	)
	(gr_line
		(start 268.850618 -23.975314)
		(end 268.869414 -23.978616)
		(stroke
			(width 0.06985)
			(type default)
		)
		(layer "In5.Cu")
	)
	(gr_line
		(start 268.920468 -16.096996)
		(end 268.945106 -16.080994)
		(stroke
			(width 0.06985)
			(type default)
		)
		(layer "In5.Cu")
	)
	(gr_line
		(start 268.945106 -16.080994)
		(end 268.961362 -16.056102)
		(stroke
			(width 0.06985)
			(type default)
		)
		(layer "In5.Cu")
	)
	(gr_line
		(start 269.018004 -160.163256)
		(end 269.018004 -160.16351)
		(stroke
			(width 0.06985)
			(type default)
		)
		(layer "In5.Cu")
	)
	(gr_line
		(start 269.018004 -160.163256)
		(end 269.021306 -160.14446)
		(stroke
			(width 0.06985)
			(type default)
		)
		(layer "In5.Cu")
	)
	(gr_line
		(start 269.018004 -160.125664)
		(end 269.021306 -160.14446)
		(stroke
			(width 0.06985)
			(type default)
		)
		(layer "In5.Cu")
	)
	(gr_line
		(start 269.222728 -14.031214)
		(end 269.281148 -14.076426)
		(stroke
			(width 0.06985)
			(type default)
		)
		(layer "In5.Cu")
	)
	(gr_line
		(start 269.341346 -20.811236)
		(end 269.361158 -20.807172)
		(stroke
			(width 0.06985)
			(type default)
		)
		(layer "In5.Cu")
	)
	(gr_line
		(start 269.344902 -56.84012)
		(end 269.360396 -56.851042)
		(stroke
			(width 0.06985)
			(type default)
		)
		(layer "In5.Cu")
	)
	(gr_line
		(start 269.347188 0.647954)
		(end 269.759176 1.059942)
		(stroke
			(width 0.0635)
			(type default)
		)
		(layer "In5.Cu")
	)
	(gr_line
		(start 269.353538 -25.411684)
		(end 269.372334 -25.408382)
		(stroke
			(width 0.06985)
			(type default)
		)
		(layer "In5.Cu")
	)
	(gr_line
		(start 269.360396 -56.851042)
		(end 269.371318 -56.866536)
		(stroke
			(width 0.06985)
			(type default)
		)
		(layer "In5.Cu")
	)
	(gr_line
		(start 269.361158 -20.807172)
		(end 269.378938 -20.795742)
		(stroke
			(width 0.06985)
			(type default)
		)
		(layer "In5.Cu")
	)
	(gr_line
		(start 269.372334 -25.408382)
		(end 269.39113 -25.411684)
		(stroke
			(width 0.06985)
			(type default)
		)
		(layer "In5.Cu")
	)
	(gr_line
		(start 269.474696 -14.225016)
		(end 269.551404 -14.284198)
		(stroke
			(width 0.06985)
			(type default)
		)
		(layer "In5.Cu")
	)
	(gr_line
		(start 269.47622 -199.412098)
		(end 269.479522 -199.431148)
		(stroke
			(width 0.06985)
			(type default)
		)
		(layer "In5.Cu")
	)
	(gr_line
		(start 269.47622 -199.412098)
		(end 269.479522 -199.393302)
		(stroke
			(width 0.06985)
			(type default)
		)
		(layer "In5.Cu")
	)
	(gr_line
		(start 269.551404 -14.284198)
		(end 269.564866 -14.378686)
		(stroke
			(width 0.06985)
			(type default)
		)
		(layer "In5.Cu")
	)
	(gr_line
		(start 269.606522 -15.061184)
		(end 269.651988 -14.99108)
		(stroke
			(width 0.06985)
			(type default)
		)
		(layer "In5.Cu")
	)
	(gr_line
		(start 269.640304 -14.908022)
		(end 269.651988 -14.99108)
		(stroke
			(width 0.06985)
			(type default)
		)
		(layer "In5.Cu")
	)
	(gr_line
		(start 269.676372 -40.241474)
		(end 269.709392 -40.247316)
		(stroke
			(width 0.06985)
			(type default)
		)
		(layer "In5.Cu")
	)
	(gr_line
		(start 269.709392 -40.247316)
		(end 269.737332 -40.266874)
		(stroke
			(width 0.06985)
			(type default)
		)
		(layer "In5.Cu")
	)
	(gr_line
		(start 269.855188 0.137414)
		(end 269.866364 0.137414)
		(stroke
			(width 0.0635)
			(type default)
		)
		(layer "In5.Cu")
	)
	(gr_line
		(start 269.866364 0.137414)
		(end 270.66748 0.93853)
		(stroke
			(width 0.0635)
			(type default)
		)
		(layer "In5.Cu")
	)
	(gr_line
		(start 270.038322 -66.455036)
		(end 270.05788 -66.482976)
		(stroke
			(width 0.06985)
			(type default)
		)
		(layer "In5.Cu")
	)
	(gr_line
		(start 270.05788 -66.482976)
		(end 270.063722 -66.515996)
		(stroke
			(width 0.06985)
			(type default)
		)
		(layer "In5.Cu")
	)
	(gr_line
		(start 270.20012 -39.153084)
		(end 270.23314 -39.158926)
		(stroke
			(width 0.06985)
			(type default)
		)
		(layer "In5.Cu")
	)
	(gr_line
		(start 270.23314 -39.158926)
		(end 270.26108 -39.178484)
		(stroke
			(width 0.06985)
			(type default)
		)
		(layer "In5.Cu")
	)
	(gr_line
		(start 270.298926 -162.658806)
		(end 270.298926 -162.65906)
		(stroke
			(width 0.06985)
			(type default)
		)
		(layer "In5.Cu")
	)
	(gr_line
		(start 270.298926 -162.658806)
		(end 270.302228 -162.64001)
		(stroke
			(width 0.06985)
			(type default)
		)
		(layer "In5.Cu")
	)
	(gr_line
		(start 270.298926 -162.621214)
		(end 270.302228 -162.64001)
		(stroke
			(width 0.06985)
			(type default)
		)
		(layer "In5.Cu")
	)
	(gr_line
		(start 270.357092 -16.059404)
		(end 270.363442 -16.089884)
		(stroke
			(width 0.06985)
			(type default)
		)
		(layer "In5.Cu")
	)
	(gr_line
		(start 270.357092 -16.059404)
		(end 270.363442 -16.029178)
		(stroke
			(width 0.06985)
			(type default)
		)
		(layer "In5.Cu")
	)
	(gr_line
		(start 270.363442 -16.028924)
		(end 270.363696 -16.027908)
		(stroke
			(width 0.06985)
			(type default)
		)
		(layer "In5.Cu")
	)
	(gr_line
		(start 270.48714 -20.075906)
		(end 270.511778 -20.059904)
		(stroke
			(width 0.06985)
			(type default)
		)
		(layer "In5.Cu")
	)
	(gr_line
		(start 270.511778 -20.059904)
		(end 270.52778 -20.035266)
		(stroke
			(width 0.06985)
			(type default)
		)
		(layer "In5.Cu")
	)
	(gr_line
		(start 270.52143 -15.28699)
		(end 270.528034 -15.256256)
		(stroke
			(width 0.06985)
			(type default)
		)
		(layer "In5.Cu")
	)
	(gr_line
		(start 270.528034 -15.256256)
		(end 270.529304 -15.254478)
		(stroke
			(width 0.06985)
			(type default)
		)
		(layer "In5.Cu")
	)
	(gr_line
		(start 270.594582 -38.063424)
		(end 270.627348 -38.069266)
		(stroke
			(width 0.06985)
			(type default)
		)
		(layer "In5.Cu")
	)
	(gr_line
		(start 270.626078 -56.145684)
		(end 270.641572 -56.156606)
		(stroke
			(width 0.06985)
			(type default)
		)
		(layer "In5.Cu")
	)
	(gr_line
		(start 270.627348 -38.069266)
		(end 270.655288 -38.088824)
		(stroke
			(width 0.06985)
			(type default)
		)
		(layer "In5.Cu")
	)
	(gr_line
		(start 270.641572 -56.156606)
		(end 270.652494 -56.1721)
		(stroke
			(width 0.06985)
			(type default)
		)
		(layer "In5.Cu")
	)
	(gr_line
		(start 270.66748 1.10109)
		(end 270.66748 0.93853)
		(stroke
			(width 0.0635)
			(type default)
		)
		(layer "In5.Cu")
	)
	(gr_line
		(start 270.893794 -210.896454)
		(end 271.011142 -210.779106)
		(stroke
			(width 0.06985)
			(type default)
		)
		(layer "In5.Cu")
	)
	(gr_line
		(start 270.905732 -19.453606)
		(end 270.917162 -19.435826)
		(stroke
			(width 0.06985)
			(type default)
		)
		(layer "In5.Cu")
	)
	(gr_line
		(start 270.917162 -19.435826)
		(end 270.921226 -19.416014)
		(stroke
			(width 0.06985)
			(type default)
		)
		(layer "In5.Cu")
	)
	(gr_arc
		(start 271.011142 -210.779106)
		(mid 271.123164 -210.611403)
		(end 271.162526 -210.4136)
		(stroke
			(width 0.06985)
			(type default)
		)
		(layer "In5.Cu")
	)
	(gr_line
		(start 271.151096 -37.13861)
		(end 271.184116 -37.144452)
		(stroke
			(width 0.06985)
			(type default)
		)
		(layer "In5.Cu")
	)
	(gr_line
		(start 271.158462 -18.238216)
		(end 271.158716 -18.239232)
		(stroke
			(width 0.06985)
			(type default)
		)
		(layer "In5.Cu")
	)
	(gr_line
		(start 271.158716 -18.299176)
		(end 271.165066 -18.269712)
		(stroke
			(width 0.06985)
			(type default)
		)
		(layer "In5.Cu")
	)
	(gr_line
		(start 271.158716 -18.239486)
		(end 271.165066 -18.269712)
		(stroke
			(width 0.06985)
			(type default)
		)
		(layer "In5.Cu")
	)
	(gr_line
		(start 271.184116 -37.144452)
		(end 271.212056 -37.16401)
		(stroke
			(width 0.06985)
			(type default)
		)
		(layer "In5.Cu")
	)
	(gr_line
		(start 271.215358 -14.766036)
		(end 271.258538 -14.739874)
		(stroke
			(width 0.06985)
			(type default)
		)
		(layer "In5.Cu")
	)
	(gr_line
		(start 271.31137 -66.453004)
		(end 271.330928 -66.480944)
		(stroke
			(width 0.06985)
			(type default)
		)
		(layer "In5.Cu")
	)
	(gr_line
		(start 271.330928 -66.480944)
		(end 271.33677 -66.513964)
		(stroke
			(width 0.06985)
			(type default)
		)
		(layer "In5.Cu")
	)
	(gr_line
		(start 271.475962 -41.484296)
		(end 271.491456 -41.495218)
		(stroke
			(width 0.06985)
			(type default)
		)
		(layer "In5.Cu")
	)
	(gr_line
		(start 271.491456 -41.495218)
		(end 271.502378 -41.510712)
		(stroke
			(width 0.06985)
			(type default)
		)
		(layer "In5.Cu")
	)
	(gr_arc
		(start 271.492726 -210.38185)
		(mid 271.547984 -210.659652)
		(end 271.705324 -210.895184)
		(stroke
			(width 0.06985)
			(type default)
		)
		(layer "In5.Cu")
	)
	(gr_line
		(start 271.561052 -55.126636)
		(end 271.575276 -55.136542)
		(stroke
			(width 0.06985)
			(type default)
		)
		(layer "In5.Cu")
	)
	(gr_line
		(start 271.575276 -55.136542)
		(end 271.585436 -55.15102)
		(stroke
			(width 0.06985)
			(type default)
		)
		(layer "In5.Cu")
	)
	(gr_arc
		(start 271.703546 -14.739874)
		(mid 271.91588 -14.681429)
		(end 272.06829 -14.52245)
		(stroke
			(width 0.06985)
			(type default)
		)
		(layer "In5.Cu")
	)
	(gr_line
		(start 271.705324 -210.895184)
		(end 271.706594 -210.896454)
		(stroke
			(width 0.06985)
			(type default)
		)
		(layer "In5.Cu")
	)
	(gr_arc
		(start 272.06829 -15.33525)
		(mid 271.981797 -15.146963)
		(end 271.789398 -15.070074)
		(stroke
			(width 0.06985)
			(type default)
		)
		(layer "In5.Cu")
	)
	(gr_line
		(start 272.13052 -36.130484)
		(end 272.16354 -36.136326)
		(stroke
			(width 0.06985)
			(type default)
		)
		(layer "In5.Cu")
	)
	(gr_line
		(start 272.16354 -36.136326)
		(end 272.19148 -36.155884)
		(stroke
			(width 0.06985)
			(type default)
		)
		(layer "In5.Cu")
	)
	(gr_line
		(start 272.39341 -20.718526)
		(end 272.422874 -20.712176)
		(stroke
			(width 0.06985)
			(type default)
		)
		(layer "In5.Cu")
	)
	(gr_line
		(start 272.40992 -40.68318)
		(end 272.425414 -40.694102)
		(stroke
			(width 0.06985)
			(type default)
		)
		(layer "In5.Cu")
	)
	(gr_line
		(start 272.422874 -20.712176)
		(end 272.452338 -20.718526)
		(stroke
			(width 0.06985)
			(type default)
		)
		(layer "In5.Cu")
	)
	(gr_line
		(start 272.424144 -34.91611)
		(end 272.457164 -34.921952)
		(stroke
			(width 0.06985)
			(type default)
		)
		(layer "In5.Cu")
	)
	(gr_line
		(start 272.425414 -40.694102)
		(end 272.436336 -40.709596)
		(stroke
			(width 0.06985)
			(type default)
		)
		(layer "In5.Cu")
	)
	(gr_line
		(start 272.449036 -65.589912)
		(end 272.468594 -65.617852)
		(stroke
			(width 0.06985)
			(type default)
		)
		(layer "In5.Cu")
	)
	(gr_line
		(start 272.457164 -34.921952)
		(end 272.485104 -34.94151)
		(stroke
			(width 0.06985)
			(type default)
		)
		(layer "In5.Cu")
	)
	(gr_line
		(start 272.468594 -65.617852)
		(end 272.474436 -65.650872)
		(stroke
			(width 0.06985)
			(type default)
		)
		(layer "In5.Cu")
	)
	(gr_line
		(start 272.486628 -54.220364)
		(end 272.502122 -54.231286)
		(stroke
			(width 0.06985)
			(type default)
		)
		(layer "In5.Cu")
	)
	(gr_line
		(start 272.502122 -54.231286)
		(end 272.513044 -54.24678)
		(stroke
			(width 0.06985)
			(type default)
		)
		(layer "In5.Cu")
	)
	(gr_line
		(start 272.548604 -21.800058)
		(end 272.578068 -21.793708)
		(stroke
			(width 0.06985)
			(type default)
		)
		(layer "In5.Cu")
	)
	(gr_line
		(start 272.578068 -21.793708)
		(end 272.607532 -21.800058)
		(stroke
			(width 0.06985)
			(type default)
		)
		(layer "In5.Cu")
	)
	(gr_line
		(start 272.650966 -43.727624)
		(end 272.661888 -43.743118)
		(stroke
			(width 0.06985)
			(type default)
		)
		(layer "In5.Cu")
	)
	(gr_line
		(start 272.661888 -43.743118)
		(end 272.677382 -43.75404)
		(stroke
			(width 0.06985)
			(type default)
		)
		(layer "In5.Cu")
	)
	(gr_line
		(start 272.703798 -33.722056)
		(end 272.736818 -33.727898)
		(stroke
			(width 0.06985)
			(type default)
		)
		(layer "In5.Cu")
	)
	(gr_line
		(start 272.736818 -33.727898)
		(end 272.764758 -33.747456)
		(stroke
			(width 0.06985)
			(type default)
		)
		(layer "In5.Cu")
	)
	(gr_line
		(start 273.022568 -53.258466)
		(end 273.038062 -53.269388)
		(stroke
			(width 0.06985)
			(type default)
		)
		(layer "In5.Cu")
	)
	(gr_line
		(start 273.038062 -53.269388)
		(end 273.048984 -53.284882)
		(stroke
			(width 0.06985)
			(type default)
		)
		(layer "In5.Cu")
	)
	(gr_line
		(start 273.218656 -39.883588)
		(end 273.23415 -39.89451)
		(stroke
			(width 0.06985)
			(type default)
		)
		(layer "In5.Cu")
	)
	(gr_line
		(start 273.23415 -39.89451)
		(end 273.245072 -39.910004)
		(stroke
			(width 0.06985)
			(type default)
		)
		(layer "In5.Cu")
	)
	(gr_line
		(start 273.488404 -10.54354)
		(end 273.988276 -11.043412)
		(stroke
			(width 0.0635)
			(type default)
		)
		(layer "In5.Cu")
	)
	(gr_line
		(start 273.584162 -32.89046)
		(end 273.617182 -32.896302)
		(stroke
			(width 0.06985)
			(type default)
		)
		(layer "In5.Cu")
	)
	(gr_line
		(start 273.617182 -32.896302)
		(end 273.645122 -32.91586)
		(stroke
			(width 0.06985)
			(type default)
		)
		(layer "In5.Cu")
	)
	(gr_line
		(start 273.621754 -30.975808)
		(end 273.654774 -30.98165)
		(stroke
			(width 0.06985)
			(type default)
		)
		(layer "In5.Cu")
	)
	(gr_line
		(start 273.654774 -30.98165)
		(end 273.682714 -31.001208)
		(stroke
			(width 0.06985)
			(type default)
		)
		(layer "In5.Cu")
	)
	(gr_line
		(start 273.682714 -43.065954)
		(end 273.693636 -43.081448)
		(stroke
			(width 0.06985)
			(type default)
		)
		(layer "In5.Cu")
	)
	(gr_line
		(start 273.693636 -43.081448)
		(end 273.70913 -43.09237)
		(stroke
			(width 0.06985)
			(type default)
		)
		(layer "In5.Cu")
	)
	(gr_line
		(start 273.878802 -176.347628)
		(end 273.878802 -176.347882)
		(stroke
			(width 0.06985)
			(type default)
		)
		(layer "In5.Cu")
	)
	(gr_line
		(start 273.878802 -176.347628)
		(end 273.882104 -176.328832)
		(stroke
			(width 0.06985)
			(type default)
		)
		(layer "In5.Cu")
	)
	(gr_line
		(start 273.878802 -176.310036)
		(end 273.882104 -176.328832)
		(stroke
			(width 0.06985)
			(type default)
		)
		(layer "In5.Cu")
	)
	(gr_line
		(start 273.892772 -22.073362)
		(end 273.912584 -22.077426)
		(stroke
			(width 0.06985)
			(type default)
		)
		(layer "In5.Cu")
	)
	(gr_line
		(start 273.912584 -22.077426)
		(end 273.930364 -22.088856)
		(stroke
			(width 0.06985)
			(type default)
		)
		(layer "In5.Cu")
	)
	(gr_line
		(start 273.996404 -10.033)
		(end 274.439126 -10.033)
		(stroke
			(width 0.0635)
			(type default)
		)
		(layer "In5.Cu")
	)
	(gr_line
		(start 274.01266 -65.331848)
		(end 274.032218 -65.359788)
		(stroke
			(width 0.06985)
			(type default)
		)
		(layer "In5.Cu")
	)
	(gr_line
		(start 274.032218 -65.359788)
		(end 274.03806 -65.392808)
		(stroke
			(width 0.06985)
			(type default)
		)
		(layer "In5.Cu")
	)
	(gr_line
		(start 274.084034 -29.90723)
		(end 274.117054 -29.913072)
		(stroke
			(width 0.06985)
			(type default)
		)
		(layer "In5.Cu")
	)
	(gr_arc
		(start 274.093686 -210.896454)
		(mid 274.272273 -210.629107)
		(end 274.334986 -210.313778)
		(stroke
			(width 0.06985)
			(type default)
		)
		(layer "In5.Cu")
	)
	(gr_line
		(start 274.098766 -39.185088)
		(end 274.11426 -39.19601)
		(stroke
			(width 0.06985)
			(type default)
		)
		(layer "In5.Cu")
	)
	(gr_line
		(start 274.11426 -39.19601)
		(end 274.125182 -39.211504)
		(stroke
			(width 0.06985)
			(type default)
		)
		(layer "In5.Cu")
	)
	(gr_line
		(start 274.117054 -29.913072)
		(end 274.144994 -29.93263)
		(stroke
			(width 0.06985)
			(type default)
		)
		(layer "In5.Cu")
	)
	(gr_line
		(start 274.25777 -41.932606)
		(end 274.268692 -41.9481)
		(stroke
			(width 0.06985)
			(type default)
		)
		(layer "In5.Cu")
	)
	(gr_line
		(start 274.268692 -41.9481)
		(end 274.284186 -41.959022)
		(stroke
			(width 0.06985)
			(type default)
		)
		(layer "In5.Cu")
	)
	(gr_line
		(start 274.439126 -10.033)
		(end 275.16201 -9.310116)
		(stroke
			(width 0.0635)
			(type default)
		)
		(layer "In5.Cu")
	)
	(gr_line
		(start 274.490688 -2.413)
		(end 274.521168 -2.44348)
		(stroke
			(width 0.0635)
			(type default)
		)
		(layer "In5.Cu")
	)
	(gr_line
		(start 274.521168 -2.44348)
		(end 274.521168 -2.842006)
		(stroke
			(width 0.0635)
			(type default)
		)
		(layer "In5.Cu")
	)
	(gr_arc
		(start 274.665186 -210.313778)
		(mid 274.727907 -210.6291)
		(end 274.906486 -210.896454)
		(stroke
			(width 0.06985)
			(type default)
		)
		(layer "In5.Cu")
	)
	(gr_line
		(start 274.832064 -38.00475)
		(end 274.847558 -38.015672)
		(stroke
			(width 0.06985)
			(type default)
		)
		(layer "In5.Cu")
	)
	(gr_line
		(start 274.847558 -38.015672)
		(end 274.85848 -38.031166)
		(stroke
			(width 0.06985)
			(type default)
		)
		(layer "In5.Cu")
	)
	(gr_line
		(start 274.898612 -40.891968)
		(end 274.909534 -40.907462)
		(stroke
			(width 0.06985)
			(type default)
		)
		(layer "In5.Cu")
	)
	(gr_line
		(start 274.909534 -40.907462)
		(end 274.925028 -40.918384)
		(stroke
			(width 0.06985)
			(type default)
		)
		(layer "In5.Cu")
	)
	(gr_line
		(start 275.033232 -7.772654)
		(end 275.360384 -7.772654)
		(stroke
			(width 0.0635)
			(type default)
		)
		(layer "In5.Cu")
	)
	(gr_line
		(start 275.051266 -21.27123)
		(end 275.071078 -21.275294)
		(stroke
			(width 0.06985)
			(type default)
		)
		(layer "In5.Cu")
	)
	(gr_line
		(start 275.071078 -21.275294)
		(end 275.088858 -21.286724)
		(stroke
			(width 0.06985)
			(type default)
		)
		(layer "In5.Cu")
	)
	(gr_line
		(start 275.178012 -2.774188)
		(end 275.178012 -2.907284)
		(stroke
			(width 0.0635)
			(type default)
		)
		(layer "In5.Cu")
	)
	(gr_line
		(start 275.178012 -2.774188)
		(end 275.5392 -2.413)
		(stroke
			(width 0.0635)
			(type default)
		)
		(layer "In5.Cu")
	)
	(gr_line
		(start 275.360384 -7.772654)
		(end 276.045422 -7.087616)
		(stroke
			(width 0.0635)
			(type default)
		)
		(layer "In5.Cu")
	)
	(gr_line
		(start 275.509482 -51.930554)
		(end 275.524976 -51.941476)
		(stroke
			(width 0.06985)
			(type default)
		)
		(layer "In5.Cu")
	)
	(gr_line
		(start 275.524976 -51.941476)
		(end 275.535898 -51.95697)
		(stroke
			(width 0.06985)
			(type default)
		)
		(layer "In5.Cu")
	)
	(gr_line
		(start 275.5392 -2.3876)
		(end 275.5392 -2.413)
		(stroke
			(width 0.0635)
			(type default)
		)
		(layer "In5.Cu")
	)
	(gr_line
		(start 275.542248 -37.082222)
		(end 275.556472 -37.092382)
		(stroke
			(width 0.06985)
			(type default)
		)
		(layer "In5.Cu")
	)
	(gr_line
		(start 275.556472 -37.092382)
		(end 275.566124 -37.106352)
		(stroke
			(width 0.06985)
			(type default)
		)
		(layer "In5.Cu")
	)
	(gr_line
		(start 275.58492 -26.503884)
		(end 275.61794 -26.509726)
		(stroke
			(width 0.06985)
			(type default)
		)
		(layer "In5.Cu")
	)
	(gr_line
		(start 275.61794 -26.509726)
		(end 275.64588 -26.529284)
		(stroke
			(width 0.06985)
			(type default)
		)
		(layer "In5.Cu")
	)
	(gr_line
		(start 275.75383 -50.533046)
		(end 275.769324 -50.543968)
		(stroke
			(width 0.06985)
			(type default)
		)
		(layer "In5.Cu")
	)
	(gr_line
		(start 275.769324 -50.543968)
		(end 275.780246 -50.559462)
		(stroke
			(width 0.06985)
			(type default)
		)
		(layer "In5.Cu")
	)
	(gr_line
		(start 275.812504 -39.969948)
		(end 275.823426 -39.985442)
		(stroke
			(width 0.06985)
			(type default)
		)
		(layer "In5.Cu")
	)
	(gr_line
		(start 275.823426 -39.985442)
		(end 275.83892 -39.996364)
		(stroke
			(width 0.06985)
			(type default)
		)
		(layer "In5.Cu")
	)
	(gr_line
		(start 275.97608 -66.299334)
		(end 275.995638 -66.327274)
		(stroke
			(width 0.06985)
			(type default)
		)
		(layer "In5.Cu")
	)
	(gr_line
		(start 275.995638 -66.327274)
		(end 276.00148 -66.360294)
		(stroke
			(width 0.06985)
			(type default)
		)
		(layer "In5.Cu")
	)
	(gr_line
		(start 276.119844 -25.257252)
		(end 276.152864 -25.263094)
		(stroke
			(width 0.06985)
			(type default)
		)
		(layer "In5.Cu")
	)
	(gr_line
		(start 276.152864 -25.263094)
		(end 276.180804 -25.282652)
		(stroke
			(width 0.06985)
			(type default)
		)
		(layer "In5.Cu")
	)
	(gr_line
		(start 276.206458 -49.758092)
		(end 276.221952 -49.769014)
		(stroke
			(width 0.06985)
			(type default)
		)
		(layer "In5.Cu")
	)
	(gr_line
		(start 276.221952 -49.769014)
		(end 276.232874 -49.784508)
		(stroke
			(width 0.06985)
			(type default)
		)
		(layer "In5.Cu")
	)
	(gr_line
		(start 276.55774 -48.748188)
		(end 276.573234 -48.75911)
		(stroke
			(width 0.06985)
			(type default)
		)
		(layer "In5.Cu")
	)
	(gr_line
		(start 276.573234 -48.75911)
		(end 276.584156 -48.774604)
		(stroke
			(width 0.06985)
			(type default)
		)
		(layer "In5.Cu")
	)
	(gr_line
		(start 276.638512 -36.459922)
		(end 276.654006 -36.470844)
		(stroke
			(width 0.06985)
			(type default)
		)
		(layer "In5.Cu")
	)
	(gr_line
		(start 276.654006 -36.470844)
		(end 276.664928 -36.486338)
		(stroke
			(width 0.06985)
			(type default)
		)
		(layer "In5.Cu")
	)
	(gr_line
		(start 276.767544 -7.087616)
		(end 277.391876 -7.711948)
		(stroke
			(width 0.0635)
			(type default)
		)
		(layer "In5.Cu")
	)
	(gr_line
		(start 276.823424 -39.477442)
		(end 276.833838 -39.492428)
		(stroke
			(width 0.06985)
			(type default)
		)
		(layer "In5.Cu")
	)
	(gr_line
		(start 276.833838 -39.492428)
		(end 276.849332 -39.50335)
		(stroke
			(width 0.06985)
			(type default)
		)
		(layer "In5.Cu")
	)
	(gr_line
		(start 277.029164 -201.272394)
		(end 277.032466 -201.291444)
		(stroke
			(width 0.06985)
			(type default)
		)
		(layer "In5.Cu")
	)
	(gr_line
		(start 277.029164 -201.272394)
		(end 277.032466 -201.253598)
		(stroke
			(width 0.06985)
			(type default)
		)
		(layer "In5.Cu")
	)
	(gr_line
		(start 277.25624 -27.657044)
		(end 277.271734 -27.667966)
		(stroke
			(width 0.06985)
			(type default)
		)
		(layer "In5.Cu")
	)
	(gr_line
		(start 277.271734 -27.667966)
		(end 277.282656 -27.68346)
		(stroke
			(width 0.06985)
			(type default)
		)
		(layer "In5.Cu")
	)
	(gr_arc
		(start 277.293578 -210.896454)
		(mid 277.472167 -210.629108)
		(end 277.534878 -210.313778)
		(stroke
			(width 0.06985)
			(type default)
		)
		(layer "In5.Cu")
	)
	(gr_line
		(start 277.344886 -35.506152)
		(end 277.36038 -35.517074)
		(stroke
			(width 0.06985)
			(type default)
		)
		(layer "In5.Cu")
	)
	(gr_line
		(start 277.36038 -35.517074)
		(end 277.371302 -35.532568)
		(stroke
			(width 0.06985)
			(type default)
		)
		(layer "In5.Cu")
	)
	(gr_line
		(start 277.699724 -66.236342)
		(end 277.719282 -66.264282)
		(stroke
			(width 0.06985)
			(type default)
		)
		(layer "In5.Cu")
	)
	(gr_line
		(start 277.700994 -38.542214)
		(end 277.711916 -38.557708)
		(stroke
			(width 0.06985)
			(type default)
		)
		(layer "In5.Cu")
	)
	(gr_line
		(start 277.711916 -38.557708)
		(end 277.72741 -38.56863)
		(stroke
			(width 0.06985)
			(type default)
		)
		(layer "In5.Cu")
	)
	(gr_line
		(start 277.719282 -66.264282)
		(end 277.725124 -66.297302)
		(stroke
			(width 0.06985)
			(type default)
		)
		(layer "In5.Cu")
	)
	(gr_line
		(start 277.728172 -33.83407)
		(end 277.743666 -33.844992)
		(stroke
			(width 0.06985)
			(type default)
		)
		(layer "In5.Cu")
	)
	(gr_line
		(start 277.743666 -33.844992)
		(end 277.754588 -33.860486)
		(stroke
			(width 0.06985)
			(type default)
		)
		(layer "In5.Cu")
	)
	(gr_arc
		(start 277.865078 -210.313778)
		(mid 277.927799 -210.6291)
		(end 278.106378 -210.896454)
		(stroke
			(width 0.06985)
			(type default)
		)
		(layer "In5.Cu")
	)
	(gr_line
		(start 277.901908 -26.487628)
		(end 277.917402 -26.49855)
		(stroke
			(width 0.06985)
			(type default)
		)
		(layer "In5.Cu")
	)
	(gr_line
		(start 277.917402 -26.49855)
		(end 277.928324 -26.514044)
		(stroke
			(width 0.06985)
			(type default)
		)
		(layer "In5.Cu")
	)
	(gr_line
		(start 278.345138 -206.8703)
		(end 278.345138 -206.870554)
		(stroke
			(width 0.06985)
			(type default)
		)
		(layer "In5.Cu")
	)
	(gr_line
		(start 278.345138 -206.8703)
		(end 278.34844 -206.851504)
		(stroke
			(width 0.06985)
			(type default)
		)
		(layer "In5.Cu")
	)
	(gr_line
		(start 278.345138 -206.832708)
		(end 278.34844 -206.851504)
		(stroke
			(width 0.06985)
			(type default)
		)
		(layer "In5.Cu")
	)
	(gr_line
		(start 278.52243 -32.997648)
		(end 278.537924 -33.00857)
		(stroke
			(width 0.06985)
			(type default)
		)
		(layer "In5.Cu")
	)
	(gr_line
		(start 278.537924 -33.00857)
		(end 278.548846 -33.024064)
		(stroke
			(width 0.06985)
			(type default)
		)
		(layer "In5.Cu")
	)
	(gr_line
		(start 278.569166 -37.819584)
		(end 278.580088 -37.835078)
		(stroke
			(width 0.06985)
			(type default)
		)
		(layer "In5.Cu")
	)
	(gr_line
		(start 278.580088 -37.835078)
		(end 278.595582 -37.846)
		(stroke
			(width 0.06985)
			(type default)
		)
		(layer "In5.Cu")
	)
	(gr_line
		(start 278.602694 -29.568648)
		(end 278.622252 -29.596588)
		(stroke
			(width 0.06985)
			(type default)
		)
		(layer "In5.Cu")
	)
	(gr_line
		(start 278.622252 -29.596588)
		(end 278.628094 -29.629608)
		(stroke
			(width 0.06985)
			(type default)
		)
		(layer "In5.Cu")
	)
	(gr_line
		(start 278.719788 -25.199086)
		(end 278.74468 -25.215342)
		(stroke
			(width 0.06985)
			(type default)
		)
		(layer "In5.Cu")
	)
	(gr_line
		(start 278.74468 -25.215342)
		(end 278.760936 -25.240234)
		(stroke
			(width 0.06985)
			(type default)
		)
		(layer "In5.Cu")
	)
	(gr_line
		(start 278.759158 -32.27578)
		(end 278.765 -32.3088)
		(stroke
			(width 0.06985)
			(type default)
		)
		(layer "In5.Cu")
	)
	(gr_line
		(start 278.765 -32.3088)
		(end 278.784558 -32.33674)
		(stroke
			(width 0.06985)
			(type default)
		)
		(layer "In5.Cu")
	)
	(gr_line
		(start 279.092406 -197.762114)
		(end 279.095708 -197.781164)
		(stroke
			(width 0.06985)
			(type default)
		)
		(layer "In5.Cu")
	)
	(gr_line
		(start 279.092406 -197.762114)
		(end 279.095708 -197.743318)
		(stroke
			(width 0.06985)
			(type default)
		)
		(layer "In5.Cu")
	)
	(gr_line
		(start 279.611074 -66.612516)
		(end 279.630632 -66.640456)
		(stroke
			(width 0.06985)
			(type default)
		)
		(layer "In5.Cu")
	)
	(gr_line
		(start 279.62225 -14.147038)
		(end 286.134302 -20.65909)
		(stroke
			(width 0.0635)
			(type default)
		)
		(layer "In5.Cu")
	)
	(gr_line
		(start 279.62225 -13.332714)
		(end 279.62225 -14.147038)
		(stroke
			(width 0.0635)
			(type default)
		)
		(layer "In5.Cu")
	)
	(gr_line
		(start 279.62225 -13.332714)
		(end 279.651968 -13.302996)
		(stroke
			(width 0.0635)
			(type default)
		)
		(layer "In5.Cu")
	)
	(gr_line
		(start 279.630632 -66.640456)
		(end 279.636474 -66.673476)
		(stroke
			(width 0.06985)
			(type default)
		)
		(layer "In5.Cu")
	)
	(gr_line
		(start 279.681686 -37.188648)
		(end 279.692608 -37.204142)
		(stroke
			(width 0.06985)
			(type default)
		)
		(layer "In5.Cu")
	)
	(gr_line
		(start 279.692608 -37.204142)
		(end 279.708102 -37.215064)
		(stroke
			(width 0.06985)
			(type default)
		)
		(layer "In5.Cu")
	)
	(gr_line
		(start 279.813258 -29.205936)
		(end 279.832816 -29.233876)
		(stroke
			(width 0.06985)
			(type default)
		)
		(layer "In5.Cu")
	)
	(gr_line
		(start 279.832816 -29.233876)
		(end 279.838658 -29.266896)
		(stroke
			(width 0.06985)
			(type default)
		)
		(layer "In5.Cu")
	)
	(gr_line
		(start 279.979628 -48.866806)
		(end 280.007568 -48.886364)
		(stroke
			(width 0.06985)
			(type default)
		)
		(layer "In5.Cu")
	)
	(gr_line
		(start 280.007568 -48.886364)
		(end 280.040588 -48.892206)
		(stroke
			(width 0.06985)
			(type default)
		)
		(layer "In5.Cu")
	)
	(gr_line
		(start 280.06167 -24.516842)
		(end 280.081228 -24.529542)
		(stroke
			(width 0.06985)
			(type default)
		)
		(layer "In5.Cu")
	)
	(gr_line
		(start 280.081228 -24.529542)
		(end 280.094944 -24.548846)
		(stroke
			(width 0.06985)
			(type default)
		)
		(layer "In5.Cu")
	)
	(gr_line
		(start 280.105358 -32.68218)
		(end 280.1112 -32.7152)
		(stroke
			(width 0.06985)
			(type default)
		)
		(layer "In5.Cu")
	)
	(gr_line
		(start 280.1112 -32.7152)
		(end 280.130758 -32.74314)
		(stroke
			(width 0.06985)
			(type default)
		)
		(layer "In5.Cu")
	)
	(gr_line
		(start 280.12517 -177.455068)
		(end 280.133298 -177.42027)
		(stroke
			(width 0.06985)
			(type default)
		)
		(layer "In5.Cu")
	)
	(gr_line
		(start 280.125678 -177.386234)
		(end 280.133298 -177.42027)
		(stroke
			(width 0.06985)
			(type default)
		)
		(layer "In5.Cu")
	)
	(gr_line
		(start 280.207212 -35.968686)
		(end 280.218134 -35.98418)
		(stroke
			(width 0.06985)
			(type default)
		)
		(layer "In5.Cu")
	)
	(gr_line
		(start 280.218134 -35.98418)
		(end 280.233628 -35.995102)
		(stroke
			(width 0.06985)
			(type default)
		)
		(layer "In5.Cu")
	)
	(gr_line
		(start 280.373074 -47.758096)
		(end 280.401014 -47.777654)
		(stroke
			(width 0.06985)
			(type default)
		)
		(layer "In5.Cu")
	)
	(gr_line
		(start 280.401014 -47.777654)
		(end 280.434034 -47.783496)
		(stroke
			(width 0.06985)
			(type default)
		)
		(layer "In5.Cu")
	)
	(gr_arc
		(start 280.493724 -210.896454)
		(mid 280.672303 -210.629105)
		(end 280.735024 -210.313778)
		(stroke
			(width 0.06985)
			(type default)
		)
		(layer "In5.Cu")
	)
	(gr_line
		(start 280.665174 -28.172664)
		(end 280.680414 -28.196286)
		(stroke
			(width 0.06985)
			(type default)
		)
		(layer "In5.Cu")
	)
	(gr_line
		(start 280.680414 -28.196286)
		(end 280.68524 -28.223464)
		(stroke
			(width 0.06985)
			(type default)
		)
		(layer "In5.Cu")
	)
	(gr_line
		(start 280.946606 -35.424618)
		(end 280.957528 -35.440112)
		(stroke
			(width 0.06985)
			(type default)
		)
		(layer "In5.Cu")
	)
	(gr_line
		(start 280.957528 -35.440112)
		(end 280.973022 -35.451034)
		(stroke
			(width 0.06985)
			(type default)
		)
		(layer "In5.Cu")
	)
	(gr_line
		(start 280.962354 -46.635416)
		(end 280.990294 -46.654974)
		(stroke
			(width 0.06985)
			(type default)
		)
		(layer "In5.Cu")
	)
	(gr_line
		(start 280.990294 -46.654974)
		(end 281.023314 -46.660816)
		(stroke
			(width 0.06985)
			(type default)
		)
		(layer "In5.Cu")
	)
	(gr_line
		(start 281.053286 -32.206438)
		(end 281.072844 -32.234378)
		(stroke
			(width 0.06985)
			(type default)
		)
		(layer "In5.Cu")
	)
	(gr_arc
		(start 281.065224 -210.313778)
		(mid 281.127945 -210.6291)
		(end 281.306524 -210.896454)
		(stroke
			(width 0.06985)
			(type default)
		)
		(layer "In5.Cu")
	)
	(gr_line
		(start 281.331416 -208.59369)
		(end 281.331416 -208.593944)
		(stroke
			(width 0.06985)
			(type default)
		)
		(layer "In5.Cu")
	)
	(gr_line
		(start 281.331416 -208.59369)
		(end 281.334718 -208.574894)
		(stroke
			(width 0.06985)
			(type default)
		)
		(layer "In5.Cu")
	)
	(gr_line
		(start 281.331416 -208.556098)
		(end 281.334718 -208.574894)
		(stroke
			(width 0.06985)
			(type default)
		)
		(layer "In5.Cu")
	)
	(gr_line
		(start 281.33548 -66.846704)
		(end 281.355038 -66.874644)
		(stroke
			(width 0.06985)
			(type default)
		)
		(layer "In5.Cu")
	)
	(gr_line
		(start 281.355038 -66.874644)
		(end 281.36088 -66.907664)
		(stroke
			(width 0.06985)
			(type default)
		)
		(layer "In5.Cu")
	)
	(gr_line
		(start 281.48661 -42.750232)
		(end 281.511502 -42.767504)
		(stroke
			(width 0.06985)
			(type default)
		)
		(layer "In5.Cu")
	)
	(gr_line
		(start 281.505914 -177.78603)
		(end 281.505914 -177.786284)
		(stroke
			(width 0.06985)
			(type default)
		)
		(layer "In5.Cu")
	)
	(gr_line
		(start 281.505914 -177.78603)
		(end 281.509216 -177.767234)
		(stroke
			(width 0.06985)
			(type default)
		)
		(layer "In5.Cu")
	)
	(gr_line
		(start 281.505914 -177.748438)
		(end 281.509216 -177.767234)
		(stroke
			(width 0.06985)
			(type default)
		)
		(layer "In5.Cu")
	)
	(gr_line
		(start 281.511502 -42.767504)
		(end 281.540712 -42.773346)
		(stroke
			(width 0.06985)
			(type default)
		)
		(layer "In5.Cu")
	)
	(gr_line
		(start 281.519122 -45.535596)
		(end 281.547062 -45.555154)
		(stroke
			(width 0.06985)
			(type default)
		)
		(layer "In5.Cu")
	)
	(gr_line
		(start 281.547062 -45.555154)
		(end 281.580082 -45.560996)
		(stroke
			(width 0.06985)
			(type default)
		)
		(layer "In5.Cu")
	)
	(gr_line
		(start 281.547316 -34.766504)
		(end 281.558238 -34.781998)
		(stroke
			(width 0.06985)
			(type default)
		)
		(layer "In5.Cu")
	)
	(gr_line
		(start 281.558238 -34.781998)
		(end 281.573732 -34.79292)
		(stroke
			(width 0.06985)
			(type default)
		)
		(layer "In5.Cu")
	)
	(gr_line
		(start 281.804872 -44.173902)
		(end 281.829764 -44.191174)
		(stroke
			(width 0.06985)
			(type default)
		)
		(layer "In5.Cu")
	)
	(gr_line
		(start 281.829764 -44.191174)
		(end 281.858974 -44.197016)
		(stroke
			(width 0.06985)
			(type default)
		)
		(layer "In5.Cu")
	)
	(gr_line
		(start 282.087574 -41.62171)
		(end 282.112212 -41.638982)
		(stroke
			(width 0.06985)
			(type default)
		)
		(layer "In5.Cu")
	)
	(gr_line
		(start 282.112212 -41.638982)
		(end 282.141422 -41.644824)
		(stroke
			(width 0.06985)
			(type default)
		)
		(layer "In5.Cu")
	)
	(gr_line
		(start 282.276804 -33.953958)
		(end 282.286964 -33.968182)
		(stroke
			(width 0.06985)
			(type default)
		)
		(layer "In5.Cu")
	)
	(gr_line
		(start 282.286964 -33.968182)
		(end 282.300934 -33.977834)
		(stroke
			(width 0.06985)
			(type default)
		)
		(layer "In5.Cu")
	)
	(gr_line
		(start 282.374848 -27.80538)
		(end 282.394406 -27.83332)
		(stroke
			(width 0.06985)
			(type default)
		)
		(layer "In5.Cu")
	)
	(gr_line
		(start 282.392628 -30.749748)
		(end 282.465272 -31.162498)
		(stroke
			(width 0.06985)
			(type default)
		)
		(layer "In5.Cu")
	)
	(gr_line
		(start 282.392628 -30.749748)
		(end 282.534868 -30.546548)
		(stroke
			(width 0.06985)
			(type default)
		)
		(layer "In5.Cu")
	)
	(gr_line
		(start 282.394406 -27.83332)
		(end 282.400248 -27.86634)
		(stroke
			(width 0.06985)
			(type default)
		)
		(layer "In5.Cu")
	)
	(gr_line
		(start 282.396438 -66.63436)
		(end 282.415996 -66.6623)
		(stroke
			(width 0.06985)
			(type default)
		)
		(layer "In5.Cu")
	)
	(gr_line
		(start 282.415996 -66.6623)
		(end 282.421838 -66.69532)
		(stroke
			(width 0.06985)
			(type default)
		)
		(layer "In5.Cu")
	)
	(gr_line
		(start 282.454858 -40.548306)
		(end 282.47975 -40.565578)
		(stroke
			(width 0.06985)
			(type default)
		)
		(layer "In5.Cu")
	)
	(gr_line
		(start 282.465272 -31.162498)
		(end 282.668726 -31.304992)
		(stroke
			(width 0.06985)
			(type default)
		)
		(layer "In5.Cu")
	)
	(gr_line
		(start 282.47975 -40.565578)
		(end 282.50896 -40.57142)
		(stroke
			(width 0.06985)
			(type default)
		)
		(layer "In5.Cu")
	)
	(gr_line
		(start 282.869132 -30.525466)
		(end 282.989782 -31.210758)
		(stroke
			(width 0.06985)
			(type default)
		)
		(layer "In5.Cu")
	)
	(gr_line
		(start 282.918662 -32.709104)
		(end 282.924504 -32.742124)
		(stroke
			(width 0.06985)
			(type default)
		)
		(layer "In5.Cu")
	)
	(gr_line
		(start 282.924504 -32.742124)
		(end 282.944062 -32.770064)
		(stroke
			(width 0.06985)
			(type default)
		)
		(layer "In5.Cu")
	)
	(gr_line
		(start 283.038042 -177.287682)
		(end 283.038042 -177.287936)
		(stroke
			(width 0.06985)
			(type default)
		)
		(layer "In5.Cu")
	)
	(gr_line
		(start 283.038042 -177.287682)
		(end 283.041344 -177.268886)
		(stroke
			(width 0.06985)
			(type default)
		)
		(layer "In5.Cu")
	)
	(gr_line
		(start 283.038042 -177.25009)
		(end 283.041344 -177.268886)
		(stroke
			(width 0.06985)
			(type default)
		)
		(layer "In5.Cu")
	)
	(gr_line
		(start 283.03855 -39.547292)
		(end 283.063188 -39.564564)
		(stroke
			(width 0.06985)
			(type default)
		)
		(layer "In5.Cu")
	)
	(gr_line
		(start 283.063188 -39.564564)
		(end 283.06395 -39.564818)
		(stroke
			(width 0.06985)
			(type default)
		)
		(layer "In5.Cu")
	)
	(gr_line
		(start 283.06395 -39.564818)
		(end 283.092398 -39.570406)
		(stroke
			(width 0.06985)
			(type default)
		)
		(layer "In5.Cu")
	)
	(gr_line
		(start 283.104336 -32.998918)
		(end 283.115258 -33.014412)
		(stroke
			(width 0.06985)
			(type default)
		)
		(layer "In5.Cu")
	)
	(gr_line
		(start 283.115258 -33.014412)
		(end 283.130752 -33.025334)
		(stroke
			(width 0.06985)
			(type default)
		)
		(layer "In5.Cu")
	)
	(gr_line
		(start 283.195522 -197.94601)
		(end 283.198824 -197.96506)
		(stroke
			(width 0.06985)
			(type default)
		)
		(layer "In5.Cu")
	)
	(gr_line
		(start 283.195522 -197.94601)
		(end 283.198824 -197.927214)
		(stroke
			(width 0.06985)
			(type default)
		)
		(layer "In5.Cu")
	)
	(gr_line
		(start 283.468572 -207.159606)
		(end 283.471874 -207.178656)
		(stroke
			(width 0.06985)
			(type default)
		)
		(layer "In5.Cu")
	)
	(gr_line
		(start 283.468572 -207.159606)
		(end 283.471874 -207.14081)
		(stroke
			(width 0.06985)
			(type default)
		)
		(layer "In5.Cu")
	)
	(gr_arc
		(start 283.693616 -210.896454)
		(mid 283.872196 -210.629106)
		(end 283.934916 -210.313778)
		(stroke
			(width 0.06985)
			(type default)
		)
		(layer "In5.Cu")
	)
	(gr_line
		(start 283.941774 -33.593278)
		(end 283.993336 -33.6296)
		(stroke
			(width 0.06985)
			(type default)
		)
		(layer "In5.Cu")
	)
	(gr_line
		(start 284.003496 -38.63467)
		(end 284.031436 -38.654228)
		(stroke
			(width 0.06985)
			(type default)
		)
		(layer "In5.Cu")
	)
	(gr_line
		(start 284.031436 -38.654228)
		(end 284.064456 -38.66007)
		(stroke
			(width 0.06985)
			(type default)
		)
		(layer "In5.Cu")
	)
	(gr_arc
		(start 284.265116 -210.4644)
		(mid 284.30017 -210.640626)
		(end 284.39999 -210.790028)
		(stroke
			(width 0.06985)
			(type default)
		)
		(layer "In5.Cu")
	)
	(gr_line
		(start 284.338014 -37.806884)
		(end 284.364938 -37.82568)
		(stroke
			(width 0.06985)
			(type default)
		)
		(layer "In5.Cu")
	)
	(gr_line
		(start 284.364938 -37.82568)
		(end 284.397704 -37.831522)
		(stroke
			(width 0.06985)
			(type default)
		)
		(layer "In5.Cu")
	)
	(gr_line
		(start 284.39999 -210.790028)
		(end 284.506416 -210.896454)
		(stroke
			(width 0.06985)
			(type default)
		)
		(layer "In5.Cu")
	)
	(gr_line
		(start 284.476698 -203.345796)
		(end 284.476698 -203.34605)
		(stroke
			(width 0.06985)
			(type default)
		)
		(layer "In5.Cu")
	)
	(gr_line
		(start 284.476698 -203.345796)
		(end 284.48 -203.327)
		(stroke
			(width 0.06985)
			(type default)
		)
		(layer "In5.Cu")
	)
	(gr_line
		(start 284.476698 -203.308204)
		(end 284.48 -203.327)
		(stroke
			(width 0.06985)
			(type default)
		)
		(layer "In5.Cu")
	)
	(gr_line
		(start 284.54604 -35.550856)
		(end 284.57398 -35.570414)
		(stroke
			(width 0.06985)
			(type default)
		)
		(layer "In5.Cu")
	)
	(gr_line
		(start 284.57398 -35.570414)
		(end 284.607254 -35.576256)
		(stroke
			(width 0.06985)
			(type default)
		)
		(layer "In5.Cu")
	)
	(gr_arc
		(start 284.60446 -33.2994)
		(mid 284.832923 -33.232043)
		(end 284.988254 -33.051496)
		(stroke
			(width 0.06985)
			(type default)
		)
		(layer "In5.Cu")
	)
	(gr_line
		(start 284.679136 -36.967414)
		(end 284.707076 -36.986972)
		(stroke
			(width 0.06985)
			(type default)
		)
		(layer "In5.Cu")
	)
	(gr_line
		(start 284.707076 -36.986972)
		(end 284.740096 -36.992814)
		(stroke
			(width 0.06985)
			(type default)
		)
		(layer "In5.Cu")
	)
	(gr_arc
		(start 284.933644 -33.809686)
		(mid 284.734119 -33.676435)
		(end 284.498796 -33.6296)
		(stroke
			(width 0.06985)
			(type default)
		)
		(layer "In5.Cu")
	)
	(gr_line
		(start 284.933644 -33.809686)
		(end 284.988254 -33.864296)
		(stroke
			(width 0.06985)
			(type default)
		)
		(layer "In5.Cu")
	)
	(gr_line
		(start 286.084264 -189.970664)
		(end 286.087566 -189.989714)
		(stroke
			(width 0.06985)
			(type default)
		)
		(layer "In5.Cu")
	)
	(gr_line
		(start 286.084264 -189.970664)
		(end 286.087566 -189.951868)
		(stroke
			(width 0.06985)
			(type default)
		)
		(layer "In5.Cu")
	)
	(gr_line
		(start 286.134302 -20.65909)
		(end 286.134302 -21.530056)
		(stroke
			(width 0.0635)
			(type default)
		)
		(layer "In5.Cu")
	)
	(gr_line
		(start 286.424116 -181.539388)
		(end 286.424116 -181.539642)
		(stroke
			(width 0.06985)
			(type default)
		)
		(layer "In5.Cu")
	)
	(gr_line
		(start 286.424116 -181.539388)
		(end 286.427418 -181.520592)
		(stroke
			(width 0.06985)
			(type default)
		)
		(layer "In5.Cu")
	)
	(gr_line
		(start 286.424116 -181.501796)
		(end 286.427418 -181.520592)
		(stroke
			(width 0.06985)
			(type default)
		)
		(layer "In5.Cu")
	)
	(gr_arc
		(start 286.893762 -210.896454)
		(mid 287.072333 -210.629103)
		(end 287.135062 -210.313778)
		(stroke
			(width 0.06985)
			(type default)
		)
		(layer "In5.Cu")
	)
	(gr_arc
		(start 287.465262 -210.313778)
		(mid 287.527983 -210.6291)
		(end 287.706562 -210.896454)
		(stroke
			(width 0.06985)
			(type default)
		)
		(layer "In5.Cu")
	)
	(gr_line
		(start 287.800542 -38.431216)
		(end 287.819338 -38.434518)
		(stroke
			(width 0.06985)
			(type default)
		)
		(layer "In5.Cu")
	)
	(gr_line
		(start 287.819338 -38.434518)
		(end 287.838134 -38.431216)
		(stroke
			(width 0.06985)
			(type default)
		)
		(layer "In5.Cu")
	)
	(gr_line
		(start 287.85566 -37.541962)
		(end 287.874456 -37.545264)
		(stroke
			(width 0.06985)
			(type default)
		)
		(layer "In5.Cu")
	)
	(gr_line
		(start 287.874456 -37.545264)
		(end 287.893252 -37.541962)
		(stroke
			(width 0.06985)
			(type default)
		)
		(layer "In5.Cu")
	)
	(gr_line
		(start 287.99282 -181.048406)
		(end 287.99282 -181.04866)
		(stroke
			(width 0.06985)
			(type default)
		)
		(layer "In5.Cu")
	)
	(gr_line
		(start 287.99282 -181.048406)
		(end 287.996122 -181.02961)
		(stroke
			(width 0.06985)
			(type default)
		)
		(layer "In5.Cu")
	)
	(gr_line
		(start 287.99282 -181.010814)
		(end 287.996122 -181.02961)
		(stroke
			(width 0.06985)
			(type default)
		)
		(layer "In5.Cu")
	)
	(gr_line
		(start 288.422588 -50.369978)
		(end 288.44367 -50.373788)
		(stroke
			(width 0.06985)
			(type default)
		)
		(layer "In5.Cu")
	)
	(gr_line
		(start 288.44367 -50.373788)
		(end 288.464498 -50.36947)
		(stroke
			(width 0.06985)
			(type default)
		)
		(layer "In5.Cu")
	)
	(gr_line
		(start 288.567368 -190.747396)
		(end 288.57067 -190.766446)
		(stroke
			(width 0.06985)
			(type default)
		)
		(layer "In5.Cu")
	)
	(gr_line
		(start 288.567368 -190.747396)
		(end 288.57067 -190.7286)
		(stroke
			(width 0.06985)
			(type default)
		)
		(layer "In5.Cu")
	)
	(gr_line
		(start 288.568384 -202.194922)
		(end 288.568384 -202.195176)
		(stroke
			(width 0.06985)
			(type default)
		)
		(layer "In5.Cu")
	)
	(gr_line
		(start 288.568384 -202.194922)
		(end 288.571686 -202.176126)
		(stroke
			(width 0.06985)
			(type default)
		)
		(layer "In5.Cu")
	)
	(gr_line
		(start 288.568384 -202.15733)
		(end 288.571686 -202.176126)
		(stroke
			(width 0.06985)
			(type default)
		)
		(layer "In5.Cu")
	)
	(gr_line
		(start 288.998152 -49.293526)
		(end 289.019234 -49.297336)
		(stroke
			(width 0.06985)
			(type default)
		)
		(layer "In5.Cu")
	)
	(gr_line
		(start 289.019234 -49.297336)
		(end 289.040062 -49.293018)
		(stroke
			(width 0.06985)
			(type default)
		)
		(layer "In5.Cu")
	)
	(gr_line
		(start 289.2298 -35.014154)
		(end 289.306 -35.0901)
		(stroke
			(width 0.06985)
			(type default)
		)
		(layer "In5.Cu")
	)
	(gr_arc
		(start 289.4584 -35.4584)
		(mid 289.418847 -35.259083)
		(end 289.306 -35.0901)
		(stroke
			(width 0.06985)
			(type default)
		)
		(layer "In5.Cu")
	)
	(gr_line
		(start 289.460432 -48.14824)
		(end 289.481514 -48.15205)
		(stroke
			(width 0.06985)
			(type default)
		)
		(layer "In5.Cu")
	)
	(gr_line
		(start 289.481514 -48.15205)
		(end 289.502342 -48.147732)
		(stroke
			(width 0.06985)
			(type default)
		)
		(layer "In5.Cu")
	)
	(gr_arc
		(start 289.92322 -35.133788)
		(mid 289.823644 -35.282713)
		(end 289.7886 -35.4584)
		(stroke
			(width 0.06985)
			(type default)
		)
		(layer "In5.Cu")
	)
	(gr_line
		(start 289.92322 -35.133788)
		(end 290.0426 -35.014154)
		(stroke
			(width 0.06985)
			(type default)
		)
		(layer "In5.Cu")
	)
	(gr_line
		(start 290.007548 -47.04715)
		(end 290.02863 -47.05096)
		(stroke
			(width 0.06985)
			(type default)
		)
		(layer "In5.Cu")
	)
	(gr_line
		(start 290.02863 -47.05096)
		(end 290.049458 -47.046642)
		(stroke
			(width 0.06985)
			(type default)
		)
		(layer "In5.Cu")
	)
	(gr_arc
		(start 290.093654 -210.896454)
		(mid 290.272226 -210.629103)
		(end 290.334954 -210.313778)
		(stroke
			(width 0.06985)
			(type default)
		)
		(layer "In5.Cu")
	)
	(gr_line
		(start 290.30803 -45.886624)
		(end 290.332668 -45.891704)
		(stroke
			(width 0.06985)
			(type default)
		)
		(layer "In5.Cu")
	)
	(gr_line
		(start 290.332668 -45.891704)
		(end 290.357306 -45.886624)
		(stroke
			(width 0.06985)
			(type default)
		)
		(layer "In5.Cu")
	)
	(gr_line
		(start 290.432744 -182.072026)
		(end 290.432744 -182.07228)
		(stroke
			(width 0.06985)
			(type default)
		)
		(layer "In5.Cu")
	)
	(gr_line
		(start 290.432744 -182.072026)
		(end 290.436046 -182.05323)
		(stroke
			(width 0.06985)
			(type default)
		)
		(layer "In5.Cu")
	)
	(gr_line
		(start 290.432744 -182.034434)
		(end 290.436046 -182.05323)
		(stroke
			(width 0.06985)
			(type default)
		)
		(layer "In5.Cu")
	)
	(gr_arc
		(start 290.665154 -210.313778)
		(mid 290.727875 -210.6291)
		(end 290.906454 -210.896454)
		(stroke
			(width 0.06985)
			(type default)
		)
		(layer "In5.Cu")
	)
	(gr_line
		(start 290.695888 -44.603924)
		(end 290.720526 -44.609004)
		(stroke
			(width 0.06985)
			(type default)
		)
		(layer "In5.Cu")
	)
	(gr_line
		(start 290.720526 -44.609004)
		(end 290.745164 -44.603924)
		(stroke
			(width 0.06985)
			(type default)
		)
		(layer "In5.Cu")
	)
	(gr_line
		(start 291.202872 -41.157906)
		(end 291.2237 -41.16197)
		(stroke
			(width 0.06985)
			(type default)
		)
		(layer "In5.Cu")
	)
	(gr_line
		(start 291.223446 -43.460924)
		(end 291.248084 -43.466004)
		(stroke
			(width 0.06985)
			(type default)
		)
		(layer "In5.Cu")
	)
	(gr_line
		(start 291.2237 -41.16197)
		(end 291.24529 -41.15816)
		(stroke
			(width 0.06985)
			(type default)
		)
		(layer "In5.Cu")
	)
	(gr_line
		(start 291.248084 -43.466004)
		(end 291.272722 -43.460924)
		(stroke
			(width 0.06985)
			(type default)
		)
		(layer "In5.Cu")
	)
	(gr_line
		(start 291.257228 -42.320972)
		(end 291.278056 -42.32529)
		(stroke
			(width 0.06985)
			(type default)
		)
		(layer "In5.Cu")
	)
	(gr_line
		(start 291.278056 -42.32529)
		(end 291.299138 -42.32148)
		(stroke
			(width 0.06985)
			(type default)
		)
		(layer "In5.Cu")
	)
	(gr_line
		(start 291.334698 -49.45888)
		(end 291.359336 -49.4538)
		(stroke
			(width 0.06985)
			(type default)
		)
		(layer "In5.Cu")
	)
	(gr_line
		(start 291.34181 -204.615796)
		(end 291.34181 -204.61605)
		(stroke
			(width 0.06985)
			(type default)
		)
		(layer "In5.Cu")
	)
	(gr_line
		(start 291.34181 -204.615796)
		(end 291.345112 -204.597)
		(stroke
			(width 0.06985)
			(type default)
		)
		(layer "In5.Cu")
	)
	(gr_line
		(start 291.34181 -204.578204)
		(end 291.345112 -204.597)
		(stroke
			(width 0.06985)
			(type default)
		)
		(layer "In5.Cu")
	)
	(gr_line
		(start 291.359336 -49.4538)
		(end 291.383974 -49.45888)
		(stroke
			(width 0.06985)
			(type default)
		)
		(layer "In5.Cu")
	)
	(gr_line
		(start 291.618416 -44.092622)
		(end 291.643054 -44.097702)
		(stroke
			(width 0.06985)
			(type default)
		)
		(layer "In5.Cu")
	)
	(gr_line
		(start 291.64788 -194.273932)
		(end 291.651182 -194.292982)
		(stroke
			(width 0.06985)
			(type default)
		)
		(layer "In5.Cu")
	)
	(gr_line
		(start 291.64788 -194.273932)
		(end 291.651182 -194.255136)
		(stroke
			(width 0.06985)
			(type default)
		)
		(layer "In5.Cu")
	)
	(gr_line
		(start 291.831014 -47.3456)
		(end 291.855652 -47.34052)
		(stroke
			(width 0.06985)
			(type default)
		)
		(layer "In5.Cu")
	)
	(gr_line
		(start 291.855652 -47.34052)
		(end 291.88029 -47.3456)
		(stroke
			(width 0.06985)
			(type default)
		)
		(layer "In5.Cu")
	)
	(gr_line
		(start 291.878512 -43.003216)
		(end 291.90315 -42.998136)
		(stroke
			(width 0.06985)
			(type default)
		)
		(layer "In5.Cu")
	)
	(gr_line
		(start 291.879528 -45.245782)
		(end 291.904166 -45.240702)
		(stroke
			(width 0.06985)
			(type default)
		)
		(layer "In5.Cu")
	)
	(gr_line
		(start 291.90315 -42.998136)
		(end 291.927788 -43.003216)
		(stroke
			(width 0.06985)
			(type default)
		)
		(layer "In5.Cu")
	)
	(gr_line
		(start 291.904166 -45.240702)
		(end 291.928804 -45.245782)
		(stroke
			(width 0.06985)
			(type default)
		)
		(layer "In5.Cu")
	)
	(gr_line
		(start 291.91458 -46.33722)
		(end 291.939218 -46.33214)
		(stroke
			(width 0.06985)
			(type default)
		)
		(layer "In5.Cu")
	)
	(gr_line
		(start 291.925756 -48.37938)
		(end 291.950394 -48.3743)
		(stroke
			(width 0.06985)
			(type default)
		)
		(layer "In5.Cu")
	)
	(gr_line
		(start 291.939218 -46.33214)
		(end 291.963856 -46.33722)
		(stroke
			(width 0.06985)
			(type default)
		)
		(layer "In5.Cu")
	)
	(gr_line
		(start 291.950394 -48.3743)
		(end 291.975032 -48.37938)
		(stroke
			(width 0.06985)
			(type default)
		)
		(layer "In5.Cu")
	)
	(gr_line
		(start 292.11143 -40.669972)
		(end 292.130226 -40.66667)
		(stroke
			(width 0.06985)
			(type default)
		)
		(layer "In5.Cu")
	)
	(gr_line
		(start 292.130226 -40.66667)
		(end 292.149022 -40.669972)
		(stroke
			(width 0.06985)
			(type default)
		)
		(layer "In5.Cu")
	)
	(gr_line
		(start 292.327584 -180.148484)
		(end 292.333426 -180.181504)
		(stroke
			(width 0.06985)
			(type default)
		)
		(layer "In5.Cu")
	)
	(gr_line
		(start 292.333426 -180.181504)
		(end 292.352984 -180.209444)
		(stroke
			(width 0.06985)
			(type default)
		)
		(layer "In5.Cu")
	)
	(gr_line
		(start 292.371272 -41.79697)
		(end 292.398704 -41.792144)
		(stroke
			(width 0.06985)
			(type default)
		)
		(layer "In5.Cu")
	)
	(gr_line
		(start 292.398704 -41.792144)
		(end 292.425628 -41.79824)
		(stroke
			(width 0.06985)
			(type default)
		)
		(layer "In5.Cu")
	)
	(gr_line
		(start 292.902894 -174.4218)
		(end 292.903656 -174.426118)
		(stroke
			(width 0.06985)
			(type default)
		)
		(layer "In5.Cu")
	)
	(gr_line
		(start 292.903656 -174.426118)
		(end 292.905434 -174.430182)
		(stroke
			(width 0.06985)
			(type default)
		)
		(layer "In5.Cu")
	)
	(gr_line
		(start 292.92042 -188.958982)
		(end 292.92042 -188.959236)
		(stroke
			(width 0.06985)
			(type default)
		)
		(layer "In5.Cu")
	)
	(gr_line
		(start 292.92042 -188.958982)
		(end 292.923722 -188.940186)
		(stroke
			(width 0.06985)
			(type default)
		)
		(layer "In5.Cu")
	)
	(gr_line
		(start 292.92042 -188.92139)
		(end 292.923722 -188.940186)
		(stroke
			(width 0.06985)
			(type default)
		)
		(layer "In5.Cu")
	)
	(gr_arc
		(start 293.293546 -210.896454)
		(mid 293.47212 -210.629104)
		(end 293.534846 -210.313778)
		(stroke
			(width 0.06985)
			(type default)
		)
		(layer "In5.Cu")
	)
	(gr_line
		(start 293.823898 -175.612044)
		(end 293.824914 -175.61433)
		(stroke
			(width 0.06985)
			(type default)
		)
		(layer "In5.Cu")
	)
	(gr_arc
		(start 293.865046 -210.313778)
		(mid 293.927767 -210.6291)
		(end 294.106346 -210.896454)
		(stroke
			(width 0.06985)
			(type default)
		)
		(layer "In5.Cu")
	)
	(gr_line
		(start 293.988744 -170.272456)
		(end 293.994586 -170.305476)
		(stroke
			(width 0.06985)
			(type default)
		)
		(layer "In5.Cu")
	)
	(gr_line
		(start 293.994586 -170.305476)
		(end 294.014144 -170.333416)
		(stroke
			(width 0.06985)
			(type default)
		)
		(layer "In5.Cu")
	)
	(gr_line
		(start 294.159178 -35.18027)
		(end 294.235378 -35.256216)
		(stroke
			(width 0.06985)
			(type default)
		)
		(layer "In5.Cu")
	)
	(gr_line
		(start 294.281606 -207.346296)
		(end 294.281606 -207.34655)
		(stroke
			(width 0.06985)
			(type default)
		)
		(layer "In5.Cu")
	)
	(gr_line
		(start 294.281606 -207.346296)
		(end 294.284908 -207.3275)
		(stroke
			(width 0.06985)
			(type default)
		)
		(layer "In5.Cu")
	)
	(gr_line
		(start 294.281606 -207.308704)
		(end 294.284908 -207.3275)
		(stroke
			(width 0.06985)
			(type default)
		)
		(layer "In5.Cu")
	)
	(gr_line
		(start 294.387524 -35.624516)
		(end 294.387778 -35.624516)
		(stroke
			(width 0.06985)
			(type default)
		)
		(layer "In5.Cu")
	)
	(gr_line
		(start 294.534336 -50.425604)
		(end 294.558974 -50.420524)
		(stroke
			(width 0.06985)
			(type default)
		)
		(layer "In5.Cu")
	)
	(gr_arc
		(start 294.852598 -35.299904)
		(mid 294.75301 -35.448825)
		(end 294.717978 -35.624516)
		(stroke
			(width 0.06985)
			(type default)
		)
		(layer "In5.Cu")
	)
	(gr_line
		(start 294.852598 -35.299904)
		(end 294.971978 -35.18027)
		(stroke
			(width 0.06985)
			(type default)
		)
		(layer "In5.Cu")
	)
	(gr_line
		(start 295.030652 -48.312324)
		(end 295.05529 -48.307244)
		(stroke
			(width 0.06985)
			(type default)
		)
		(layer "In5.Cu")
	)
	(gr_line
		(start 295.114218 -47.303944)
		(end 295.138856 -47.298864)
		(stroke
			(width 0.06985)
			(type default)
		)
		(layer "In5.Cu")
	)
	(gr_line
		(start 295.125394 -49.346104)
		(end 295.150032 -49.341024)
		(stroke
			(width 0.06985)
			(type default)
		)
		(layer "In5.Cu")
	)
	(gr_line
		(start 295.29151 -46.25467)
		(end 295.316148 -46.25975)
		(stroke
			(width 0.06985)
			(type default)
		)
		(layer "In5.Cu")
	)
	(gr_line
		(start 295.316148 -46.25975)
		(end 295.340786 -46.25467)
		(stroke
			(width 0.06985)
			(type default)
		)
		(layer "In5.Cu")
	)
	(gr_line
		(start 295.330626 -168.0464)
		(end 295.336468 -168.07942)
		(stroke
			(width 0.06985)
			(type default)
		)
		(layer "In5.Cu")
	)
	(gr_line
		(start 295.336468 -168.07942)
		(end 295.356026 -168.10736)
		(stroke
			(width 0.06985)
			(type default)
		)
		(layer "In5.Cu")
	)
	(gr_line
		(start 295.620186 -45.22978)
		(end 295.644824 -45.2247)
		(stroke
			(width 0.06985)
			(type default)
		)
		(layer "In5.Cu")
	)
	(gr_line
		(start 295.755314 -36.699698)
		(end 295.795192 -36.692586)
		(stroke
			(width 0.06985)
			(type default)
		)
		(layer "In5.Cu")
	)
	(gr_line
		(start 295.795192 -36.692586)
		(end 295.834308 -36.704778)
		(stroke
			(width 0.06985)
			(type default)
		)
		(layer "In5.Cu")
	)
	(gr_line
		(start 295.987978 -44.151804)
		(end 296.012616 -44.156884)
		(stroke
			(width 0.06985)
			(type default)
		)
		(layer "In5.Cu")
	)
	(gr_line
		(start 296.012616 -44.156884)
		(end 296.037254 -44.151804)
		(stroke
			(width 0.06985)
			(type default)
		)
		(layer "In5.Cu")
	)
	(gr_line
		(start 296.517314 -40.85463)
		(end 296.53611 -40.857932)
		(stroke
			(width 0.06985)
			(type default)
		)
		(layer "In5.Cu")
	)
	(gr_line
		(start 296.53611 -40.857932)
		(end 296.554906 -40.85463)
		(stroke
			(width 0.06985)
			(type default)
		)
		(layer "In5.Cu")
	)
	(gr_line
		(start 296.557954 -43.083988)
		(end 296.586148 -43.090338)
		(stroke
			(width 0.06985)
			(type default)
		)
		(layer "In5.Cu")
	)
	(gr_line
		(start 296.586148 -43.090338)
		(end 296.61358 -43.085258)
		(stroke
			(width 0.06985)
			(type default)
		)
		(layer "In5.Cu")
	)
	(gr_line
		(start 296.926254 -166.63162)
		(end 296.932096 -166.66464)
		(stroke
			(width 0.06985)
			(type default)
		)
		(layer "In5.Cu")
	)
	(gr_line
		(start 296.932096 -166.66464)
		(end 296.951654 -166.69258)
		(stroke
			(width 0.06985)
			(type default)
		)
		(layer "In5.Cu")
	)
	(gr_line
		(start 297.05935 -41.870884)
		(end 297.07713 -41.874186)
		(stroke
			(width 0.06985)
			(type default)
		)
		(layer "In5.Cu")
	)
	(gr_line
		(start 297.07713 -41.874186)
		(end 297.095418 -41.870884)
		(stroke
			(width 0.06985)
			(type default)
		)
		(layer "In5.Cu")
	)
	(gr_line
		(start 297.202098 -158.649416)
		(end 297.20794 -158.682436)
		(stroke
			(width 0.06985)
			(type default)
		)
		(layer "In5.Cu")
	)
	(gr_line
		(start 297.20794 -158.682436)
		(end 297.227498 -158.710376)
		(stroke
			(width 0.06985)
			(type default)
		)
		(layer "In5.Cu")
	)
	(gr_line
		(start 297.709336 -49.4538)
		(end 297.733974 -49.45888)
		(stroke
			(width 0.06985)
			(type default)
		)
		(layer "In5.Cu")
	)
	(gr_line
		(start 297.770042 -155.636976)
		(end 297.775884 -155.669996)
		(stroke
			(width 0.06985)
			(type default)
		)
		(layer "In5.Cu")
	)
	(gr_line
		(start 297.775884 -155.669996)
		(end 297.795442 -155.697936)
		(stroke
			(width 0.06985)
			(type default)
		)
		(layer "In5.Cu")
	)
	(gr_line
		(start 298.130722 -37.772594)
		(end 298.188634 -37.790882)
		(stroke
			(width 0.06985)
			(type default)
		)
		(layer "In5.Cu")
	)
	(gr_line
		(start 298.188634 -37.790882)
		(end 298.2468 -37.773102)
		(stroke
			(width 0.06985)
			(type default)
		)
		(layer "In5.Cu")
	)
	(gr_line
		(start 298.300394 -48.3743)
		(end 298.325032 -48.37938)
		(stroke
			(width 0.06985)
			(type default)
		)
		(layer "In5.Cu")
	)
	(gr_line
		(start 298.701968 -188.700664)
		(end 298.721526 -188.728604)
		(stroke
			(width 0.06985)
			(type default)
		)
		(layer "In5.Cu")
	)
	(gr_line
		(start 298.721526 -188.728604)
		(end 298.727368 -188.761624)
		(stroke
			(width 0.06985)
			(type default)
		)
		(layer "In5.Cu")
	)
	(gr_line
		(start 298.815252 -47.2186)
		(end 298.83989 -47.22368)
		(stroke
			(width 0.06985)
			(type default)
		)
		(layer "In5.Cu")
	)
	(gr_arc
		(start 298.893738 -210.896454)
		(mid 299.072365 -210.62912)
		(end 299.135038 -210.313778)
		(stroke
			(width 0.06985)
			(type default)
		)
		(layer "In5.Cu")
	)
	(gr_line
		(start 298.89577 -204.366114)
		(end 298.899072 -204.385164)
		(stroke
			(width 0.06985)
			(type default)
		)
		(layer "In5.Cu")
	)
	(gr_line
		(start 298.89577 -204.366114)
		(end 298.899072 -204.347318)
		(stroke
			(width 0.06985)
			(type default)
		)
		(layer "In5.Cu")
	)
	(gr_line
		(start 299.356272 -46.11878)
		(end 299.38091 -46.1137)
		(stroke
			(width 0.06985)
			(type default)
		)
		(layer "In5.Cu")
	)
	(gr_line
		(start 299.38091 -46.1137)
		(end 299.405548 -46.11878)
		(stroke
			(width 0.06985)
			(type default)
		)
		(layer "In5.Cu")
	)
	(gr_line
		(start 299.430694 -36.189412)
		(end 299.532294 -36.291012)
		(stroke
			(width 0.06985)
			(type default)
		)
		(layer "In5.Cu")
	)
	(gr_arc
		(start 299.465238 -210.313778)
		(mid 299.527905 -210.629129)
		(end 299.706538 -210.896454)
		(stroke
			(width 0.06985)
			(type default)
		)
		(layer "In5.Cu")
	)
	(gr_line
		(start 299.570394 -37.370004)
		(end 299.610272 -37.357812)
		(stroke
			(width 0.06985)
			(type default)
		)
		(layer "In5.Cu")
	)
	(gr_arc
		(start 299.6819 -36.6522)
		(mid 299.643018 -36.456727)
		(end 299.532294 -36.291012)
		(stroke
			(width 0.06985)
			(type default)
		)
		(layer "In5.Cu")
	)
	(gr_line
		(start 299.716698 -207.155796)
		(end 299.716698 -207.15605)
		(stroke
			(width 0.06985)
			(type default)
		)
		(layer "In5.Cu")
	)
	(gr_line
		(start 299.716698 -207.155796)
		(end 299.72 -207.137)
		(stroke
			(width 0.06985)
			(type default)
		)
		(layer "In5.Cu")
	)
	(gr_line
		(start 299.716698 -207.118204)
		(end 299.72 -207.137)
		(stroke
			(width 0.06985)
			(type default)
		)
		(layer "In5.Cu")
	)
	(gr_line
		(start 300.070012 -44.972224)
		(end 300.09465 -44.967144)
		(stroke
			(width 0.06985)
			(type default)
		)
		(layer "In5.Cu")
	)
	(gr_line
		(start 300.09465 -44.967144)
		(end 300.119288 -44.972224)
		(stroke
			(width 0.06985)
			(type default)
		)
		(layer "In5.Cu")
	)
	(gr_arc
		(start 300.175676 -36.25723)
		(mid 300.054593 -36.438444)
		(end 300.0121 -36.6522)
		(stroke
			(width 0.06985)
			(type default)
		)
		(layer "In5.Cu")
	)
	(gr_line
		(start 300.175676 -36.25723)
		(end 300.243494 -36.189412)
		(stroke
			(width 0.06985)
			(type default)
		)
		(layer "In5.Cu")
	)
	(gr_line
		(start 300.351698 -198.011796)
		(end 300.351698 -198.01205)
		(stroke
			(width 0.06985)
			(type default)
		)
		(layer "In5.Cu")
	)
	(gr_line
		(start 300.351698 -198.011796)
		(end 300.355 -197.993)
		(stroke
			(width 0.06985)
			(type default)
		)
		(layer "In5.Cu")
	)
	(gr_line
		(start 300.351698 -197.974204)
		(end 300.355 -197.993)
		(stroke
			(width 0.06985)
			(type default)
		)
		(layer "In5.Cu")
	)
	(gr_line
		(start 300.785276 -40.108378)
		(end 300.818296 -40.102536)
		(stroke
			(width 0.06985)
			(type default)
		)
		(layer "In5.Cu")
	)
	(gr_line
		(start 300.818296 -40.102536)
		(end 300.846236 -40.082978)
		(stroke
			(width 0.06985)
			(type default)
		)
		(layer "In5.Cu")
	)
	(gr_line
		(start 300.884336 -50.425604)
		(end 300.908974 -50.420524)
		(stroke
			(width 0.06985)
			(type default)
		)
		(layer "In5.Cu")
	)
	(gr_line
		(start 301.025306 -156.57957)
		(end 301.031148 -156.61259)
		(stroke
			(width 0.06985)
			(type default)
		)
		(layer "In5.Cu")
	)
	(gr_line
		(start 301.031148 -156.61259)
		(end 301.050706 -156.64053)
		(stroke
			(width 0.06985)
			(type default)
		)
		(layer "In5.Cu")
	)
	(gr_line
		(start 301.153576 -43.786298)
		(end 301.174658 -43.790108)
		(stroke
			(width 0.06985)
			(type default)
		)
		(layer "In5.Cu")
	)
	(gr_line
		(start 301.475394 -49.346104)
		(end 301.500032 -49.341024)
		(stroke
			(width 0.06985)
			(type default)
		)
		(layer "In5.Cu")
	)
	(gr_line
		(start 301.613316 -41.039542)
		(end 301.644812 -41.0337)
		(stroke
			(width 0.06985)
			(type default)
		)
		(layer "In5.Cu")
	)
	(gr_line
		(start 301.644812 -41.0337)
		(end 301.671228 -41.015158)
		(stroke
			(width 0.06985)
			(type default)
		)
		(layer "In5.Cu")
	)
	(gr_line
		(start 301.744126 -188.837316)
		(end 301.763684 -188.865256)
		(stroke
			(width 0.06985)
			(type default)
		)
		(layer "In5.Cu")
	)
	(gr_line
		(start 301.763684 -188.865256)
		(end 301.769526 -188.898276)
		(stroke
			(width 0.06985)
			(type default)
		)
		(layer "In5.Cu")
	)
	(gr_arc
		(start 301.879 -35.556698)
		(mid 301.82188 -35.269676)
		(end 301.65929 -35.026346)
		(stroke
			(width 0.06985)
			(type default)
		)
		(layer "In5.Cu")
	)
	(gr_line
		(start 301.990252 -48.190404)
		(end 302.01489 -48.185324)
		(stroke
			(width 0.06985)
			(type default)
		)
		(layer "In5.Cu")
	)
	(gr_line
		(start 301.993808 -36.772088)
		(end 301.999396 -36.803838)
		(stroke
			(width 0.06985)
			(type default)
		)
		(layer "In5.Cu")
	)
	(gr_line
		(start 301.999396 -36.803838)
		(end 302.018192 -36.830762)
		(stroke
			(width 0.06985)
			(type default)
		)
		(layer "In5.Cu")
	)
	(gr_line
		(start 302.037242 -205.445106)
		(end 302.040544 -205.464156)
		(stroke
			(width 0.06985)
			(type default)
		)
		(layer "In5.Cu")
	)
	(gr_line
		(start 302.037242 -205.445106)
		(end 302.040544 -205.42631)
		(stroke
			(width 0.06985)
			(type default)
		)
		(layer "In5.Cu")
	)
	(gr_arc
		(start 302.09363 -210.896454)
		(mid 302.272208 -210.629105)
		(end 302.33493 -210.313778)
		(stroke
			(width 0.06985)
			(type default)
		)
		(layer "In5.Cu")
	)
	(gr_arc
		(start 302.403002 -35.095434)
		(mid 302.259571 -35.310094)
		(end 302.2092 -35.563302)
		(stroke
			(width 0.06985)
			(type default)
		)
		(layer "In5.Cu")
	)
	(gr_line
		(start 302.403002 -35.095434)
		(end 302.47209 -35.026346)
		(stroke
			(width 0.06985)
			(type default)
		)
		(layer "In5.Cu")
	)
	(gr_line
		(start 302.55591 -47.085504)
		(end 302.580548 -47.080424)
		(stroke
			(width 0.06985)
			(type default)
		)
		(layer "In5.Cu")
	)
	(gr_line
		(start 302.600868 -38.853872)
		(end 302.615346 -38.843712)
		(stroke
			(width 0.06985)
			(type default)
		)
		(layer "In5.Cu")
	)
	(gr_line
		(start 302.615346 -38.843712)
		(end 302.624998 -38.829742)
		(stroke
			(width 0.06985)
			(type default)
		)
		(layer "In5.Cu")
	)
	(gr_arc
		(start 302.66513 -210.313778)
		(mid 302.727851 -210.6291)
		(end 302.90643 -210.896454)
		(stroke
			(width 0.06985)
			(type default)
		)
		(layer "In5.Cu")
	)
	(gr_line
		(start 302.835056 -38.53053)
		(end 302.854106 -38.503098)
		(stroke
			(width 0.06985)
			(type default)
		)
		(layer "In5.Cu")
	)
	(gr_line
		(start 302.848264 -37.440362)
		(end 302.867822 -37.468302)
		(stroke
			(width 0.06985)
			(type default)
		)
		(layer "In5.Cu")
	)
	(gr_line
		(start 302.854106 -38.503098)
		(end 302.859948 -38.470078)
		(stroke
			(width 0.06985)
			(type default)
		)
		(layer "In5.Cu")
	)
	(gr_line
		(start 302.867822 -37.468302)
		(end 302.873664 -37.501322)
		(stroke
			(width 0.06985)
			(type default)
		)
		(layer "In5.Cu")
	)
	(gr_line
		(start 302.8823 -208.372456)
		(end 302.8823 -208.37271)
		(stroke
			(width 0.06985)
			(type default)
		)
		(layer "In5.Cu")
	)
	(gr_line
		(start 302.8823 -208.372456)
		(end 302.885602 -208.35366)
		(stroke
			(width 0.06985)
			(type default)
		)
		(layer "In5.Cu")
	)
	(gr_line
		(start 302.8823 -208.334864)
		(end 302.885602 -208.35366)
		(stroke
			(width 0.06985)
			(type default)
		)
		(layer "In5.Cu")
	)
	(gr_line
		(start 302.948848 -37.965888)
		(end 302.95215 -37.947092)
		(stroke
			(width 0.06985)
			(type default)
		)
		(layer "In5.Cu")
	)
	(gr_line
		(start 302.948848 -37.928042)
		(end 302.948848 -37.928296)
		(stroke
			(width 0.06985)
			(type default)
		)
		(layer "In5.Cu")
	)
	(gr_line
		(start 302.948848 -37.928042)
		(end 302.95215 -37.947092)
		(stroke
			(width 0.06985)
			(type default)
		)
		(layer "In5.Cu")
	)
	(gr_line
		(start 303.00803 -45.886624)
		(end 303.032668 -45.891704)
		(stroke
			(width 0.06985)
			(type default)
		)
		(layer "In5.Cu")
	)
	(gr_line
		(start 303.031906 -44.452794)
		(end 303.050702 -44.456096)
		(stroke
			(width 0.06985)
			(type default)
		)
		(layer "In5.Cu")
	)
	(gr_line
		(start 303.032668 -45.891704)
		(end 303.057306 -45.886624)
		(stroke
			(width 0.06985)
			(type default)
		)
		(layer "In5.Cu")
	)
	(gr_line
		(start 303.050702 -44.456096)
		(end 303.069498 -44.452794)
		(stroke
			(width 0.06985)
			(type default)
		)
		(layer "In5.Cu")
	)
	(gr_line
		(start 303.346612 -39.841678)
		(end 303.383442 -39.81577)
		(stroke
			(width 0.06985)
			(type default)
		)
		(layer "In5.Cu")
	)
	(gr_line
		(start 303.383442 -39.81577)
		(end 303.403508 -39.775638)
		(stroke
			(width 0.06985)
			(type default)
		)
		(layer "In5.Cu")
	)
	(gr_line
		(start 303.526698 -198.900796)
		(end 303.526698 -198.90105)
		(stroke
			(width 0.06985)
			(type default)
		)
		(layer "In5.Cu")
	)
	(gr_line
		(start 303.526698 -198.900796)
		(end 303.53 -198.882)
		(stroke
			(width 0.06985)
			(type default)
		)
		(layer "In5.Cu")
	)
	(gr_line
		(start 303.526698 -198.863204)
		(end 303.53 -198.882)
		(stroke
			(width 0.06985)
			(type default)
		)
		(layer "In5.Cu")
	)
	(gr_line
		(start 303.598326 -158.304738)
		(end 303.604168 -158.337504)
		(stroke
			(width 0.06985)
			(type default)
		)
		(layer "In5.Cu")
	)
	(gr_line
		(start 303.604168 -158.337504)
		(end 303.622964 -158.364428)
		(stroke
			(width 0.06985)
			(type default)
		)
		(layer "In5.Cu")
	)
	(gr_arc
		(start 304.0761 -37.062156)
		(mid 304.014383 -36.654877)
		(end 303.8348 -36.284154)
		(stroke
			(width 0.06985)
			(type default)
		)
		(layer "In5.Cu")
	)
	(gr_line
		(start 304.405792 -37.423344)
		(end 304.4063 -37.421058)
		(stroke
			(width 0.06985)
			(type default)
		)
		(layer "In5.Cu")
	)
	(gr_arc
		(start 304.6476 -36.284154)
		(mid 304.468014 -36.654875)
		(end 304.4063 -37.062156)
		(stroke
			(width 0.06985)
			(type default)
		)
		(layer "In5.Cu")
	)
	(gr_line
		(start 304.739548 -157.639512)
		(end 304.74539 -157.672278)
		(stroke
			(width 0.06985)
			(type default)
		)
		(layer "In5.Cu")
	)
	(gr_line
		(start 304.74539 -157.672278)
		(end 304.764186 -157.699202)
		(stroke
			(width 0.06985)
			(type default)
		)
		(layer "In5.Cu")
	)
	(gr_line
		(start 304.886106 -41.552114)
		(end 304.892456 -41.550844)
		(stroke
			(width 0.06985)
			(type default)
		)
		(layer "In5.Cu")
	)
	(gr_line
		(start 304.892456 -41.550844)
		(end 304.898298 -41.54805)
		(stroke
			(width 0.06985)
			(type default)
		)
		(layer "In5.Cu")
	)
	(gr_line
		(start 305.717448 -41.14292)
		(end 305.731164 -41.136062)
		(stroke
			(width 0.06985)
			(type default)
		)
		(layer "In5.Cu")
	)
	(gr_line
		(start 305.738784 -157.500066)
		(end 305.744626 -157.533086)
		(stroke
			(width 0.06985)
			(type default)
		)
		(layer "In5.Cu")
	)
	(gr_line
		(start 305.744626 -157.533086)
		(end 305.764184 -157.561026)
		(stroke
			(width 0.06985)
			(type default)
		)
		(layer "In5.Cu")
	)
	(gr_line
		(start 305.762914 -39.80942)
		(end 305.93411 -39.980616)
		(stroke
			(width 0.06985)
			(type default)
		)
		(layer "In5.Cu")
	)
	(gr_line
		(start 306.174394 -43.905424)
		(end 306.207414 -43.899582)
		(stroke
			(width 0.06985)
			(type default)
		)
		(layer "In5.Cu")
	)
	(gr_line
		(start 306.207414 -43.899582)
		(end 306.235354 -43.880024)
		(stroke
			(width 0.06985)
			(type default)
		)
		(layer "In5.Cu")
	)
	(gr_line
		(start 306.211478 -45.255942)
		(end 306.240688 -45.2501)
		(stroke
			(width 0.06985)
			(type default)
		)
		(layer "In5.Cu")
	)
	(gr_line
		(start 306.240688 -45.2501)
		(end 306.26558 -45.232828)
		(stroke
			(width 0.06985)
			(type default)
		)
		(layer "In5.Cu")
	)
	(gr_line
		(start 306.266342 -40.60063)
		(end 306.334414 -40.532558)
		(stroke
			(width 0.06985)
			(type default)
		)
		(layer "In5.Cu")
	)
	(gr_line
		(start 306.404518 -39.980616)
		(end 306.575714 -39.80942)
		(stroke
			(width 0.06985)
			(type default)
		)
		(layer "In5.Cu")
	)
	(gr_line
		(start 306.672234 -46.26229)
		(end 306.701444 -46.256448)
		(stroke
			(width 0.06985)
			(type default)
		)
		(layer "In5.Cu")
	)
	(gr_line
		(start 306.696618 -157.213554)
		(end 306.70246 -157.246574)
		(stroke
			(width 0.06985)
			(type default)
		)
		(layer "In5.Cu")
	)
	(gr_line
		(start 306.701444 -46.256448)
		(end 306.726336 -46.239176)
		(stroke
			(width 0.06985)
			(type default)
		)
		(layer "In5.Cu")
	)
	(gr_line
		(start 306.70246 -157.246574)
		(end 306.722018 -157.274514)
		(stroke
			(width 0.06985)
			(type default)
		)
		(layer "In5.Cu")
	)
	(gr_line
		(start 306.90947 -41.977564)
		(end 306.928266 -41.973754)
		(stroke
			(width 0.06985)
			(type default)
		)
		(layer "In5.Cu")
	)
	(gr_line
		(start 306.928266 -41.973754)
		(end 306.944522 -41.963848)
		(stroke
			(width 0.06985)
			(type default)
		)
		(layer "In5.Cu")
	)
	(gr_line
		(start 307.122322 -47.16399)
		(end 307.151532 -47.158148)
		(stroke
			(width 0.06985)
			(type default)
		)
		(layer "In5.Cu")
	)
	(gr_line
		(start 307.151532 -47.158148)
		(end 307.176424 -47.140876)
		(stroke
			(width 0.06985)
			(type default)
		)
		(layer "In5.Cu")
	)
	(gr_line
		(start 307.342794 -41.720008)
		(end 307.360574 -41.709086)
		(stroke
			(width 0.06985)
			(type default)
		)
		(layer "In5.Cu")
	)
	(gr_line
		(start 307.360574 -41.709086)
		(end 307.372766 -41.69283)
		(stroke
			(width 0.06985)
			(type default)
		)
		(layer "In5.Cu")
	)
	(gr_line
		(start 307.709062 -48.099472)
		(end 307.738272 -48.09363)
		(stroke
			(width 0.06985)
			(type default)
		)
		(layer "In5.Cu")
	)
	(gr_line
		(start 307.738272 -48.09363)
		(end 307.763164 -48.076358)
		(stroke
			(width 0.06985)
			(type default)
		)
		(layer "In5.Cu")
	)
	(gr_line
		(start 307.976778 -40.90289)
		(end 307.98897 -40.886888)
		(stroke
			(width 0.06985)
			(type default)
		)
		(layer "In5.Cu")
	)
	(gr_line
		(start 307.98897 -40.886888)
		(end 307.994812 -40.867838)
		(stroke
			(width 0.06985)
			(type default)
		)
		(layer "In5.Cu")
	)
	(gr_line
		(start 308.038246 -42.617644)
		(end 308.05374 -42.606722)
		(stroke
			(width 0.06985)
			(type default)
		)
		(layer "In5.Cu")
	)
	(gr_line
		(start 308.05374 -42.606722)
		(end 308.064662 -42.591228)
		(stroke
			(width 0.06985)
			(type default)
		)
		(layer "In5.Cu")
	)
	(gr_line
		(start 308.216046 -39.022528)
		(end 308.237636 -38.952424)
		(stroke
			(width 0.06985)
			(type default)
		)
		(layer "In5.Cu")
	)
	(gr_line
		(start 308.237636 -38.952424)
		(end 308.297834 -38.91026)
		(stroke
			(width 0.06985)
			(type default)
		)
		(layer "In5.Cu")
	)
	(gr_line
		(start 308.494176 -48.903636)
		(end 308.523386 -48.897794)
		(stroke
			(width 0.06985)
			(type default)
		)
		(layer "In5.Cu")
	)
	(gr_line
		(start 308.523386 -48.897794)
		(end 308.548278 -48.880522)
		(stroke
			(width 0.06985)
			(type default)
		)
		(layer "In5.Cu")
	)
	(gr_line
		(start 308.632606 -43.575478)
		(end 308.6481 -43.564556)
		(stroke
			(width 0.06985)
			(type default)
		)
		(layer "In5.Cu")
	)
	(gr_line
		(start 308.6481 -43.564556)
		(end 308.659022 -43.549062)
		(stroke
			(width 0.06985)
			(type default)
		)
		(layer "In5.Cu")
	)
	(gr_line
		(start 308.893464 -40.831262)
		(end 308.904386 -40.815768)
		(stroke
			(width 0.06985)
			(type default)
		)
		(layer "In5.Cu")
	)
	(gr_line
		(start 308.904386 -40.815768)
		(end 308.91988 -40.804846)
		(stroke
			(width 0.06985)
			(type default)
		)
		(layer "In5.Cu")
	)
	(gr_line
		(start 308.976522 -191.128904)
		(end 308.99608 -191.156844)
		(stroke
			(width 0.06985)
			(type default)
		)
		(layer "In5.Cu")
	)
	(gr_line
		(start 308.99608 -191.156844)
		(end 309.001922 -191.189864)
		(stroke
			(width 0.06985)
			(type default)
		)
		(layer "In5.Cu")
	)
	(gr_line
		(start 309.229506 -44.486322)
		(end 309.245 -44.4754)
		(stroke
			(width 0.06985)
			(type default)
		)
		(layer "In5.Cu")
	)
	(gr_line
		(start 309.245 -44.4754)
		(end 309.255922 -44.459906)
		(stroke
			(width 0.06985)
			(type default)
		)
		(layer "In5.Cu")
	)
	(gr_line
		(start 309.66029 -38.359588)
		(end 309.675784 -38.348666)
		(stroke
			(width 0.06985)
			(type default)
		)
		(layer "In5.Cu")
	)
	(gr_line
		(start 309.675784 -38.348666)
		(end 309.686706 -38.333172)
		(stroke
			(width 0.06985)
			(type default)
		)
		(layer "In5.Cu")
	)
	(gr_line
		(start 309.915306 -45.222922)
		(end 309.9308 -45.212)
		(stroke
			(width 0.06985)
			(type default)
		)
		(layer "In5.Cu")
	)
	(gr_line
		(start 309.9308 -45.212)
		(end 309.941722 -45.196506)
		(stroke
			(width 0.06985)
			(type default)
		)
		(layer "In5.Cu")
	)
	(gr_line
		(start 309.972456 -41.097454)
		(end 309.983378 -41.08196)
		(stroke
			(width 0.06985)
			(type default)
		)
		(layer "In5.Cu")
	)
	(gr_line
		(start 309.983378 -41.08196)
		(end 309.998872 -41.071038)
		(stroke
			(width 0.06985)
			(type default)
		)
		(layer "In5.Cu")
	)
	(gr_arc
		(start 310.093868 -210.896454)
		(mid 310.272459 -210.629108)
		(end 310.335168 -210.313778)
		(stroke
			(width 0.06985)
			(type default)
		)
		(layer "In5.Cu")
	)
	(gr_line
		(start 310.179466 -206.756)
		(end 310.182768 -206.77505)
		(stroke
			(width 0.06985)
			(type default)
		)
		(layer "In5.Cu")
	)
	(gr_line
		(start 310.179466 -206.756)
		(end 310.182768 -206.737204)
		(stroke
			(width 0.06985)
			(type default)
		)
		(layer "In5.Cu")
	)
	(gr_line
		(start 310.335168 -210.0326)
		(end 310.335676 -210.032092)
		(stroke
			(width 0.06985)
			(type default)
		)
		(layer "In5.Cu")
	)
	(gr_line
		(start 310.337708 -210.020154)
		(end 310.343296 -209.988658)
		(stroke
			(width 0.06985)
			(type default)
		)
		(layer "In5.Cu")
	)
	(gr_line
		(start 310.507126 -42.097706)
		(end 310.516778 -42.083736)
		(stroke
			(width 0.06985)
			(type default)
		)
		(layer "In5.Cu")
	)
	(gr_line
		(start 310.516778 -42.083736)
		(end 310.530748 -42.07383)
		(stroke
			(width 0.06985)
			(type default)
		)
		(layer "In5.Cu")
	)
	(gr_arc
		(start 310.665368 -210.313778)
		(mid 310.728089 -210.6291)
		(end 310.906668 -210.896454)
		(stroke
			(width 0.06985)
			(type default)
		)
		(layer "In5.Cu")
	)
	(gr_line
		(start 310.665368 -210.061556)
		(end 310.665368 -210.063842)
		(stroke
			(width 0.06985)
			(type default)
		)
		(layer "In5.Cu")
	)
	(gr_line
		(start 310.665876 -210.061048)
		(end 310.665368 -210.061556)
		(stroke
			(width 0.06985)
			(type default)
		)
		(layer "In5.Cu")
	)
	(gr_arc
		(start 310.6674 -35.625532)
		(mid 310.60452 -35.309651)
		(end 310.425592 -35.04184)
		(stroke
			(width 0.06985)
			(type default)
		)
		(layer "In5.Cu")
	)
	(gr_line
		(start 310.677306 -46.035722)
		(end 310.6928 -46.0248)
		(stroke
			(width 0.06985)
			(type default)
		)
		(layer "In5.Cu")
	)
	(gr_line
		(start 310.6928 -46.0248)
		(end 310.703722 -46.009306)
		(stroke
			(width 0.06985)
			(type default)
		)
		(layer "In5.Cu")
	)
	(gr_line
		(start 310.87822 -36.631626)
		(end 310.897778 -36.603686)
		(stroke
			(width 0.06985)
			(type default)
		)
		(layer "In5.Cu")
	)
	(gr_line
		(start 310.878474 -208.85404)
		(end 310.881776 -208.835244)
		(stroke
			(width 0.06985)
			(type default)
		)
		(layer "In5.Cu")
	)
	(gr_line
		(start 310.878474 -208.816448)
		(end 310.881776 -208.835244)
		(stroke
			(width 0.06985)
			(type default)
		)
		(layer "In5.Cu")
	)
	(gr_line
		(start 310.897778 -36.603686)
		(end 310.90362 -36.570666)
		(stroke
			(width 0.06985)
			(type default)
		)
		(layer "In5.Cu")
	)
	(gr_line
		(start 311.127648 -203.28255)
		(end 311.127648 -203.282804)
		(stroke
			(width 0.06985)
			(type default)
		)
		(layer "In5.Cu")
	)
	(gr_line
		(start 311.127648 -203.28255)
		(end 311.13095 -203.263754)
		(stroke
			(width 0.06985)
			(type default)
		)
		(layer "In5.Cu")
	)
	(gr_line
		(start 311.127648 -203.244958)
		(end 311.13095 -203.263754)
		(stroke
			(width 0.06985)
			(type default)
		)
		(layer "In5.Cu")
	)
	(gr_arc
		(start 311.14365 -35.136582)
		(mid 311.035571 -35.298334)
		(end 310.9976 -35.489134)
		(stroke
			(width 0.06985)
			(type default)
		)
		(layer "In5.Cu")
	)
	(gr_line
		(start 311.14365 -35.136582)
		(end 311.238392 -35.04184)
		(stroke
			(width 0.06985)
			(type default)
		)
		(layer "In5.Cu")
	)
	(gr_line
		(start 311.35955 -42.595546)
		(end 311.370472 -42.580052)
		(stroke
			(width 0.06985)
			(type default)
		)
		(layer "In5.Cu")
	)
	(gr_line
		(start 311.370472 -42.580052)
		(end 311.385966 -42.56913)
		(stroke
			(width 0.06985)
			(type default)
		)
		(layer "In5.Cu")
	)
	(gr_line
		(start 311.549288 -39.36746)
		(end 311.564782 -39.356538)
		(stroke
			(width 0.06985)
			(type default)
		)
		(layer "In5.Cu")
	)
	(gr_line
		(start 311.564782 -39.356538)
		(end 311.575704 -39.341044)
		(stroke
			(width 0.06985)
			(type default)
		)
		(layer "In5.Cu")
	)
	(gr_line
		(start 311.81167 -46.595284)
		(end 311.827164 -46.584362)
		(stroke
			(width 0.06985)
			(type default)
		)
		(layer "In5.Cu")
	)
	(gr_line
		(start 311.827164 -46.584362)
		(end 311.838086 -46.568868)
		(stroke
			(width 0.06985)
			(type default)
		)
		(layer "In5.Cu")
	)
	(gr_line
		(start 311.902602 -43.720766)
		(end 311.913524 -43.705272)
		(stroke
			(width 0.06985)
			(type default)
		)
		(layer "In5.Cu")
	)
	(gr_line
		(start 311.913524 -43.705272)
		(end 311.929018 -43.69435)
		(stroke
			(width 0.06985)
			(type default)
		)
		(layer "In5.Cu")
	)
	(gr_line
		(start 311.97296 -191.261238)
		(end 311.992518 -191.289178)
		(stroke
			(width 0.06985)
			(type default)
		)
		(layer "In5.Cu")
	)
	(gr_line
		(start 311.992518 -191.289178)
		(end 311.99836 -191.322198)
		(stroke
			(width 0.06985)
			(type default)
		)
		(layer "In5.Cu")
	)
	(gr_arc
		(start 312.89244 -36.707318)
		(mid 312.83623 -36.424971)
		(end 312.676286 -36.185602)
		(stroke
			(width 0.06985)
			(type default)
		)
		(layer "In5.Cu")
	)
	(gr_line
		(start 313.00801 -44.321984)
		(end 313.018932 -44.30649)
		(stroke
			(width 0.06985)
			(type default)
		)
		(layer "In5.Cu")
	)
	(gr_line
		(start 313.018932 -44.30649)
		(end 313.034426 -44.295568)
		(stroke
			(width 0.06985)
			(type default)
		)
		(layer "In5.Cu")
	)
	(gr_line
		(start 313.055 -206.883)
		(end 313.058302 -206.90205)
		(stroke
			(width 0.06985)
			(type default)
		)
		(layer "In5.Cu")
	)
	(gr_line
		(start 313.055 -206.883)
		(end 313.058302 -206.864204)
		(stroke
			(width 0.06985)
			(type default)
		)
		(layer "In5.Cu")
	)
	(gr_line
		(start 313.186572 -37.03955)
		(end 313.22264 -36.987988)
		(stroke
			(width 0.06985)
			(type default)
		)
		(layer "In5.Cu")
	)
	(gr_arc
		(start 313.29376 -210.896454)
		(mid 313.472331 -210.629103)
		(end 313.53506 -210.313778)
		(stroke
			(width 0.06985)
			(type default)
		)
		(layer "In5.Cu")
	)
	(gr_arc
		(start 313.35472 -36.320222)
		(mid 313.256967 -36.46633)
		(end 313.22264 -36.638738)
		(stroke
			(width 0.06985)
			(type default)
		)
		(layer "In5.Cu")
	)
	(gr_line
		(start 313.35472 -36.320222)
		(end 313.489086 -36.185602)
		(stroke
			(width 0.06985)
			(type default)
		)
		(layer "In5.Cu")
	)
	(gr_line
		(start 313.361324 -40.092884)
		(end 313.389264 -40.073326)
		(stroke
			(width 0.06985)
			(type default)
		)
		(layer "In5.Cu")
	)
	(gr_line
		(start 313.389264 -40.073326)
		(end 313.422284 -40.067484)
		(stroke
			(width 0.06985)
			(type default)
		)
		(layer "In5.Cu")
	)
	(gr_arc
		(start 313.86526 -210.313778)
		(mid 313.927981 -210.6291)
		(end 314.10656 -210.896454)
		(stroke
			(width 0.06985)
			(type default)
		)
		(layer "In5.Cu")
	)
	(gr_line
		(start 313.877706 -40.824658)
		(end 313.905646 -40.8051)
		(stroke
			(width 0.06985)
			(type default)
		)
		(layer "In5.Cu")
	)
	(gr_line
		(start 313.905646 -40.8051)
		(end 313.938666 -40.799258)
		(stroke
			(width 0.06985)
			(type default)
		)
		(layer "In5.Cu")
	)
	(gr_line
		(start 314.063126 -203.06919)
		(end 314.063126 -203.069444)
		(stroke
			(width 0.06985)
			(type default)
		)
		(layer "In5.Cu")
	)
	(gr_line
		(start 314.063126 -203.06919)
		(end 314.066428 -203.050394)
		(stroke
			(width 0.06985)
			(type default)
		)
		(layer "In5.Cu")
	)
	(gr_line
		(start 314.063126 -203.031598)
		(end 314.066428 -203.050394)
		(stroke
			(width 0.06985)
			(type default)
		)
		(layer "In5.Cu")
	)
	(gr_line
		(start 314.084462 -38.613842)
		(end 314.099956 -38.60292)
		(stroke
			(width 0.06985)
			(type default)
		)
		(layer "In5.Cu")
	)
	(gr_line
		(start 314.099956 -38.60292)
		(end 314.110878 -38.587426)
		(stroke
			(width 0.06985)
			(type default)
		)
		(layer "In5.Cu")
	)
	(gr_arc
		(start 315.1251 -35.59683)
		(mid 315.062437 -35.281475)
		(end 314.8838 -35.014154)
		(stroke
			(width 0.06985)
			(type default)
		)
		(layer "In5.Cu")
	)
	(gr_line
		(start 315.221366 -41.389046)
		(end 315.249306 -41.369488)
		(stroke
			(width 0.06985)
			(type default)
		)
		(layer "In5.Cu")
	)
	(gr_line
		(start 315.249306 -41.369488)
		(end 315.282326 -41.363646)
		(stroke
			(width 0.06985)
			(type default)
		)
		(layer "In5.Cu")
	)
	(gr_line
		(start 315.295534 -36.895278)
		(end 315.315092 -36.867338)
		(stroke
			(width 0.06985)
			(type default)
		)
		(layer "In5.Cu")
	)
	(gr_line
		(start 315.315092 -36.867338)
		(end 315.320934 -36.834318)
		(stroke
			(width 0.06985)
			(type default)
		)
		(layer "In5.Cu")
	)
	(gr_arc
		(start 315.620908 -35.089846)
		(mid 315.498345 -35.273274)
		(end 315.4553 -35.489642)
		(stroke
			(width 0.06985)
			(type default)
		)
		(layer "In5.Cu")
	)
	(gr_line
		(start 315.620908 -35.089846)
		(end 315.6966 -35.014154)
		(stroke
			(width 0.06985)
			(type default)
		)
		(layer "In5.Cu")
	)
	(gr_line
		(start 316.304422 -42.006012)
		(end 316.332362 -41.986454)
		(stroke
			(width 0.06985)
			(type default)
		)
		(layer "In5.Cu")
	)
	(gr_line
		(start 316.332362 -41.986454)
		(end 316.365382 -41.980612)
		(stroke
			(width 0.06985)
			(type default)
		)
		(layer "In5.Cu")
	)
	(gr_arc
		(start 316.493906 -210.896454)
		(mid 316.672533 -210.62912)
		(end 316.735206 -210.313778)
		(stroke
			(width 0.06985)
			(type default)
		)
		(layer "In5.Cu")
	)
	(gr_line
		(start 316.505844 -206.891382)
		(end 316.509146 -206.910432)
		(stroke
			(width 0.06985)
			(type default)
		)
		(layer "In5.Cu")
	)
	(gr_line
		(start 316.505844 -206.891382)
		(end 316.509146 -206.872586)
		(stroke
			(width 0.06985)
			(type default)
		)
		(layer "In5.Cu")
	)
	(gr_line
		(start 316.509146 -206.910178)
		(end 316.509146 -206.910432)
		(stroke
			(width 0.06985)
			(type default)
		)
		(layer "In5.Cu")
	)
	(gr_line
		(start 316.612778 -194.196208)
		(end 316.632336 -194.224148)
		(stroke
			(width 0.06985)
			(type default)
		)
		(layer "In5.Cu")
	)
	(gr_line
		(start 316.632336 -194.224148)
		(end 316.638178 -194.257168)
		(stroke
			(width 0.06985)
			(type default)
		)
		(layer "In5.Cu")
	)
	(gr_line
		(start 316.735206 -209.983578)
		(end 316.735206 -210.313778)
		(stroke
			(width 0.06985)
			(type default)
		)
		(layer "In5.Cu")
	)
	(gr_line
		(start 317.065152 -210.313778)
		(end 317.065406 -210.313778)
		(stroke
			(width 0.06985)
			(type default)
		)
		(layer "In5.Cu")
	)
	(gr_arc
		(start 317.065152 -210.313778)
		(mid 317.127953 -210.629148)
		(end 317.306706 -210.896454)
		(stroke
			(width 0.06985)
			(type default)
		)
		(layer "In5.Cu")
	)
	(gr_line
		(start 317.224156 -209.101182)
		(end 317.227458 -209.082386)
		(stroke
			(width 0.06985)
			(type default)
		)
		(layer "In5.Cu")
	)
	(gr_line
		(start 317.224156 -209.06359)
		(end 317.227458 -209.082386)
		(stroke
			(width 0.06985)
			(type default)
		)
		(layer "In5.Cu")
	)
	(gr_line
		(start 317.680848 -39.651178)
		(end 317.708026 -39.646352)
		(stroke
			(width 0.06985)
			(type default)
		)
		(layer "In5.Cu")
	)
	(gr_line
		(start 317.708026 -39.646352)
		(end 317.731648 -39.631112)
		(stroke
			(width 0.06985)
			(type default)
		)
		(layer "In5.Cu")
	)
	(gr_line
		(start 317.850266 -201.169524)
		(end 317.850266 -201.169778)
		(stroke
			(width 0.06985)
			(type default)
		)
		(layer "In5.Cu")
	)
	(gr_line
		(start 317.850266 -201.169524)
		(end 317.853568 -201.150728)
		(stroke
			(width 0.06985)
			(type default)
		)
		(layer "In5.Cu")
	)
	(gr_line
		(start 317.850266 -201.131932)
		(end 317.853568 -201.150728)
		(stroke
			(width 0.06985)
			(type default)
		)
		(layer "In5.Cu")
	)
	(gr_line
		(start 319.553082 -40.1447)
		(end 319.58026 -40.139874)
		(stroke
			(width 0.06985)
			(type default)
		)
		(layer "In5.Cu")
	)
	(gr_line
		(start 319.58026 -40.139874)
		(end 319.603882 -40.124634)
		(stroke
			(width 0.06985)
			(type default)
		)
		(layer "In5.Cu")
	)
	(gr_line
		(start 319.587626 -207.926686)
		(end 319.590928 -207.945736)
		(stroke
			(width 0.06985)
			(type default)
		)
		(layer "In5.Cu")
	)
	(gr_line
		(start 319.587626 -207.926686)
		(end 319.590928 -207.90789)
		(stroke
			(width 0.06985)
			(type default)
		)
		(layer "In5.Cu")
	)
	(gr_arc
		(start 319.693798 -210.896454)
		(mid 319.872425 -210.62912)
		(end 319.935098 -210.313778)
		(stroke
			(width 0.06985)
			(type default)
		)
		(layer "In5.Cu")
	)
	(gr_line
		(start 319.846198 -206.459074)
		(end 319.85204 -206.426054)
		(stroke
			(width 0.06985)
			(type default)
		)
		(layer "In5.Cu")
	)
	(gr_line
		(start 319.85204 -206.426054)
		(end 319.871598 -206.398114)
		(stroke
			(width 0.06985)
			(type default)
		)
		(layer "In5.Cu")
	)
	(gr_arc
		(start 319.951862 -37.427154)
		(mid 319.890018 -37.195558)
		(end 319.720976 -37.02558)
		(stroke
			(width 0.06985)
			(type default)
		)
		(layer "In5.Cu")
	)
	(gr_arc
		(start 320.265298 -210.313778)
		(mid 320.328019 -210.6291)
		(end 320.506598 -210.896454)
		(stroke
			(width 0.06985)
			(type default)
		)
		(layer "In5.Cu")
	)
	(gr_arc
		(start 320.533776 -37.02558)
		(mid 320.350195 -37.19018)
		(end 320.282062 -37.427154)
		(stroke
			(width 0.06985)
			(type default)
		)
		(layer "In5.Cu")
	)
	(gr_line
		(start 320.867278 -191.89573)
		(end 320.886836 -191.92367)
		(stroke
			(width 0.06985)
			(type default)
		)
		(layer "In5.Cu")
	)
	(gr_line
		(start 320.886836 -191.92367)
		(end 320.892678 -191.95669)
		(stroke
			(width 0.06985)
			(type default)
		)
		(layer "In5.Cu")
	)
	(gr_line
		(start 321.45732 -204.710538)
		(end 321.476878 -204.682598)
		(stroke
			(width 0.06985)
			(type default)
		)
		(layer "In5.Cu")
	)
	(gr_line
		(start 321.476878 -204.682598)
		(end 321.48272 -204.649578)
		(stroke
			(width 0.06985)
			(type default)
		)
		(layer "In5.Cu")
	)
	(gr_line
		(start 321.925442 -189.58306)
		(end 321.945 -189.611)
		(stroke
			(width 0.06985)
			(type default)
		)
		(layer "In5.Cu")
	)
	(gr_line
		(start 321.945 -189.611)
		(end 321.950842 -189.64402)
		(stroke
			(width 0.06985)
			(type default)
		)
		(layer "In5.Cu")
	)
	(gr_line
		(start 322.303394 -199.995028)
		(end 322.306696 -199.976232)
		(stroke
			(width 0.06985)
			(type default)
		)
		(layer "In5.Cu")
	)
	(gr_line
		(start 322.303394 -199.957436)
		(end 322.306696 -199.976232)
		(stroke
			(width 0.06985)
			(type default)
		)
		(layer "In5.Cu")
	)
	(gr_line
		(start 322.610734 -206.756)
		(end 322.614036 -206.77505)
		(stroke
			(width 0.06985)
			(type default)
		)
		(layer "In5.Cu")
	)
	(gr_line
		(start 322.610734 -206.756)
		(end 322.614036 -206.737204)
		(stroke
			(width 0.06985)
			(type default)
		)
		(layer "In5.Cu")
	)
	(gr_line
		(start 322.809616 -41.180004)
		(end 322.842636 -41.174162)
		(stroke
			(width 0.06985)
			(type default)
		)
		(layer "In5.Cu")
	)
	(gr_line
		(start 322.842636 -41.174162)
		(end 322.870576 -41.154604)
		(stroke
			(width 0.06985)
			(type default)
		)
		(layer "In5.Cu")
	)
	(gr_arc
		(start 322.89369 -210.896454)
		(mid 323.072317 -210.62912)
		(end 323.13499 -210.313778)
		(stroke
			(width 0.06985)
			(type default)
		)
		(layer "In5.Cu")
	)
	(gr_arc
		(start 323.46519 -210.313778)
		(mid 323.527855 -210.629132)
		(end 323.70649 -210.896454)
		(stroke
			(width 0.06985)
			(type default)
		)
		(layer "In5.Cu")
	)
	(gr_line
		(start 323.61251 -34.968942)
		(end 323.649594 -35.005772)
		(stroke
			(width 0.06985)
			(type default)
		)
		(layer "In5.Cu")
	)
	(gr_arc
		(start 323.839332 -35.464242)
		(mid 323.790071 -35.216131)
		(end 323.649594 -35.005772)
		(stroke
			(width 0.06985)
			(type default)
		)
		(layer "In5.Cu")
	)
	(gr_line
		(start 323.953886 -201.041762)
		(end 323.953886 -201.042016)
		(stroke
			(width 0.06985)
			(type default)
		)
		(layer "In5.Cu")
	)
	(gr_line
		(start 323.953886 -201.041762)
		(end 323.957188 -201.022966)
		(stroke
			(width 0.06985)
			(type default)
		)
		(layer "In5.Cu")
	)
	(gr_line
		(start 323.953886 -201.00417)
		(end 323.957188 -201.022966)
		(stroke
			(width 0.06985)
			(type default)
		)
		(layer "In5.Cu")
	)
	(gr_arc
		(start 324.33895 -35.055302)
		(mid 324.213584 -35.242925)
		(end 324.169532 -35.464242)
		(stroke
			(width 0.06985)
			(type default)
		)
		(layer "In5.Cu")
	)
	(gr_line
		(start 324.33895 -35.055302)
		(end 324.42531 -34.968942)
		(stroke
			(width 0.06985)
			(type default)
		)
		(layer "In5.Cu")
	)
	(gr_line
		(start 324.51929 -189.580774)
		(end 324.538848 -189.608714)
		(stroke
			(width 0.06985)
			(type default)
		)
		(layer "In5.Cu")
	)
	(gr_line
		(start 324.538848 -189.608714)
		(end 324.54469 -189.641734)
		(stroke
			(width 0.06985)
			(type default)
		)
		(layer "In5.Cu")
	)
	(gr_line
		(start 325.795894 -38.002972)
		(end 325.815452 -37.989256)
		(stroke
			(width 0.06985)
			(type default)
		)
		(layer "In5.Cu")
	)
	(gr_line
		(start 325.815452 -37.989256)
		(end 325.828152 -37.969698)
		(stroke
			(width 0.06985)
			(type default)
		)
		(layer "In5.Cu")
	)
	(gr_line
		(start 325.99122 -207.66786)
		(end 325.994522 -207.68691)
		(stroke
			(width 0.06985)
			(type default)
		)
		(layer "In5.Cu")
	)
	(gr_line
		(start 325.99122 -207.66786)
		(end 325.994522 -207.649064)
		(stroke
			(width 0.06985)
			(type default)
		)
		(layer "In5.Cu")
	)
	(gr_arc
		(start 326.093582 -210.896454)
		(mid 326.27217 -210.629107)
		(end 326.334882 -210.313778)
		(stroke
			(width 0.06985)
			(type default)
		)
		(layer "In5.Cu")
	)
	(gr_arc
		(start 326.183752 -36.479734)
		(mid 326.127981 -36.199302)
		(end 325.969122 -35.961574)
		(stroke
			(width 0.06985)
			(type default)
		)
		(layer "In5.Cu")
	)
	(gr_line
		(start 326.48271 -36.962334)
		(end 326.513952 -36.914074)
		(stroke
			(width 0.06985)
			(type default)
		)
		(layer "In5.Cu")
	)
	(gr_arc
		(start 326.665082 -210.313778)
		(mid 326.727803 -210.6291)
		(end 326.906382 -210.896454)
		(stroke
			(width 0.06985)
			(type default)
		)
		(layer "In5.Cu")
	)
	(gr_arc
		(start 326.714104 -36.029646)
		(mid 326.566032 -36.251177)
		(end 326.513952 -36.5125)
		(stroke
			(width 0.06985)
			(type default)
		)
		(layer "In5.Cu")
	)
	(gr_line
		(start 326.714104 -36.029646)
		(end 326.781922 -35.961574)
		(stroke
			(width 0.06985)
			(type default)
		)
		(layer "In5.Cu")
	)
	(gr_line
		(start 327.021698 -203.726796)
		(end 327.021698 -203.72705)
		(stroke
			(width 0.06985)
			(type default)
		)
		(layer "In5.Cu")
	)
	(gr_line
		(start 327.021698 -203.726796)
		(end 327.025 -203.708)
		(stroke
			(width 0.06985)
			(type default)
		)
		(layer "In5.Cu")
	)
	(gr_line
		(start 327.021698 -203.688696)
		(end 327.025 -203.708)
		(stroke
			(width 0.06985)
			(type default)
		)
		(layer "In5.Cu")
	)
	(gr_line
		(start 328.375518 -34.919412)
		(end 328.486262 -35.030156)
		(stroke
			(width 0.06985)
			(type default)
		)
		(layer "In5.Cu")
	)
	(gr_arc
		(start 328.637646 -35.395662)
		(mid 328.5983 -35.197857)
		(end 328.486262 -35.030156)
		(stroke
			(width 0.06985)
			(type default)
		)
		(layer "In5.Cu")
	)
	(gr_arc
		(start 329.148694 -34.959036)
		(mid 329.014841 -35.159362)
		(end 328.967846 -35.395662)
		(stroke
			(width 0.06985)
			(type default)
		)
		(layer "In5.Cu")
	)
	(gr_line
		(start 329.148694 -34.959036)
		(end 329.188318 -34.919412)
		(stroke
			(width 0.06985)
			(type default)
		)
		(layer "In5.Cu")
	)
	(gr_line
		(start 332.404466 -204.851)
		(end 332.407768 -204.87005)
		(stroke
			(width 0.06985)
			(type default)
		)
		(layer "In5.Cu")
	)
	(gr_line
		(start 332.404466 -204.851)
		(end 332.407768 -204.832204)
		(stroke
			(width 0.06985)
			(type default)
		)
		(layer "In5.Cu")
	)
	(gr_arc
		(start 332.493874 -210.896454)
		(mid 332.672463 -210.629108)
		(end 332.735174 -210.313778)
		(stroke
			(width 0.06985)
			(type default)
		)
		(layer "In5.Cu")
	)
	(gr_line
		(start 332.737714 -199.949308)
		(end 332.775306 -200.067672)
		(stroke
			(width 0.06985)
			(type default)
		)
		(layer "In5.Cu")
	)
	(gr_line
		(start 332.775306 -200.067672)
		(end 332.78191 -200.070974)
		(stroke
			(width 0.06985)
			(type default)
		)
		(layer "In5.Cu")
	)
	(gr_line
		(start 333.028036 -199.783446)
		(end 333.065374 -199.836786)
		(stroke
			(width 0.06985)
			(type default)
		)
		(layer "In5.Cu")
	)
	(gr_arc
		(start 333.065374 -210.313778)
		(mid 333.128095 -210.6291)
		(end 333.306674 -210.896454)
		(stroke
			(width 0.06985)
			(type default)
		)
		(layer "In5.Cu")
	)
	(gr_line
		(start 333.065374 -199.836786)
		(end 333.105506 -199.962516)
		(stroke
			(width 0.06985)
			(type default)
		)
		(layer "In5.Cu")
	)
	(gr_line
		(start 333.101442 -199.969882)
		(end 333.105506 -199.962516)
		(stroke
			(width 0.06985)
			(type default)
		)
		(layer "In5.Cu")
	)
	(gr_line
		(start 333.2988 -208.05775)
		(end 333.2988 -208.058004)
		(stroke
			(width 0.06985)
			(type default)
		)
		(layer "In5.Cu")
	)
	(gr_line
		(start 333.2988 -208.05775)
		(end 333.302102 -208.038954)
		(stroke
			(width 0.06985)
			(type default)
		)
		(layer "In5.Cu")
	)
	(gr_line
		(start 333.2988 -208.020158)
		(end 333.302102 -208.038954)
		(stroke
			(width 0.06985)
			(type default)
		)
		(layer "In5.Cu")
	)
	(gr_line
		(start 333.409036 -200.948544)
		(end 333.421228 -200.987152)
		(stroke
			(width 0.06985)
			(type default)
		)
		(layer "In5.Cu")
	)
	(gr_line
		(start 333.414116 -201.02703)
		(end 333.421228 -200.987152)
		(stroke
			(width 0.06985)
			(type default)
		)
		(layer "In5.Cu")
	)
	(gr_arc
		(start 335.693766 -210.896454)
		(mid 335.872357 -210.629108)
		(end 335.935066 -210.313778)
		(stroke
			(width 0.06985)
			(type default)
		)
		(layer "In5.Cu")
	)
	(gr_line
		(start 335.800954 -201.448416)
		(end 335.820512 -201.476356)
		(stroke
			(width 0.06985)
			(type default)
		)
		(layer "In5.Cu")
	)
	(gr_line
		(start 335.820512 -201.476356)
		(end 335.826354 -201.509376)
		(stroke
			(width 0.06985)
			(type default)
		)
		(layer "In5.Cu")
	)
	(gr_line
		(start 335.935066 -204.028294)
		(end 335.935066 -204.301344)
		(stroke
			(width 0.06985)
			(type default)
		)
		(layer "In5.Cu")
	)
	(gr_line
		(start 336.26044 -203.97089)
		(end 336.26044 -203.971144)
		(stroke
			(width 0.06985)
			(type default)
		)
		(layer "In5.Cu")
	)
	(gr_arc
		(start 336.265266 -210.313778)
		(mid 336.327987 -210.6291)
		(end 336.506566 -210.896454)
		(stroke
			(width 0.06985)
			(type default)
		)
		(layer "In5.Cu")
	)
	(gr_arc
		(start 338.893658 -210.896454)
		(mid 339.07223 -210.629103)
		(end 339.134958 -210.313778)
		(stroke
			(width 0.06985)
			(type default)
		)
		(layer "In5.Cu")
	)
	(gr_line
		(start 339.42909 -205.063344)
		(end 339.465158 -205.114906)
		(stroke
			(width 0.06985)
			(type default)
		)
		(layer "In5.Cu")
	)
	(gr_arc
		(start 339.465158 -210.313778)
		(mid 339.527879 -210.6291)
		(end 339.706458 -210.896454)
		(stroke
			(width 0.06985)
			(type default)
		)
		(layer "In5.Cu")
	)
	(gr_line
		(start 342.09355 -210.896454)
		(end 342.21801 -210.772248)
		(stroke
			(width 0.06985)
			(type default)
		)
		(layer "In5.Cu")
	)
	(gr_arc
		(start 342.21801 -210.772248)
		(mid 342.304515 -210.642645)
		(end 342.33485 -210.4898)
		(stroke
			(width 0.06985)
			(type default)
		)
		(layer "In5.Cu")
	)
	(gr_line
		(start 342.628982 -207.979264)
		(end 342.66505 -208.030826)
		(stroke
			(width 0.06985)
			(type default)
		)
		(layer "In5.Cu")
	)
	(gr_arc
		(start 342.66505 -210.4898)
		(mid 342.695369 -210.642652)
		(end 342.78189 -210.772248)
		(stroke
			(width 0.06985)
			(type default)
		)
		(layer "In5.Cu")
	)
	(gr_line
		(start 342.78189 -210.772248)
		(end 342.90635 -210.896454)
		(stroke
			(width 0.06985)
			(type default)
		)
		(layer "In5.Cu")
	)
	(gr_line
		(start 0 -212.499956)
		(end 0 -28.010104)
		(stroke
			(width 1.524)
			(type default)
		)
		(layer "In6.Cu")
	)
	(gr_arc
		(start 0 -212.499956)
		(mid 0.292895 -213.207058)
		(end 0.999998 -213.499954)
		(stroke
			(width 1.524)
			(type default)
		)
		(layer "In6.Cu")
	)
	(gr_arc
		(start 1.999996 -26.010108)
		(mid 0.585785 -26.595893)
		(end 0 -28.010104)
		(stroke
			(width 1.524)
			(type default)
		)
		(layer "In6.Cu")
	)
	(gr_line
		(start 1.999996 -26.010108)
		(end 49.950116 -26.010108)
		(stroke
			(width 1.524)
			(type default)
		)
		(layer "In6.Cu")
	)
	(gr_line
		(start 9.6647 -55.559452)
		(end 10.477246 -55.559452)
		(stroke
			(width 0.2)
			(type default)
		)
		(layer "In6.Cu")
	)
	(gr_arc
		(start 9.6647 -54.538372)
		(mid 9.15416 -55.048912)
		(end 9.6647 -55.559452)
		(stroke
			(width 0.2)
			(type default)
		)
		(layer "In6.Cu")
	)
	(gr_arc
		(start 10.477246 -55.559452)
		(mid 10.98804 -55.049039)
		(end 10.4775 -54.538372)
		(stroke
			(width 0.2)
			(type default)
		)
		(layer "In6.Cu")
	)
	(gr_line
		(start 10.4775 -54.538372)
		(end 9.6647 -54.538372)
		(stroke
			(width 0.2)
			(type default)
		)
		(layer "In6.Cu")
	)
	(gr_line
		(start 13.5636 -54.340252)
		(end 14.3764 -54.340252)
		(stroke
			(width 0.2)
			(type default)
		)
		(layer "In6.Cu")
	)
	(gr_arc
		(start 13.563854 -53.319172)
		(mid 13.05306 -53.829585)
		(end 13.5636 -54.340252)
		(stroke
			(width 0.2)
			(type default)
		)
		(layer "In6.Cu")
	)
	(gr_arc
		(start 13.66266 -68.451222)
		(mid 14.1732 -68.961762)
		(end 14.68374 -68.451222)
		(stroke
			(width 0.2)
			(type default)
		)
		(layer "In6.Cu")
	)
	(gr_line
		(start 13.66266 -67.638422)
		(end 13.66266 -68.451222)
		(stroke
			(width 0.2)
			(type default)
		)
		(layer "In6.Cu")
	)
	(gr_arc
		(start 14.3764 -54.340252)
		(mid 14.88694 -53.829712)
		(end 14.3764 -53.319172)
		(stroke
			(width 0.2)
			(type default)
		)
		(layer "In6.Cu")
	)
	(gr_line
		(start 14.3764 -53.319172)
		(end 13.563854 -53.319172)
		(stroke
			(width 0.2)
			(type default)
		)
		(layer "In6.Cu")
	)
	(gr_line
		(start 14.68374 -68.451222)
		(end 14.68374 -67.638676)
		(stroke
			(width 0.2)
			(type default)
		)
		(layer "In6.Cu")
	)
	(gr_arc
		(start 14.68374 -67.638676)
		(mid 14.173327 -67.127882)
		(end 13.66266 -67.638422)
		(stroke
			(width 0.2)
			(type default)
		)
		(layer "In6.Cu")
	)
	(gr_arc
		(start 15.66926 -67.03695)
		(mid 16.1798 -67.54749)
		(end 16.69034 -67.03695)
		(stroke
			(width 0.2)
			(type default)
		)
		(layer "In6.Cu")
	)
	(gr_line
		(start 15.66926 -66.22415)
		(end 15.66926 -67.03695)
		(stroke
			(width 0.2)
			(type default)
		)
		(layer "In6.Cu")
	)
	(gr_line
		(start 15.7988 -73.727564)
		(end 16.6116 -73.727564)
		(stroke
			(width 0.2)
			(type default)
		)
		(layer "In6.Cu")
	)
	(gr_arc
		(start 15.799054 -72.706484)
		(mid 15.28826 -73.216897)
		(end 15.7988 -73.727564)
		(stroke
			(width 0.2)
			(type default)
		)
		(layer "In6.Cu")
	)
	(gr_line
		(start 15.8496 -87.65794)
		(end 16.9672 -87.65794)
		(stroke
			(width 0.2)
			(type default)
		)
		(layer "In6.Cu")
	)
	(gr_arc
		(start 15.8496 -86.43366)
		(mid 15.23746 -87.0458)
		(end 15.8496 -87.65794)
		(stroke
			(width 0.2)
			(type default)
		)
		(layer "In6.Cu")
	)
	(gr_arc
		(start 16.6116 -73.727564)
		(mid 17.12214 -73.217024)
		(end 16.6116 -72.706484)
		(stroke
			(width 0.2)
			(type default)
		)
		(layer "In6.Cu")
	)
	(gr_line
		(start 16.6116 -72.706484)
		(end 15.799054 -72.706484)
		(stroke
			(width 0.2)
			(type default)
		)
		(layer "In6.Cu")
	)
	(gr_line
		(start 16.69034 -67.03695)
		(end 16.69034 -66.224404)
		(stroke
			(width 0.2)
			(type default)
		)
		(layer "In6.Cu")
	)
	(gr_arc
		(start 16.69034 -66.224404)
		(mid 16.179927 -65.71361)
		(end 15.66926 -66.22415)
		(stroke
			(width 0.2)
			(type default)
		)
		(layer "In6.Cu")
	)
	(gr_arc
		(start 16.9672 -87.65794)
		(mid 17.57934 -87.0458)
		(end 16.9672 -86.43366)
		(stroke
			(width 0.2)
			(type default)
		)
		(layer "In6.Cu")
	)
	(gr_line
		(start 16.9672 -86.43366)
		(end 15.8496 -86.43366)
		(stroke
			(width 0.2)
			(type default)
		)
		(layer "In6.Cu")
	)
	(gr_line
		(start 18.57375 -73.721214)
		(end 19.38655 -73.721214)
		(stroke
			(width 0.2)
			(type default)
		)
		(layer "In6.Cu")
	)
	(gr_arc
		(start 18.574004 -72.700134)
		(mid 18.06321 -73.210547)
		(end 18.57375 -73.721214)
		(stroke
			(width 0.2)
			(type default)
		)
		(layer "In6.Cu")
	)
	(gr_line
		(start 18.6944 -58.851546)
		(end 19.812 -58.851546)
		(stroke
			(width 0.2)
			(type default)
		)
		(layer "In6.Cu")
	)
	(gr_arc
		(start 18.6944 -57.627266)
		(mid 18.08226 -58.239406)
		(end 18.6944 -58.851546)
		(stroke
			(width 0.2)
			(type default)
		)
		(layer "In6.Cu")
	)
	(gr_line
		(start 18.8468 -55.508652)
		(end 19.659346 -55.508652)
		(stroke
			(width 0.2)
			(type default)
		)
		(layer "In6.Cu")
	)
	(gr_arc
		(start 18.8468 -54.487572)
		(mid 18.33626 -54.998112)
		(end 18.8468 -55.508652)
		(stroke
			(width 0.2)
			(type default)
		)
		(layer "In6.Cu")
	)
	(gr_line
		(start 18.852134 -82.41792)
		(end 19.664934 -82.41792)
		(stroke
			(width 0.2)
			(type default)
		)
		(layer "In6.Cu")
	)
	(gr_arc
		(start 18.852388 -81.39684)
		(mid 18.341594 -81.907253)
		(end 18.852134 -82.41792)
		(stroke
			(width 0.2)
			(type default)
		)
		(layer "In6.Cu")
	)
	(gr_arc
		(start 19.38655 -73.721214)
		(mid 19.89709 -73.210674)
		(end 19.38655 -72.700134)
		(stroke
			(width 0.2)
			(type default)
		)
		(layer "In6.Cu")
	)
	(gr_line
		(start 19.38655 -72.700134)
		(end 18.574004 -72.700134)
		(stroke
			(width 0.2)
			(type default)
		)
		(layer "In6.Cu")
	)
	(gr_arc
		(start 19.659346 -55.508652)
		(mid 20.17014 -54.998239)
		(end 19.6596 -54.487572)
		(stroke
			(width 0.2)
			(type default)
		)
		(layer "In6.Cu")
	)
	(gr_line
		(start 19.6596 -54.487572)
		(end 18.8468 -54.487572)
		(stroke
			(width 0.2)
			(type default)
		)
		(layer "In6.Cu")
	)
	(gr_arc
		(start 19.664934 -82.41792)
		(mid 20.175474 -81.90738)
		(end 19.664934 -81.39684)
		(stroke
			(width 0.2)
			(type default)
		)
		(layer "In6.Cu")
	)
	(gr_line
		(start 19.664934 -81.39684)
		(end 18.852388 -81.39684)
		(stroke
			(width 0.2)
			(type default)
		)
		(layer "In6.Cu")
	)
	(gr_arc
		(start 19.812 -58.851546)
		(mid 20.42414 -58.239406)
		(end 19.812 -57.627266)
		(stroke
			(width 0.2)
			(type default)
		)
		(layer "In6.Cu")
	)
	(gr_line
		(start 19.812 -57.627266)
		(end 18.6944 -57.627266)
		(stroke
			(width 0.2)
			(type default)
		)
		(layer "In6.Cu")
	)
	(gr_line
		(start 20.3962 -87.93734)
		(end 21.209 -87.93734)
		(stroke
			(width 0.2)
			(type default)
		)
		(layer "In6.Cu")
	)
	(gr_arc
		(start 20.396454 -86.91626)
		(mid 19.88566 -87.426673)
		(end 20.3962 -87.93734)
		(stroke
			(width 0.2)
			(type default)
		)
		(layer "In6.Cu")
	)
	(gr_arc
		(start 21.209 -87.93734)
		(mid 21.71954 -87.4268)
		(end 21.209 -86.91626)
		(stroke
			(width 0.2)
			(type default)
		)
		(layer "In6.Cu")
	)
	(gr_line
		(start 21.209 -86.91626)
		(end 20.396454 -86.91626)
		(stroke
			(width 0.2)
			(type default)
		)
		(layer "In6.Cu")
	)
	(gr_line
		(start 22.417786 -57.300876)
		(end 23.535386 -57.300876)
		(stroke
			(width 0.2)
			(type default)
		)
		(layer "In6.Cu")
	)
	(gr_arc
		(start 22.417786 -56.076596)
		(mid 21.805646 -56.688736)
		(end 22.417786 -57.300876)
		(stroke
			(width 0.2)
			(type default)
		)
		(layer "In6.Cu")
	)
	(gr_arc
		(start 22.55266 -115.1128)
		(mid 23.1648 -115.72494)
		(end 23.77694 -115.1128)
		(stroke
			(width 0.2)
			(type default)
		)
		(layer "In6.Cu")
	)
	(gr_line
		(start 22.55266 -113.9952)
		(end 22.55266 -115.1128)
		(stroke
			(width 0.2)
			(type default)
		)
		(layer "In6.Cu")
	)
	(gr_line
		(start 22.5552 -54.066694)
		(end 23.368 -54.066694)
		(stroke
			(width 0.2)
			(type default)
		)
		(layer "In6.Cu")
	)
	(gr_arc
		(start 22.555454 -53.045614)
		(mid 22.04466 -53.556027)
		(end 22.5552 -54.066694)
		(stroke
			(width 0.2)
			(type default)
		)
		(layer "In6.Cu")
	)
	(gr_arc
		(start 23.368 -54.066694)
		(mid 23.87854 -53.556154)
		(end 23.368 -53.045614)
		(stroke
			(width 0.2)
			(type default)
		)
		(layer "In6.Cu")
	)
	(gr_line
		(start 23.368 -53.045614)
		(end 22.555454 -53.045614)
		(stroke
			(width 0.2)
			(type default)
		)
		(layer "In6.Cu")
	)
	(gr_arc
		(start 23.535386 -57.300876)
		(mid 24.147526 -56.688736)
		(end 23.535386 -56.076596)
		(stroke
			(width 0.2)
			(type default)
		)
		(layer "In6.Cu")
	)
	(gr_line
		(start 23.535386 -56.076596)
		(end 22.417786 -56.076596)
		(stroke
			(width 0.2)
			(type default)
		)
		(layer "In6.Cu")
	)
	(gr_line
		(start 23.77694 -115.1128)
		(end 23.77694 -113.995454)
		(stroke
			(width 0.2)
			(type default)
		)
		(layer "In6.Cu")
	)
	(gr_arc
		(start 23.77694 -113.995454)
		(mid 23.164927 -113.38306)
		(end 22.55266 -113.9952)
		(stroke
			(width 0.2)
			(type default)
		)
		(layer "In6.Cu")
	)
	(gr_arc
		(start 23.861014 -112.521746)
		(mid 24.473027 -113.13414)
		(end 25.085294 -112.522)
		(stroke
			(width 0.2)
			(type default)
		)
		(layer "In6.Cu")
	)
	(gr_line
		(start 23.861014 -111.4044)
		(end 23.861014 -112.521746)
		(stroke
			(width 0.2)
			(type default)
		)
		(layer "In6.Cu")
	)
	(gr_line
		(start 25.085294 -112.522)
		(end 25.085294 -111.4044)
		(stroke
			(width 0.2)
			(type default)
		)
		(layer "In6.Cu")
	)
	(gr_arc
		(start 25.085294 -111.4044)
		(mid 24.473154 -110.79226)
		(end 23.861014 -111.4044)
		(stroke
			(width 0.2)
			(type default)
		)
		(layer "In6.Cu")
	)
	(gr_line
		(start 25.4 -213.499954)
		(end 0.999998 -213.499954)
		(stroke
			(width 1.524)
			(type default)
		)
		(layer "In6.Cu")
	)
	(gr_arc
		(start 25.51684 -143.69796)
		(mid 26.12898 -144.3101)
		(end 26.74112 -143.69796)
		(stroke
			(width 0.2)
			(type default)
		)
		(layer "In6.Cu")
	)
	(gr_line
		(start 25.51684 -142.58036)
		(end 25.51684 -143.69796)
		(stroke
			(width 0.2)
			(type default)
		)
		(layer "In6.Cu")
	)
	(gr_line
		(start 26.699972 -221.400116)
		(end 26.699972 -214.799926)
		(stroke
			(width 1.524)
			(type default)
		)
		(layer "In6.Cu")
	)
	(gr_arc
		(start 26.699972 -221.400116)
		(mid 26.846532 -221.75362)
		(end 27.200098 -221.899988)
		(stroke
			(width 1.524)
			(type default)
		)
		(layer "In6.Cu")
	)
	(gr_arc
		(start 26.699972 -214.799926)
		(mid 26.319219 -213.880707)
		(end 25.4 -213.499954)
		(stroke
			(width 1.524)
			(type default)
		)
		(layer "In6.Cu")
	)
	(gr_line
		(start 26.74112 -143.69796)
		(end 26.74112 -142.580614)
		(stroke
			(width 0.2)
			(type default)
		)
		(layer "In6.Cu")
	)
	(gr_arc
		(start 26.74112 -142.580614)
		(mid 26.129107 -141.96822)
		(end 25.51684 -142.58036)
		(stroke
			(width 0.2)
			(type default)
		)
		(layer "In6.Cu")
	)
	(gr_line
		(start 27.60853 -106.369612)
		(end 28.398978 -107.16006)
		(stroke
			(width 0.2)
			(type default)
		)
		(layer "In6.Cu")
	)
	(gr_line
		(start 27.610308 -106.367834)
		(end 27.60853 -106.369612)
		(stroke
			(width 0.2)
			(type default)
		)
		(layer "In6.Cu")
	)
	(gr_line
		(start 27.999944 -221.899988)
		(end 27.200098 -221.899988)
		(stroke
			(width 1.524)
			(type default)
		)
		(layer "In6.Cu")
	)
	(gr_line
		(start 28.398978 -107.16006)
		(end 28.400756 -107.158282)
		(stroke
			(width 0.2)
			(type default)
		)
		(layer "In6.Cu")
	)
	(gr_arc
		(start 28.400756 -107.158282)
		(mid 29.266388 -107.158282)
		(end 29.266388 -106.29265)
		(stroke
			(width 0.2)
			(type default)
		)
		(layer "In6.Cu")
	)
	(gr_arc
		(start 28.47594 -105.502202)
		(mid 27.610308 -105.502202)
		(end 27.610308 -106.367834)
		(stroke
			(width 0.2)
			(type default)
		)
		(layer "In6.Cu")
	)
	(gr_line
		(start 28.477464 -105.500678)
		(end 28.47594 -105.502202)
		(stroke
			(width 0.2)
			(type default)
		)
		(layer "In6.Cu")
	)
	(gr_line
		(start 28.477972 -105.500678)
		(end 28.477464 -105.500678)
		(stroke
			(width 0.2)
			(type default)
		)
		(layer "In6.Cu")
	)
	(gr_line
		(start 28.50007 -228.000052)
		(end 28.50007 -222.400114)
		(stroke
			(width 1.524)
			(type default)
		)
		(layer "In6.Cu")
	)
	(gr_arc
		(start 28.50007 -222.400114)
		(mid 28.353586 -222.046472)
		(end 27.999944 -221.899988)
		(stroke
			(width 1.524)
			(type default)
		)
		(layer "In6.Cu")
	)
	(gr_line
		(start 29.266388 -106.29265)
		(end 29.268166 -106.290872)
		(stroke
			(width 0.2)
			(type default)
		)
		(layer "In6.Cu")
	)
	(gr_line
		(start 29.268166 -106.290872)
		(end 28.477972 -105.500678)
		(stroke
			(width 0.2)
			(type default)
		)
		(layer "In6.Cu")
	)
	(gr_line
		(start 48.49368 -211.406994)
		(end 49.30648 -211.406994)
		(stroke
			(width 0.2)
			(type default)
		)
		(layer "In6.Cu")
	)
	(gr_arc
		(start 48.493934 -210.385914)
		(mid 47.98314 -210.896327)
		(end 48.49368 -211.406994)
		(stroke
			(width 0.2)
			(type default)
		)
		(layer "In6.Cu")
	)
	(gr_arc
		(start 49.30648 -211.406994)
		(mid 49.81702 -210.896454)
		(end 49.30648 -210.385914)
		(stroke
			(width 0.2)
			(type default)
		)
		(layer "In6.Cu")
	)
	(gr_line
		(start 49.30648 -210.385914)
		(end 48.493934 -210.385914)
		(stroke
			(width 0.2)
			(type default)
		)
		(layer "In6.Cu")
	)
	(gr_arc
		(start 49.950116 -26.010108)
		(mid 51.364327 -25.424323)
		(end 51.950112 -24.010112)
		(stroke
			(width 1.524)
			(type default)
		)
		(layer "In6.Cu")
	)
	(gr_line
		(start 50.093372 -221.916244)
		(end 50.905918 -221.916244)
		(stroke
			(width 0.2)
			(type default)
		)
		(layer "In6.Cu")
	)
	(gr_arc
		(start 50.093372 -220.895164)
		(mid 49.582832 -221.405704)
		(end 50.093372 -221.916244)
		(stroke
			(width 0.2)
			(type default)
		)
		(layer "In6.Cu")
	)
	(gr_line
		(start 50.14468 -209.222594)
		(end 50.95748 -209.222594)
		(stroke
			(width 0.2)
			(type default)
		)
		(layer "In6.Cu")
	)
	(gr_arc
		(start 50.144934 -208.201514)
		(mid 49.63414 -208.711927)
		(end 50.14468 -209.222594)
		(stroke
			(width 0.2)
			(type default)
		)
		(layer "In6.Cu")
	)
	(gr_arc
		(start 50.8254 -130.9624)
		(mid 50.855158 -131.034242)
		(end 50.927 -131.064)
		(stroke
			(width 0.2)
			(type default)
		)
		(layer "In6.Cu")
	)
	(gr_line
		(start 50.8254 -129.58826)
		(end 50.8254 -130.9624)
		(stroke
			(width 0.2)
			(type default)
		)
		(layer "In6.Cu")
	)
	(gr_arc
		(start 50.905918 -221.916244)
		(mid 51.416712 -221.405831)
		(end 50.906172 -220.895164)
		(stroke
			(width 0.2)
			(type default)
		)
		(layer "In6.Cu")
	)
	(gr_line
		(start 50.906172 -220.895164)
		(end 50.093372 -220.895164)
		(stroke
			(width 0.2)
			(type default)
		)
		(layer "In6.Cu")
	)
	(gr_line
		(start 50.927 -131.064)
		(end 52.1462 -131.064)
		(stroke
			(width 0.2)
			(type default)
		)
		(layer "In6.Cu")
	)
	(gr_arc
		(start 50.927 -129.48666)
		(mid 50.855158 -129.516418)
		(end 50.8254 -129.58826)
		(stroke
			(width 0.2)
			(type default)
		)
		(layer "In6.Cu")
	)
	(gr_arc
		(start 50.95748 -209.222594)
		(mid 51.46802 -208.712054)
		(end 50.95748 -208.201514)
		(stroke
			(width 0.2)
			(type default)
		)
		(layer "In6.Cu")
	)
	(gr_line
		(start 50.95748 -208.201514)
		(end 50.144934 -208.201514)
		(stroke
			(width 0.2)
			(type default)
		)
		(layer "In6.Cu")
	)
	(gr_line
		(start 51.693572 -211.406994)
		(end 52.506372 -211.406994)
		(stroke
			(width 0.2)
			(type default)
		)
		(layer "In6.Cu")
	)
	(gr_arc
		(start 51.693826 -210.385914)
		(mid 51.183032 -210.896327)
		(end 51.693572 -211.406994)
		(stroke
			(width 0.2)
			(type default)
		)
		(layer "In6.Cu")
	)
	(gr_line
		(start 51.950112 -24.010112)
		(end 51.950112 -1.999996)
		(stroke
			(width 1.524)
			(type default)
		)
		(layer "In6.Cu")
	)
	(gr_arc
		(start 52.063904 -52.197)
		(mid 52.093662 -52.268842)
		(end 52.165504 -52.2986)
		(stroke
			(width 0.2)
			(type default)
		)
		(layer "In6.Cu")
	)
	(gr_line
		(start 52.063904 -50.9778)
		(end 52.063904 -52.197)
		(stroke
			(width 0.2)
			(type default)
		)
		(layer "In6.Cu")
	)
	(gr_arc
		(start 52.1462 -131.064)
		(mid 52.218042 -131.034242)
		(end 52.2478 -130.9624)
		(stroke
			(width 0.2)
			(type default)
		)
		(layer "In6.Cu")
	)
	(gr_line
		(start 52.1462 -129.48666)
		(end 50.927 -129.48666)
		(stroke
			(width 0.2)
			(type default)
		)
		(layer "In6.Cu")
	)
	(gr_line
		(start 52.165504 -52.2986)
		(end 53.539644 -52.2986)
		(stroke
			(width 0.2)
			(type default)
		)
		(layer "In6.Cu")
	)
	(gr_arc
		(start 52.165504 -50.8762)
		(mid 52.093662 -50.905958)
		(end 52.063904 -50.9778)
		(stroke
			(width 0.2)
			(type default)
		)
		(layer "In6.Cu")
	)
	(gr_line
		(start 52.2478 -130.9624)
		(end 52.2478 -129.58826)
		(stroke
			(width 0.2)
			(type default)
		)
		(layer "In6.Cu")
	)
	(gr_arc
		(start 52.2478 -129.58826)
		(mid 52.218042 -129.516418)
		(end 52.1462 -129.48666)
		(stroke
			(width 0.2)
			(type default)
		)
		(layer "In6.Cu")
	)
	(gr_line
		(start 52.399438 -48.387508)
		(end 53.305964 -48.387508)
		(stroke
			(width 0.2)
			(type default)
		)
		(layer "In6.Cu")
	)
	(gr_arc
		(start 52.399692 -47.366428)
		(mid 51.888898 -47.876841)
		(end 52.399438 -48.387508)
		(stroke
			(width 0.2)
			(type default)
		)
		(layer "In6.Cu")
	)
	(gr_arc
		(start 52.506372 -211.406994)
		(mid 53.016912 -210.896454)
		(end 52.506372 -210.385914)
		(stroke
			(width 0.2)
			(type default)
		)
		(layer "In6.Cu")
	)
	(gr_line
		(start 52.506372 -210.385914)
		(end 51.693826 -210.385914)
		(stroke
			(width 0.2)
			(type default)
		)
		(layer "In6.Cu")
	)
	(gr_line
		(start 53.293518 -222.805244)
		(end 54.106064 -222.805244)
		(stroke
			(width 0.2)
			(type default)
		)
		(layer "In6.Cu")
	)
	(gr_arc
		(start 53.293518 -221.784164)
		(mid 52.782978 -222.294704)
		(end 53.293518 -222.805244)
		(stroke
			(width 0.2)
			(type default)
		)
		(layer "In6.Cu")
	)
	(gr_arc
		(start 53.305964 -48.387508)
		(mid 53.816504 -47.876968)
		(end 53.305964 -47.366428)
		(stroke
			(width 0.2)
			(type default)
		)
		(layer "In6.Cu")
	)
	(gr_line
		(start 53.305964 -47.366428)
		(end 52.399692 -47.366428)
		(stroke
			(width 0.2)
			(type default)
		)
		(layer "In6.Cu")
	)
	(gr_arc
		(start 53.539644 -52.2986)
		(mid 53.611486 -52.268842)
		(end 53.641244 -52.197)
		(stroke
			(width 0.2)
			(type default)
		)
		(layer "In6.Cu")
	)
	(gr_line
		(start 53.539644 -50.8762)
		(end 52.165504 -50.8762)
		(stroke
			(width 0.2)
			(type default)
		)
		(layer "In6.Cu")
	)
	(gr_line
		(start 53.641244 -52.197)
		(end 53.641244 -50.9778)
		(stroke
			(width 0.2)
			(type default)
		)
		(layer "In6.Cu")
	)
	(gr_arc
		(start 53.641244 -50.9778)
		(mid 53.611486 -50.905958)
		(end 53.539644 -50.8762)
		(stroke
			(width 0.2)
			(type default)
		)
		(layer "In6.Cu")
	)
	(gr_arc
		(start 53.950108 0)
		(mid 52.535891 -0.585782)
		(end 51.950112 -1.999996)
		(stroke
			(width 1.524)
			(type default)
		)
		(layer "In6.Cu")
	)
	(gr_line
		(start 53.950108 0)
		(end 119.637556 0)
		(stroke
			(width 1.524)
			(type default)
		)
		(layer "In6.Cu")
	)
	(gr_arc
		(start 54.106064 -222.805244)
		(mid 54.616858 -222.294831)
		(end 54.106318 -221.784164)
		(stroke
			(width 0.2)
			(type default)
		)
		(layer "In6.Cu")
	)
	(gr_line
		(start 54.106318 -221.784164)
		(end 53.293518 -221.784164)
		(stroke
			(width 0.2)
			(type default)
		)
		(layer "In6.Cu")
	)
	(gr_line
		(start 54.893718 -211.406994)
		(end 55.706264 -211.406994)
		(stroke
			(width 0.2)
			(type default)
		)
		(layer "In6.Cu")
	)
	(gr_arc
		(start 54.893718 -210.385914)
		(mid 54.383178 -210.896454)
		(end 54.893718 -211.406994)
		(stroke
			(width 0.2)
			(type default)
		)
		(layer "In6.Cu")
	)
	(gr_arc
		(start 55.6387 -86.32825)
		(mid 56.25084 -86.94039)
		(end 56.86298 -86.32825)
		(stroke
			(width 0.2)
			(type default)
		)
		(layer "In6.Cu")
	)
	(gr_line
		(start 55.6387 -85.21065)
		(end 55.6387 -86.32825)
		(stroke
			(width 0.2)
			(type default)
		)
		(layer "In6.Cu")
	)
	(gr_arc
		(start 55.706264 -211.406994)
		(mid 56.217058 -210.896581)
		(end 55.706518 -210.385914)
		(stroke
			(width 0.2)
			(type default)
		)
		(layer "In6.Cu")
	)
	(gr_line
		(start 55.706518 -210.385914)
		(end 54.893718 -210.385914)
		(stroke
			(width 0.2)
			(type default)
		)
		(layer "In6.Cu")
	)
	(gr_line
		(start 56.49341 -222.805244)
		(end 57.305956 -222.805244)
		(stroke
			(width 0.2)
			(type default)
		)
		(layer "In6.Cu")
	)
	(gr_arc
		(start 56.49341 -221.784164)
		(mid 55.98287 -222.294704)
		(end 56.49341 -222.805244)
		(stroke
			(width 0.2)
			(type default)
		)
		(layer "In6.Cu")
	)
	(gr_line
		(start 56.86298 -86.32825)
		(end 56.86298 -85.210904)
		(stroke
			(width 0.2)
			(type default)
		)
		(layer "In6.Cu")
	)
	(gr_arc
		(start 56.86298 -85.210904)
		(mid 56.250967 -84.59851)
		(end 55.6387 -85.21065)
		(stroke
			(width 0.2)
			(type default)
		)
		(layer "In6.Cu")
	)
	(gr_arc
		(start 57.305956 -222.805244)
		(mid 57.81675 -222.294831)
		(end 57.30621 -221.784164)
		(stroke
			(width 0.2)
			(type default)
		)
		(layer "In6.Cu")
	)
	(gr_line
		(start 57.30621 -221.784164)
		(end 56.49341 -221.784164)
		(stroke
			(width 0.2)
			(type default)
		)
		(layer "In6.Cu")
	)
	(gr_line
		(start 58.0517 -196.77634)
		(end 58.8645 -196.77634)
		(stroke
			(width 0.2)
			(type default)
		)
		(layer "In6.Cu")
	)
	(gr_arc
		(start 58.051954 -195.75526)
		(mid 57.54116 -196.265673)
		(end 58.0517 -196.77634)
		(stroke
			(width 0.2)
			(type default)
		)
		(layer "In6.Cu")
	)
	(gr_line
		(start 58.09361 -211.406994)
		(end 58.90641 -211.406994)
		(stroke
			(width 0.2)
			(type default)
		)
		(layer "In6.Cu")
	)
	(gr_arc
		(start 58.093864 -210.385914)
		(mid 57.58307 -210.896327)
		(end 58.09361 -211.406994)
		(stroke
			(width 0.2)
			(type default)
		)
		(layer "In6.Cu")
	)
	(gr_arc
		(start 58.8645 -196.77634)
		(mid 59.37504 -196.2658)
		(end 58.8645 -195.75526)
		(stroke
			(width 0.2)
			(type default)
		)
		(layer "In6.Cu")
	)
	(gr_line
		(start 58.8645 -195.75526)
		(end 58.051954 -195.75526)
		(stroke
			(width 0.2)
			(type default)
		)
		(layer "In6.Cu")
	)
	(gr_arc
		(start 58.90641 -211.406994)
		(mid 59.41695 -210.896454)
		(end 58.90641 -210.385914)
		(stroke
			(width 0.2)
			(type default)
		)
		(layer "In6.Cu")
	)
	(gr_line
		(start 58.90641 -210.385914)
		(end 58.093864 -210.385914)
		(stroke
			(width 0.2)
			(type default)
		)
		(layer "In6.Cu")
	)
	(gr_line
		(start 59.693302 -222.805244)
		(end 60.505848 -222.805244)
		(stroke
			(width 0.2)
			(type default)
		)
		(layer "In6.Cu")
	)
	(gr_arc
		(start 59.693302 -221.784164)
		(mid 59.182762 -222.294704)
		(end 59.693302 -222.805244)
		(stroke
			(width 0.2)
			(type default)
		)
		(layer "In6.Cu")
	)
	(gr_arc
		(start 60.505848 -222.805244)
		(mid 61.016642 -222.294831)
		(end 60.506102 -221.784164)
		(stroke
			(width 0.2)
			(type default)
		)
		(layer "In6.Cu")
	)
	(gr_line
		(start 60.506102 -221.784164)
		(end 59.693302 -221.784164)
		(stroke
			(width 0.2)
			(type default)
		)
		(layer "In6.Cu")
	)
	(gr_line
		(start 63.693548 -211.406994)
		(end 64.506348 -211.406994)
		(stroke
			(width 0.2)
			(type default)
		)
		(layer "In6.Cu")
	)
	(gr_arc
		(start 63.693802 -210.385914)
		(mid 63.183008 -210.896327)
		(end 63.693548 -211.406994)
		(stroke
			(width 0.2)
			(type default)
		)
		(layer "In6.Cu")
	)
	(gr_arc
		(start 64.506348 -211.406994)
		(mid 65.016888 -210.896454)
		(end 64.506348 -210.385914)
		(stroke
			(width 0.2)
			(type default)
		)
		(layer "In6.Cu")
	)
	(gr_line
		(start 64.506348 -210.385914)
		(end 63.693802 -210.385914)
		(stroke
			(width 0.2)
			(type default)
		)
		(layer "In6.Cu")
	)
	(gr_line
		(start 65.293494 -222.805244)
		(end 66.10604 -222.805244)
		(stroke
			(width 0.2)
			(type default)
		)
		(layer "In6.Cu")
	)
	(gr_arc
		(start 65.293494 -221.784164)
		(mid 64.782954 -222.294704)
		(end 65.293494 -222.805244)
		(stroke
			(width 0.2)
			(type default)
		)
		(layer "In6.Cu")
	)
	(gr_line
		(start 65.330578 -128.189736)
		(end 66.143378 -128.189736)
		(stroke
			(width 0.2)
			(type default)
		)
		(layer "In6.Cu")
	)
	(gr_arc
		(start 65.330832 -127.168656)
		(mid 64.820038 -127.679069)
		(end 65.330578 -128.189736)
		(stroke
			(width 0.2)
			(type default)
		)
		(layer "In6.Cu")
	)
	(gr_arc
		(start 66.10604 -222.805244)
		(mid 66.616834 -222.294831)
		(end 66.106294 -221.784164)
		(stroke
			(width 0.2)
			(type default)
		)
		(layer "In6.Cu")
	)
	(gr_line
		(start 66.106294 -221.784164)
		(end 65.293494 -221.784164)
		(stroke
			(width 0.2)
			(type default)
		)
		(layer "In6.Cu")
	)
	(gr_arc
		(start 66.143378 -128.189736)
		(mid 66.653918 -127.679196)
		(end 66.143378 -127.168656)
		(stroke
			(width 0.2)
			(type default)
		)
		(layer "In6.Cu")
	)
	(gr_line
		(start 66.143378 -127.168656)
		(end 65.330832 -127.168656)
		(stroke
			(width 0.2)
			(type default)
		)
		(layer "In6.Cu")
	)
	(gr_line
		(start 66.893694 -211.406994)
		(end 67.706494 -211.406994)
		(stroke
			(width 0.2)
			(type default)
		)
		(layer "In6.Cu")
	)
	(gr_arc
		(start 66.893948 -210.385914)
		(mid 66.383154 -210.896327)
		(end 66.893694 -211.406994)
		(stroke
			(width 0.2)
			(type default)
		)
		(layer "In6.Cu")
	)
	(gr_arc
		(start 67.706494 -211.406994)
		(mid 68.217034 -210.896454)
		(end 67.706494 -210.385914)
		(stroke
			(width 0.2)
			(type default)
		)
		(layer "In6.Cu")
	)
	(gr_line
		(start 67.706494 -210.385914)
		(end 66.893948 -210.385914)
		(stroke
			(width 0.2)
			(type default)
		)
		(layer "In6.Cu")
	)
	(gr_line
		(start 68.493386 -222.805244)
		(end 69.305932 -222.805244)
		(stroke
			(width 0.2)
			(type default)
		)
		(layer "In6.Cu")
	)
	(gr_arc
		(start 68.493386 -221.784164)
		(mid 67.982846 -222.294704)
		(end 68.493386 -222.805244)
		(stroke
			(width 0.2)
			(type default)
		)
		(layer "In6.Cu")
	)
	(gr_arc
		(start 69.305932 -222.805244)
		(mid 69.816726 -222.294831)
		(end 69.306186 -221.784164)
		(stroke
			(width 0.2)
			(type default)
		)
		(layer "In6.Cu")
	)
	(gr_line
		(start 69.306186 -221.784164)
		(end 68.493386 -221.784164)
		(stroke
			(width 0.2)
			(type default)
		)
		(layer "In6.Cu")
	)
	(gr_line
		(start 70.093586 -211.406994)
		(end 70.906386 -211.406994)
		(stroke
			(width 0.2)
			(type default)
		)
		(layer "In6.Cu")
	)
	(gr_arc
		(start 70.09384 -210.385914)
		(mid 69.583046 -210.896327)
		(end 70.093586 -211.406994)
		(stroke
			(width 0.2)
			(type default)
		)
		(layer "In6.Cu")
	)
	(gr_arc
		(start 70.906386 -211.406994)
		(mid 71.416926 -210.896454)
		(end 70.906386 -210.385914)
		(stroke
			(width 0.2)
			(type default)
		)
		(layer "In6.Cu")
	)
	(gr_line
		(start 70.906386 -210.385914)
		(end 70.09384 -210.385914)
		(stroke
			(width 0.2)
			(type default)
		)
		(layer "In6.Cu")
	)
	(gr_line
		(start 71.7042 -220.52534)
		(end 72.516746 -220.52534)
		(stroke
			(width 0.2)
			(type default)
		)
		(layer "In6.Cu")
	)
	(gr_arc
		(start 71.7042 -219.50426)
		(mid 71.19366 -220.0148)
		(end 71.7042 -220.52534)
		(stroke
			(width 0.2)
			(type default)
		)
		(layer "In6.Cu")
	)
	(gr_arc
		(start 72.516746 -220.52534)
		(mid 73.02754 -220.014927)
		(end 72.517 -219.50426)
		(stroke
			(width 0.2)
			(type default)
		)
		(layer "In6.Cu")
	)
	(gr_line
		(start 72.517 -219.50426)
		(end 71.7042 -219.50426)
		(stroke
			(width 0.2)
			(type default)
		)
		(layer "In6.Cu")
	)
	(gr_line
		(start 74.099928 -228.000052)
		(end 28.50007 -228.000052)
		(stroke
			(width 5.08)
			(type default)
		)
		(layer "In6.Cu")
	)
	(gr_line
		(start 74.099928 -222.600012)
		(end 74.099928 -228.000052)
		(stroke
			(width 1.524)
			(type default)
		)
		(layer "In6.Cu")
	)
	(gr_line
		(start 76.499974 -228.000052)
		(end 76.499974 -222.600012)
		(stroke
			(width 1.524)
			(type default)
		)
		(layer "In6.Cu")
	)
	(gr_arc
		(start 76.499974 -222.600012)
		(mid 75.300078 -221.400116)
		(end 74.099928 -222.600012)
		(stroke
			(width 1.524)
			(type default)
		)
		(layer "In6.Cu")
	)
	(gr_line
		(start 78.16977 -220.392244)
		(end 78.982316 -220.392244)
		(stroke
			(width 0.2)
			(type default)
		)
		(layer "In6.Cu")
	)
	(gr_arc
		(start 78.16977 -219.371164)
		(mid 77.65923 -219.881704)
		(end 78.16977 -220.392244)
		(stroke
			(width 0.2)
			(type default)
		)
		(layer "In6.Cu")
	)
	(gr_arc
		(start 78.982316 -220.392244)
		(mid 79.49311 -219.881831)
		(end 78.98257 -219.371164)
		(stroke
			(width 0.2)
			(type default)
		)
		(layer "In6.Cu")
	)
	(gr_line
		(start 78.98257 -219.371164)
		(end 78.16977 -219.371164)
		(stroke
			(width 0.2)
			(type default)
		)
		(layer "In6.Cu")
	)
	(gr_line
		(start 79.693516 -211.406994)
		(end 80.506316 -211.406994)
		(stroke
			(width 0.2)
			(type default)
		)
		(layer "In6.Cu")
	)
	(gr_arc
		(start 79.69377 -210.385914)
		(mid 79.182976 -210.896327)
		(end 79.693516 -211.406994)
		(stroke
			(width 0.2)
			(type default)
		)
		(layer "In6.Cu")
	)
	(gr_arc
		(start 80.506316 -211.406994)
		(mid 81.016856 -210.896454)
		(end 80.506316 -210.385914)
		(stroke
			(width 0.2)
			(type default)
		)
		(layer "In6.Cu")
	)
	(gr_line
		(start 80.506316 -210.385914)
		(end 79.69377 -210.385914)
		(stroke
			(width 0.2)
			(type default)
		)
		(layer "In6.Cu")
	)
	(gr_line
		(start 81.293462 -222.805244)
		(end 82.106008 -222.805244)
		(stroke
			(width 0.2)
			(type default)
		)
		(layer "In6.Cu")
	)
	(gr_arc
		(start 81.293462 -221.784164)
		(mid 80.782922 -222.294704)
		(end 81.293462 -222.805244)
		(stroke
			(width 0.2)
			(type default)
		)
		(layer "In6.Cu")
	)
	(gr_arc
		(start 82.106008 -222.805244)
		(mid 82.616802 -222.294831)
		(end 82.106262 -221.784164)
		(stroke
			(width 0.2)
			(type default)
		)
		(layer "In6.Cu")
	)
	(gr_line
		(start 82.106262 -221.784164)
		(end 81.293462 -221.784164)
		(stroke
			(width 0.2)
			(type default)
		)
		(layer "In6.Cu")
	)
	(gr_line
		(start 82.893662 -211.406994)
		(end 83.706462 -211.406994)
		(stroke
			(width 0.2)
			(type default)
		)
		(layer "In6.Cu")
	)
	(gr_arc
		(start 82.893916 -210.385914)
		(mid 82.383122 -210.896327)
		(end 82.893662 -211.406994)
		(stroke
			(width 0.2)
			(type default)
		)
		(layer "In6.Cu")
	)
	(gr_arc
		(start 83.706462 -211.406994)
		(mid 84.217002 -210.896454)
		(end 83.706462 -210.385914)
		(stroke
			(width 0.2)
			(type default)
		)
		(layer "In6.Cu")
	)
	(gr_line
		(start 83.706462 -210.385914)
		(end 82.893916 -210.385914)
		(stroke
			(width 0.2)
			(type default)
		)
		(layer "In6.Cu")
	)
	(gr_line
		(start 84.493354 -222.805244)
		(end 85.3059 -222.805244)
		(stroke
			(width 0.2)
			(type default)
		)
		(layer "In6.Cu")
	)
	(gr_arc
		(start 84.493354 -221.784164)
		(mid 83.982814 -222.294704)
		(end 84.493354 -222.805244)
		(stroke
			(width 0.2)
			(type default)
		)
		(layer "In6.Cu")
	)
	(gr_arc
		(start 85.3059 -222.805244)
		(mid 85.816694 -222.294831)
		(end 85.306154 -221.784164)
		(stroke
			(width 0.2)
			(type default)
		)
		(layer "In6.Cu")
	)
	(gr_line
		(start 85.306154 -221.784164)
		(end 84.493354 -221.784164)
		(stroke
			(width 0.2)
			(type default)
		)
		(layer "In6.Cu")
	)
	(gr_line
		(start 86.093554 -211.406994)
		(end 86.906354 -211.406994)
		(stroke
			(width 0.2)
			(type default)
		)
		(layer "In6.Cu")
	)
	(gr_arc
		(start 86.093808 -210.385914)
		(mid 85.583014 -210.896327)
		(end 86.093554 -211.406994)
		(stroke
			(width 0.2)
			(type default)
		)
		(layer "In6.Cu")
	)
	(gr_arc
		(start 86.269068 -77.478382)
		(mid 86.779481 -77.989176)
		(end 87.290148 -77.478636)
		(stroke
			(width 0.2)
			(type default)
		)
		(layer "In6.Cu")
	)
	(gr_line
		(start 86.269068 -76.589636)
		(end 86.269068 -77.478382)
		(stroke
			(width 0.2)
			(type default)
		)
		(layer "In6.Cu")
	)
	(gr_arc
		(start 86.906354 -211.406994)
		(mid 87.416894 -210.896454)
		(end 86.906354 -210.385914)
		(stroke
			(width 0.2)
			(type default)
		)
		(layer "In6.Cu")
	)
	(gr_line
		(start 86.906354 -210.385914)
		(end 86.093808 -210.385914)
		(stroke
			(width 0.2)
			(type default)
		)
		(layer "In6.Cu")
	)
	(gr_line
		(start 87.290148 -77.478636)
		(end 87.290148 -76.589636)
		(stroke
			(width 0.2)
			(type default)
		)
		(layer "In6.Cu")
	)
	(gr_arc
		(start 87.290148 -76.589636)
		(mid 86.779608 -76.079096)
		(end 86.269068 -76.589636)
		(stroke
			(width 0.2)
			(type default)
		)
		(layer "In6.Cu")
	)
	(gr_line
		(start 87.6935 -222.805244)
		(end 88.506046 -222.805244)
		(stroke
			(width 0.2)
			(type default)
		)
		(layer "In6.Cu")
	)
	(gr_arc
		(start 87.6935 -221.784164)
		(mid 87.18296 -222.294704)
		(end 87.6935 -222.805244)
		(stroke
			(width 0.2)
			(type default)
		)
		(layer "In6.Cu")
	)
	(gr_arc
		(start 88.506046 -222.805244)
		(mid 89.01684 -222.294831)
		(end 88.5063 -221.784164)
		(stroke
			(width 0.2)
			(type default)
		)
		(layer "In6.Cu")
	)
	(gr_line
		(start 88.5063 -221.784164)
		(end 87.6935 -221.784164)
		(stroke
			(width 0.2)
			(type default)
		)
		(layer "In6.Cu")
	)
	(gr_line
		(start 89.2937 -211.406994)
		(end 90.1065 -211.406994)
		(stroke
			(width 0.2)
			(type default)
		)
		(layer "In6.Cu")
	)
	(gr_arc
		(start 89.293954 -210.385914)
		(mid 88.78316 -210.896327)
		(end 89.2937 -211.406994)
		(stroke
			(width 0.2)
			(type default)
		)
		(layer "In6.Cu")
	)
	(gr_arc
		(start 90.1065 -211.406994)
		(mid 90.61704 -210.896454)
		(end 90.1065 -210.385914)
		(stroke
			(width 0.2)
			(type default)
		)
		(layer "In6.Cu")
	)
	(gr_line
		(start 90.1065 -210.385914)
		(end 89.293954 -210.385914)
		(stroke
			(width 0.2)
			(type default)
		)
		(layer "In6.Cu")
	)
	(gr_line
		(start 90.893392 -222.805244)
		(end 91.705938 -222.805244)
		(stroke
			(width 0.2)
			(type default)
		)
		(layer "In6.Cu")
	)
	(gr_arc
		(start 90.893392 -221.784164)
		(mid 90.382852 -222.294704)
		(end 90.893392 -222.805244)
		(stroke
			(width 0.2)
			(type default)
		)
		(layer "In6.Cu")
	)
	(gr_line
		(start 91.608402 -185.665364)
		(end 92.18295 -186.240166)
		(stroke
			(width 0.2)
			(type default)
		)
		(layer "In6.Cu")
	)
	(gr_line
		(start 91.61018 -185.663586)
		(end 91.608402 -185.665364)
		(stroke
			(width 0.2)
			(type default)
		)
		(layer "In6.Cu")
	)
	(gr_arc
		(start 91.705938 -222.805244)
		(mid 92.216732 -222.294831)
		(end 91.706192 -221.784164)
		(stroke
			(width 0.2)
			(type default)
		)
		(layer "In6.Cu")
	)
	(gr_line
		(start 91.706192 -221.784164)
		(end 90.893392 -221.784164)
		(stroke
			(width 0.2)
			(type default)
		)
		(layer "In6.Cu")
	)
	(gr_line
		(start 92.18295 -186.240166)
		(end 92.183204 -186.240166)
		(stroke
			(width 0.2)
			(type default)
		)
		(layer "In6.Cu")
	)
	(gr_line
		(start 92.183204 -186.240166)
		(end 92.184982 -186.238388)
		(stroke
			(width 0.2)
			(type default)
		)
		(layer "In6.Cu")
	)
	(gr_arc
		(start 92.184982 -186.238388)
		(mid 92.90685 -186.238388)
		(end 92.90685 -185.51652)
		(stroke
			(width 0.2)
			(type default)
		)
		(layer "In6.Cu")
	)
	(gr_arc
		(start 92.332048 -184.941718)
		(mid 91.61018 -184.941718)
		(end 91.61018 -185.663586)
		(stroke
			(width 0.2)
			(type default)
		)
		(layer "In6.Cu")
	)
	(gr_line
		(start 92.333826 -184.93994)
		(end 92.332048 -184.941718)
		(stroke
			(width 0.2)
			(type default)
		)
		(layer "In6.Cu")
	)
	(gr_line
		(start 92.493592 -211.406994)
		(end 93.306392 -211.406994)
		(stroke
			(width 0.2)
			(type default)
		)
		(layer "In6.Cu")
	)
	(gr_arc
		(start 92.493846 -210.385914)
		(mid 91.983052 -210.896327)
		(end 92.493592 -211.406994)
		(stroke
			(width 0.2)
			(type default)
		)
		(layer "In6.Cu")
	)
	(gr_line
		(start 92.90685 -185.51652)
		(end 92.908628 -185.514742)
		(stroke
			(width 0.2)
			(type default)
		)
		(layer "In6.Cu")
	)
	(gr_line
		(start 92.908628 -185.514742)
		(end 92.333826 -184.93994)
		(stroke
			(width 0.2)
			(type default)
		)
		(layer "In6.Cu")
	)
	(gr_arc
		(start 93.306392 -211.406994)
		(mid 93.816932 -210.896454)
		(end 93.306392 -210.385914)
		(stroke
			(width 0.2)
			(type default)
		)
		(layer "In6.Cu")
	)
	(gr_line
		(start 93.306392 -210.385914)
		(end 92.493846 -210.385914)
		(stroke
			(width 0.2)
			(type default)
		)
		(layer "In6.Cu")
	)
	(gr_line
		(start 93.38945 -184.15254)
		(end 94.201996 -184.15254)
		(stroke
			(width 0.2)
			(type default)
		)
		(layer "In6.Cu")
	)
	(gr_arc
		(start 93.38945 -183.13146)
		(mid 92.87891 -183.642)
		(end 93.38945 -184.15254)
		(stroke
			(width 0.2)
			(type default)
		)
		(layer "In6.Cu")
	)
	(gr_arc
		(start 94.201996 -184.15254)
		(mid 94.71279 -183.642127)
		(end 94.20225 -183.13146)
		(stroke
			(width 0.2)
			(type default)
		)
		(layer "In6.Cu")
	)
	(gr_line
		(start 94.20225 -183.13146)
		(end 93.38945 -183.13146)
		(stroke
			(width 0.2)
			(type default)
		)
		(layer "In6.Cu")
	)
	(gr_line
		(start 96.493584 -222.805244)
		(end 97.30613 -222.805244)
		(stroke
			(width 0.2)
			(type default)
		)
		(layer "In6.Cu")
	)
	(gr_arc
		(start 96.493584 -221.784164)
		(mid 95.983044 -222.294704)
		(end 96.493584 -222.805244)
		(stroke
			(width 0.2)
			(type default)
		)
		(layer "In6.Cu")
	)
	(gr_arc
		(start 97.30613 -222.805244)
		(mid 97.816924 -222.294831)
		(end 97.306384 -221.784164)
		(stroke
			(width 0.2)
			(type default)
		)
		(layer "In6.Cu")
	)
	(gr_line
		(start 97.306384 -221.784164)
		(end 96.493584 -221.784164)
		(stroke
			(width 0.2)
			(type default)
		)
		(layer "In6.Cu")
	)
	(gr_line
		(start 98.093784 -211.406994)
		(end 98.906584 -211.406994)
		(stroke
			(width 0.2)
			(type default)
		)
		(layer "In6.Cu")
	)
	(gr_arc
		(start 98.094038 -210.385914)
		(mid 97.583244 -210.896327)
		(end 98.093784 -211.406994)
		(stroke
			(width 0.2)
			(type default)
		)
		(layer "In6.Cu")
	)
	(gr_arc
		(start 98.906584 -211.406994)
		(mid 99.417124 -210.896454)
		(end 98.906584 -210.385914)
		(stroke
			(width 0.2)
			(type default)
		)
		(layer "In6.Cu")
	)
	(gr_line
		(start 98.906584 -210.385914)
		(end 98.094038 -210.385914)
		(stroke
			(width 0.2)
			(type default)
		)
		(layer "In6.Cu")
	)
	(gr_line
		(start 99.693476 -222.805244)
		(end 100.506022 -222.805244)
		(stroke
			(width 0.2)
			(type default)
		)
		(layer "In6.Cu")
	)
	(gr_arc
		(start 99.693476 -221.784164)
		(mid 99.182936 -222.294704)
		(end 99.693476 -222.805244)
		(stroke
			(width 0.2)
			(type default)
		)
		(layer "In6.Cu")
	)
	(gr_arc
		(start 100.506022 -222.805244)
		(mid 101.016816 -222.294831)
		(end 100.506276 -221.784164)
		(stroke
			(width 0.2)
			(type default)
		)
		(layer "In6.Cu")
	)
	(gr_line
		(start 100.506276 -221.784164)
		(end 99.693476 -221.784164)
		(stroke
			(width 0.2)
			(type default)
		)
		(layer "In6.Cu")
	)
	(gr_line
		(start 101.293676 -211.406994)
		(end 102.106222 -211.406994)
		(stroke
			(width 0.2)
			(type default)
		)
		(layer "In6.Cu")
	)
	(gr_arc
		(start 101.293676 -210.385914)
		(mid 100.783136 -210.896454)
		(end 101.293676 -211.406994)
		(stroke
			(width 0.2)
			(type default)
		)
		(layer "In6.Cu")
	)
	(gr_arc
		(start 101.41966 -39.80561)
		(mid 101.9302 -40.31615)
		(end 102.44074 -39.80561)
		(stroke
			(width 0.2)
			(type default)
		)
		(layer "In6.Cu")
	)
	(gr_line
		(start 101.41966 -38.91661)
		(end 101.41966 -39.80561)
		(stroke
			(width 0.2)
			(type default)
		)
		(layer "In6.Cu")
	)
	(gr_arc
		(start 102.00386 -37.094414)
		(mid 102.514273 -37.605208)
		(end 103.02494 -37.094668)
		(stroke
			(width 0.2)
			(type default)
		)
		(layer "In6.Cu")
	)
	(gr_line
		(start 102.00386 -36.205668)
		(end 102.00386 -37.094414)
		(stroke
			(width 0.2)
			(type default)
		)
		(layer "In6.Cu")
	)
	(gr_arc
		(start 102.01402 -82.1182)
		(mid 102.62616 -82.73034)
		(end 103.2383 -82.1182)
		(stroke
			(width 0.2)
			(type default)
		)
		(layer "In6.Cu")
	)
	(gr_line
		(start 102.01402 -81.0006)
		(end 102.01402 -82.1182)
		(stroke
			(width 0.2)
			(type default)
		)
		(layer "In6.Cu")
	)
	(gr_arc
		(start 102.106222 -211.406994)
		(mid 102.617016 -210.896581)
		(end 102.106476 -210.385914)
		(stroke
			(width 0.2)
			(type default)
		)
		(layer "In6.Cu")
	)
	(gr_line
		(start 102.106476 -210.385914)
		(end 101.293676 -210.385914)
		(stroke
			(width 0.2)
			(type default)
		)
		(layer "In6.Cu")
	)
	(gr_line
		(start 102.44074 -39.80561)
		(end 102.44074 -38.916864)
		(stroke
			(width 0.2)
			(type default)
		)
		(layer "In6.Cu")
	)
	(gr_arc
		(start 102.44074 -38.916864)
		(mid 101.930327 -38.40607)
		(end 101.41966 -38.91661)
		(stroke
			(width 0.2)
			(type default)
		)
		(layer "In6.Cu")
	)
	(gr_line
		(start 102.893368 -222.805244)
		(end 103.705914 -222.805244)
		(stroke
			(width 0.2)
			(type default)
		)
		(layer "In6.Cu")
	)
	(gr_arc
		(start 102.893368 -221.784164)
		(mid 102.382828 -222.294704)
		(end 102.893368 -222.805244)
		(stroke
			(width 0.2)
			(type default)
		)
		(layer "In6.Cu")
	)
	(gr_line
		(start 103.02494 -37.094668)
		(end 103.02494 -36.205668)
		(stroke
			(width 0.2)
			(type default)
		)
		(layer "In6.Cu")
	)
	(gr_arc
		(start 103.02494 -36.205668)
		(mid 102.5144 -35.695128)
		(end 102.00386 -36.205668)
		(stroke
			(width 0.2)
			(type default)
		)
		(layer "In6.Cu")
	)
	(gr_line
		(start 103.2383 -82.1182)
		(end 103.2383 -81.000854)
		(stroke
			(width 0.2)
			(type default)
		)
		(layer "In6.Cu")
	)
	(gr_arc
		(start 103.2383 -81.000854)
		(mid 102.626287 -80.38846)
		(end 102.01402 -81.0006)
		(stroke
			(width 0.2)
			(type default)
		)
		(layer "In6.Cu")
	)
	(gr_arc
		(start 103.705914 -222.805244)
		(mid 104.216708 -222.294831)
		(end 103.706168 -221.784164)
		(stroke
			(width 0.2)
			(type default)
		)
		(layer "In6.Cu")
	)
	(gr_line
		(start 103.706168 -221.784164)
		(end 102.893368 -221.784164)
		(stroke
			(width 0.2)
			(type default)
		)
		(layer "In6.Cu")
	)
	(gr_line
		(start 104.493822 -211.406994)
		(end 105.306622 -211.406994)
		(stroke
			(width 0.2)
			(type default)
		)
		(layer "In6.Cu")
	)
	(gr_arc
		(start 104.494076 -210.385914)
		(mid 103.983282 -210.896327)
		(end 104.493822 -211.406994)
		(stroke
			(width 0.2)
			(type default)
		)
		(layer "In6.Cu")
	)
	(gr_arc
		(start 105.306622 -211.406994)
		(mid 105.817162 -210.896454)
		(end 105.306622 -210.385914)
		(stroke
			(width 0.2)
			(type default)
		)
		(layer "In6.Cu")
	)
	(gr_line
		(start 105.306622 -210.385914)
		(end 104.494076 -210.385914)
		(stroke
			(width 0.2)
			(type default)
		)
		(layer "In6.Cu")
	)
	(gr_line
		(start 106.093514 -222.805244)
		(end 106.90606 -222.805244)
		(stroke
			(width 0.2)
			(type default)
		)
		(layer "In6.Cu")
	)
	(gr_arc
		(start 106.093514 -221.784164)
		(mid 105.582974 -222.294704)
		(end 106.093514 -222.805244)
		(stroke
			(width 0.2)
			(type default)
		)
		(layer "In6.Cu")
	)
	(gr_arc
		(start 106.90606 -222.805244)
		(mid 107.416854 -222.294831)
		(end 106.906314 -221.784164)
		(stroke
			(width 0.2)
			(type default)
		)
		(layer "In6.Cu")
	)
	(gr_line
		(start 106.906314 -221.784164)
		(end 106.093514 -221.784164)
		(stroke
			(width 0.2)
			(type default)
		)
		(layer "In6.Cu")
	)
	(gr_line
		(start 107.693714 -211.406994)
		(end 108.506514 -211.406994)
		(stroke
			(width 0.2)
			(type default)
		)
		(layer "In6.Cu")
	)
	(gr_arc
		(start 107.693968 -210.385914)
		(mid 107.183174 -210.896327)
		(end 107.693714 -211.406994)
		(stroke
			(width 0.2)
			(type default)
		)
		(layer "In6.Cu")
	)
	(gr_arc
		(start 108.506514 -211.406994)
		(mid 109.017054 -210.896454)
		(end 108.506514 -210.385914)
		(stroke
			(width 0.2)
			(type default)
		)
		(layer "In6.Cu")
	)
	(gr_line
		(start 108.506514 -210.385914)
		(end 107.693968 -210.385914)
		(stroke
			(width 0.2)
			(type default)
		)
		(layer "In6.Cu")
	)
	(gr_line
		(start 112.499902 -228.000052)
		(end 76.499974 -228.000052)
		(stroke
			(width 5.08)
			(type default)
		)
		(layer "In6.Cu")
	)
	(gr_line
		(start 112.499902 -222.400114)
		(end 112.499902 -228.000052)
		(stroke
			(width 1.524)
			(type default)
		)
		(layer "In6.Cu")
	)
	(gr_arc
		(start 113.000028 -221.899988)
		(mid 112.646386 -222.046472)
		(end 112.499902 -222.400114)
		(stroke
			(width 1.524)
			(type default)
		)
		(layer "In6.Cu")
	)
	(gr_line
		(start 113.799874 -221.899988)
		(end 113.000028 -221.899988)
		(stroke
			(width 1.524)
			(type default)
		)
		(layer "In6.Cu")
	)
	(gr_arc
		(start 113.799874 -221.899988)
		(mid 114.153489 -221.75366)
		(end 114.3 -221.400116)
		(stroke
			(width 1.524)
			(type default)
		)
		(layer "In6.Cu")
	)
	(gr_line
		(start 114.3 -214.799926)
		(end 114.3 -221.400116)
		(stroke
			(width 1.524)
			(type default)
		)
		(layer "In6.Cu")
	)
	(gr_arc
		(start 115.599972 -213.499954)
		(mid 114.680753 -213.880707)
		(end 114.3 -214.799926)
		(stroke
			(width 1.524)
			(type default)
		)
		(layer "In6.Cu")
	)
	(gr_arc
		(start 119.637556 0)
		(mid 121.051767 0.585785)
		(end 121.637552 1.999996)
		(stroke
			(width 1.524)
			(type default)
		)
		(layer "In6.Cu")
	)
	(gr_line
		(start 121.637552 1.999996)
		(end 121.637552 2.999994)
		(stroke
			(width 1.524)
			(type default)
		)
		(layer "In6.Cu")
	)
	(gr_arc
		(start 123.637548 4.99999)
		(mid 122.223308 4.414221)
		(end 121.637552 2.999994)
		(stroke
			(width 1.524)
			(type default)
		)
		(layer "In6.Cu")
	)
	(gr_line
		(start 123.637548 4.99999)
		(end 330.74991 4.99999)
		(stroke
			(width 1.524)
			(type default)
		)
		(layer "In6.Cu")
	)
	(gr_line
		(start 131.0894 -35.783774)
		(end 131.9022 -35.783774)
		(stroke
			(width 0.2)
			(type default)
		)
		(layer "In6.Cu")
	)
	(gr_arc
		(start 131.089654 -34.762694)
		(mid 130.57886 -35.273107)
		(end 131.0894 -35.783774)
		(stroke
			(width 0.2)
			(type default)
		)
		(layer "In6.Cu")
	)
	(gr_arc
		(start 131.134104 -42.7228)
		(mid 131.746244 -43.33494)
		(end 132.358384 -42.7228)
		(stroke
			(width 0.2)
			(type default)
		)
		(layer "In6.Cu")
	)
	(gr_line
		(start 131.134104 -41.6052)
		(end 131.134104 -42.7228)
		(stroke
			(width 0.2)
			(type default)
		)
		(layer "In6.Cu")
	)
	(gr_line
		(start 131.400042 -213.499954)
		(end 115.599972 -213.499954)
		(stroke
			(width 1.524)
			(type default)
		)
		(layer "In6.Cu")
	)
	(gr_arc
		(start 131.9022 -35.783774)
		(mid 132.41274 -35.273234)
		(end 131.9022 -34.762694)
		(stroke
			(width 0.2)
			(type default)
		)
		(layer "In6.Cu")
	)
	(gr_line
		(start 131.9022 -34.762694)
		(end 131.089654 -34.762694)
		(stroke
			(width 0.2)
			(type default)
		)
		(layer "In6.Cu")
	)
	(gr_line
		(start 132.358384 -42.7228)
		(end 132.358384 -41.605454)
		(stroke
			(width 0.2)
			(type default)
		)
		(layer "In6.Cu")
	)
	(gr_arc
		(start 132.358384 -41.605454)
		(mid 131.746371 -40.99306)
		(end 131.134104 -41.6052)
		(stroke
			(width 0.2)
			(type default)
		)
		(layer "In6.Cu")
	)
	(gr_line
		(start 132.581396 -25.033732)
		(end 132.58165 -25.033986)
		(stroke
			(width 0.2)
			(type default)
		)
		(layer "In6.Cu")
	)
	(gr_line
		(start 132.581396 -13.633958)
		(end 132.583428 -13.635228)
		(stroke
			(width 0.2)
			(type default)
		)
		(layer "In6.Cu")
	)
	(gr_line
		(start 132.58165 -25.033986)
		(end 132.583682 -25.035002)
		(stroke
			(width 0.2)
			(type default)
		)
		(layer "In6.Cu")
	)
	(gr_arc
		(start 132.583428 -13.635228)
		(mid 132.83946 -14.481048)
		(end 133.68528 -14.225016)
		(stroke
			(width 0.2)
			(type default)
		)
		(layer "In6.Cu")
	)
	(gr_arc
		(start 132.583682 -25.035002)
		(mid 132.839358 -25.880903)
		(end 133.68528 -25.625044)
		(stroke
			(width 0.2)
			(type default)
		)
		(layer "In6.Cu")
	)
	(gr_line
		(start 132.700014 -221.400116)
		(end 132.700014 -214.799926)
		(stroke
			(width 1.524)
			(type default)
		)
		(layer "In6.Cu")
	)
	(gr_arc
		(start 132.700014 -221.400116)
		(mid 132.846428 -221.753573)
		(end 133.199886 -221.899988)
		(stroke
			(width 1.524)
			(type default)
		)
		(layer "In6.Cu")
	)
	(gr_arc
		(start 132.700014 -214.799926)
		(mid 132.319261 -213.880707)
		(end 131.400042 -213.499954)
		(stroke
			(width 1.524)
			(type default)
		)
		(layer "In6.Cu")
	)
	(gr_line
		(start 133.331458 -23.633938)
		(end 132.581396 -25.033732)
		(stroke
			(width 0.2)
			(type default)
		)
		(layer "In6.Cu")
	)
	(gr_line
		(start 133.331458 -12.23391)
		(end 132.581396 -13.633958)
		(stroke
			(width 0.2)
			(type default)
		)
		(layer "In6.Cu")
	)
	(gr_line
		(start 133.33349 -23.635208)
		(end 133.331458 -23.633938)
		(stroke
			(width 0.2)
			(type default)
		)
		(layer "In6.Cu")
	)
	(gr_line
		(start 133.33349 -12.23518)
		(end 133.331458 -12.23391)
		(stroke
			(width 0.2)
			(type default)
		)
		(layer "In6.Cu")
	)
	(gr_line
		(start 133.68528 -25.625044)
		(end 133.687312 -25.626314)
		(stroke
			(width 0.2)
			(type default)
		)
		(layer "In6.Cu")
	)
	(gr_line
		(start 133.68528 -14.225016)
		(end 133.687312 -14.226286)
		(stroke
			(width 0.2)
			(type default)
		)
		(layer "In6.Cu")
	)
	(gr_line
		(start 133.687312 -25.626314)
		(end 134.437374 -24.226266)
		(stroke
			(width 0.2)
			(type default)
		)
		(layer "In6.Cu")
	)
	(gr_line
		(start 133.687312 -14.226286)
		(end 134.437374 -12.826492)
		(stroke
			(width 0.2)
			(type default)
		)
		(layer "In6.Cu")
	)
	(gr_line
		(start 133.852158 -36.250372)
		(end 134.664704 -36.250372)
		(stroke
			(width 0.2)
			(type default)
		)
		(layer "In6.Cu")
	)
	(gr_arc
		(start 133.852158 -35.229292)
		(mid 133.341618 -35.739832)
		(end 133.852158 -36.250372)
		(stroke
			(width 0.2)
			(type default)
		)
		(layer "In6.Cu")
	)
	(gr_line
		(start 133.999986 -221.899988)
		(end 133.199886 -221.899988)
		(stroke
			(width 1.524)
			(type default)
		)
		(layer "In6.Cu")
	)
	(gr_arc
		(start 134.435088 -12.825222)
		(mid 134.179412 -11.979321)
		(end 133.33349 -12.23518)
		(stroke
			(width 0.2)
			(type default)
		)
		(layer "In6.Cu")
	)
	(gr_arc
		(start 134.435342 -24.224996)
		(mid 134.17931 -23.379176)
		(end 133.33349 -23.635208)
		(stroke
			(width 0.2)
			(type default)
		)
		(layer "In6.Cu")
	)
	(gr_line
		(start 134.43712 -12.826238)
		(end 134.435088 -12.825222)
		(stroke
			(width 0.2)
			(type default)
		)
		(layer "In6.Cu")
	)
	(gr_line
		(start 134.437374 -24.226266)
		(end 134.435342 -24.224996)
		(stroke
			(width 0.2)
			(type default)
		)
		(layer "In6.Cu")
	)
	(gr_line
		(start 134.437374 -12.826492)
		(end 134.43712 -12.826238)
		(stroke
			(width 0.2)
			(type default)
		)
		(layer "In6.Cu")
	)
	(gr_line
		(start 134.500112 -228.000052)
		(end 134.500112 -222.400114)
		(stroke
			(width 1.524)
			(type default)
		)
		(layer "In6.Cu")
	)
	(gr_arc
		(start 134.500112 -222.400114)
		(mid 134.353628 -222.046472)
		(end 133.999986 -221.899988)
		(stroke
			(width 1.524)
			(type default)
		)
		(layer "In6.Cu")
	)
	(gr_arc
		(start 134.664704 -36.250372)
		(mid 135.175498 -35.739959)
		(end 134.664958 -35.229292)
		(stroke
			(width 0.2)
			(type default)
		)
		(layer "In6.Cu")
	)
	(gr_line
		(start 134.664958 -35.229292)
		(end 133.852158 -35.229292)
		(stroke
			(width 0.2)
			(type default)
		)
		(layer "In6.Cu")
	)
	(gr_line
		(start 134.831582 -17.433544)
		(end 134.831836 -17.433798)
		(stroke
			(width 0.2)
			(type default)
		)
		(layer "In6.Cu")
	)
	(gr_line
		(start 134.831836 -17.433798)
		(end 134.833868 -17.434814)
		(stroke
			(width 0.2)
			(type default)
		)
		(layer "In6.Cu")
	)
	(gr_arc
		(start 134.833614 -13.635228)
		(mid 135.089646 -14.481048)
		(end 135.935466 -14.225016)
		(stroke
			(width 0.2)
			(type default)
		)
		(layer "In6.Cu")
	)
	(gr_arc
		(start 134.833868 -17.434814)
		(mid 135.089544 -18.280715)
		(end 135.935466 -18.024856)
		(stroke
			(width 0.2)
			(type default)
		)
		(layer "In6.Cu")
	)
	(gr_arc
		(start 134.837678 -25.027636)
		(mid 135.085812 -25.879089)
		(end 135.935466 -25.625044)
		(stroke
			(width 0.2)
			(type default)
		)
		(layer "In6.Cu")
	)
	(gr_arc
		(start 134.837678 -21.227542)
		(mid 135.085812 -22.078995)
		(end 135.935466 -21.82495)
		(stroke
			(width 0.2)
			(type default)
		)
		(layer "In6.Cu")
	)
	(gr_line
		(start 135.58139 -16.034004)
		(end 134.831582 -17.433544)
		(stroke
			(width 0.2)
			(type default)
		)
		(layer "In6.Cu")
	)
	(gr_line
		(start 135.583422 -23.635208)
		(end 134.837678 -25.027636)
		(stroke
			(width 0.2)
			(type default)
		)
		(layer "In6.Cu")
	)
	(gr_line
		(start 135.583422 -19.835114)
		(end 134.837678 -21.227542)
		(stroke
			(width 0.2)
			(type default)
		)
		(layer "In6.Cu")
	)
	(gr_line
		(start 135.583422 -16.035274)
		(end 135.58139 -16.034004)
		(stroke
			(width 0.2)
			(type default)
		)
		(layer "In6.Cu")
	)
	(gr_line
		(start 135.583422 -12.23518)
		(end 134.833614 -13.635228)
		(stroke
			(width 0.2)
			(type default)
		)
		(layer "In6.Cu")
	)
	(gr_line
		(start 135.935466 -25.625044)
		(end 136.685274 -24.224996)
		(stroke
			(width 0.2)
			(type default)
		)
		(layer "In6.Cu")
	)
	(gr_line
		(start 135.935466 -21.82495)
		(end 136.685274 -20.424902)
		(stroke
			(width 0.2)
			(type default)
		)
		(layer "In6.Cu")
	)
	(gr_line
		(start 135.935466 -18.024856)
		(end 135.937498 -18.026126)
		(stroke
			(width 0.2)
			(type default)
		)
		(layer "In6.Cu")
	)
	(gr_line
		(start 135.935466 -14.225016)
		(end 136.68121 -12.832588)
		(stroke
			(width 0.2)
			(type default)
		)
		(layer "In6.Cu")
	)
	(gr_line
		(start 135.937498 -18.026126)
		(end 136.687306 -16.626332)
		(stroke
			(width 0.2)
			(type default)
		)
		(layer "In6.Cu")
	)
	(gr_arc
		(start 136.68121 -12.832588)
		(mid 136.433076 -11.981135)
		(end 135.583422 -12.23518)
		(stroke
			(width 0.2)
			(type default)
		)
		(layer "In6.Cu")
	)
	(gr_arc
		(start 136.685274 -24.224996)
		(mid 136.429242 -23.379176)
		(end 135.583422 -23.635208)
		(stroke
			(width 0.2)
			(type default)
		)
		(layer "In6.Cu")
	)
	(gr_arc
		(start 136.685274 -20.424902)
		(mid 136.429242 -19.579082)
		(end 135.583422 -19.835114)
		(stroke
			(width 0.2)
			(type default)
		)
		(layer "In6.Cu")
	)
	(gr_arc
		(start 136.685274 -16.625062)
		(mid 136.429242 -15.779242)
		(end 135.583422 -16.035274)
		(stroke
			(width 0.2)
			(type default)
		)
		(layer "In6.Cu")
	)
	(gr_line
		(start 136.687306 -16.626332)
		(end 136.685274 -16.625062)
		(stroke
			(width 0.2)
			(type default)
		)
		(layer "In6.Cu")
	)
	(gr_line
		(start 136.893554 -222.805244)
		(end 137.7061 -222.805244)
		(stroke
			(width 0.2)
			(type default)
		)
		(layer "In6.Cu")
	)
	(gr_arc
		(start 136.893554 -221.784164)
		(mid 136.383014 -222.294704)
		(end 136.893554 -222.805244)
		(stroke
			(width 0.2)
			(type default)
		)
		(layer "In6.Cu")
	)
	(gr_line
		(start 137.081514 -25.033732)
		(end 137.081768 -25.033986)
		(stroke
			(width 0.2)
			(type default)
		)
		(layer "In6.Cu")
	)
	(gr_line
		(start 137.081514 -21.233638)
		(end 137.081768 -21.233892)
		(stroke
			(width 0.2)
			(type default)
		)
		(layer "In6.Cu")
	)
	(gr_line
		(start 137.081514 -17.433544)
		(end 137.081768 -17.433798)
		(stroke
			(width 0.2)
			(type default)
		)
		(layer "In6.Cu")
	)
	(gr_line
		(start 137.081514 -13.633958)
		(end 137.083546 -13.635228)
		(stroke
			(width 0.2)
			(type default)
		)
		(layer "In6.Cu")
	)
	(gr_line
		(start 137.081768 -25.033986)
		(end 137.0838 -25.035002)
		(stroke
			(width 0.2)
			(type default)
		)
		(layer "In6.Cu")
	)
	(gr_line
		(start 137.081768 -21.233892)
		(end 137.0838 -21.234908)
		(stroke
			(width 0.2)
			(type default)
		)
		(layer "In6.Cu")
	)
	(gr_line
		(start 137.081768 -17.433798)
		(end 137.0838 -17.434814)
		(stroke
			(width 0.2)
			(type default)
		)
		(layer "In6.Cu")
	)
	(gr_arc
		(start 137.083546 -13.635228)
		(mid 137.339578 -14.481048)
		(end 138.185398 -14.225016)
		(stroke
			(width 0.2)
			(type default)
		)
		(layer "In6.Cu")
	)
	(gr_arc
		(start 137.0838 -25.035002)
		(mid 137.339476 -25.880903)
		(end 138.185398 -25.625044)
		(stroke
			(width 0.2)
			(type default)
		)
		(layer "In6.Cu")
	)
	(gr_arc
		(start 137.0838 -21.234908)
		(mid 137.339476 -22.080809)
		(end 138.185398 -21.82495)
		(stroke
			(width 0.2)
			(type default)
		)
		(layer "In6.Cu")
	)
	(gr_arc
		(start 137.0838 -17.434814)
		(mid 137.339324 -18.280634)
		(end 138.185144 -18.02511)
		(stroke
			(width 0.2)
			(type default)
		)
		(layer "In6.Cu")
	)
	(gr_line
		(start 137.5664 -35.503866)
		(end 138.378946 -35.503866)
		(stroke
			(width 0.2)
			(type default)
		)
		(layer "In6.Cu")
	)
	(gr_arc
		(start 137.5664 -34.482786)
		(mid 137.05586 -34.993326)
		(end 137.5664 -35.503866)
		(stroke
			(width 0.2)
			(type default)
		)
		(layer "In6.Cu")
	)
	(gr_arc
		(start 137.7061 -222.805244)
		(mid 138.216894 -222.294831)
		(end 137.706354 -221.784164)
		(stroke
			(width 0.2)
			(type default)
		)
		(layer "In6.Cu")
	)
	(gr_line
		(start 137.706354 -221.784164)
		(end 136.893554 -221.784164)
		(stroke
			(width 0.2)
			(type default)
		)
		(layer "In6.Cu")
	)
	(gr_line
		(start 137.831576 -23.633938)
		(end 137.081514 -25.033732)
		(stroke
			(width 0.2)
			(type default)
		)
		(layer "In6.Cu")
	)
	(gr_line
		(start 137.831576 -19.833844)
		(end 137.081514 -21.233638)
		(stroke
			(width 0.2)
			(type default)
		)
		(layer "In6.Cu")
	)
	(gr_line
		(start 137.831576 -16.03375)
		(end 137.081514 -17.433544)
		(stroke
			(width 0.2)
			(type default)
		)
		(layer "In6.Cu")
	)
	(gr_line
		(start 137.831576 -12.23391)
		(end 137.081514 -13.633958)
		(stroke
			(width 0.2)
			(type default)
		)
		(layer "In6.Cu")
	)
	(gr_line
		(start 137.833608 -23.635208)
		(end 137.831576 -23.633938)
		(stroke
			(width 0.2)
			(type default)
		)
		(layer "In6.Cu")
	)
	(gr_line
		(start 137.833608 -19.835114)
		(end 137.831576 -19.833844)
		(stroke
			(width 0.2)
			(type default)
		)
		(layer "In6.Cu")
	)
	(gr_line
		(start 137.833608 -12.23518)
		(end 137.831576 -12.23391)
		(stroke
			(width 0.2)
			(type default)
		)
		(layer "In6.Cu")
	)
	(gr_line
		(start 137.833862 -16.03502)
		(end 137.831576 -16.03375)
		(stroke
			(width 0.2)
			(type default)
		)
		(layer "In6.Cu")
	)
	(gr_line
		(start 138.185144 -18.02511)
		(end 138.18743 -18.02638)
		(stroke
			(width 0.2)
			(type default)
		)
		(layer "In6.Cu")
	)
	(gr_line
		(start 138.185398 -25.625044)
		(end 138.18743 -25.626314)
		(stroke
			(width 0.2)
			(type default)
		)
		(layer "In6.Cu")
	)
	(gr_line
		(start 138.185398 -21.82495)
		(end 138.18743 -21.82622)
		(stroke
			(width 0.2)
			(type default)
		)
		(layer "In6.Cu")
	)
	(gr_line
		(start 138.185398 -14.225016)
		(end 138.18743 -14.226286)
		(stroke
			(width 0.2)
			(type default)
		)
		(layer "In6.Cu")
	)
	(gr_line
		(start 138.18743 -25.626314)
		(end 138.937492 -24.226266)
		(stroke
			(width 0.2)
			(type default)
		)
		(layer "In6.Cu")
	)
	(gr_line
		(start 138.18743 -21.82622)
		(end 138.937492 -20.426172)
		(stroke
			(width 0.2)
			(type default)
		)
		(layer "In6.Cu")
	)
	(gr_line
		(start 138.18743 -18.02638)
		(end 138.937492 -16.626586)
		(stroke
			(width 0.2)
			(type default)
		)
		(layer "In6.Cu")
	)
	(gr_line
		(start 138.18743 -14.226286)
		(end 138.937492 -12.826492)
		(stroke
			(width 0.2)
			(type default)
		)
		(layer "In6.Cu")
	)
	(gr_arc
		(start 138.378946 -35.503866)
		(mid 138.88974 -34.993453)
		(end 138.3792 -34.482786)
		(stroke
			(width 0.2)
			(type default)
		)
		(layer "In6.Cu")
	)
	(gr_line
		(start 138.3792 -34.482786)
		(end 137.5664 -34.482786)
		(stroke
			(width 0.2)
			(type default)
		)
		(layer "In6.Cu")
	)
	(gr_line
		(start 138.493754 -211.406994)
		(end 139.306554 -211.406994)
		(stroke
			(width 0.2)
			(type default)
		)
		(layer "In6.Cu")
	)
	(gr_arc
		(start 138.494008 -210.385914)
		(mid 137.983214 -210.896327)
		(end 138.493754 -211.406994)
		(stroke
			(width 0.2)
			(type default)
		)
		(layer "In6.Cu")
	)
	(gr_line
		(start 138.557 -39.16934)
		(end 139.3698 -39.16934)
		(stroke
			(width 0.2)
			(type default)
		)
		(layer "In6.Cu")
	)
	(gr_arc
		(start 138.557254 -38.14826)
		(mid 138.04646 -38.658673)
		(end 138.557 -39.16934)
		(stroke
			(width 0.2)
			(type default)
		)
		(layer "In6.Cu")
	)
	(gr_arc
		(start 138.935206 -16.625316)
		(mid 138.679682 -15.779496)
		(end 137.833862 -16.03502)
		(stroke
			(width 0.2)
			(type default)
		)
		(layer "In6.Cu")
	)
	(gr_arc
		(start 138.935206 -12.825222)
		(mid 138.67953 -11.979321)
		(end 137.833608 -12.23518)
		(stroke
			(width 0.2)
			(type default)
		)
		(layer "In6.Cu")
	)
	(gr_arc
		(start 138.93546 -24.224996)
		(mid 138.679428 -23.379176)
		(end 137.833608 -23.635208)
		(stroke
			(width 0.2)
			(type default)
		)
		(layer "In6.Cu")
	)
	(gr_arc
		(start 138.93546 -20.424902)
		(mid 138.679428 -19.579082)
		(end 137.833608 -19.835114)
		(stroke
			(width 0.2)
			(type default)
		)
		(layer "In6.Cu")
	)
	(gr_line
		(start 138.937238 -12.826238)
		(end 138.935206 -12.825222)
		(stroke
			(width 0.2)
			(type default)
		)
		(layer "In6.Cu")
	)
	(gr_line
		(start 138.937492 -24.226266)
		(end 138.93546 -24.224996)
		(stroke
			(width 0.2)
			(type default)
		)
		(layer "In6.Cu")
	)
	(gr_line
		(start 138.937492 -20.426172)
		(end 138.93546 -20.424902)
		(stroke
			(width 0.2)
			(type default)
		)
		(layer "In6.Cu")
	)
	(gr_line
		(start 138.937492 -16.626586)
		(end 138.935206 -16.625316)
		(stroke
			(width 0.2)
			(type default)
		)
		(layer "In6.Cu")
	)
	(gr_line
		(start 138.937492 -12.826492)
		(end 138.937238 -12.826238)
		(stroke
			(width 0.2)
			(type default)
		)
		(layer "In6.Cu")
	)
	(gr_arc
		(start 139.306554 -211.406994)
		(mid 139.817094 -210.896454)
		(end 139.306554 -210.385914)
		(stroke
			(width 0.2)
			(type default)
		)
		(layer "In6.Cu")
	)
	(gr_line
		(start 139.306554 -210.385914)
		(end 138.494008 -210.385914)
		(stroke
			(width 0.2)
			(type default)
		)
		(layer "In6.Cu")
	)
	(gr_arc
		(start 139.3698 -39.16934)
		(mid 139.88034 -38.6588)
		(end 139.3698 -38.14826)
		(stroke
			(width 0.2)
			(type default)
		)
		(layer "In6.Cu")
	)
	(gr_line
		(start 139.3698 -38.14826)
		(end 138.557254 -38.14826)
		(stroke
			(width 0.2)
			(type default)
		)
		(layer "In6.Cu")
	)
	(gr_line
		(start 140.0937 -222.805244)
		(end 140.906246 -222.805244)
		(stroke
			(width 0.2)
			(type default)
		)
		(layer "In6.Cu")
	)
	(gr_arc
		(start 140.0937 -221.784164)
		(mid 139.58316 -222.294704)
		(end 140.0937 -222.805244)
		(stroke
			(width 0.2)
			(type default)
		)
		(layer "In6.Cu")
	)
	(gr_arc
		(start 140.906246 -222.805244)
		(mid 141.41704 -222.294831)
		(end 140.9065 -221.784164)
		(stroke
			(width 0.2)
			(type default)
		)
		(layer "In6.Cu")
	)
	(gr_line
		(start 140.9065 -221.784164)
		(end 140.0937 -221.784164)
		(stroke
			(width 0.2)
			(type default)
		)
		(layer "In6.Cu")
	)
	(gr_line
		(start 141.6939 -211.406994)
		(end 142.5067 -211.406994)
		(stroke
			(width 0.2)
			(type default)
		)
		(layer "In6.Cu")
	)
	(gr_arc
		(start 141.694154 -210.385914)
		(mid 141.18336 -210.896327)
		(end 141.6939 -211.406994)
		(stroke
			(width 0.2)
			(type default)
		)
		(layer "In6.Cu")
	)
	(gr_arc
		(start 142.5067 -211.406994)
		(mid 143.01724 -210.896454)
		(end 142.5067 -210.385914)
		(stroke
			(width 0.2)
			(type default)
		)
		(layer "In6.Cu")
	)
	(gr_line
		(start 142.5067 -210.385914)
		(end 141.694154 -210.385914)
		(stroke
			(width 0.2)
			(type default)
		)
		(layer "In6.Cu")
	)
	(gr_line
		(start 143.293592 -222.805244)
		(end 144.106138 -222.805244)
		(stroke
			(width 0.2)
			(type default)
		)
		(layer "In6.Cu")
	)
	(gr_arc
		(start 143.293592 -221.784164)
		(mid 142.783052 -222.294704)
		(end 143.293592 -222.805244)
		(stroke
			(width 0.2)
			(type default)
		)
		(layer "In6.Cu")
	)
	(gr_line
		(start 143.581374 -25.033986)
		(end 143.583406 -25.035256)
		(stroke
			(width 0.2)
			(type default)
		)
		(layer "In6.Cu")
	)
	(gr_line
		(start 143.581374 -13.633704)
		(end 143.581628 -13.633958)
		(stroke
			(width 0.2)
			(type default)
		)
		(layer "In6.Cu")
	)
	(gr_line
		(start 143.581628 -13.633958)
		(end 143.58366 -13.634974)
		(stroke
			(width 0.2)
			(type default)
		)
		(layer "In6.Cu")
	)
	(gr_arc
		(start 143.583406 -25.035256)
		(mid 143.839438 -25.881076)
		(end 144.685258 -25.625044)
		(stroke
			(width 0.2)
			(type default)
		)
		(layer "In6.Cu")
	)
	(gr_arc
		(start 143.58366 -13.634974)
		(mid 143.839336 -14.480875)
		(end 144.685258 -14.225016)
		(stroke
			(width 0.2)
			(type default)
		)
		(layer "In6.Cu")
	)
	(gr_arc
		(start 144.106138 -222.805244)
		(mid 144.616932 -222.294831)
		(end 144.106392 -221.784164)
		(stroke
			(width 0.2)
			(type default)
		)
		(layer "In6.Cu")
	)
	(gr_line
		(start 144.106392 -221.784164)
		(end 143.293592 -221.784164)
		(stroke
			(width 0.2)
			(type default)
		)
		(layer "In6.Cu")
	)
	(gr_line
		(start 144.331436 -23.633938)
		(end 143.581374 -25.033986)
		(stroke
			(width 0.2)
			(type default)
		)
		(layer "In6.Cu")
	)
	(gr_line
		(start 144.331436 -12.23391)
		(end 143.581374 -13.633704)
		(stroke
			(width 0.2)
			(type default)
		)
		(layer "In6.Cu")
	)
	(gr_line
		(start 144.333468 -23.635208)
		(end 144.331436 -23.633938)
		(stroke
			(width 0.2)
			(type default)
		)
		(layer "In6.Cu")
	)
	(gr_line
		(start 144.333468 -12.23518)
		(end 144.331436 -12.23391)
		(stroke
			(width 0.2)
			(type default)
		)
		(layer "In6.Cu")
	)
	(gr_line
		(start 144.685258 -25.625044)
		(end 144.68729 -25.626314)
		(stroke
			(width 0.2)
			(type default)
		)
		(layer "In6.Cu")
	)
	(gr_line
		(start 144.685258 -14.225016)
		(end 144.68729 -14.226286)
		(stroke
			(width 0.2)
			(type default)
		)
		(layer "In6.Cu")
	)
	(gr_line
		(start 144.68729 -25.626314)
		(end 145.437352 -24.22652)
		(stroke
			(width 0.2)
			(type default)
		)
		(layer "In6.Cu")
	)
	(gr_line
		(start 144.68729 -14.226286)
		(end 145.437352 -12.826238)
		(stroke
			(width 0.2)
			(type default)
		)
		(layer "In6.Cu")
	)
	(gr_line
		(start 144.893792 -211.406994)
		(end 145.706592 -211.406994)
		(stroke
			(width 0.2)
			(type default)
		)
		(layer "In6.Cu")
	)
	(gr_arc
		(start 144.894046 -210.385914)
		(mid 144.383252 -210.896327)
		(end 144.893792 -211.406994)
		(stroke
			(width 0.2)
			(type default)
		)
		(layer "In6.Cu")
	)
	(gr_arc
		(start 145.435066 -24.22525)
		(mid 145.17939 -23.379349)
		(end 144.333468 -23.635208)
		(stroke
			(width 0.2)
			(type default)
		)
		(layer "In6.Cu")
	)
	(gr_arc
		(start 145.43532 -12.824968)
		(mid 145.179288 -11.979148)
		(end 144.333468 -12.23518)
		(stroke
			(width 0.2)
			(type default)
		)
		(layer "In6.Cu")
	)
	(gr_line
		(start 145.437098 -24.226266)
		(end 145.435066 -24.22525)
		(stroke
			(width 0.2)
			(type default)
		)
		(layer "In6.Cu")
	)
	(gr_line
		(start 145.437352 -24.22652)
		(end 145.437098 -24.226266)
		(stroke
			(width 0.2)
			(type default)
		)
		(layer "In6.Cu")
	)
	(gr_line
		(start 145.437352 -12.826238)
		(end 145.43532 -12.824968)
		(stroke
			(width 0.2)
			(type default)
		)
		(layer "In6.Cu")
	)
	(gr_arc
		(start 145.706592 -211.406994)
		(mid 146.217132 -210.896454)
		(end 145.706592 -210.385914)
		(stroke
			(width 0.2)
			(type default)
		)
		(layer "In6.Cu")
	)
	(gr_line
		(start 145.706592 -210.385914)
		(end 144.894046 -210.385914)
		(stroke
			(width 0.2)
			(type default)
		)
		(layer "In6.Cu")
	)
	(gr_line
		(start 145.83156 -17.433544)
		(end 145.831814 -17.433798)
		(stroke
			(width 0.2)
			(type default)
		)
		(layer "In6.Cu")
	)
	(gr_line
		(start 145.831814 -17.433798)
		(end 145.833846 -17.434814)
		(stroke
			(width 0.2)
			(type default)
		)
		(layer "In6.Cu")
	)
	(gr_arc
		(start 145.833592 -21.235162)
		(mid 146.089624 -22.080982)
		(end 146.935444 -21.82495)
		(stroke
			(width 0.2)
			(type default)
		)
		(layer "In6.Cu")
	)
	(gr_arc
		(start 145.833846 -17.434814)
		(mid 146.089522 -18.280715)
		(end 146.935444 -18.024856)
		(stroke
			(width 0.2)
			(type default)
		)
		(layer "In6.Cu")
	)
	(gr_arc
		(start 145.837656 -25.027636)
		(mid 146.08579 -25.879089)
		(end 146.935444 -25.625044)
		(stroke
			(width 0.2)
			(type default)
		)
		(layer "In6.Cu")
	)
	(gr_arc
		(start 145.837656 -13.627608)
		(mid 146.08579 -14.479061)
		(end 146.935444 -14.225016)
		(stroke
			(width 0.2)
			(type default)
		)
		(layer "In6.Cu")
	)
	(gr_line
		(start 145.9103 -35.50666)
		(end 146.7231 -35.50666)
		(stroke
			(width 0.2)
			(type default)
		)
		(layer "In6.Cu")
	)
	(gr_arc
		(start 145.910554 -34.48558)
		(mid 145.39976 -34.995993)
		(end 145.9103 -35.50666)
		(stroke
			(width 0.2)
			(type default)
		)
		(layer "In6.Cu")
	)
	(gr_line
		(start 146.493738 -222.805244)
		(end 147.306284 -222.805244)
		(stroke
			(width 0.2)
			(type default)
		)
		(layer "In6.Cu")
	)
	(gr_arc
		(start 146.493738 -221.784164)
		(mid 145.983198 -222.294704)
		(end 146.493738 -222.805244)
		(stroke
			(width 0.2)
			(type default)
		)
		(layer "In6.Cu")
	)
	(gr_line
		(start 146.581368 -16.034004)
		(end 145.83156 -17.433544)
		(stroke
			(width 0.2)
			(type default)
		)
		(layer "In6.Cu")
	)
	(gr_line
		(start 146.5834 -23.635208)
		(end 145.837656 -25.027636)
		(stroke
			(width 0.2)
			(type default)
		)
		(layer "In6.Cu")
	)
	(gr_line
		(start 146.5834 -19.835114)
		(end 145.833592 -21.235162)
		(stroke
			(width 0.2)
			(type default)
		)
		(layer "In6.Cu")
	)
	(gr_line
		(start 146.5834 -16.035274)
		(end 146.581368 -16.034004)
		(stroke
			(width 0.2)
			(type default)
		)
		(layer "In6.Cu")
	)
	(gr_line
		(start 146.5834 -12.23518)
		(end 145.837656 -13.627608)
		(stroke
			(width 0.2)
			(type default)
		)
		(layer "In6.Cu")
	)
	(gr_arc
		(start 146.7231 -35.50666)
		(mid 147.23364 -34.99612)
		(end 146.7231 -34.48558)
		(stroke
			(width 0.2)
			(type default)
		)
		(layer "In6.Cu")
	)
	(gr_line
		(start 146.7231 -34.48558)
		(end 145.910554 -34.48558)
		(stroke
			(width 0.2)
			(type default)
		)
		(layer "In6.Cu")
	)
	(gr_line
		(start 146.935444 -25.625044)
		(end 147.685252 -24.224996)
		(stroke
			(width 0.2)
			(type default)
		)
		(layer "In6.Cu")
	)
	(gr_line
		(start 146.935444 -21.82495)
		(end 147.681188 -20.432522)
		(stroke
			(width 0.2)
			(type default)
		)
		(layer "In6.Cu")
	)
	(gr_line
		(start 146.935444 -18.024856)
		(end 146.937476 -18.026126)
		(stroke
			(width 0.2)
			(type default)
		)
		(layer "In6.Cu")
	)
	(gr_line
		(start 146.935444 -14.225016)
		(end 147.685252 -12.824968)
		(stroke
			(width 0.2)
			(type default)
		)
		(layer "In6.Cu")
	)
	(gr_line
		(start 146.937476 -18.026126)
		(end 147.687284 -16.626332)
		(stroke
			(width 0.2)
			(type default)
		)
		(layer "In6.Cu")
	)
	(gr_arc
		(start 147.306284 -222.805244)
		(mid 147.817078 -222.294831)
		(end 147.306538 -221.784164)
		(stroke
			(width 0.2)
			(type default)
		)
		(layer "In6.Cu")
	)
	(gr_line
		(start 147.306538 -221.784164)
		(end 146.493738 -221.784164)
		(stroke
			(width 0.2)
			(type default)
		)
		(layer "In6.Cu")
	)
	(gr_arc
		(start 147.681188 -20.432522)
		(mid 147.433054 -19.581069)
		(end 146.5834 -19.835114)
		(stroke
			(width 0.2)
			(type default)
		)
		(layer "In6.Cu")
	)
	(gr_arc
		(start 147.685252 -24.224996)
		(mid 147.42922 -23.379176)
		(end 146.5834 -23.635208)
		(stroke
			(width 0.2)
			(type default)
		)
		(layer "In6.Cu")
	)
	(gr_arc
		(start 147.685252 -16.625062)
		(mid 147.42922 -15.779242)
		(end 146.5834 -16.035274)
		(stroke
			(width 0.2)
			(type default)
		)
		(layer "In6.Cu")
	)
	(gr_arc
		(start 147.685252 -12.824968)
		(mid 147.42922 -11.979148)
		(end 146.5834 -12.23518)
		(stroke
			(width 0.2)
			(type default)
		)
		(layer "In6.Cu")
	)
	(gr_line
		(start 147.687284 -16.626332)
		(end 147.685252 -16.625062)
		(stroke
			(width 0.2)
			(type default)
		)
		(layer "In6.Cu")
	)
	(gr_line
		(start 148.081492 -25.033732)
		(end 148.081746 -25.033986)
		(stroke
			(width 0.2)
			(type default)
		)
		(layer "In6.Cu")
	)
	(gr_line
		(start 148.081492 -21.233892)
		(end 148.083524 -21.235162)
		(stroke
			(width 0.2)
			(type default)
		)
		(layer "In6.Cu")
	)
	(gr_line
		(start 148.081492 -17.433544)
		(end 148.081746 -17.433798)
		(stroke
			(width 0.2)
			(type default)
		)
		(layer "In6.Cu")
	)
	(gr_line
		(start 148.081492 -13.633704)
		(end 148.081746 -13.633958)
		(stroke
			(width 0.2)
			(type default)
		)
		(layer "In6.Cu")
	)
	(gr_line
		(start 148.081746 -25.033986)
		(end 148.083778 -25.035002)
		(stroke
			(width 0.2)
			(type default)
		)
		(layer "In6.Cu")
	)
	(gr_line
		(start 148.081746 -17.433798)
		(end 148.083778 -17.434814)
		(stroke
			(width 0.2)
			(type default)
		)
		(layer "In6.Cu")
	)
	(gr_line
		(start 148.081746 -13.633958)
		(end 148.083778 -13.634974)
		(stroke
			(width 0.2)
			(type default)
		)
		(layer "In6.Cu")
	)
	(gr_arc
		(start 148.083524 -21.235162)
		(mid 148.339556 -22.080982)
		(end 149.185376 -21.82495)
		(stroke
			(width 0.2)
			(type default)
		)
		(layer "In6.Cu")
	)
	(gr_arc
		(start 148.083778 -25.035002)
		(mid 148.339454 -25.880903)
		(end 149.185376 -25.625044)
		(stroke
			(width 0.2)
			(type default)
		)
		(layer "In6.Cu")
	)
	(gr_arc
		(start 148.083778 -17.434814)
		(mid 148.339302 -18.280634)
		(end 149.185122 -18.02511)
		(stroke
			(width 0.2)
			(type default)
		)
		(layer "In6.Cu")
	)
	(gr_arc
		(start 148.083778 -13.634974)
		(mid 148.339454 -14.480875)
		(end 149.185376 -14.225016)
		(stroke
			(width 0.2)
			(type default)
		)
		(layer "In6.Cu")
	)
	(gr_line
		(start 148.093684 -211.406994)
		(end 148.906484 -211.406994)
		(stroke
			(width 0.2)
			(type default)
		)
		(layer "In6.Cu")
	)
	(gr_arc
		(start 148.093938 -210.385914)
		(mid 147.583144 -210.896327)
		(end 148.093684 -211.406994)
		(stroke
			(width 0.2)
			(type default)
		)
		(layer "In6.Cu")
	)
	(gr_line
		(start 148.5011 -35.51174)
		(end 149.313646 -35.51174)
		(stroke
			(width 0.2)
			(type default)
		)
		(layer "In6.Cu")
	)
	(gr_arc
		(start 148.5011 -34.49066)
		(mid 147.99056 -35.0012)
		(end 148.5011 -35.51174)
		(stroke
			(width 0.2)
			(type default)
		)
		(layer "In6.Cu")
	)
	(gr_line
		(start 148.831554 -23.633938)
		(end 148.081492 -25.033732)
		(stroke
			(width 0.2)
			(type default)
		)
		(layer "In6.Cu")
	)
	(gr_line
		(start 148.831554 -19.833844)
		(end 148.081492 -21.233892)
		(stroke
			(width 0.2)
			(type default)
		)
		(layer "In6.Cu")
	)
	(gr_line
		(start 148.831554 -16.03375)
		(end 148.081492 -17.433544)
		(stroke
			(width 0.2)
			(type default)
		)
		(layer "In6.Cu")
	)
	(gr_line
		(start 148.831554 -12.23391)
		(end 148.081492 -13.633704)
		(stroke
			(width 0.2)
			(type default)
		)
		(layer "In6.Cu")
	)
	(gr_line
		(start 148.833586 -23.635208)
		(end 148.831554 -23.633938)
		(stroke
			(width 0.2)
			(type default)
		)
		(layer "In6.Cu")
	)
	(gr_line
		(start 148.833586 -19.835114)
		(end 148.831554 -19.833844)
		(stroke
			(width 0.2)
			(type default)
		)
		(layer "In6.Cu")
	)
	(gr_line
		(start 148.833586 -12.23518)
		(end 148.831554 -12.23391)
		(stroke
			(width 0.2)
			(type default)
		)
		(layer "In6.Cu")
	)
	(gr_line
		(start 148.83384 -16.03502)
		(end 148.831554 -16.03375)
		(stroke
			(width 0.2)
			(type default)
		)
		(layer "In6.Cu")
	)
	(gr_arc
		(start 148.906484 -211.406994)
		(mid 149.417024 -210.896454)
		(end 148.906484 -210.385914)
		(stroke
			(width 0.2)
			(type default)
		)
		(layer "In6.Cu")
	)
	(gr_line
		(start 148.906484 -210.385914)
		(end 148.093938 -210.385914)
		(stroke
			(width 0.2)
			(type default)
		)
		(layer "In6.Cu")
	)
	(gr_line
		(start 149.185122 -18.02511)
		(end 149.187408 -18.02638)
		(stroke
			(width 0.2)
			(type default)
		)
		(layer "In6.Cu")
	)
	(gr_line
		(start 149.185376 -25.625044)
		(end 149.187408 -25.626314)
		(stroke
			(width 0.2)
			(type default)
		)
		(layer "In6.Cu")
	)
	(gr_line
		(start 149.185376 -21.82495)
		(end 149.187408 -21.82622)
		(stroke
			(width 0.2)
			(type default)
		)
		(layer "In6.Cu")
	)
	(gr_line
		(start 149.185376 -14.225016)
		(end 149.187408 -14.226286)
		(stroke
			(width 0.2)
			(type default)
		)
		(layer "In6.Cu")
	)
	(gr_line
		(start 149.187408 -25.626314)
		(end 149.93747 -24.226266)
		(stroke
			(width 0.2)
			(type default)
		)
		(layer "In6.Cu")
	)
	(gr_line
		(start 149.187408 -21.82622)
		(end 149.93747 -20.426426)
		(stroke
			(width 0.2)
			(type default)
		)
		(layer "In6.Cu")
	)
	(gr_line
		(start 149.187408 -18.02638)
		(end 149.93747 -16.626586)
		(stroke
			(width 0.2)
			(type default)
		)
		(layer "In6.Cu")
	)
	(gr_line
		(start 149.187408 -14.226286)
		(end 149.93747 -12.826238)
		(stroke
			(width 0.2)
			(type default)
		)
		(layer "In6.Cu")
	)
	(gr_arc
		(start 149.313646 -35.51174)
		(mid 149.82444 -35.001327)
		(end 149.3139 -34.49066)
		(stroke
			(width 0.2)
			(type default)
		)
		(layer "In6.Cu")
	)
	(gr_line
		(start 149.3139 -34.49066)
		(end 148.5011 -34.49066)
		(stroke
			(width 0.2)
			(type default)
		)
		(layer "In6.Cu")
	)
	(gr_line
		(start 149.69363 -222.805244)
		(end 150.506176 -222.805244)
		(stroke
			(width 0.2)
			(type default)
		)
		(layer "In6.Cu")
	)
	(gr_arc
		(start 149.69363 -221.784164)
		(mid 149.18309 -222.294704)
		(end 149.69363 -222.805244)
		(stroke
			(width 0.2)
			(type default)
		)
		(layer "In6.Cu")
	)
	(gr_arc
		(start 149.935184 -20.425156)
		(mid 149.679508 -19.579255)
		(end 148.833586 -19.835114)
		(stroke
			(width 0.2)
			(type default)
		)
		(layer "In6.Cu")
	)
	(gr_arc
		(start 149.935184 -16.625316)
		(mid 149.67966 -15.779496)
		(end 148.83384 -16.03502)
		(stroke
			(width 0.2)
			(type default)
		)
		(layer "In6.Cu")
	)
	(gr_arc
		(start 149.935438 -24.224996)
		(mid 149.679406 -23.379176)
		(end 148.833586 -23.635208)
		(stroke
			(width 0.2)
			(type default)
		)
		(layer "In6.Cu")
	)
	(gr_arc
		(start 149.935438 -12.824968)
		(mid 149.679406 -11.979148)
		(end 148.833586 -12.23518)
		(stroke
			(width 0.2)
			(type default)
		)
		(layer "In6.Cu")
	)
	(gr_line
		(start 149.937216 -20.426172)
		(end 149.935184 -20.425156)
		(stroke
			(width 0.2)
			(type default)
		)
		(layer "In6.Cu")
	)
	(gr_line
		(start 149.93747 -24.226266)
		(end 149.935438 -24.224996)
		(stroke
			(width 0.2)
			(type default)
		)
		(layer "In6.Cu")
	)
	(gr_line
		(start 149.93747 -20.426426)
		(end 149.937216 -20.426172)
		(stroke
			(width 0.2)
			(type default)
		)
		(layer "In6.Cu")
	)
	(gr_line
		(start 149.93747 -16.626586)
		(end 149.935184 -16.625316)
		(stroke
			(width 0.2)
			(type default)
		)
		(layer "In6.Cu")
	)
	(gr_line
		(start 149.93747 -12.826238)
		(end 149.935438 -12.824968)
		(stroke
			(width 0.2)
			(type default)
		)
		(layer "In6.Cu")
	)
	(gr_arc
		(start 150.506176 -222.805244)
		(mid 151.01697 -222.294831)
		(end 150.50643 -221.784164)
		(stroke
			(width 0.2)
			(type default)
		)
		(layer "In6.Cu")
	)
	(gr_line
		(start 150.50643 -221.784164)
		(end 149.69363 -221.784164)
		(stroke
			(width 0.2)
			(type default)
		)
		(layer "In6.Cu")
	)
	(gr_line
		(start 150.9141 -38.59784)
		(end 151.726646 -38.59784)
		(stroke
			(width 0.2)
			(type default)
		)
		(layer "In6.Cu")
	)
	(gr_arc
		(start 150.9141 -37.57676)
		(mid 150.40356 -38.0873)
		(end 150.9141 -38.59784)
		(stroke
			(width 0.2)
			(type default)
		)
		(layer "In6.Cu")
	)
	(gr_line
		(start 151.29383 -211.406994)
		(end 152.10663 -211.406994)
		(stroke
			(width 0.2)
			(type default)
		)
		(layer "In6.Cu")
	)
	(gr_arc
		(start 151.294084 -210.385914)
		(mid 150.78329 -210.896327)
		(end 151.29383 -211.406994)
		(stroke
			(width 0.2)
			(type default)
		)
		(layer "In6.Cu")
	)
	(gr_arc
		(start 151.726646 -38.59784)
		(mid 152.23744 -38.087427)
		(end 151.7269 -37.57676)
		(stroke
			(width 0.2)
			(type default)
		)
		(layer "In6.Cu")
	)
	(gr_line
		(start 151.7269 -37.57676)
		(end 150.9141 -37.57676)
		(stroke
			(width 0.2)
			(type default)
		)
		(layer "In6.Cu")
	)
	(gr_arc
		(start 152.10663 -211.406994)
		(mid 152.61717 -210.896454)
		(end 152.10663 -210.385914)
		(stroke
			(width 0.2)
			(type default)
		)
		(layer "In6.Cu")
	)
	(gr_line
		(start 152.10663 -210.385914)
		(end 151.294084 -210.385914)
		(stroke
			(width 0.2)
			(type default)
		)
		(layer "In6.Cu")
	)
	(gr_line
		(start 152.7175 -35.50666)
		(end 153.530046 -35.50666)
		(stroke
			(width 0.2)
			(type default)
		)
		(layer "In6.Cu")
	)
	(gr_arc
		(start 152.7175 -34.48558)
		(mid 152.20696 -34.99612)
		(end 152.7175 -35.50666)
		(stroke
			(width 0.2)
			(type default)
		)
		(layer "In6.Cu")
	)
	(gr_line
		(start 152.893776 -222.805244)
		(end 153.706322 -222.805244)
		(stroke
			(width 0.2)
			(type default)
		)
		(layer "In6.Cu")
	)
	(gr_arc
		(start 152.893776 -221.784164)
		(mid 152.383236 -222.294704)
		(end 152.893776 -222.805244)
		(stroke
			(width 0.2)
			(type default)
		)
		(layer "In6.Cu")
	)
	(gr_arc
		(start 153.530046 -35.50666)
		(mid 154.04084 -34.996247)
		(end 153.5303 -34.48558)
		(stroke
			(width 0.2)
			(type default)
		)
		(layer "In6.Cu")
	)
	(gr_line
		(start 153.5303 -34.48558)
		(end 152.7175 -34.48558)
		(stroke
			(width 0.2)
			(type default)
		)
		(layer "In6.Cu")
	)
	(gr_arc
		(start 153.706322 -222.805244)
		(mid 154.217116 -222.294831)
		(end 153.706576 -221.784164)
		(stroke
			(width 0.2)
			(type default)
		)
		(layer "In6.Cu")
	)
	(gr_line
		(start 153.706576 -221.784164)
		(end 152.893776 -221.784164)
		(stroke
			(width 0.2)
			(type default)
		)
		(layer "In6.Cu")
	)
	(gr_line
		(start 154.493722 -211.406994)
		(end 155.306522 -211.406994)
		(stroke
			(width 0.2)
			(type default)
		)
		(layer "In6.Cu")
	)
	(gr_arc
		(start 154.493976 -210.385914)
		(mid 153.983182 -210.896327)
		(end 154.493722 -211.406994)
		(stroke
			(width 0.2)
			(type default)
		)
		(layer "In6.Cu")
	)
	(gr_arc
		(start 154.583638 -25.035256)
		(mid 154.83967 -25.881076)
		(end 155.68549 -25.625044)
		(stroke
			(width 0.2)
			(type default)
		)
		(layer "In6.Cu")
	)
	(gr_arc
		(start 154.587702 -13.627608)
		(mid 154.835836 -14.479061)
		(end 155.68549 -14.225016)
		(stroke
			(width 0.2)
			(type default)
		)
		(layer "In6.Cu")
	)
	(gr_arc
		(start 155.306522 -211.406994)
		(mid 155.817062 -210.896454)
		(end 155.306522 -210.385914)
		(stroke
			(width 0.2)
			(type default)
		)
		(layer "In6.Cu")
	)
	(gr_line
		(start 155.306522 -210.385914)
		(end 154.493976 -210.385914)
		(stroke
			(width 0.2)
			(type default)
		)
		(layer "In6.Cu")
	)
	(gr_line
		(start 155.333446 -23.635208)
		(end 154.583638 -25.035256)
		(stroke
			(width 0.2)
			(type default)
		)
		(layer "In6.Cu")
	)
	(gr_line
		(start 155.333446 -12.23518)
		(end 154.587702 -13.627608)
		(stroke
			(width 0.2)
			(type default)
		)
		(layer "In6.Cu")
	)
	(gr_line
		(start 155.68549 -25.625044)
		(end 156.431234 -24.232616)
		(stroke
			(width 0.2)
			(type default)
		)
		(layer "In6.Cu")
	)
	(gr_line
		(start 155.68549 -14.225016)
		(end 156.435298 -12.824968)
		(stroke
			(width 0.2)
			(type default)
		)
		(layer "In6.Cu")
	)
	(gr_line
		(start 156.093668 -222.805244)
		(end 156.906214 -222.805244)
		(stroke
			(width 0.2)
			(type default)
		)
		(layer "In6.Cu")
	)
	(gr_arc
		(start 156.093668 -221.784164)
		(mid 155.583128 -222.294704)
		(end 156.093668 -222.805244)
		(stroke
			(width 0.2)
			(type default)
		)
		(layer "In6.Cu")
	)
	(gr_arc
		(start 156.431234 -24.232616)
		(mid 156.1831 -23.381163)
		(end 155.333446 -23.635208)
		(stroke
			(width 0.2)
			(type default)
		)
		(layer "In6.Cu")
	)
	(gr_arc
		(start 156.435298 -12.824968)
		(mid 156.179266 -11.979148)
		(end 155.333446 -12.23518)
		(stroke
			(width 0.2)
			(type default)
		)
		(layer "In6.Cu")
	)
	(gr_line
		(start 156.831538 -25.033732)
		(end 156.831792 -25.033986)
		(stroke
			(width 0.2)
			(type default)
		)
		(layer "In6.Cu")
	)
	(gr_line
		(start 156.831538 -21.233892)
		(end 156.83357 -21.235162)
		(stroke
			(width 0.2)
			(type default)
		)
		(layer "In6.Cu")
	)
	(gr_line
		(start 156.831538 -17.433544)
		(end 156.831792 -17.433798)
		(stroke
			(width 0.2)
			(type default)
		)
		(layer "In6.Cu")
	)
	(gr_line
		(start 156.831538 -13.633704)
		(end 156.831792 -13.633958)
		(stroke
			(width 0.2)
			(type default)
		)
		(layer "In6.Cu")
	)
	(gr_line
		(start 156.831792 -25.033986)
		(end 156.833824 -25.035002)
		(stroke
			(width 0.2)
			(type default)
		)
		(layer "In6.Cu")
	)
	(gr_line
		(start 156.831792 -17.433798)
		(end 156.833824 -17.434814)
		(stroke
			(width 0.2)
			(type default)
		)
		(layer "In6.Cu")
	)
	(gr_line
		(start 156.831792 -13.633958)
		(end 156.833824 -13.634974)
		(stroke
			(width 0.2)
			(type default)
		)
		(layer "In6.Cu")
	)
	(gr_arc
		(start 156.83357 -21.235162)
		(mid 157.089602 -22.080982)
		(end 157.935422 -21.82495)
		(stroke
			(width 0.2)
			(type default)
		)
		(layer "In6.Cu")
	)
	(gr_arc
		(start 156.833824 -25.035002)
		(mid 157.0895 -25.880903)
		(end 157.935422 -25.625044)
		(stroke
			(width 0.2)
			(type default)
		)
		(layer "In6.Cu")
	)
	(gr_arc
		(start 156.833824 -17.434814)
		(mid 157.089348 -18.280634)
		(end 157.935168 -18.02511)
		(stroke
			(width 0.2)
			(type default)
		)
		(layer "In6.Cu")
	)
	(gr_arc
		(start 156.833824 -13.634974)
		(mid 157.0895 -14.480875)
		(end 157.935422 -14.225016)
		(stroke
			(width 0.2)
			(type default)
		)
		(layer "In6.Cu")
	)
	(gr_arc
		(start 156.906214 -222.805244)
		(mid 157.417008 -222.294831)
		(end 156.906468 -221.784164)
		(stroke
			(width 0.2)
			(type default)
		)
		(layer "In6.Cu")
	)
	(gr_line
		(start 156.906468 -221.784164)
		(end 156.093668 -221.784164)
		(stroke
			(width 0.2)
			(type default)
		)
		(layer "In6.Cu")
	)
	(gr_line
		(start 157.5816 -23.633938)
		(end 156.831538 -25.033732)
		(stroke
			(width 0.2)
			(type default)
		)
		(layer "In6.Cu")
	)
	(gr_line
		(start 157.5816 -19.833844)
		(end 156.831538 -21.233892)
		(stroke
			(width 0.2)
			(type default)
		)
		(layer "In6.Cu")
	)
	(gr_line
		(start 157.5816 -16.03375)
		(end 156.831538 -17.433544)
		(stroke
			(width 0.2)
			(type default)
		)
		(layer "In6.Cu")
	)
	(gr_line
		(start 157.5816 -12.23391)
		(end 156.831538 -13.633704)
		(stroke
			(width 0.2)
			(type default)
		)
		(layer "In6.Cu")
	)
	(gr_line
		(start 157.583632 -23.635208)
		(end 157.5816 -23.633938)
		(stroke
			(width 0.2)
			(type default)
		)
		(layer "In6.Cu")
	)
	(gr_line
		(start 157.583632 -19.835114)
		(end 157.5816 -19.833844)
		(stroke
			(width 0.2)
			(type default)
		)
		(layer "In6.Cu")
	)
	(gr_line
		(start 157.583632 -12.23518)
		(end 157.5816 -12.23391)
		(stroke
			(width 0.2)
			(type default)
		)
		(layer "In6.Cu")
	)
	(gr_line
		(start 157.583886 -16.03502)
		(end 157.5816 -16.03375)
		(stroke
			(width 0.2)
			(type default)
		)
		(layer "In6.Cu")
	)
	(gr_line
		(start 157.693868 -211.406994)
		(end 158.506668 -211.406994)
		(stroke
			(width 0.2)
			(type default)
		)
		(layer "In6.Cu")
	)
	(gr_arc
		(start 157.694122 -210.385914)
		(mid 157.183328 -210.896327)
		(end 157.693868 -211.406994)
		(stroke
			(width 0.2)
			(type default)
		)
		(layer "In6.Cu")
	)
	(gr_line
		(start 157.935168 -18.02511)
		(end 157.937454 -18.02638)
		(stroke
			(width 0.2)
			(type default)
		)
		(layer "In6.Cu")
	)
	(gr_line
		(start 157.935422 -25.625044)
		(end 157.937454 -25.626314)
		(stroke
			(width 0.2)
			(type default)
		)
		(layer "In6.Cu")
	)
	(gr_line
		(start 157.935422 -21.82495)
		(end 157.937454 -21.82622)
		(stroke
			(width 0.2)
			(type default)
		)
		(layer "In6.Cu")
	)
	(gr_line
		(start 157.935422 -14.225016)
		(end 157.937454 -14.226286)
		(stroke
			(width 0.2)
			(type default)
		)
		(layer "In6.Cu")
	)
	(gr_line
		(start 157.937454 -25.626314)
		(end 158.687516 -24.226266)
		(stroke
			(width 0.2)
			(type default)
		)
		(layer "In6.Cu")
	)
	(gr_line
		(start 157.937454 -21.82622)
		(end 158.687516 -20.426426)
		(stroke
			(width 0.2)
			(type default)
		)
		(layer "In6.Cu")
	)
	(gr_line
		(start 157.937454 -18.02638)
		(end 158.687516 -16.626586)
		(stroke
			(width 0.2)
			(type default)
		)
		(layer "In6.Cu")
	)
	(gr_line
		(start 157.937454 -14.226286)
		(end 158.687516 -12.826238)
		(stroke
			(width 0.2)
			(type default)
		)
		(layer "In6.Cu")
	)
	(gr_arc
		(start 158.506668 -211.406994)
		(mid 159.017208 -210.896454)
		(end 158.506668 -210.385914)
		(stroke
			(width 0.2)
			(type default)
		)
		(layer "In6.Cu")
	)
	(gr_line
		(start 158.506668 -210.385914)
		(end 157.694122 -210.385914)
		(stroke
			(width 0.2)
			(type default)
		)
		(layer "In6.Cu")
	)
	(gr_line
		(start 158.655004 -35.53206)
		(end 159.467804 -35.53206)
		(stroke
			(width 0.2)
			(type default)
		)
		(layer "In6.Cu")
	)
	(gr_arc
		(start 158.655258 -34.51098)
		(mid 158.144464 -35.021393)
		(end 158.655004 -35.53206)
		(stroke
			(width 0.2)
			(type default)
		)
		(layer "In6.Cu")
	)
	(gr_arc
		(start 158.68523 -20.425156)
		(mid 158.429554 -19.579255)
		(end 157.583632 -19.835114)
		(stroke
			(width 0.2)
			(type default)
		)
		(layer "In6.Cu")
	)
	(gr_arc
		(start 158.68523 -16.625316)
		(mid 158.429706 -15.779496)
		(end 157.583886 -16.03502)
		(stroke
			(width 0.2)
			(type default)
		)
		(layer "In6.Cu")
	)
	(gr_arc
		(start 158.685484 -24.224996)
		(mid 158.429452 -23.379176)
		(end 157.583632 -23.635208)
		(stroke
			(width 0.2)
			(type default)
		)
		(layer "In6.Cu")
	)
	(gr_arc
		(start 158.685484 -12.824968)
		(mid 158.429452 -11.979148)
		(end 157.583632 -12.23518)
		(stroke
			(width 0.2)
			(type default)
		)
		(layer "In6.Cu")
	)
	(gr_line
		(start 158.687262 -20.426172)
		(end 158.68523 -20.425156)
		(stroke
			(width 0.2)
			(type default)
		)
		(layer "In6.Cu")
	)
	(gr_line
		(start 158.687516 -24.226266)
		(end 158.685484 -24.224996)
		(stroke
			(width 0.2)
			(type default)
		)
		(layer "In6.Cu")
	)
	(gr_line
		(start 158.687516 -20.426426)
		(end 158.687262 -20.426172)
		(stroke
			(width 0.2)
			(type default)
		)
		(layer "In6.Cu")
	)
	(gr_line
		(start 158.687516 -16.626586)
		(end 158.68523 -16.625316)
		(stroke
			(width 0.2)
			(type default)
		)
		(layer "In6.Cu")
	)
	(gr_line
		(start 158.687516 -12.826238)
		(end 158.685484 -12.824968)
		(stroke
			(width 0.2)
			(type default)
		)
		(layer "In6.Cu")
	)
	(gr_line
		(start 159.08147 -25.033732)
		(end 159.081724 -25.033986)
		(stroke
			(width 0.2)
			(type default)
		)
		(layer "In6.Cu")
	)
	(gr_line
		(start 159.08147 -21.233892)
		(end 159.083502 -21.235162)
		(stroke
			(width 0.2)
			(type default)
		)
		(layer "In6.Cu")
	)
	(gr_line
		(start 159.08147 -17.433544)
		(end 159.081724 -17.433798)
		(stroke
			(width 0.2)
			(type default)
		)
		(layer "In6.Cu")
	)
	(gr_line
		(start 159.08147 -13.633704)
		(end 159.081724 -13.633958)
		(stroke
			(width 0.2)
			(type default)
		)
		(layer "In6.Cu")
	)
	(gr_line
		(start 159.081724 -25.033986)
		(end 159.083756 -25.035002)
		(stroke
			(width 0.2)
			(type default)
		)
		(layer "In6.Cu")
	)
	(gr_line
		(start 159.081724 -17.433798)
		(end 159.083756 -17.434814)
		(stroke
			(width 0.2)
			(type default)
		)
		(layer "In6.Cu")
	)
	(gr_line
		(start 159.081724 -13.633958)
		(end 159.083756 -13.634974)
		(stroke
			(width 0.2)
			(type default)
		)
		(layer "In6.Cu")
	)
	(gr_arc
		(start 159.083502 -21.235162)
		(mid 159.339534 -22.080982)
		(end 160.185354 -21.82495)
		(stroke
			(width 0.2)
			(type default)
		)
		(layer "In6.Cu")
	)
	(gr_arc
		(start 159.083756 -25.035002)
		(mid 159.339432 -25.880903)
		(end 160.185354 -25.625044)
		(stroke
			(width 0.2)
			(type default)
		)
		(layer "In6.Cu")
	)
	(gr_arc
		(start 159.083756 -17.434814)
		(mid 159.33928 -18.280634)
		(end 160.1851 -18.02511)
		(stroke
			(width 0.2)
			(type default)
		)
		(layer "In6.Cu")
	)
	(gr_arc
		(start 159.083756 -13.634974)
		(mid 159.339432 -14.480875)
		(end 160.185354 -14.225016)
		(stroke
			(width 0.2)
			(type default)
		)
		(layer "In6.Cu")
	)
	(gr_line
		(start 159.29356 -222.805244)
		(end 160.106106 -222.805244)
		(stroke
			(width 0.2)
			(type default)
		)
		(layer "In6.Cu")
	)
	(gr_arc
		(start 159.29356 -221.784164)
		(mid 158.78302 -222.294704)
		(end 159.29356 -222.805244)
		(stroke
			(width 0.2)
			(type default)
		)
		(layer "In6.Cu")
	)
	(gr_arc
		(start 159.467804 -35.53206)
		(mid 159.978344 -35.02152)
		(end 159.467804 -34.51098)
		(stroke
			(width 0.2)
			(type default)
		)
		(layer "In6.Cu")
	)
	(gr_line
		(start 159.467804 -34.51098)
		(end 158.655258 -34.51098)
		(stroke
			(width 0.2)
			(type default)
		)
		(layer "In6.Cu")
	)
	(gr_line
		(start 159.831532 -23.633938)
		(end 159.08147 -25.033732)
		(stroke
			(width 0.2)
			(type default)
		)
		(layer "In6.Cu")
	)
	(gr_line
		(start 159.831532 -19.833844)
		(end 159.08147 -21.233892)
		(stroke
			(width 0.2)
			(type default)
		)
		(layer "In6.Cu")
	)
	(gr_line
		(start 159.831532 -16.03375)
		(end 159.08147 -17.433544)
		(stroke
			(width 0.2)
			(type default)
		)
		(layer "In6.Cu")
	)
	(gr_line
		(start 159.831532 -12.23391)
		(end 159.08147 -13.633704)
		(stroke
			(width 0.2)
			(type default)
		)
		(layer "In6.Cu")
	)
	(gr_line
		(start 159.833564 -23.635208)
		(end 159.831532 -23.633938)
		(stroke
			(width 0.2)
			(type default)
		)
		(layer "In6.Cu")
	)
	(gr_line
		(start 159.833564 -19.835114)
		(end 159.831532 -19.833844)
		(stroke
			(width 0.2)
			(type default)
		)
		(layer "In6.Cu")
	)
	(gr_line
		(start 159.833564 -12.23518)
		(end 159.831532 -12.23391)
		(stroke
			(width 0.2)
			(type default)
		)
		(layer "In6.Cu")
	)
	(gr_line
		(start 159.833818 -16.03502)
		(end 159.831532 -16.03375)
		(stroke
			(width 0.2)
			(type default)
		)
		(layer "In6.Cu")
	)
	(gr_arc
		(start 160.106106 -222.805244)
		(mid 160.6169 -222.294831)
		(end 160.10636 -221.784164)
		(stroke
			(width 0.2)
			(type default)
		)
		(layer "In6.Cu")
	)
	(gr_line
		(start 160.10636 -221.784164)
		(end 159.29356 -221.784164)
		(stroke
			(width 0.2)
			(type default)
		)
		(layer "In6.Cu")
	)
	(gr_line
		(start 160.1851 -18.02511)
		(end 160.187386 -18.02638)
		(stroke
			(width 0.2)
			(type default)
		)
		(layer "In6.Cu")
	)
	(gr_line
		(start 160.185354 -25.625044)
		(end 160.187386 -25.626314)
		(stroke
			(width 0.2)
			(type default)
		)
		(layer "In6.Cu")
	)
	(gr_line
		(start 160.185354 -21.82495)
		(end 160.187386 -21.82622)
		(stroke
			(width 0.2)
			(type default)
		)
		(layer "In6.Cu")
	)
	(gr_line
		(start 160.185354 -14.225016)
		(end 160.187386 -14.226286)
		(stroke
			(width 0.2)
			(type default)
		)
		(layer "In6.Cu")
	)
	(gr_line
		(start 160.187386 -25.626314)
		(end 160.937448 -24.226266)
		(stroke
			(width 0.2)
			(type default)
		)
		(layer "In6.Cu")
	)
	(gr_line
		(start 160.187386 -21.82622)
		(end 160.937448 -20.426426)
		(stroke
			(width 0.2)
			(type default)
		)
		(layer "In6.Cu")
	)
	(gr_line
		(start 160.187386 -18.02638)
		(end 160.937448 -16.626586)
		(stroke
			(width 0.2)
			(type default)
		)
		(layer "In6.Cu")
	)
	(gr_line
		(start 160.187386 -14.226286)
		(end 160.937448 -12.826238)
		(stroke
			(width 0.2)
			(type default)
		)
		(layer "In6.Cu")
	)
	(gr_line
		(start 160.89376 -211.406994)
		(end 161.70656 -211.406994)
		(stroke
			(width 0.2)
			(type default)
		)
		(layer "In6.Cu")
	)
	(gr_arc
		(start 160.894014 -210.385914)
		(mid 160.38322 -210.896327)
		(end 160.89376 -211.406994)
		(stroke
			(width 0.2)
			(type default)
		)
		(layer "In6.Cu")
	)
	(gr_arc
		(start 160.935162 -20.425156)
		(mid 160.679486 -19.579255)
		(end 159.833564 -19.835114)
		(stroke
			(width 0.2)
			(type default)
		)
		(layer "In6.Cu")
	)
	(gr_arc
		(start 160.935162 -16.625316)
		(mid 160.679638 -15.779496)
		(end 159.833818 -16.03502)
		(stroke
			(width 0.2)
			(type default)
		)
		(layer "In6.Cu")
	)
	(gr_arc
		(start 160.935416 -24.224996)
		(mid 160.679384 -23.379176)
		(end 159.833564 -23.635208)
		(stroke
			(width 0.2)
			(type default)
		)
		(layer "In6.Cu")
	)
	(gr_arc
		(start 160.935416 -12.824968)
		(mid 160.679384 -11.979148)
		(end 159.833564 -12.23518)
		(stroke
			(width 0.2)
			(type default)
		)
		(layer "In6.Cu")
	)
	(gr_line
		(start 160.937194 -20.426172)
		(end 160.935162 -20.425156)
		(stroke
			(width 0.2)
			(type default)
		)
		(layer "In6.Cu")
	)
	(gr_line
		(start 160.937448 -24.226266)
		(end 160.935416 -24.224996)
		(stroke
			(width 0.2)
			(type default)
		)
		(layer "In6.Cu")
	)
	(gr_line
		(start 160.937448 -20.426426)
		(end 160.937194 -20.426172)
		(stroke
			(width 0.2)
			(type default)
		)
		(layer "In6.Cu")
	)
	(gr_line
		(start 160.937448 -16.626586)
		(end 160.935162 -16.625316)
		(stroke
			(width 0.2)
			(type default)
		)
		(layer "In6.Cu")
	)
	(gr_line
		(start 160.937448 -12.826238)
		(end 160.935416 -12.824968)
		(stroke
			(width 0.2)
			(type default)
		)
		(layer "In6.Cu")
	)
	(gr_line
		(start 161.2773 -35.53206)
		(end 162.0901 -35.53206)
		(stroke
			(width 0.2)
			(type default)
		)
		(layer "In6.Cu")
	)
	(gr_arc
		(start 161.277554 -34.51098)
		(mid 160.76676 -35.021393)
		(end 161.2773 -35.53206)
		(stroke
			(width 0.2)
			(type default)
		)
		(layer "In6.Cu")
	)
	(gr_arc
		(start 161.70656 -211.406994)
		(mid 162.2171 -210.896454)
		(end 161.70656 -210.385914)
		(stroke
			(width 0.2)
			(type default)
		)
		(layer "In6.Cu")
	)
	(gr_line
		(start 161.70656 -210.385914)
		(end 160.894014 -210.385914)
		(stroke
			(width 0.2)
			(type default)
		)
		(layer "In6.Cu")
	)
	(gr_line
		(start 161.7853 -38.52164)
		(end 162.597846 -38.52164)
		(stroke
			(width 0.2)
			(type default)
		)
		(layer "In6.Cu")
	)
	(gr_arc
		(start 161.7853 -37.50056)
		(mid 161.27476 -38.0111)
		(end 161.7853 -38.52164)
		(stroke
			(width 0.2)
			(type default)
		)
		(layer "In6.Cu")
	)
	(gr_arc
		(start 162.0901 -35.53206)
		(mid 162.60064 -35.02152)
		(end 162.0901 -34.51098)
		(stroke
			(width 0.2)
			(type default)
		)
		(layer "In6.Cu")
	)
	(gr_line
		(start 162.0901 -34.51098)
		(end 161.277554 -34.51098)
		(stroke
			(width 0.2)
			(type default)
		)
		(layer "In6.Cu")
	)
	(gr_arc
		(start 162.597846 -38.52164)
		(mid 163.10864 -38.011227)
		(end 162.5981 -37.50056)
		(stroke
			(width 0.2)
			(type default)
		)
		(layer "In6.Cu")
	)
	(gr_line
		(start 162.5981 -37.50056)
		(end 161.7853 -37.50056)
		(stroke
			(width 0.2)
			(type default)
		)
		(layer "In6.Cu")
	)
	(gr_line
		(start 162.6997 -82.17154)
		(end 163.512246 -82.17154)
		(stroke
			(width 0.2)
			(type default)
		)
		(layer "In6.Cu")
	)
	(gr_arc
		(start 162.6997 -81.15046)
		(mid 162.18916 -81.661)
		(end 162.6997 -82.17154)
		(stroke
			(width 0.2)
			(type default)
		)
		(layer "In6.Cu")
	)
	(gr_arc
		(start 163.512246 -82.17154)
		(mid 164.02304 -81.661127)
		(end 163.5125 -81.15046)
		(stroke
			(width 0.2)
			(type default)
		)
		(layer "In6.Cu")
	)
	(gr_line
		(start 163.5125 -81.15046)
		(end 162.6997 -81.15046)
		(stroke
			(width 0.2)
			(type default)
		)
		(layer "In6.Cu")
	)
	(gr_line
		(start 164.893752 -222.805244)
		(end 165.706298 -222.805244)
		(stroke
			(width 0.2)
			(type default)
		)
		(layer "In6.Cu")
	)
	(gr_arc
		(start 164.893752 -221.784164)
		(mid 164.383212 -222.294704)
		(end 164.893752 -222.805244)
		(stroke
			(width 0.2)
			(type default)
		)
		(layer "In6.Cu")
	)
	(gr_arc
		(start 165.583616 -25.035256)
		(mid 165.839648 -25.881076)
		(end 166.685468 -25.625044)
		(stroke
			(width 0.2)
			(type default)
		)
		(layer "In6.Cu")
	)
	(gr_arc
		(start 165.58768 -13.627608)
		(mid 165.835814 -14.479061)
		(end 166.685468 -14.225016)
		(stroke
			(width 0.2)
			(type default)
		)
		(layer "In6.Cu")
	)
	(gr_arc
		(start 165.706298 -222.805244)
		(mid 166.217092 -222.294831)
		(end 165.706552 -221.784164)
		(stroke
			(width 0.2)
			(type default)
		)
		(layer "In6.Cu")
	)
	(gr_line
		(start 165.706552 -221.784164)
		(end 164.893752 -221.784164)
		(stroke
			(width 0.2)
			(type default)
		)
		(layer "In6.Cu")
	)
	(gr_line
		(start 166.333424 -23.635208)
		(end 165.583616 -25.035256)
		(stroke
			(width 0.2)
			(type default)
		)
		(layer "In6.Cu")
	)
	(gr_line
		(start 166.333424 -12.23518)
		(end 165.58768 -13.627608)
		(stroke
			(width 0.2)
			(type default)
		)
		(layer "In6.Cu")
	)
	(gr_line
		(start 166.493698 -211.406994)
		(end 167.306498 -211.406994)
		(stroke
			(width 0.2)
			(type default)
		)
		(layer "In6.Cu")
	)
	(gr_arc
		(start 166.493952 -210.385914)
		(mid 165.983158 -210.896327)
		(end 166.493698 -211.406994)
		(stroke
			(width 0.2)
			(type default)
		)
		(layer "In6.Cu")
	)
	(gr_line
		(start 166.685468 -25.625044)
		(end 167.431212 -24.232616)
		(stroke
			(width 0.2)
			(type default)
		)
		(layer "In6.Cu")
	)
	(gr_line
		(start 166.685468 -14.225016)
		(end 167.435276 -12.824968)
		(stroke
			(width 0.2)
			(type default)
		)
		(layer "In6.Cu")
	)
	(gr_arc
		(start 167.191436 -89.4588)
		(mid 167.701976 -89.96934)
		(end 168.212516 -89.4588)
		(stroke
			(width 0.2)
			(type default)
		)
		(layer "In6.Cu")
	)
	(gr_line
		(start 167.191436 -88.646)
		(end 167.191436 -89.4588)
		(stroke
			(width 0.2)
			(type default)
		)
		(layer "In6.Cu")
	)
	(gr_arc
		(start 167.306498 -211.406994)
		(mid 167.817038 -210.896454)
		(end 167.306498 -210.385914)
		(stroke
			(width 0.2)
			(type default)
		)
		(layer "In6.Cu")
	)
	(gr_line
		(start 167.306498 -210.385914)
		(end 166.493952 -210.385914)
		(stroke
			(width 0.2)
			(type default)
		)
		(layer "In6.Cu")
	)
	(gr_arc
		(start 167.431212 -24.232616)
		(mid 167.183078 -23.381163)
		(end 166.333424 -23.635208)
		(stroke
			(width 0.2)
			(type default)
		)
		(layer "In6.Cu")
	)
	(gr_arc
		(start 167.435276 -12.824968)
		(mid 167.179244 -11.979148)
		(end 166.333424 -12.23518)
		(stroke
			(width 0.2)
			(type default)
		)
		(layer "In6.Cu")
	)
	(gr_line
		(start 167.831516 -25.033732)
		(end 167.83177 -25.033986)
		(stroke
			(width 0.2)
			(type default)
		)
		(layer "In6.Cu")
	)
	(gr_line
		(start 167.831516 -21.233892)
		(end 167.833548 -21.235162)
		(stroke
			(width 0.2)
			(type default)
		)
		(layer "In6.Cu")
	)
	(gr_line
		(start 167.831516 -17.433544)
		(end 167.83177 -17.433798)
		(stroke
			(width 0.2)
			(type default)
		)
		(layer "In6.Cu")
	)
	(gr_line
		(start 167.831516 -13.633704)
		(end 167.83177 -13.633958)
		(stroke
			(width 0.2)
			(type default)
		)
		(layer "In6.Cu")
	)
	(gr_line
		(start 167.83177 -25.033986)
		(end 167.833802 -25.035002)
		(stroke
			(width 0.2)
			(type default)
		)
		(layer "In6.Cu")
	)
	(gr_line
		(start 167.83177 -17.433798)
		(end 167.833802 -17.434814)
		(stroke
			(width 0.2)
			(type default)
		)
		(layer "In6.Cu")
	)
	(gr_line
		(start 167.83177 -13.633958)
		(end 167.833802 -13.634974)
		(stroke
			(width 0.2)
			(type default)
		)
		(layer "In6.Cu")
	)
	(gr_arc
		(start 167.833548 -21.235162)
		(mid 168.08958 -22.080982)
		(end 168.9354 -21.82495)
		(stroke
			(width 0.2)
			(type default)
		)
		(layer "In6.Cu")
	)
	(gr_arc
		(start 167.833802 -25.035002)
		(mid 168.089478 -25.880903)
		(end 168.9354 -25.625044)
		(stroke
			(width 0.2)
			(type default)
		)
		(layer "In6.Cu")
	)
	(gr_arc
		(start 167.833802 -17.434814)
		(mid 168.089326 -18.280634)
		(end 168.935146 -18.02511)
		(stroke
			(width 0.2)
			(type default)
		)
		(layer "In6.Cu")
	)
	(gr_arc
		(start 167.833802 -13.634974)
		(mid 168.089478 -14.480875)
		(end 168.9354 -14.225016)
		(stroke
			(width 0.2)
			(type default)
		)
		(layer "In6.Cu")
	)
	(gr_line
		(start 168.093644 -222.805244)
		(end 168.90619 -222.805244)
		(stroke
			(width 0.2)
			(type default)
		)
		(layer "In6.Cu")
	)
	(gr_arc
		(start 168.093644 -221.784164)
		(mid 167.583104 -222.294704)
		(end 168.093644 -222.805244)
		(stroke
			(width 0.2)
			(type default)
		)
		(layer "In6.Cu")
	)
	(gr_line
		(start 168.212516 -89.4588)
		(end 168.212516 -88.646254)
		(stroke
			(width 0.2)
			(type default)
		)
		(layer "In6.Cu")
	)
	(gr_arc
		(start 168.212516 -88.646254)
		(mid 167.702103 -88.13546)
		(end 167.191436 -88.646)
		(stroke
			(width 0.2)
			(type default)
		)
		(layer "In6.Cu")
	)
	(gr_line
		(start 168.581578 -23.633938)
		(end 167.831516 -25.033732)
		(stroke
			(width 0.2)
			(type default)
		)
		(layer "In6.Cu")
	)
	(gr_line
		(start 168.581578 -19.833844)
		(end 167.831516 -21.233892)
		(stroke
			(width 0.2)
			(type default)
		)
		(layer "In6.Cu")
	)
	(gr_line
		(start 168.581578 -16.03375)
		(end 167.831516 -17.433544)
		(stroke
			(width 0.2)
			(type default)
		)
		(layer "In6.Cu")
	)
	(gr_line
		(start 168.581578 -12.23391)
		(end 167.831516 -13.633704)
		(stroke
			(width 0.2)
			(type default)
		)
		(layer "In6.Cu")
	)
	(gr_line
		(start 168.58361 -23.635208)
		(end 168.581578 -23.633938)
		(stroke
			(width 0.2)
			(type default)
		)
		(layer "In6.Cu")
	)
	(gr_line
		(start 168.58361 -19.835114)
		(end 168.581578 -19.833844)
		(stroke
			(width 0.2)
			(type default)
		)
		(layer "In6.Cu")
	)
	(gr_line
		(start 168.58361 -12.23518)
		(end 168.581578 -12.23391)
		(stroke
			(width 0.2)
			(type default)
		)
		(layer "In6.Cu")
	)
	(gr_line
		(start 168.583864 -16.03502)
		(end 168.581578 -16.03375)
		(stroke
			(width 0.2)
			(type default)
		)
		(layer "In6.Cu")
	)
	(gr_arc
		(start 168.90619 -222.805244)
		(mid 169.416984 -222.294831)
		(end 168.906444 -221.784164)
		(stroke
			(width 0.2)
			(type default)
		)
		(layer "In6.Cu")
	)
	(gr_line
		(start 168.906444 -221.784164)
		(end 168.093644 -221.784164)
		(stroke
			(width 0.2)
			(type default)
		)
		(layer "In6.Cu")
	)
	(gr_line
		(start 168.935146 -18.02511)
		(end 168.937432 -18.02638)
		(stroke
			(width 0.2)
			(type default)
		)
		(layer "In6.Cu")
	)
	(gr_line
		(start 168.9354 -25.625044)
		(end 168.937432 -25.626314)
		(stroke
			(width 0.2)
			(type default)
		)
		(layer "In6.Cu")
	)
	(gr_line
		(start 168.9354 -21.82495)
		(end 168.937432 -21.82622)
		(stroke
			(width 0.2)
			(type default)
		)
		(layer "In6.Cu")
	)
	(gr_line
		(start 168.9354 -14.225016)
		(end 168.937432 -14.226286)
		(stroke
			(width 0.2)
			(type default)
		)
		(layer "In6.Cu")
	)
	(gr_line
		(start 168.937432 -25.626314)
		(end 169.687494 -24.226266)
		(stroke
			(width 0.2)
			(type default)
		)
		(layer "In6.Cu")
	)
	(gr_line
		(start 168.937432 -21.82622)
		(end 169.687494 -20.426426)
		(stroke
			(width 0.2)
			(type default)
		)
		(layer "In6.Cu")
	)
	(gr_line
		(start 168.937432 -18.02638)
		(end 169.687494 -16.626586)
		(stroke
			(width 0.2)
			(type default)
		)
		(layer "In6.Cu")
	)
	(gr_line
		(start 168.937432 -14.226286)
		(end 169.687494 -12.826238)
		(stroke
			(width 0.2)
			(type default)
		)
		(layer "In6.Cu")
	)
	(gr_arc
		(start 169.685208 -20.425156)
		(mid 169.429532 -19.579255)
		(end 168.58361 -19.835114)
		(stroke
			(width 0.2)
			(type default)
		)
		(layer "In6.Cu")
	)
	(gr_arc
		(start 169.685208 -16.625316)
		(mid 169.429684 -15.779496)
		(end 168.583864 -16.03502)
		(stroke
			(width 0.2)
			(type default)
		)
		(layer "In6.Cu")
	)
	(gr_arc
		(start 169.685462 -24.224996)
		(mid 169.42943 -23.379176)
		(end 168.58361 -23.635208)
		(stroke
			(width 0.2)
			(type default)
		)
		(layer "In6.Cu")
	)
	(gr_arc
		(start 169.685462 -12.824968)
		(mid 169.42943 -11.979148)
		(end 168.58361 -12.23518)
		(stroke
			(width 0.2)
			(type default)
		)
		(layer "In6.Cu")
	)
	(gr_line
		(start 169.68724 -20.426172)
		(end 169.685208 -20.425156)
		(stroke
			(width 0.2)
			(type default)
		)
		(layer "In6.Cu")
	)
	(gr_line
		(start 169.687494 -24.226266)
		(end 169.685462 -24.224996)
		(stroke
			(width 0.2)
			(type default)
		)
		(layer "In6.Cu")
	)
	(gr_line
		(start 169.687494 -20.426426)
		(end 169.68724 -20.426172)
		(stroke
			(width 0.2)
			(type default)
		)
		(layer "In6.Cu")
	)
	(gr_line
		(start 169.687494 -16.626586)
		(end 169.685208 -16.625316)
		(stroke
			(width 0.2)
			(type default)
		)
		(layer "In6.Cu")
	)
	(gr_line
		(start 169.687494 -12.826238)
		(end 169.685462 -12.824968)
		(stroke
			(width 0.2)
			(type default)
		)
		(layer "In6.Cu")
	)
	(gr_line
		(start 169.69359 -211.406994)
		(end 170.50639 -211.406994)
		(stroke
			(width 0.2)
			(type default)
		)
		(layer "In6.Cu")
	)
	(gr_arc
		(start 169.693844 -210.385914)
		(mid 169.18305 -210.896327)
		(end 169.69359 -211.406994)
		(stroke
			(width 0.2)
			(type default)
		)
		(layer "In6.Cu")
	)
	(gr_line
		(start 170.081448 -25.033732)
		(end 170.081702 -25.033986)
		(stroke
			(width 0.2)
			(type default)
		)
		(layer "In6.Cu")
	)
	(gr_line
		(start 170.081448 -21.233892)
		(end 170.08348 -21.235162)
		(stroke
			(width 0.2)
			(type default)
		)
		(layer "In6.Cu")
	)
	(gr_line
		(start 170.081448 -17.433544)
		(end 170.081702 -17.433798)
		(stroke
			(width 0.2)
			(type default)
		)
		(layer "In6.Cu")
	)
	(gr_line
		(start 170.081448 -13.633704)
		(end 170.081702 -13.633958)
		(stroke
			(width 0.2)
			(type default)
		)
		(layer "In6.Cu")
	)
	(gr_line
		(start 170.081702 -25.033986)
		(end 170.083734 -25.035002)
		(stroke
			(width 0.2)
			(type default)
		)
		(layer "In6.Cu")
	)
	(gr_line
		(start 170.081702 -17.433798)
		(end 170.083734 -17.434814)
		(stroke
			(width 0.2)
			(type default)
		)
		(layer "In6.Cu")
	)
	(gr_line
		(start 170.081702 -13.633958)
		(end 170.083734 -13.634974)
		(stroke
			(width 0.2)
			(type default)
		)
		(layer "In6.Cu")
	)
	(gr_arc
		(start 170.08348 -21.235162)
		(mid 170.339512 -22.080982)
		(end 171.185332 -21.82495)
		(stroke
			(width 0.2)
			(type default)
		)
		(layer "In6.Cu")
	)
	(gr_arc
		(start 170.083734 -25.035002)
		(mid 170.33941 -25.880903)
		(end 171.185332 -25.625044)
		(stroke
			(width 0.2)
			(type default)
		)
		(layer "In6.Cu")
	)
	(gr_arc
		(start 170.083734 -17.434814)
		(mid 170.339258 -18.280634)
		(end 171.185078 -18.02511)
		(stroke
			(width 0.2)
			(type default)
		)
		(layer "In6.Cu")
	)
	(gr_arc
		(start 170.083734 -13.634974)
		(mid 170.33941 -14.480875)
		(end 171.185332 -14.225016)
		(stroke
			(width 0.2)
			(type default)
		)
		(layer "In6.Cu")
	)
	(gr_arc
		(start 170.50639 -211.406994)
		(mid 171.01693 -210.896454)
		(end 170.50639 -210.385914)
		(stroke
			(width 0.2)
			(type default)
		)
		(layer "In6.Cu")
	)
	(gr_line
		(start 170.50639 -210.385914)
		(end 169.693844 -210.385914)
		(stroke
			(width 0.2)
			(type default)
		)
		(layer "In6.Cu")
	)
	(gr_line
		(start 170.83151 -23.633938)
		(end 170.081448 -25.033732)
		(stroke
			(width 0.2)
			(type default)
		)
		(layer "In6.Cu")
	)
	(gr_line
		(start 170.83151 -19.833844)
		(end 170.081448 -21.233892)
		(stroke
			(width 0.2)
			(type default)
		)
		(layer "In6.Cu")
	)
	(gr_line
		(start 170.83151 -16.03375)
		(end 170.081448 -17.433544)
		(stroke
			(width 0.2)
			(type default)
		)
		(layer "In6.Cu")
	)
	(gr_line
		(start 170.83151 -12.23391)
		(end 170.081448 -13.633704)
		(stroke
			(width 0.2)
			(type default)
		)
		(layer "In6.Cu")
	)
	(gr_line
		(start 170.833542 -23.635208)
		(end 170.83151 -23.633938)
		(stroke
			(width 0.2)
			(type default)
		)
		(layer "In6.Cu")
	)
	(gr_line
		(start 170.833542 -19.835114)
		(end 170.83151 -19.833844)
		(stroke
			(width 0.2)
			(type default)
		)
		(layer "In6.Cu")
	)
	(gr_line
		(start 170.833542 -12.23518)
		(end 170.83151 -12.23391)
		(stroke
			(width 0.2)
			(type default)
		)
		(layer "In6.Cu")
	)
	(gr_line
		(start 170.833796 -16.03502)
		(end 170.83151 -16.03375)
		(stroke
			(width 0.2)
			(type default)
		)
		(layer "In6.Cu")
	)
	(gr_line
		(start 171.185078 -18.02511)
		(end 171.187364 -18.02638)
		(stroke
			(width 0.2)
			(type default)
		)
		(layer "In6.Cu")
	)
	(gr_line
		(start 171.185332 -25.625044)
		(end 171.187364 -25.626314)
		(stroke
			(width 0.2)
			(type default)
		)
		(layer "In6.Cu")
	)
	(gr_line
		(start 171.185332 -21.82495)
		(end 171.187364 -21.82622)
		(stroke
			(width 0.2)
			(type default)
		)
		(layer "In6.Cu")
	)
	(gr_line
		(start 171.185332 -14.225016)
		(end 171.187364 -14.226286)
		(stroke
			(width 0.2)
			(type default)
		)
		(layer "In6.Cu")
	)
	(gr_line
		(start 171.187364 -25.626314)
		(end 171.937426 -24.226266)
		(stroke
			(width 0.2)
			(type default)
		)
		(layer "In6.Cu")
	)
	(gr_line
		(start 171.187364 -21.82622)
		(end 171.937426 -20.426426)
		(stroke
			(width 0.2)
			(type default)
		)
		(layer "In6.Cu")
	)
	(gr_line
		(start 171.187364 -18.02638)
		(end 171.937426 -16.626586)
		(stroke
			(width 0.2)
			(type default)
		)
		(layer "In6.Cu")
	)
	(gr_line
		(start 171.187364 -14.226286)
		(end 171.937426 -12.826238)
		(stroke
			(width 0.2)
			(type default)
		)
		(layer "In6.Cu")
	)
	(gr_line
		(start 171.29379 -222.805244)
		(end 172.106336 -222.805244)
		(stroke
			(width 0.2)
			(type default)
		)
		(layer "In6.Cu")
	)
	(gr_arc
		(start 171.29379 -221.784164)
		(mid 170.78325 -222.294704)
		(end 171.29379 -222.805244)
		(stroke
			(width 0.2)
			(type default)
		)
		(layer "In6.Cu")
	)
	(gr_arc
		(start 171.93514 -20.425156)
		(mid 171.679464 -19.579255)
		(end 170.833542 -19.835114)
		(stroke
			(width 0.2)
			(type default)
		)
		(layer "In6.Cu")
	)
	(gr_arc
		(start 171.93514 -16.625316)
		(mid 171.679616 -15.779496)
		(end 170.833796 -16.03502)
		(stroke
			(width 0.2)
			(type default)
		)
		(layer "In6.Cu")
	)
	(gr_arc
		(start 171.935394 -24.224996)
		(mid 171.679362 -23.379176)
		(end 170.833542 -23.635208)
		(stroke
			(width 0.2)
			(type default)
		)
		(layer "In6.Cu")
	)
	(gr_arc
		(start 171.935394 -12.824968)
		(mid 171.679362 -11.979148)
		(end 170.833542 -12.23518)
		(stroke
			(width 0.2)
			(type default)
		)
		(layer "In6.Cu")
	)
	(gr_line
		(start 171.937172 -20.426172)
		(end 171.93514 -20.425156)
		(stroke
			(width 0.2)
			(type default)
		)
		(layer "In6.Cu")
	)
	(gr_line
		(start 171.937426 -24.226266)
		(end 171.935394 -24.224996)
		(stroke
			(width 0.2)
			(type default)
		)
		(layer "In6.Cu")
	)
	(gr_line
		(start 171.937426 -20.426426)
		(end 171.937172 -20.426172)
		(stroke
			(width 0.2)
			(type default)
		)
		(layer "In6.Cu")
	)
	(gr_line
		(start 171.937426 -16.626586)
		(end 171.93514 -16.625316)
		(stroke
			(width 0.2)
			(type default)
		)
		(layer "In6.Cu")
	)
	(gr_line
		(start 171.937426 -12.826238)
		(end 171.935394 -12.824968)
		(stroke
			(width 0.2)
			(type default)
		)
		(layer "In6.Cu")
	)
	(gr_arc
		(start 172.106336 -222.805244)
		(mid 172.61713 -222.294831)
		(end 172.10659 -221.784164)
		(stroke
			(width 0.2)
			(type default)
		)
		(layer "In6.Cu")
	)
	(gr_line
		(start 172.10659 -221.784164)
		(end 171.29379 -221.784164)
		(stroke
			(width 0.2)
			(type default)
		)
		(layer "In6.Cu")
	)
	(gr_line
		(start 172.7454 -96.704912)
		(end 173.6344 -96.704912)
		(stroke
			(width 0.2)
			(type default)
		)
		(layer "In6.Cu")
	)
	(gr_arc
		(start 172.745654 -95.683832)
		(mid 172.23486 -96.194245)
		(end 172.7454 -96.704912)
		(stroke
			(width 0.2)
			(type default)
		)
		(layer "In6.Cu")
	)
	(gr_line
		(start 172.893736 -211.406994)
		(end 173.706536 -211.406994)
		(stroke
			(width 0.2)
			(type default)
		)
		(layer "In6.Cu")
	)
	(gr_arc
		(start 172.89399 -210.385914)
		(mid 172.383196 -210.896327)
		(end 172.893736 -211.406994)
		(stroke
			(width 0.2)
			(type default)
		)
		(layer "In6.Cu")
	)
	(gr_arc
		(start 173.6344 -96.704912)
		(mid 174.14494 -96.194372)
		(end 173.6344 -95.683832)
		(stroke
			(width 0.2)
			(type default)
		)
		(layer "In6.Cu")
	)
	(gr_line
		(start 173.6344 -95.683832)
		(end 172.745654 -95.683832)
		(stroke
			(width 0.2)
			(type default)
		)
		(layer "In6.Cu")
	)
	(gr_arc
		(start 173.706536 -211.406994)
		(mid 174.217076 -210.896454)
		(end 173.706536 -210.385914)
		(stroke
			(width 0.2)
			(type default)
		)
		(layer "In6.Cu")
	)
	(gr_line
		(start 173.706536 -210.385914)
		(end 172.89399 -210.385914)
		(stroke
			(width 0.2)
			(type default)
		)
		(layer "In6.Cu")
	)
	(gr_line
		(start 174.493682 -222.805244)
		(end 175.306228 -222.805244)
		(stroke
			(width 0.2)
			(type default)
		)
		(layer "In6.Cu")
	)
	(gr_arc
		(start 174.493682 -221.784164)
		(mid 173.983142 -222.294704)
		(end 174.493682 -222.805244)
		(stroke
			(width 0.2)
			(type default)
		)
		(layer "In6.Cu")
	)
	(gr_arc
		(start 175.306228 -222.805244)
		(mid 175.817022 -222.294831)
		(end 175.306482 -221.784164)
		(stroke
			(width 0.2)
			(type default)
		)
		(layer "In6.Cu")
	)
	(gr_line
		(start 175.306482 -221.784164)
		(end 174.493682 -221.784164)
		(stroke
			(width 0.2)
			(type default)
		)
		(layer "In6.Cu")
	)
	(gr_line
		(start 176.093628 -211.406994)
		(end 176.906428 -211.406994)
		(stroke
			(width 0.2)
			(type default)
		)
		(layer "In6.Cu")
	)
	(gr_arc
		(start 176.093882 -210.385914)
		(mid 175.583088 -210.896327)
		(end 176.093628 -211.406994)
		(stroke
			(width 0.2)
			(type default)
		)
		(layer "In6.Cu")
	)
	(gr_arc
		(start 176.906428 -211.406994)
		(mid 177.416968 -210.896454)
		(end 176.906428 -210.385914)
		(stroke
			(width 0.2)
			(type default)
		)
		(layer "In6.Cu")
	)
	(gr_line
		(start 176.906428 -210.385914)
		(end 176.093882 -210.385914)
		(stroke
			(width 0.2)
			(type default)
		)
		(layer "In6.Cu")
	)
	(gr_line
		(start 177.5968 -221.18574)
		(end 178.409346 -221.18574)
		(stroke
			(width 0.2)
			(type default)
		)
		(layer "In6.Cu")
	)
	(gr_arc
		(start 177.5968 -220.16466)
		(mid 177.08626 -220.6752)
		(end 177.5968 -221.18574)
		(stroke
			(width 0.2)
			(type default)
		)
		(layer "In6.Cu")
	)
	(gr_arc
		(start 178.409346 -221.18574)
		(mid 178.92014 -220.675327)
		(end 178.4096 -220.16466)
		(stroke
			(width 0.2)
			(type default)
		)
		(layer "In6.Cu")
	)
	(gr_line
		(start 178.4096 -220.16466)
		(end 177.5968 -220.16466)
		(stroke
			(width 0.2)
			(type default)
		)
		(layer "In6.Cu")
	)
	(gr_line
		(start 180.09997 -228.000052)
		(end 134.500112 -228.000052)
		(stroke
			(width 5.08)
			(type default)
		)
		(layer "In6.Cu")
	)
	(gr_line
		(start 180.09997 -222.600012)
		(end 180.09997 -228.000052)
		(stroke
			(width 1.524)
			(type default)
		)
		(layer "In6.Cu")
	)
	(gr_arc
		(start 181.33568 -13.6906)
		(mid 181.373621 -13.782199)
		(end 181.46522 -13.82014)
		(stroke
			(width 0.2)
			(type default)
		)
		(layer "In6.Cu")
	)
	(gr_line
		(start 181.33568 -12.2936)
		(end 181.33568 -13.6906)
		(stroke
			(width 0.2)
			(type default)
		)
		(layer "In6.Cu")
	)
	(gr_arc
		(start 181.42712 -7.71652)
		(mid 181.457622 -7.790158)
		(end 181.53126 -7.82066)
		(stroke
			(width 0.2)
			(type default)
		)
		(layer "In6.Cu")
	)
	(gr_line
		(start 181.42712 -7.36092)
		(end 181.42712 -7.71652)
		(stroke
			(width 0.2)
			(type default)
		)
		(layer "In6.Cu")
	)
	(gr_arc
		(start 181.42712 -6.65226)
		(mid 181.427355 -6.659772)
		(end 181.428136 -6.667246)
		(stroke
			(width 0.2)
			(type default)
		)
		(layer "In6.Cu")
	)
	(gr_line
		(start 181.42712 -6.29666)
		(end 181.42712 -6.65226)
		(stroke
			(width 0.2)
			(type default)
		)
		(layer "In6.Cu")
	)
	(gr_arc
		(start 181.428136 -7.346442)
		(mid 181.427378 -7.353663)
		(end 181.42712 -7.36092)
		(stroke
			(width 0.2)
			(type default)
		)
		(layer "In6.Cu")
	)
	(gr_line
		(start 181.428136 -6.667246)
		(end 181.428136 -7.346442)
		(stroke
			(width 0.2)
			(type default)
		)
		(layer "In6.Cu")
	)
	(gr_line
		(start 181.46522 -13.82014)
		(end 182.68442 -13.82014)
		(stroke
			(width 0.2)
			(type default)
		)
		(layer "In6.Cu")
	)
	(gr_arc
		(start 181.46522 -12.16406)
		(mid 181.373621 -12.202001)
		(end 181.33568 -12.2936)
		(stroke
			(width 0.2)
			(type default)
		)
		(layer "In6.Cu")
	)
	(gr_line
		(start 181.53126 -7.82066)
		(end 182.357776 -7.82066)
		(stroke
			(width 0.2)
			(type default)
		)
		(layer "In6.Cu")
	)
	(gr_arc
		(start 181.53126 -6.19252)
		(mid 181.457622 -6.223022)
		(end 181.42712 -6.29666)
		(stroke
			(width 0.2)
			(type default)
		)
		(layer "In6.Cu")
	)
	(gr_line
		(start 181.82082 -12.16406)
		(end 181.46522 -12.16406)
		(stroke
			(width 0.2)
			(type default)
		)
		(layer "In6.Cu")
	)
	(gr_arc
		(start 181.838854 -12.16533)
		(mid 181.829859 -12.164384)
		(end 181.82082 -12.16406)
		(stroke
			(width 0.2)
			(type default)
		)
		(layer "In6.Cu")
	)
	(gr_line
		(start 181.88686 -6.19252)
		(end 181.53126 -6.19252)
		(stroke
			(width 0.2)
			(type default)
		)
		(layer "In6.Cu")
	)
	(gr_arc
		(start 181.896766 -6.193028)
		(mid 181.891819 -6.192662)
		(end 181.88686 -6.19252)
		(stroke
			(width 0.2)
			(type default)
		)
		(layer "In6.Cu")
	)
	(gr_line
		(start 182.310786 -12.16533)
		(end 181.838854 -12.16533)
		(stroke
			(width 0.2)
			(type default)
		)
		(layer "In6.Cu")
	)
	(gr_arc
		(start 182.32882 -12.16406)
		(mid 182.31978 -12.164376)
		(end 182.310786 -12.16533)
		(stroke
			(width 0.2)
			(type default)
		)
		(layer "In6.Cu")
	)
	(gr_arc
		(start 182.357776 -7.82066)
		(mid 182.373581 -7.824433)
		(end 182.38978 -7.82574)
		(stroke
			(width 0.2)
			(type default)
		)
		(layer "In6.Cu")
	)
	(gr_line
		(start 182.3847 -6.193028)
		(end 181.896766 -6.193028)
		(stroke
			(width 0.2)
			(type default)
		)
		(layer "In6.Cu")
	)
	(gr_line
		(start 182.38978 -7.82574)
		(end 182.74538 -7.82574)
		(stroke
			(width 0.2)
			(type default)
		)
		(layer "In6.Cu")
	)
	(gr_arc
		(start 182.39486 -6.19252)
		(mid 182.389773 -6.192644)
		(end 182.3847 -6.193028)
		(stroke
			(width 0.2)
			(type default)
		)
		(layer "In6.Cu")
	)
	(gr_line
		(start 182.500016 -228.000052)
		(end 182.500016 -222.600012)
		(stroke
			(width 1.524)
			(type default)
		)
		(layer "In6.Cu")
	)
	(gr_arc
		(start 182.500016 -222.600012)
		(mid 181.30012 -221.400116)
		(end 180.09997 -222.600012)
		(stroke
			(width 1.524)
			(type default)
		)
		(layer "In6.Cu")
	)
	(gr_arc
		(start 182.57266 -29.8069)
		(mid 183.0832 -30.31744)
		(end 183.59374 -29.8069)
		(stroke
			(width 0.2)
			(type default)
		)
		(layer "In6.Cu")
	)
	(gr_line
		(start 182.57266 -28.9941)
		(end 182.57266 -29.8069)
		(stroke
			(width 0.2)
			(type default)
		)
		(layer "In6.Cu")
	)
	(gr_arc
		(start 182.57266 -26.7589)
		(mid 183.0832 -27.26944)
		(end 183.59374 -26.7589)
		(stroke
			(width 0.2)
			(type default)
		)
		(layer "In6.Cu")
	)
	(gr_line
		(start 182.57266 -25.9461)
		(end 182.57266 -26.7589)
		(stroke
			(width 0.2)
			(type default)
		)
		(layer "In6.Cu")
	)
	(gr_arc
		(start 182.57266 -24.472646)
		(mid 183.083073 -24.98344)
		(end 183.59374 -24.4729)
		(stroke
			(width 0.2)
			(type default)
		)
		(layer "In6.Cu")
	)
	(gr_line
		(start 182.57266 -23.6601)
		(end 182.57266 -24.472646)
		(stroke
			(width 0.2)
			(type default)
		)
		(layer "In6.Cu")
	)
	(gr_arc
		(start 182.57266 -20.6629)
		(mid 183.0832 -21.17344)
		(end 183.59374 -20.6629)
		(stroke
			(width 0.2)
			(type default)
		)
		(layer "In6.Cu")
	)
	(gr_line
		(start 182.57266 -19.8501)
		(end 182.57266 -20.6629)
		(stroke
			(width 0.2)
			(type default)
		)
		(layer "In6.Cu")
	)
	(gr_arc
		(start 182.68442 -13.82014)
		(mid 182.776019 -13.782199)
		(end 182.81396 -13.6906)
		(stroke
			(width 0.2)
			(type default)
		)
		(layer "In6.Cu")
	)
	(gr_line
		(start 182.68442 -12.16406)
		(end 182.32882 -12.16406)
		(stroke
			(width 0.2)
			(type default)
		)
		(layer "In6.Cu")
	)
	(gr_arc
		(start 182.74538 -7.82574)
		(mid 182.819018 -7.795238)
		(end 182.84952 -7.7216)
		(stroke
			(width 0.2)
			(type default)
		)
		(layer "In6.Cu")
	)
	(gr_line
		(start 182.75046 -6.19252)
		(end 182.39486 -6.19252)
		(stroke
			(width 0.2)
			(type default)
		)
		(layer "In6.Cu")
	)
	(gr_line
		(start 182.81396 -13.6906)
		(end 182.81396 -12.2936)
		(stroke
			(width 0.2)
			(type default)
		)
		(layer "In6.Cu")
	)
	(gr_arc
		(start 182.81396 -12.2936)
		(mid 182.776019 -12.202001)
		(end 182.68442 -12.16406)
		(stroke
			(width 0.2)
			(type default)
		)
		(layer "In6.Cu")
	)
	(gr_line
		(start 182.84952 -7.7216)
		(end 182.84952 -7.366)
		(stroke
			(width 0.2)
			(type default)
		)
		(layer "In6.Cu")
	)
	(gr_line
		(start 182.84952 -7.366)
		(end 182.84952 -6.684264)
		(stroke
			(width 0.2)
			(type default)
		)
		(layer "In6.Cu")
	)
	(gr_arc
		(start 182.84952 -6.684264)
		(mid 182.853293 -6.668459)
		(end 182.8546 -6.65226)
		(stroke
			(width 0.2)
			(type default)
		)
		(layer "In6.Cu")
	)
	(gr_line
		(start 182.8546 -6.65226)
		(end 182.8546 -6.29666)
		(stroke
			(width 0.2)
			(type default)
		)
		(layer "In6.Cu")
	)
	(gr_arc
		(start 182.8546 -6.29666)
		(mid 182.824098 -6.223022)
		(end 182.75046 -6.19252)
		(stroke
			(width 0.2)
			(type default)
		)
		(layer "In6.Cu")
	)
	(gr_line
		(start 183.59374 -29.8069)
		(end 183.59374 -28.994354)
		(stroke
			(width 0.2)
			(type default)
		)
		(layer "In6.Cu")
	)
	(gr_arc
		(start 183.59374 -28.994354)
		(mid 183.083327 -28.48356)
		(end 182.57266 -28.9941)
		(stroke
			(width 0.2)
			(type default)
		)
		(layer "In6.Cu")
	)
	(gr_line
		(start 183.59374 -26.7589)
		(end 183.59374 -25.946354)
		(stroke
			(width 0.2)
			(type default)
		)
		(layer "In6.Cu")
	)
	(gr_arc
		(start 183.59374 -25.946354)
		(mid 183.083327 -25.43556)
		(end 182.57266 -25.9461)
		(stroke
			(width 0.2)
			(type default)
		)
		(layer "In6.Cu")
	)
	(gr_line
		(start 183.59374 -24.4729)
		(end 183.59374 -23.6601)
		(stroke
			(width 0.2)
			(type default)
		)
		(layer "In6.Cu")
	)
	(gr_arc
		(start 183.59374 -23.6601)
		(mid 183.0832 -23.14956)
		(end 182.57266 -23.6601)
		(stroke
			(width 0.2)
			(type default)
		)
		(layer "In6.Cu")
	)
	(gr_line
		(start 183.59374 -20.6629)
		(end 183.59374 -19.850354)
		(stroke
			(width 0.2)
			(type default)
		)
		(layer "In6.Cu")
	)
	(gr_arc
		(start 183.59374 -19.850354)
		(mid 183.083327 -19.33956)
		(end 182.57266 -19.8501)
		(stroke
			(width 0.2)
			(type default)
		)
		(layer "In6.Cu")
	)
	(gr_line
		(start 183.63057 -8.91667)
		(end 184.443116 -8.91667)
		(stroke
			(width 0.2)
			(type default)
		)
		(layer "In6.Cu")
	)
	(gr_arc
		(start 183.63057 -7.89559)
		(mid 183.12003 -8.40613)
		(end 183.63057 -8.91667)
		(stroke
			(width 0.2)
			(type default)
		)
		(layer "In6.Cu")
	)
	(gr_arc
		(start 184.048146 -12.509754)
		(mid 184.558686 -13.020294)
		(end 185.069226 -12.509754)
		(stroke
			(width 0.2)
			(type default)
		)
		(layer "In6.Cu")
	)
	(gr_line
		(start 184.048146 -11.696954)
		(end 184.048146 -12.509754)
		(stroke
			(width 0.2)
			(type default)
		)
		(layer "In6.Cu")
	)
	(gr_line
		(start 184.093612 -211.406994)
		(end 184.906412 -211.406994)
		(stroke
			(width 0.2)
			(type default)
		)
		(layer "In6.Cu")
	)
	(gr_arc
		(start 184.093866 -210.385914)
		(mid 183.583072 -210.896327)
		(end 184.093612 -211.406994)
		(stroke
			(width 0.2)
			(type default)
		)
		(layer "In6.Cu")
	)
	(gr_arc
		(start 184.443116 -8.91667)
		(mid 184.95391 -8.406257)
		(end 184.44337 -7.89559)
		(stroke
			(width 0.2)
			(type default)
		)
		(layer "In6.Cu")
	)
	(gr_line
		(start 184.44337 -7.89559)
		(end 183.63057 -7.89559)
		(stroke
			(width 0.2)
			(type default)
		)
		(layer "In6.Cu")
	)
	(gr_arc
		(start 184.906412 -211.406994)
		(mid 185.416952 -210.896454)
		(end 184.906412 -210.385914)
		(stroke
			(width 0.2)
			(type default)
		)
		(layer "In6.Cu")
	)
	(gr_line
		(start 184.906412 -210.385914)
		(end 184.093866 -210.385914)
		(stroke
			(width 0.2)
			(type default)
		)
		(layer "In6.Cu")
	)
	(gr_line
		(start 185.069226 -12.509754)
		(end 185.069226 -11.697208)
		(stroke
			(width 0.2)
			(type default)
		)
		(layer "In6.Cu")
	)
	(gr_arc
		(start 185.069226 -11.697208)
		(mid 184.558813 -11.186414)
		(end 184.048146 -11.696954)
		(stroke
			(width 0.2)
			(type default)
		)
		(layer "In6.Cu")
	)
	(gr_arc
		(start 185.54446 -25.811734)
		(mid 186.055 -26.322274)
		(end 186.56554 -25.811734)
		(stroke
			(width 0.2)
			(type default)
		)
		(layer "In6.Cu")
	)
	(gr_line
		(start 185.54446 -24.998934)
		(end 185.54446 -25.811734)
		(stroke
			(width 0.2)
			(type default)
		)
		(layer "In6.Cu")
	)
	(gr_line
		(start 185.693558 -222.805244)
		(end 186.506358 -222.805244)
		(stroke
			(width 0.2)
			(type default)
		)
		(layer "In6.Cu")
	)
	(gr_arc
		(start 185.693812 -221.784164)
		(mid 185.183018 -222.294577)
		(end 185.693558 -222.805244)
		(stroke
			(width 0.2)
			(type default)
		)
		(layer "In6.Cu")
	)
	(gr_arc
		(start 186.506358 -222.805244)
		(mid 187.016898 -222.294704)
		(end 186.506358 -221.784164)
		(stroke
			(width 0.2)
			(type default)
		)
		(layer "In6.Cu")
	)
	(gr_line
		(start 186.506358 -221.784164)
		(end 185.693812 -221.784164)
		(stroke
			(width 0.2)
			(type default)
		)
		(layer "In6.Cu")
	)
	(gr_line
		(start 186.56554 -25.811734)
		(end 186.56554 -24.999188)
		(stroke
			(width 0.2)
			(type default)
		)
		(layer "In6.Cu")
	)
	(gr_arc
		(start 186.56554 -24.999188)
		(mid 186.055127 -24.488394)
		(end 185.54446 -24.998934)
		(stroke
			(width 0.2)
			(type default)
		)
		(layer "In6.Cu")
	)
	(gr_line
		(start 187.293758 -211.406994)
		(end 188.106558 -211.406994)
		(stroke
			(width 0.2)
			(type default)
		)
		(layer "In6.Cu")
	)
	(gr_arc
		(start 187.294012 -210.385914)
		(mid 186.783218 -210.896327)
		(end 187.293758 -211.406994)
		(stroke
			(width 0.2)
			(type default)
		)
		(layer "In6.Cu")
	)
	(gr_arc
		(start 188.106558 -211.406994)
		(mid 188.617098 -210.896454)
		(end 188.106558 -210.385914)
		(stroke
			(width 0.2)
			(type default)
		)
		(layer "In6.Cu")
	)
	(gr_line
		(start 188.106558 -210.385914)
		(end 187.294012 -210.385914)
		(stroke
			(width 0.2)
			(type default)
		)
		(layer "In6.Cu")
	)
	(gr_line
		(start 188.893704 -222.805244)
		(end 189.70625 -222.805244)
		(stroke
			(width 0.2)
			(type default)
		)
		(layer "In6.Cu")
	)
	(gr_arc
		(start 188.893704 -221.784164)
		(mid 188.383164 -222.294704)
		(end 188.893704 -222.805244)
		(stroke
			(width 0.2)
			(type default)
		)
		(layer "In6.Cu")
	)
	(gr_arc
		(start 189.70625 -222.805244)
		(mid 190.217044 -222.294831)
		(end 189.706504 -221.784164)
		(stroke
			(width 0.2)
			(type default)
		)
		(layer "In6.Cu")
	)
	(gr_line
		(start 189.706504 -221.784164)
		(end 188.893704 -221.784164)
		(stroke
			(width 0.2)
			(type default)
		)
		(layer "In6.Cu")
	)
	(gr_line
		(start 190.49365 -211.406994)
		(end 191.30645 -211.406994)
		(stroke
			(width 0.2)
			(type default)
		)
		(layer "In6.Cu")
	)
	(gr_arc
		(start 190.493904 -210.385914)
		(mid 189.98311 -210.896327)
		(end 190.49365 -211.406994)
		(stroke
			(width 0.2)
			(type default)
		)
		(layer "In6.Cu")
	)
	(gr_arc
		(start 191.30645 -211.406994)
		(mid 191.81699 -210.896454)
		(end 191.30645 -210.385914)
		(stroke
			(width 0.2)
			(type default)
		)
		(layer "In6.Cu")
	)
	(gr_line
		(start 191.30645 -210.385914)
		(end 190.493904 -210.385914)
		(stroke
			(width 0.2)
			(type default)
		)
		(layer "In6.Cu")
	)
	(gr_line
		(start 192.093596 -222.805244)
		(end 192.906142 -222.805244)
		(stroke
			(width 0.2)
			(type default)
		)
		(layer "In6.Cu")
	)
	(gr_arc
		(start 192.093596 -221.784164)
		(mid 191.583056 -222.294704)
		(end 192.093596 -222.805244)
		(stroke
			(width 0.2)
			(type default)
		)
		(layer "In6.Cu")
	)
	(gr_arc
		(start 192.906142 -222.805244)
		(mid 193.416936 -222.294831)
		(end 192.906396 -221.784164)
		(stroke
			(width 0.2)
			(type default)
		)
		(layer "In6.Cu")
	)
	(gr_line
		(start 192.906396 -221.784164)
		(end 192.093596 -221.784164)
		(stroke
			(width 0.2)
			(type default)
		)
		(layer "In6.Cu")
	)
	(gr_line
		(start 193.693796 -211.406994)
		(end 194.506596 -211.406994)
		(stroke
			(width 0.2)
			(type default)
		)
		(layer "In6.Cu")
	)
	(gr_arc
		(start 193.69405 -210.385914)
		(mid 193.183256 -210.896327)
		(end 193.693796 -211.406994)
		(stroke
			(width 0.2)
			(type default)
		)
		(layer "In6.Cu")
	)
	(gr_arc
		(start 194.506596 -211.406994)
		(mid 195.017136 -210.896454)
		(end 194.506596 -210.385914)
		(stroke
			(width 0.2)
			(type default)
		)
		(layer "In6.Cu")
	)
	(gr_line
		(start 194.506596 -210.385914)
		(end 193.69405 -210.385914)
		(stroke
			(width 0.2)
			(type default)
		)
		(layer "In6.Cu")
	)
	(gr_line
		(start 195.293742 -222.805244)
		(end 196.106288 -222.805244)
		(stroke
			(width 0.2)
			(type default)
		)
		(layer "In6.Cu")
	)
	(gr_arc
		(start 195.293742 -221.784164)
		(mid 194.783202 -222.294704)
		(end 195.293742 -222.805244)
		(stroke
			(width 0.2)
			(type default)
		)
		(layer "In6.Cu")
	)
	(gr_arc
		(start 196.106288 -222.805244)
		(mid 196.617082 -222.294831)
		(end 196.106542 -221.784164)
		(stroke
			(width 0.2)
			(type default)
		)
		(layer "In6.Cu")
	)
	(gr_line
		(start 196.106542 -221.784164)
		(end 195.293742 -221.784164)
		(stroke
			(width 0.2)
			(type default)
		)
		(layer "In6.Cu")
	)
	(gr_line
		(start 196.893688 -211.406994)
		(end 197.706488 -211.406994)
		(stroke
			(width 0.2)
			(type default)
		)
		(layer "In6.Cu")
	)
	(gr_arc
		(start 196.893942 -210.385914)
		(mid 196.383148 -210.896327)
		(end 196.893688 -211.406994)
		(stroke
			(width 0.2)
			(type default)
		)
		(layer "In6.Cu")
	)
	(gr_arc
		(start 197.204838 -46.70806)
		(mid 197.816978 -47.3202)
		(end 198.429118 -46.70806)
		(stroke
			(width 0.2)
			(type default)
		)
		(layer "In6.Cu")
	)
	(gr_line
		(start 197.204838 -45.59046)
		(end 197.204838 -46.70806)
		(stroke
			(width 0.2)
			(type default)
		)
		(layer "In6.Cu")
	)
	(gr_arc
		(start 197.706488 -211.406994)
		(mid 198.217028 -210.896454)
		(end 197.706488 -210.385914)
		(stroke
			(width 0.2)
			(type default)
		)
		(layer "In6.Cu")
	)
	(gr_line
		(start 197.706488 -210.385914)
		(end 196.893942 -210.385914)
		(stroke
			(width 0.2)
			(type default)
		)
		(layer "In6.Cu")
	)
	(gr_line
		(start 198.429118 -46.70806)
		(end 198.429118 -45.590714)
		(stroke
			(width 0.2)
			(type default)
		)
		(layer "In6.Cu")
	)
	(gr_arc
		(start 198.429118 -45.590714)
		(mid 197.817105 -44.97832)
		(end 197.204838 -45.59046)
		(stroke
			(width 0.2)
			(type default)
		)
		(layer "In6.Cu")
	)
	(gr_line
		(start 198.493634 -222.805244)
		(end 199.30618 -222.805244)
		(stroke
			(width 0.2)
			(type default)
		)
		(layer "In6.Cu")
	)
	(gr_arc
		(start 198.493634 -221.784164)
		(mid 197.983094 -222.294704)
		(end 198.493634 -222.805244)
		(stroke
			(width 0.2)
			(type default)
		)
		(layer "In6.Cu")
	)
	(gr_arc
		(start 199.30618 -222.805244)
		(mid 199.816974 -222.294831)
		(end 199.306434 -221.784164)
		(stroke
			(width 0.2)
			(type default)
		)
		(layer "In6.Cu")
	)
	(gr_line
		(start 199.306434 -221.784164)
		(end 198.493634 -221.784164)
		(stroke
			(width 0.2)
			(type default)
		)
		(layer "In6.Cu")
	)
	(gr_arc
		(start 200.046844 -49.122076)
		(mid 199.43826 -49.737772)
		(end 200.053956 -50.346356)
		(stroke
			(width 0.2)
			(type default)
		)
		(layer "In6.Cu")
	)
	(gr_line
		(start 200.053956 -50.346356)
		(end 201.171302 -50.339752)
		(stroke
			(width 0.2)
			(type default)
		)
		(layer "In6.Cu")
	)
	(gr_line
		(start 200.09358 -211.406994)
		(end 200.90638 -211.406994)
		(stroke
			(width 0.2)
			(type default)
		)
		(layer "In6.Cu")
	)
	(gr_arc
		(start 200.093834 -210.385914)
		(mid 199.58304 -210.896327)
		(end 200.09358 -211.406994)
		(stroke
			(width 0.2)
			(type default)
		)
		(layer "In6.Cu")
	)
	(gr_arc
		(start 200.7489 -45.832268)
		(mid 201.360913 -46.444662)
		(end 201.97318 -45.832522)
		(stroke
			(width 0.2)
			(type default)
		)
		(layer "In6.Cu")
	)
	(gr_line
		(start 200.7489 -44.714922)
		(end 200.7489 -45.832268)
		(stroke
			(width 0.2)
			(type default)
		)
		(layer "In6.Cu")
	)
	(gr_arc
		(start 200.90638 -211.406994)
		(mid 201.41692 -210.896454)
		(end 200.90638 -210.385914)
		(stroke
			(width 0.2)
			(type default)
		)
		(layer "In6.Cu")
	)
	(gr_line
		(start 200.90638 -210.385914)
		(end 200.093834 -210.385914)
		(stroke
			(width 0.2)
			(type default)
		)
		(layer "In6.Cu")
	)
	(gr_line
		(start 201.164444 -49.115472)
		(end 200.046844 -49.122076)
		(stroke
			(width 0.2)
			(type default)
		)
		(layer "In6.Cu")
	)
	(gr_arc
		(start 201.171302 -50.339752)
		(mid 201.780139 -49.724183)
		(end 201.164444 -49.115472)
		(stroke
			(width 0.2)
			(type default)
		)
		(layer "In6.Cu")
	)
	(gr_line
		(start 201.69378 -222.805244)
		(end 202.506326 -222.805244)
		(stroke
			(width 0.2)
			(type default)
		)
		(layer "In6.Cu")
	)
	(gr_arc
		(start 201.69378 -221.784164)
		(mid 201.18324 -222.294704)
		(end 201.69378 -222.805244)
		(stroke
			(width 0.2)
			(type default)
		)
		(layer "In6.Cu")
	)
	(gr_line
		(start 201.97318 -45.832522)
		(end 201.97318 -44.714922)
		(stroke
			(width 0.2)
			(type default)
		)
		(layer "In6.Cu")
	)
	(gr_arc
		(start 201.97318 -44.714922)
		(mid 201.36104 -44.102782)
		(end 200.7489 -44.714922)
		(stroke
			(width 0.2)
			(type default)
		)
		(layer "In6.Cu")
	)
	(gr_arc
		(start 202.506326 -222.805244)
		(mid 203.01712 -222.294831)
		(end 202.50658 -221.784164)
		(stroke
			(width 0.2)
			(type default)
		)
		(layer "In6.Cu")
	)
	(gr_line
		(start 202.50658 -221.784164)
		(end 201.69378 -221.784164)
		(stroke
			(width 0.2)
			(type default)
		)
		(layer "In6.Cu")
	)
	(gr_line
		(start 202.946 -50.29454)
		(end 203.7588 -50.29454)
		(stroke
			(width 0.2)
			(type default)
		)
		(layer "In6.Cu")
	)
	(gr_arc
		(start 202.946254 -49.27346)
		(mid 202.43546 -49.783873)
		(end 202.946 -50.29454)
		(stroke
			(width 0.2)
			(type default)
		)
		(layer "In6.Cu")
	)
	(gr_line
		(start 203.293726 -211.406994)
		(end 204.106526 -211.406994)
		(stroke
			(width 0.2)
			(type default)
		)
		(layer "In6.Cu")
	)
	(gr_arc
		(start 203.29398 -210.385914)
		(mid 202.783186 -210.896327)
		(end 203.293726 -211.406994)
		(stroke
			(width 0.2)
			(type default)
		)
		(layer "In6.Cu")
	)
	(gr_arc
		(start 203.7588 -50.29454)
		(mid 204.26934 -49.784)
		(end 203.7588 -49.27346)
		(stroke
			(width 0.2)
			(type default)
		)
		(layer "In6.Cu")
	)
	(gr_line
		(start 203.7588 -49.27346)
		(end 202.946254 -49.27346)
		(stroke
			(width 0.2)
			(type default)
		)
		(layer "In6.Cu")
	)
	(gr_arc
		(start 204.106526 -211.406994)
		(mid 204.617066 -210.896454)
		(end 204.106526 -210.385914)
		(stroke
			(width 0.2)
			(type default)
		)
		(layer "In6.Cu")
	)
	(gr_line
		(start 204.106526 -210.385914)
		(end 203.29398 -210.385914)
		(stroke
			(width 0.2)
			(type default)
		)
		(layer "In6.Cu")
	)
	(gr_line
		(start 204.893672 -222.805244)
		(end 205.706218 -222.805244)
		(stroke
			(width 0.2)
			(type default)
		)
		(layer "In6.Cu")
	)
	(gr_arc
		(start 204.893672 -221.784164)
		(mid 204.383132 -222.294704)
		(end 204.893672 -222.805244)
		(stroke
			(width 0.2)
			(type default)
		)
		(layer "In6.Cu")
	)
	(gr_arc
		(start 205.706218 -222.805244)
		(mid 206.217012 -222.294831)
		(end 205.706472 -221.784164)
		(stroke
			(width 0.2)
			(type default)
		)
		(layer "In6.Cu")
	)
	(gr_line
		(start 205.706472 -221.784164)
		(end 204.893672 -221.784164)
		(stroke
			(width 0.2)
			(type default)
		)
		(layer "In6.Cu")
	)
	(gr_line
		(start 206.493618 -211.406994)
		(end 207.306418 -211.406994)
		(stroke
			(width 0.2)
			(type default)
		)
		(layer "In6.Cu")
	)
	(gr_arc
		(start 206.493872 -210.385914)
		(mid 205.983078 -210.896327)
		(end 206.493618 -211.406994)
		(stroke
			(width 0.2)
			(type default)
		)
		(layer "In6.Cu")
	)
	(gr_arc
		(start 207.306418 -211.406994)
		(mid 207.816958 -210.896454)
		(end 207.306418 -210.385914)
		(stroke
			(width 0.2)
			(type default)
		)
		(layer "In6.Cu")
	)
	(gr_line
		(start 207.306418 -210.385914)
		(end 206.493872 -210.385914)
		(stroke
			(width 0.2)
			(type default)
		)
		(layer "In6.Cu")
	)
	(gr_arc
		(start 210.4898 -45.847)
		(mid 210.526997 -45.936803)
		(end 210.6168 -45.974)
		(stroke
			(width 0.2)
			(type default)
		)
		(layer "In6.Cu")
	)
	(gr_line
		(start 210.4898 -44.5516)
		(end 210.4898 -45.847)
		(stroke
			(width 0.2)
			(type default)
		)
		(layer "In6.Cu")
	)
	(gr_line
		(start 210.6168 -45.974)
		(end 211.9376 -45.974)
		(stroke
			(width 0.2)
			(type default)
		)
		(layer "In6.Cu")
	)
	(gr_arc
		(start 210.6168 -44.4246)
		(mid 210.526997 -44.461797)
		(end 210.4898 -44.5516)
		(stroke
			(width 0.2)
			(type default)
		)
		(layer "In6.Cu")
	)
	(gr_line
		(start 211.29371 -222.805244)
		(end 212.106256 -222.805244)
		(stroke
			(width 0.2)
			(type default)
		)
		(layer "In6.Cu")
	)
	(gr_arc
		(start 211.29371 -221.784164)
		(mid 210.78317 -222.294704)
		(end 211.29371 -222.805244)
		(stroke
			(width 0.2)
			(type default)
		)
		(layer "In6.Cu")
	)
	(gr_arc
		(start 211.9376 -45.974)
		(mid 212.027403 -45.936803)
		(end 212.0646 -45.847)
		(stroke
			(width 0.2)
			(type default)
		)
		(layer "In6.Cu")
	)
	(gr_line
		(start 211.9376 -44.4246)
		(end 210.6168 -44.4246)
		(stroke
			(width 0.2)
			(type default)
		)
		(layer "In6.Cu")
	)
	(gr_line
		(start 212.0646 -45.847)
		(end 212.0646 -44.5516)
		(stroke
			(width 0.2)
			(type default)
		)
		(layer "In6.Cu")
	)
	(gr_arc
		(start 212.0646 -44.5516)
		(mid 212.027403 -44.461797)
		(end 211.9376 -44.4246)
		(stroke
			(width 0.2)
			(type default)
		)
		(layer "In6.Cu")
	)
	(gr_arc
		(start 212.106256 -222.805244)
		(mid 212.61705 -222.294831)
		(end 212.10651 -221.784164)
		(stroke
			(width 0.2)
			(type default)
		)
		(layer "In6.Cu")
	)
	(gr_line
		(start 212.10651 -221.784164)
		(end 211.29371 -221.784164)
		(stroke
			(width 0.2)
			(type default)
		)
		(layer "In6.Cu")
	)
	(gr_line
		(start 212.893656 -211.406994)
		(end 213.706456 -211.406994)
		(stroke
			(width 0.2)
			(type default)
		)
		(layer "In6.Cu")
	)
	(gr_arc
		(start 212.89391 -210.385914)
		(mid 212.383116 -210.896327)
		(end 212.893656 -211.406994)
		(stroke
			(width 0.2)
			(type default)
		)
		(layer "In6.Cu")
	)
	(gr_arc
		(start 213.706456 -211.406994)
		(mid 214.216996 -210.896454)
		(end 213.706456 -210.385914)
		(stroke
			(width 0.2)
			(type default)
		)
		(layer "In6.Cu")
	)
	(gr_line
		(start 213.706456 -210.385914)
		(end 212.89391 -210.385914)
		(stroke
			(width 0.2)
			(type default)
		)
		(layer "In6.Cu")
	)
	(gr_line
		(start 214.493602 -222.805244)
		(end 215.306148 -222.805244)
		(stroke
			(width 0.2)
			(type default)
		)
		(layer "In6.Cu")
	)
	(gr_arc
		(start 214.493602 -221.784164)
		(mid 213.983062 -222.294704)
		(end 214.493602 -222.805244)
		(stroke
			(width 0.2)
			(type default)
		)
		(layer "In6.Cu")
	)
	(gr_arc
		(start 215.306148 -222.805244)
		(mid 215.816942 -222.294831)
		(end 215.306402 -221.784164)
		(stroke
			(width 0.2)
			(type default)
		)
		(layer "In6.Cu")
	)
	(gr_line
		(start 215.306402 -221.784164)
		(end 214.493602 -221.784164)
		(stroke
			(width 0.2)
			(type default)
		)
		(layer "In6.Cu")
	)
	(gr_line
		(start 216.093548 -211.406994)
		(end 216.906348 -211.406994)
		(stroke
			(width 0.2)
			(type default)
		)
		(layer "In6.Cu")
	)
	(gr_arc
		(start 216.093802 -210.385914)
		(mid 215.583008 -210.896327)
		(end 216.093548 -211.406994)
		(stroke
			(width 0.2)
			(type default)
		)
		(layer "In6.Cu")
	)
	(gr_arc
		(start 216.906348 -211.406994)
		(mid 217.416888 -210.896454)
		(end 216.906348 -210.385914)
		(stroke
			(width 0.2)
			(type default)
		)
		(layer "In6.Cu")
	)
	(gr_line
		(start 216.906348 -210.385914)
		(end 216.093802 -210.385914)
		(stroke
			(width 0.2)
			(type default)
		)
		(layer "In6.Cu")
	)
	(gr_line
		(start 218.499944 -228.000052)
		(end 182.500016 -228.000052)
		(stroke
			(width 5.08)
			(type default)
		)
		(layer "In6.Cu")
	)
	(gr_line
		(start 218.499944 -222.400114)
		(end 218.499944 -228.000052)
		(stroke
			(width 1.524)
			(type default)
		)
		(layer "In6.Cu")
	)
	(gr_arc
		(start 219.00007 -221.899988)
		(mid 218.646428 -222.046472)
		(end 218.499944 -222.400114)
		(stroke
			(width 1.524)
			(type default)
		)
		(layer "In6.Cu")
	)
	(gr_line
		(start 219.799916 -221.899988)
		(end 219.00007 -221.899988)
		(stroke
			(width 1.524)
			(type default)
		)
		(layer "In6.Cu")
	)
	(gr_arc
		(start 219.799916 -221.899988)
		(mid 220.153445 -221.753586)
		(end 220.300042 -221.400116)
		(stroke
			(width 1.524)
			(type default)
		)
		(layer "In6.Cu")
	)
	(gr_line
		(start 220.300042 -214.799926)
		(end 220.300042 -221.400116)
		(stroke
			(width 1.524)
			(type default)
		)
		(layer "In6.Cu")
	)
	(gr_arc
		(start 221.600014 -213.499954)
		(mid 220.680795 -213.880707)
		(end 220.300042 -214.799926)
		(stroke
			(width 1.524)
			(type default)
		)
		(layer "In6.Cu")
	)
	(gr_line
		(start 229.142036 -213.499954)
		(end 221.600014 -213.499954)
		(stroke
			(width 1.524)
			(type default)
		)
		(layer "In6.Cu")
	)
	(gr_arc
		(start 229.142036 -213.499954)
		(mid 232.677527 -212.035476)
		(end 234.142026 -208.499964)
		(stroke
			(width 1.524)
			(type default)
		)
		(layer "In6.Cu")
	)
	(gr_line
		(start 234.142026 -165.269926)
		(end 234.142026 -208.499964)
		(stroke
			(width 1.524)
			(type default)
		)
		(layer "In6.Cu")
	)
	(gr_arc
		(start 235.412026 -163.999926)
		(mid 234.514 -164.3719)
		(end 234.142026 -165.269926)
		(stroke
			(width 1.524)
			(type default)
		)
		(layer "In6.Cu")
	)
	(gr_line
		(start 249.871992 -163.999926)
		(end 235.412026 -163.999926)
		(stroke
			(width 1.524)
			(type default)
		)
		(layer "In6.Cu")
	)
	(gr_line
		(start 251.141992 -208.499964)
		(end 251.141992 -165.269926)
		(stroke
			(width 1.524)
			(type default)
		)
		(layer "In6.Cu")
	)
	(gr_arc
		(start 251.141992 -208.499964)
		(mid 252.606441 -212.03552)
		(end 256.141982 -213.499954)
		(stroke
			(width 1.524)
			(type default)
		)
		(layer "In6.Cu")
	)
	(gr_arc
		(start 251.141992 -165.269926)
		(mid 250.770018 -164.3719)
		(end 249.871992 -163.999926)
		(stroke
			(width 1.524)
			(type default)
		)
		(layer "In6.Cu")
	)
	(gr_line
		(start 257.400044 -213.499954)
		(end 256.141982 -213.499954)
		(stroke
			(width 1.524)
			(type default)
		)
		(layer "In6.Cu")
	)
	(gr_line
		(start 258.700016 -221.400116)
		(end 258.700016 -214.799926)
		(stroke
			(width 1.524)
			(type default)
		)
		(layer "In6.Cu")
	)
	(gr_arc
		(start 258.700016 -221.400116)
		(mid 258.84643 -221.753573)
		(end 259.199888 -221.899988)
		(stroke
			(width 1.524)
			(type default)
		)
		(layer "In6.Cu")
	)
	(gr_arc
		(start 258.700016 -214.799926)
		(mid 258.319263 -213.880707)
		(end 257.400044 -213.499954)
		(stroke
			(width 1.524)
			(type default)
		)
		(layer "In6.Cu")
	)
	(gr_line
		(start 259.999988 -221.899988)
		(end 259.199888 -221.899988)
		(stroke
			(width 1.524)
			(type default)
		)
		(layer "In6.Cu")
	)
	(gr_line
		(start 260.500114 -228.000052)
		(end 260.500114 -222.400114)
		(stroke
			(width 1.524)
			(type default)
		)
		(layer "In6.Cu")
	)
	(gr_arc
		(start 260.500114 -222.400114)
		(mid 260.35363 -222.046472)
		(end 259.999988 -221.899988)
		(stroke
			(width 1.524)
			(type default)
		)
		(layer "In6.Cu")
	)
	(gr_line
		(start 262.893556 -222.805244)
		(end 263.706102 -222.805244)
		(stroke
			(width 0.2)
			(type default)
		)
		(layer "In6.Cu")
	)
	(gr_arc
		(start 262.893556 -221.784164)
		(mid 262.383016 -222.294704)
		(end 262.893556 -222.805244)
		(stroke
			(width 0.2)
			(type default)
		)
		(layer "In6.Cu")
	)
	(gr_arc
		(start 263.706102 -222.805244)
		(mid 264.216896 -222.294831)
		(end 263.706356 -221.784164)
		(stroke
			(width 0.2)
			(type default)
		)
		(layer "In6.Cu")
	)
	(gr_line
		(start 263.706356 -221.784164)
		(end 262.893556 -221.784164)
		(stroke
			(width 0.2)
			(type default)
		)
		(layer "In6.Cu")
	)
	(gr_line
		(start 264.493756 -211.406994)
		(end 265.306556 -211.406994)
		(stroke
			(width 0.2)
			(type default)
		)
		(layer "In6.Cu")
	)
	(gr_arc
		(start 264.49401 -210.385914)
		(mid 263.983216 -210.896327)
		(end 264.493756 -211.406994)
		(stroke
			(width 0.2)
			(type default)
		)
		(layer "In6.Cu")
	)
	(gr_arc
		(start 265.306556 -211.406994)
		(mid 265.817096 -210.896454)
		(end 265.306556 -210.385914)
		(stroke
			(width 0.2)
			(type default)
		)
		(layer "In6.Cu")
	)
	(gr_line
		(start 265.306556 -210.385914)
		(end 264.49401 -210.385914)
		(stroke
			(width 0.2)
			(type default)
		)
		(layer "In6.Cu")
	)
	(gr_line
		(start 266.093702 -222.805244)
		(end 266.906248 -222.805244)
		(stroke
			(width 0.2)
			(type default)
		)
		(layer "In6.Cu")
	)
	(gr_arc
		(start 266.093702 -221.784164)
		(mid 265.583162 -222.294704)
		(end 266.093702 -222.805244)
		(stroke
			(width 0.2)
			(type default)
		)
		(layer "In6.Cu")
	)
	(gr_arc
		(start 266.906248 -222.805244)
		(mid 267.417042 -222.294831)
		(end 266.906502 -221.784164)
		(stroke
			(width 0.2)
			(type default)
		)
		(layer "In6.Cu")
	)
	(gr_line
		(start 266.906502 -221.784164)
		(end 266.093702 -221.784164)
		(stroke
			(width 0.2)
			(type default)
		)
		(layer "In6.Cu")
	)
	(gr_line
		(start 267.693648 -211.406994)
		(end 268.506448 -211.406994)
		(stroke
			(width 0.2)
			(type default)
		)
		(layer "In6.Cu")
	)
	(gr_arc
		(start 267.693902 -210.385914)
		(mid 267.183108 -210.896327)
		(end 267.693648 -211.406994)
		(stroke
			(width 0.2)
			(type default)
		)
		(layer "In6.Cu")
	)
	(gr_arc
		(start 267.96746 -14.6558)
		(mid 268.478 -15.16634)
		(end 268.98854 -14.6558)
		(stroke
			(width 0.2)
			(type default)
		)
		(layer "In6.Cu")
	)
	(gr_line
		(start 267.96746 -13.843)
		(end 267.96746 -14.6558)
		(stroke
			(width 0.2)
			(type default)
		)
		(layer "In6.Cu")
	)
	(gr_arc
		(start 268.441424 -18.568162)
		(mid 268.471182 -18.640004)
		(end 268.543024 -18.669762)
		(stroke
			(width 0.2)
			(type default)
		)
		(layer "In6.Cu")
	)
	(gr_line
		(start 268.441424 -17.194022)
		(end 268.441424 -18.568162)
		(stroke
			(width 0.2)
			(type default)
		)
		(layer "In6.Cu")
	)
	(gr_arc
		(start 268.506448 -211.406994)
		(mid 269.016988 -210.896454)
		(end 268.506448 -210.385914)
		(stroke
			(width 0.2)
			(type default)
		)
		(layer "In6.Cu")
	)
	(gr_line
		(start 268.506448 -210.385914)
		(end 267.693902 -210.385914)
		(stroke
			(width 0.2)
			(type default)
		)
		(layer "In6.Cu")
	)
	(gr_line
		(start 268.543024 -18.669762)
		(end 269.762224 -18.669762)
		(stroke
			(width 0.2)
			(type default)
		)
		(layer "In6.Cu")
	)
	(gr_arc
		(start 268.543024 -17.092422)
		(mid 268.471182 -17.12218)
		(end 268.441424 -17.194022)
		(stroke
			(width 0.2)
			(type default)
		)
		(layer "In6.Cu")
	)
	(gr_line
		(start 268.98854 -14.6558)
		(end 268.98854 -13.843254)
		(stroke
			(width 0.2)
			(type default)
		)
		(layer "In6.Cu")
	)
	(gr_arc
		(start 268.98854 -13.843254)
		(mid 268.478127 -13.33246)
		(end 267.96746 -13.843)
		(stroke
			(width 0.2)
			(type default)
		)
		(layer "In6.Cu")
	)
	(gr_arc
		(start 269.03426 -6.118352)
		(mid 269.5448 -6.628892)
		(end 270.05534 -6.118352)
		(stroke
			(width 0.2)
			(type default)
		)
		(layer "In6.Cu")
	)
	(gr_line
		(start 269.03426 -5.305552)
		(end 269.03426 -6.118352)
		(stroke
			(width 0.2)
			(type default)
		)
		(layer "In6.Cu")
	)
	(gr_arc
		(start 269.762224 -18.669762)
		(mid 269.834066 -18.640004)
		(end 269.863824 -18.568162)
		(stroke
			(width 0.2)
			(type default)
		)
		(layer "In6.Cu")
	)
	(gr_line
		(start 269.762224 -17.092422)
		(end 268.543024 -17.092422)
		(stroke
			(width 0.2)
			(type default)
		)
		(layer "In6.Cu")
	)
	(gr_line
		(start 269.863824 -18.568162)
		(end 269.863824 -17.194022)
		(stroke
			(width 0.2)
			(type default)
		)
		(layer "In6.Cu")
	)
	(gr_arc
		(start 269.863824 -17.194022)
		(mid 269.834066 -17.12218)
		(end 269.762224 -17.092422)
		(stroke
			(width 0.2)
			(type default)
		)
		(layer "In6.Cu")
	)
	(gr_line
		(start 270.05534 -6.118352)
		(end 270.05534 -5.305806)
		(stroke
			(width 0.2)
			(type default)
		)
		(layer "In6.Cu")
	)
	(gr_arc
		(start 270.05534 -5.305806)
		(mid 269.544927 -4.795012)
		(end 269.03426 -5.305552)
		(stroke
			(width 0.2)
			(type default)
		)
		(layer "In6.Cu")
	)
	(gr_arc
		(start 270.17726 -9.166352)
		(mid 270.6878 -9.676892)
		(end 271.19834 -9.166352)
		(stroke
			(width 0.2)
			(type default)
		)
		(layer "In6.Cu")
	)
	(gr_line
		(start 270.17726 -8.353552)
		(end 270.17726 -9.166352)
		(stroke
			(width 0.2)
			(type default)
		)
		(layer "In6.Cu")
	)
	(gr_arc
		(start 270.3068 -6.4008)
		(mid 270.336558 -6.472642)
		(end 270.4084 -6.5024)
		(stroke
			(width 0.2)
			(type default)
		)
		(layer "In6.Cu")
	)
	(gr_line
		(start 270.3068 -5.0292)
		(end 270.3068 -6.4008)
		(stroke
			(width 0.2)
			(type default)
		)
		(layer "In6.Cu")
	)
	(gr_line
		(start 270.4084 -6.5024)
		(end 271.6276 -6.5024)
		(stroke
			(width 0.2)
			(type default)
		)
		(layer "In6.Cu")
	)
	(gr_arc
		(start 270.4084 -4.9276)
		(mid 270.336558 -4.957358)
		(end 270.3068 -5.0292)
		(stroke
			(width 0.2)
			(type default)
		)
		(layer "In6.Cu")
	)
	(gr_line
		(start 270.893794 -211.406994)
		(end 271.706594 -211.406994)
		(stroke
			(width 0.2)
			(type default)
		)
		(layer "In6.Cu")
	)
	(gr_arc
		(start 270.894048 -210.385914)
		(mid 270.383254 -210.896327)
		(end 270.893794 -211.406994)
		(stroke
			(width 0.2)
			(type default)
		)
		(layer "In6.Cu")
	)
	(gr_line
		(start 271.19834 -9.166352)
		(end 271.19834 -8.353806)
		(stroke
			(width 0.2)
			(type default)
		)
		(layer "In6.Cu")
	)
	(gr_arc
		(start 271.19834 -8.353806)
		(mid 270.687927 -7.843012)
		(end 270.17726 -8.353552)
		(stroke
			(width 0.2)
			(type default)
		)
		(layer "In6.Cu")
	)
	(gr_arc
		(start 271.4498 -9.4488)
		(mid 271.479558 -9.520642)
		(end 271.5514 -9.5504)
		(stroke
			(width 0.2)
			(type default)
		)
		(layer "In6.Cu")
	)
	(gr_line
		(start 271.4498 -8.0772)
		(end 271.4498 -9.4488)
		(stroke
			(width 0.2)
			(type default)
		)
		(layer "In6.Cu")
	)
	(gr_line
		(start 271.5514 -9.5504)
		(end 272.7706 -9.5504)
		(stroke
			(width 0.2)
			(type default)
		)
		(layer "In6.Cu")
	)
	(gr_arc
		(start 271.5514 -7.9756)
		(mid 271.479558 -8.005358)
		(end 271.4498 -8.0772)
		(stroke
			(width 0.2)
			(type default)
		)
		(layer "In6.Cu")
	)
	(gr_arc
		(start 271.55775 -15.334996)
		(mid 272.068163 -15.84579)
		(end 272.57883 -15.33525)
		(stroke
			(width 0.2)
			(type default)
		)
		(layer "In6.Cu")
	)
	(gr_line
		(start 271.55775 -14.52245)
		(end 271.55775 -15.334996)
		(stroke
			(width 0.2)
			(type default)
		)
		(layer "In6.Cu")
	)
	(gr_arc
		(start 271.6276 -6.5024)
		(mid 271.699442 -6.472642)
		(end 271.7292 -6.4008)
		(stroke
			(width 0.2)
			(type default)
		)
		(layer "In6.Cu")
	)
	(gr_line
		(start 271.6276 -4.9276)
		(end 270.4084 -4.9276)
		(stroke
			(width 0.2)
			(type default)
		)
		(layer "In6.Cu")
	)
	(gr_arc
		(start 271.706594 -211.406994)
		(mid 272.217134 -210.896454)
		(end 271.706594 -210.385914)
		(stroke
			(width 0.2)
			(type default)
		)
		(layer "In6.Cu")
	)
	(gr_line
		(start 271.706594 -210.385914)
		(end 270.894048 -210.385914)
		(stroke
			(width 0.2)
			(type default)
		)
		(layer "In6.Cu")
	)
	(gr_line
		(start 271.7292 -6.4008)
		(end 271.7292 -5.0292)
		(stroke
			(width 0.2)
			(type default)
		)
		(layer "In6.Cu")
	)
	(gr_arc
		(start 271.7292 -5.0292)
		(mid 271.699442 -4.957358)
		(end 271.6276 -4.9276)
		(stroke
			(width 0.2)
			(type default)
		)
		(layer "In6.Cu")
	)
	(gr_line
		(start 272.49374 -222.805244)
		(end 273.306286 -222.805244)
		(stroke
			(width 0.2)
			(type default)
		)
		(layer "In6.Cu")
	)
	(gr_arc
		(start 272.49374 -221.784164)
		(mid 271.9832 -222.294704)
		(end 272.49374 -222.805244)
		(stroke
			(width 0.2)
			(type default)
		)
		(layer "In6.Cu")
	)
	(gr_line
		(start 272.57883 -15.33525)
		(end 272.57883 -14.52245)
		(stroke
			(width 0.2)
			(type default)
		)
		(layer "In6.Cu")
	)
	(gr_arc
		(start 272.57883 -14.52245)
		(mid 272.06829 -14.01191)
		(end 271.55775 -14.52245)
		(stroke
			(width 0.2)
			(type default)
		)
		(layer "In6.Cu")
	)
	(gr_arc
		(start 272.7706 -9.5504)
		(mid 272.842442 -9.520642)
		(end 272.8722 -9.4488)
		(stroke
			(width 0.2)
			(type default)
		)
		(layer "In6.Cu")
	)
	(gr_line
		(start 272.7706 -7.9756)
		(end 271.5514 -7.9756)
		(stroke
			(width 0.2)
			(type default)
		)
		(layer "In6.Cu")
	)
	(gr_line
		(start 272.8722 -9.4488)
		(end 272.8722 -8.0772)
		(stroke
			(width 0.2)
			(type default)
		)
		(layer "In6.Cu")
	)
	(gr_arc
		(start 272.8722 -8.0772)
		(mid 272.842442 -8.005358)
		(end 272.7706 -7.9756)
		(stroke
			(width 0.2)
			(type default)
		)
		(layer "In6.Cu")
	)
	(gr_arc
		(start 273.306286 -222.805244)
		(mid 273.81708 -222.294831)
		(end 273.30654 -221.784164)
		(stroke
			(width 0.2)
			(type default)
		)
		(layer "In6.Cu")
	)
	(gr_line
		(start 273.30654 -221.784164)
		(end 272.49374 -221.784164)
		(stroke
			(width 0.2)
			(type default)
		)
		(layer "In6.Cu")
	)
	(gr_line
		(start 274.093686 -211.406994)
		(end 274.906486 -211.406994)
		(stroke
			(width 0.2)
			(type default)
		)
		(layer "In6.Cu")
	)
	(gr_arc
		(start 274.09394 -210.385914)
		(mid 273.583146 -210.896327)
		(end 274.093686 -211.406994)
		(stroke
			(width 0.2)
			(type default)
		)
		(layer "In6.Cu")
	)
	(gr_arc
		(start 274.906486 -211.406994)
		(mid 275.417026 -210.896454)
		(end 274.906486 -210.385914)
		(stroke
			(width 0.2)
			(type default)
		)
		(layer "In6.Cu")
	)
	(gr_line
		(start 274.906486 -210.385914)
		(end 274.09394 -210.385914)
		(stroke
			(width 0.2)
			(type default)
		)
		(layer "In6.Cu")
	)
	(gr_line
		(start 275.693632 -222.805244)
		(end 276.506178 -222.805244)
		(stroke
			(width 0.2)
			(type default)
		)
		(layer "In6.Cu")
	)
	(gr_arc
		(start 275.693632 -221.784164)
		(mid 275.183092 -222.294704)
		(end 275.693632 -222.805244)
		(stroke
			(width 0.2)
			(type default)
		)
		(layer "In6.Cu")
	)
	(gr_arc
		(start 276.506178 -222.805244)
		(mid 277.016972 -222.294831)
		(end 276.506432 -221.784164)
		(stroke
			(width 0.2)
			(type default)
		)
		(layer "In6.Cu")
	)
	(gr_line
		(start 276.506432 -221.784164)
		(end 275.693632 -221.784164)
		(stroke
			(width 0.2)
			(type default)
		)
		(layer "In6.Cu")
	)
	(gr_line
		(start 277.293578 -211.406994)
		(end 278.106378 -211.406994)
		(stroke
			(width 0.2)
			(type default)
		)
		(layer "In6.Cu")
	)
	(gr_arc
		(start 277.293832 -210.385914)
		(mid 276.783038 -210.896327)
		(end 277.293578 -211.406994)
		(stroke
			(width 0.2)
			(type default)
		)
		(layer "In6.Cu")
	)
	(gr_arc
		(start 278.106378 -211.406994)
		(mid 278.616918 -210.896454)
		(end 278.106378 -210.385914)
		(stroke
			(width 0.2)
			(type default)
		)
		(layer "In6.Cu")
	)
	(gr_line
		(start 278.106378 -210.385914)
		(end 277.293832 -210.385914)
		(stroke
			(width 0.2)
			(type default)
		)
		(layer "In6.Cu")
	)
	(gr_line
		(start 278.893778 -222.805244)
		(end 279.706324 -222.805244)
		(stroke
			(width 0.2)
			(type default)
		)
		(layer "In6.Cu")
	)
	(gr_arc
		(start 278.893778 -221.784164)
		(mid 278.383238 -222.294704)
		(end 278.893778 -222.805244)
		(stroke
			(width 0.2)
			(type default)
		)
		(layer "In6.Cu")
	)
	(gr_arc
		(start 279.706324 -222.805244)
		(mid 280.217118 -222.294831)
		(end 279.706578 -221.784164)
		(stroke
			(width 0.2)
			(type default)
		)
		(layer "In6.Cu")
	)
	(gr_line
		(start 279.706578 -221.784164)
		(end 278.893778 -221.784164)
		(stroke
			(width 0.2)
			(type default)
		)
		(layer "In6.Cu")
	)
	(gr_arc
		(start 279.72766 -18.762726)
		(mid 280.230326 -19.28114)
		(end 280.74874 -18.778474)
		(stroke
			(width 0.2)
			(type default)
		)
		(layer "In6.Cu")
	)
	(gr_line
		(start 279.740106 -17.949926)
		(end 279.72766 -18.762726)
		(stroke
			(width 0.2)
			(type default)
		)
		(layer "In6.Cu")
	)
	(gr_line
		(start 280.493724 -211.406994)
		(end 281.306524 -211.406994)
		(stroke
			(width 0.2)
			(type default)
		)
		(layer "In6.Cu")
	)
	(gr_arc
		(start 280.493978 -210.385914)
		(mid 279.983184 -210.896327)
		(end 280.493724 -211.406994)
		(stroke
			(width 0.2)
			(type default)
		)
		(layer "In6.Cu")
	)
	(gr_line
		(start 280.74874 -18.778474)
		(end 280.761186 -17.965928)
		(stroke
			(width 0.2)
			(type default)
		)
		(layer "In6.Cu")
	)
	(gr_arc
		(start 280.761186 -17.965928)
		(mid 280.258647 -17.447516)
		(end 279.740106 -17.949926)
		(stroke
			(width 0.2)
			(type default)
		)
		(layer "In6.Cu")
	)
	(gr_arc
		(start 281.306524 -211.406994)
		(mid 281.817064 -210.896454)
		(end 281.306524 -210.385914)
		(stroke
			(width 0.2)
			(type default)
		)
		(layer "In6.Cu")
	)
	(gr_line
		(start 281.306524 -210.385914)
		(end 280.493978 -210.385914)
		(stroke
			(width 0.2)
			(type default)
		)
		(layer "In6.Cu")
	)
	(gr_line
		(start 282.09367 -222.805244)
		(end 282.906216 -222.805244)
		(stroke
			(width 0.2)
			(type default)
		)
		(layer "In6.Cu")
	)
	(gr_arc
		(start 282.09367 -221.784164)
		(mid 281.58313 -222.294704)
		(end 282.09367 -222.805244)
		(stroke
			(width 0.2)
			(type default)
		)
		(layer "In6.Cu")
	)
	(gr_line
		(start 282.244546 -20.841208)
		(end 282.788614 -21.44522)
		(stroke
			(width 0.2)
			(type default)
		)
		(layer "In6.Cu")
	)
	(gr_line
		(start 282.246578 -20.83943)
		(end 282.244546 -20.841208)
		(stroke
			(width 0.2)
			(type default)
		)
		(layer "In6.Cu")
	)
	(gr_line
		(start 282.788614 -21.44522)
		(end 282.790646 -21.443442)
		(stroke
			(width 0.2)
			(type default)
		)
		(layer "In6.Cu")
	)
	(gr_arc
		(start 282.790646 -21.443442)
		(mid 283.511498 -21.481034)
		(end 283.54909 -20.760182)
		(stroke
			(width 0.2)
			(type default)
		)
		(layer "In6.Cu")
	)
	(gr_arc
		(start 282.906216 -222.805244)
		(mid 283.41701 -222.294831)
		(end 282.90647 -221.784164)
		(stroke
			(width 0.2)
			(type default)
		)
		(layer "In6.Cu")
	)
	(gr_line
		(start 282.90647 -221.784164)
		(end 282.09367 -221.784164)
		(stroke
			(width 0.2)
			(type default)
		)
		(layer "In6.Cu")
	)
	(gr_arc
		(start 283.005276 -20.15617)
		(mid 282.284107 -20.118381)
		(end 282.246578 -20.83943)
		(stroke
			(width 0.2)
			(type default)
		)
		(layer "In6.Cu")
	)
	(gr_line
		(start 283.0068 -20.154646)
		(end 283.005276 -20.15617)
		(stroke
			(width 0.2)
			(type default)
		)
		(layer "In6.Cu")
	)
	(gr_line
		(start 283.007308 -20.154646)
		(end 283.0068 -20.154646)
		(stroke
			(width 0.2)
			(type default)
		)
		(layer "In6.Cu")
	)
	(gr_line
		(start 283.54909 -20.760182)
		(end 283.551122 -20.758404)
		(stroke
			(width 0.2)
			(type default)
		)
		(layer "In6.Cu")
	)
	(gr_line
		(start 283.551122 -20.758404)
		(end 283.007308 -20.154646)
		(stroke
			(width 0.2)
			(type default)
		)
		(layer "In6.Cu")
	)
	(gr_line
		(start 283.693616 -211.406994)
		(end 284.506416 -211.406994)
		(stroke
			(width 0.2)
			(type default)
		)
		(layer "In6.Cu")
	)
	(gr_arc
		(start 283.69387 -210.385914)
		(mid 283.183076 -210.896327)
		(end 283.693616 -211.406994)
		(stroke
			(width 0.2)
			(type default)
		)
		(layer "In6.Cu")
	)
	(gr_arc
		(start 284.477714 -33.864042)
		(mid 284.988127 -34.374836)
		(end 285.498794 -33.864296)
		(stroke
			(width 0.2)
			(type default)
		)
		(layer "In6.Cu")
	)
	(gr_line
		(start 284.477714 -33.051496)
		(end 284.477714 -33.864042)
		(stroke
			(width 0.2)
			(type default)
		)
		(layer "In6.Cu")
	)
	(gr_arc
		(start 284.506416 -211.406994)
		(mid 285.016956 -210.896454)
		(end 284.506416 -210.385914)
		(stroke
			(width 0.2)
			(type default)
		)
		(layer "In6.Cu")
	)
	(gr_line
		(start 284.506416 -210.385914)
		(end 283.69387 -210.385914)
		(stroke
			(width 0.2)
			(type default)
		)
		(layer "In6.Cu")
	)
	(gr_line
		(start 285.293562 -222.805244)
		(end 286.106108 -222.805244)
		(stroke
			(width 0.2)
			(type default)
		)
		(layer "In6.Cu")
	)
	(gr_arc
		(start 285.293562 -221.784164)
		(mid 284.783022 -222.294704)
		(end 285.293562 -222.805244)
		(stroke
			(width 0.2)
			(type default)
		)
		(layer "In6.Cu")
	)
	(gr_line
		(start 285.498794 -33.864296)
		(end 285.498794 -33.051496)
		(stroke
			(width 0.2)
			(type default)
		)
		(layer "In6.Cu")
	)
	(gr_arc
		(start 285.498794 -33.051496)
		(mid 284.988254 -32.540956)
		(end 284.477714 -33.051496)
		(stroke
			(width 0.2)
			(type default)
		)
		(layer "In6.Cu")
	)
	(gr_line
		(start 285.581344 -25.033732)
		(end 285.581598 -25.033986)
		(stroke
			(width 0.2)
			(type default)
		)
		(layer "In6.Cu")
	)
	(gr_line
		(start 285.581344 -13.633958)
		(end 285.583376 -13.635228)
		(stroke
			(width 0.2)
			(type default)
		)
		(layer "In6.Cu")
	)
	(gr_line
		(start 285.581598 -25.033986)
		(end 285.58363 -25.035002)
		(stroke
			(width 0.2)
			(type default)
		)
		(layer "In6.Cu")
	)
	(gr_arc
		(start 285.583376 -13.635228)
		(mid 285.839408 -14.481048)
		(end 286.685228 -14.225016)
		(stroke
			(width 0.2)
			(type default)
		)
		(layer "In6.Cu")
	)
	(gr_arc
		(start 285.58363 -25.035002)
		(mid 285.839306 -25.880903)
		(end 286.685228 -25.625044)
		(stroke
			(width 0.2)
			(type default)
		)
		(layer "In6.Cu")
	)
	(gr_arc
		(start 286.106108 -222.805244)
		(mid 286.616902 -222.294831)
		(end 286.106362 -221.784164)
		(stroke
			(width 0.2)
			(type default)
		)
		(layer "In6.Cu")
	)
	(gr_line
		(start 286.106362 -221.784164)
		(end 285.293562 -221.784164)
		(stroke
			(width 0.2)
			(type default)
		)
		(layer "In6.Cu")
	)
	(gr_line
		(start 286.331406 -23.633938)
		(end 285.581344 -25.033732)
		(stroke
			(width 0.2)
			(type default)
		)
		(layer "In6.Cu")
	)
	(gr_line
		(start 286.331406 -12.23391)
		(end 285.581344 -13.633958)
		(stroke
			(width 0.2)
			(type default)
		)
		(layer "In6.Cu")
	)
	(gr_line
		(start 286.333438 -23.635208)
		(end 286.331406 -23.633938)
		(stroke
			(width 0.2)
			(type default)
		)
		(layer "In6.Cu")
	)
	(gr_line
		(start 286.333438 -12.23518)
		(end 286.331406 -12.23391)
		(stroke
			(width 0.2)
			(type default)
		)
		(layer "In6.Cu")
	)
	(gr_line
		(start 286.685228 -25.625044)
		(end 286.68726 -25.626314)
		(stroke
			(width 0.2)
			(type default)
		)
		(layer "In6.Cu")
	)
	(gr_line
		(start 286.685228 -14.225016)
		(end 286.68726 -14.226286)
		(stroke
			(width 0.2)
			(type default)
		)
		(layer "In6.Cu")
	)
	(gr_line
		(start 286.68726 -25.626314)
		(end 287.437322 -24.226266)
		(stroke
			(width 0.2)
			(type default)
		)
		(layer "In6.Cu")
	)
	(gr_line
		(start 286.68726 -14.226286)
		(end 287.437322 -12.826492)
		(stroke
			(width 0.2)
			(type default)
		)
		(layer "In6.Cu")
	)
	(gr_line
		(start 286.893762 -211.406994)
		(end 287.706308 -211.406994)
		(stroke
			(width 0.2)
			(type default)
		)
		(layer "In6.Cu")
	)
	(gr_arc
		(start 286.893762 -210.385914)
		(mid 286.383222 -210.896454)
		(end 286.893762 -211.406994)
		(stroke
			(width 0.2)
			(type default)
		)
		(layer "In6.Cu")
	)
	(gr_arc
		(start 287.435036 -12.825222)
		(mid 287.17936 -11.979321)
		(end 286.333438 -12.23518)
		(stroke
			(width 0.2)
			(type default)
		)
		(layer "In6.Cu")
	)
	(gr_arc
		(start 287.43529 -24.224996)
		(mid 287.179258 -23.379176)
		(end 286.333438 -23.635208)
		(stroke
			(width 0.2)
			(type default)
		)
		(layer "In6.Cu")
	)
	(gr_line
		(start 287.437068 -12.826238)
		(end 287.435036 -12.825222)
		(stroke
			(width 0.2)
			(type default)
		)
		(layer "In6.Cu")
	)
	(gr_line
		(start 287.437322 -24.226266)
		(end 287.43529 -24.224996)
		(stroke
			(width 0.2)
			(type default)
		)
		(layer "In6.Cu")
	)
	(gr_line
		(start 287.437322 -12.826492)
		(end 287.437068 -12.826238)
		(stroke
			(width 0.2)
			(type default)
		)
		(layer "In6.Cu")
	)
	(gr_arc
		(start 287.706308 -211.406994)
		(mid 288.217102 -210.896581)
		(end 287.706562 -210.385914)
		(stroke
			(width 0.2)
			(type default)
		)
		(layer "In6.Cu")
	)
	(gr_line
		(start 287.706562 -210.385914)
		(end 286.893762 -210.385914)
		(stroke
			(width 0.2)
			(type default)
		)
		(layer "In6.Cu")
	)
	(gr_line
		(start 287.83153 -17.433544)
		(end 287.831784 -17.433798)
		(stroke
			(width 0.2)
			(type default)
		)
		(layer "In6.Cu")
	)
	(gr_line
		(start 287.831784 -17.433798)
		(end 287.833816 -17.434814)
		(stroke
			(width 0.2)
			(type default)
		)
		(layer "In6.Cu")
	)
	(gr_arc
		(start 287.833562 -13.635228)
		(mid 288.089594 -14.481048)
		(end 288.935414 -14.225016)
		(stroke
			(width 0.2)
			(type default)
		)
		(layer "In6.Cu")
	)
	(gr_arc
		(start 287.833816 -17.434814)
		(mid 288.089492 -18.280715)
		(end 288.935414 -18.024856)
		(stroke
			(width 0.2)
			(type default)
		)
		(layer "In6.Cu")
	)
	(gr_arc
		(start 287.837626 -25.027636)
		(mid 288.08576 -25.879089)
		(end 288.935414 -25.625044)
		(stroke
			(width 0.2)
			(type default)
		)
		(layer "In6.Cu")
	)
	(gr_arc
		(start 287.837626 -21.227542)
		(mid 288.08576 -22.078995)
		(end 288.935414 -21.82495)
		(stroke
			(width 0.2)
			(type default)
		)
		(layer "In6.Cu")
	)
	(gr_line
		(start 288.493708 -222.805244)
		(end 289.306254 -222.805244)
		(stroke
			(width 0.2)
			(type default)
		)
		(layer "In6.Cu")
	)
	(gr_arc
		(start 288.493708 -221.784164)
		(mid 287.983168 -222.294704)
		(end 288.493708 -222.805244)
		(stroke
			(width 0.2)
			(type default)
		)
		(layer "In6.Cu")
	)
	(gr_line
		(start 288.581338 -16.034004)
		(end 287.83153 -17.433544)
		(stroke
			(width 0.2)
			(type default)
		)
		(layer "In6.Cu")
	)
	(gr_line
		(start 288.58337 -23.635208)
		(end 287.837626 -25.027636)
		(stroke
			(width 0.2)
			(type default)
		)
		(layer "In6.Cu")
	)
	(gr_line
		(start 288.58337 -19.835114)
		(end 287.837626 -21.227542)
		(stroke
			(width 0.2)
			(type default)
		)
		(layer "In6.Cu")
	)
	(gr_line
		(start 288.58337 -16.035274)
		(end 288.581338 -16.034004)
		(stroke
			(width 0.2)
			(type default)
		)
		(layer "In6.Cu")
	)
	(gr_line
		(start 288.58337 -12.23518)
		(end 287.833562 -13.635228)
		(stroke
			(width 0.2)
			(type default)
		)
		(layer "In6.Cu")
	)
	(gr_line
		(start 288.935414 -25.625044)
		(end 289.685222 -24.224996)
		(stroke
			(width 0.2)
			(type default)
		)
		(layer "In6.Cu")
	)
	(gr_line
		(start 288.935414 -21.82495)
		(end 289.685222 -20.424902)
		(stroke
			(width 0.2)
			(type default)
		)
		(layer "In6.Cu")
	)
	(gr_line
		(start 288.935414 -18.024856)
		(end 288.937446 -18.026126)
		(stroke
			(width 0.2)
			(type default)
		)
		(layer "In6.Cu")
	)
	(gr_line
		(start 288.935414 -14.225016)
		(end 289.681158 -12.832588)
		(stroke
			(width 0.2)
			(type default)
		)
		(layer "In6.Cu")
	)
	(gr_line
		(start 288.937446 -18.026126)
		(end 289.687254 -16.626332)
		(stroke
			(width 0.2)
			(type default)
		)
		(layer "In6.Cu")
	)
	(gr_line
		(start 289.2298 -35.524694)
		(end 290.042346 -35.524694)
		(stroke
			(width 0.2)
			(type default)
		)
		(layer "In6.Cu")
	)
	(gr_arc
		(start 289.2298 -34.503614)
		(mid 288.71926 -35.014154)
		(end 289.2298 -35.524694)
		(stroke
			(width 0.2)
			(type default)
		)
		(layer "In6.Cu")
	)
	(gr_arc
		(start 289.306254 -222.805244)
		(mid 289.817048 -222.294831)
		(end 289.306508 -221.784164)
		(stroke
			(width 0.2)
			(type default)
		)
		(layer "In6.Cu")
	)
	(gr_line
		(start 289.306508 -221.784164)
		(end 288.493708 -221.784164)
		(stroke
			(width 0.2)
			(type default)
		)
		(layer "In6.Cu")
	)
	(gr_arc
		(start 289.681158 -12.832588)
		(mid 289.433024 -11.981135)
		(end 288.58337 -12.23518)
		(stroke
			(width 0.2)
			(type default)
		)
		(layer "In6.Cu")
	)
	(gr_arc
		(start 289.685222 -24.224996)
		(mid 289.42919 -23.379176)
		(end 288.58337 -23.635208)
		(stroke
			(width 0.2)
			(type default)
		)
		(layer "In6.Cu")
	)
	(gr_arc
		(start 289.685222 -20.424902)
		(mid 289.42919 -19.579082)
		(end 288.58337 -19.835114)
		(stroke
			(width 0.2)
			(type default)
		)
		(layer "In6.Cu")
	)
	(gr_arc
		(start 289.685222 -16.625062)
		(mid 289.42919 -15.779242)
		(end 288.58337 -16.035274)
		(stroke
			(width 0.2)
			(type default)
		)
		(layer "In6.Cu")
	)
	(gr_line
		(start 289.687254 -16.626332)
		(end 289.685222 -16.625062)
		(stroke
			(width 0.2)
			(type default)
		)
		(layer "In6.Cu")
	)
	(gr_arc
		(start 290.042346 -35.524694)
		(mid 290.55314 -35.014281)
		(end 290.0426 -34.503614)
		(stroke
			(width 0.2)
			(type default)
		)
		(layer "In6.Cu")
	)
	(gr_line
		(start 290.0426 -34.503614)
		(end 289.2298 -34.503614)
		(stroke
			(width 0.2)
			(type default)
		)
		(layer "In6.Cu")
	)
	(gr_line
		(start 290.081462 -25.033732)
		(end 290.081716 -25.033986)
		(stroke
			(width 0.2)
			(type default)
		)
		(layer "In6.Cu")
	)
	(gr_line
		(start 290.081462 -21.233638)
		(end 290.081716 -21.233892)
		(stroke
			(width 0.2)
			(type default)
		)
		(layer "In6.Cu")
	)
	(gr_line
		(start 290.081462 -17.433544)
		(end 290.081716 -17.433798)
		(stroke
			(width 0.2)
			(type default)
		)
		(layer "In6.Cu")
	)
	(gr_line
		(start 290.081462 -13.633958)
		(end 290.083494 -13.635228)
		(stroke
			(width 0.2)
			(type default)
		)
		(layer "In6.Cu")
	)
	(gr_line
		(start 290.081716 -25.033986)
		(end 290.083748 -25.035002)
		(stroke
			(width 0.2)
			(type default)
		)
		(layer "In6.Cu")
	)
	(gr_line
		(start 290.081716 -21.233892)
		(end 290.083748 -21.234908)
		(stroke
			(width 0.2)
			(type default)
		)
		(layer "In6.Cu")
	)
	(gr_line
		(start 290.081716 -17.433798)
		(end 290.083748 -17.434814)
		(stroke
			(width 0.2)
			(type default)
		)
		(layer "In6.Cu")
	)
	(gr_arc
		(start 290.083494 -13.635228)
		(mid 290.339526 -14.481048)
		(end 291.185346 -14.225016)
		(stroke
			(width 0.2)
			(type default)
		)
		(layer "In6.Cu")
	)
	(gr_arc
		(start 290.083748 -25.035002)
		(mid 290.339424 -25.880903)
		(end 291.185346 -25.625044)
		(stroke
			(width 0.2)
			(type default)
		)
		(layer "In6.Cu")
	)
	(gr_arc
		(start 290.083748 -21.234908)
		(mid 290.339424 -22.080809)
		(end 291.185346 -21.82495)
		(stroke
			(width 0.2)
			(type default)
		)
		(layer "In6.Cu")
	)
	(gr_arc
		(start 290.083748 -17.434814)
		(mid 290.339272 -18.280634)
		(end 291.185092 -18.02511)
		(stroke
			(width 0.2)
			(type default)
		)
		(layer "In6.Cu")
	)
	(gr_line
		(start 290.093654 -211.406994)
		(end 290.906454 -211.406994)
		(stroke
			(width 0.2)
			(type default)
		)
		(layer "In6.Cu")
	)
	(gr_arc
		(start 290.093908 -210.385914)
		(mid 289.583114 -210.896327)
		(end 290.093654 -211.406994)
		(stroke
			(width 0.2)
			(type default)
		)
		(layer "In6.Cu")
	)
	(gr_line
		(start 290.831524 -23.633938)
		(end 290.081462 -25.033732)
		(stroke
			(width 0.2)
			(type default)
		)
		(layer "In6.Cu")
	)
	(gr_line
		(start 290.831524 -19.833844)
		(end 290.081462 -21.233638)
		(stroke
			(width 0.2)
			(type default)
		)
		(layer "In6.Cu")
	)
	(gr_line
		(start 290.831524 -16.03375)
		(end 290.081462 -17.433544)
		(stroke
			(width 0.2)
			(type default)
		)
		(layer "In6.Cu")
	)
	(gr_line
		(start 290.831524 -12.23391)
		(end 290.081462 -13.633958)
		(stroke
			(width 0.2)
			(type default)
		)
		(layer "In6.Cu")
	)
	(gr_line
		(start 290.833556 -23.635208)
		(end 290.831524 -23.633938)
		(stroke
			(width 0.2)
			(type default)
		)
		(layer "In6.Cu")
	)
	(gr_line
		(start 290.833556 -19.835114)
		(end 290.831524 -19.833844)
		(stroke
			(width 0.2)
			(type default)
		)
		(layer "In6.Cu")
	)
	(gr_line
		(start 290.833556 -12.23518)
		(end 290.831524 -12.23391)
		(stroke
			(width 0.2)
			(type default)
		)
		(layer "In6.Cu")
	)
	(gr_line
		(start 290.83381 -16.03502)
		(end 290.831524 -16.03375)
		(stroke
			(width 0.2)
			(type default)
		)
		(layer "In6.Cu")
	)
	(gr_arc
		(start 290.906454 -211.406994)
		(mid 291.416994 -210.896454)
		(end 290.906454 -210.385914)
		(stroke
			(width 0.2)
			(type default)
		)
		(layer "In6.Cu")
	)
	(gr_line
		(start 290.906454 -210.385914)
		(end 290.093908 -210.385914)
		(stroke
			(width 0.2)
			(type default)
		)
		(layer "In6.Cu")
	)
	(gr_line
		(start 291.185092 -18.02511)
		(end 291.187378 -18.02638)
		(stroke
			(width 0.2)
			(type default)
		)
		(layer "In6.Cu")
	)
	(gr_line
		(start 291.185346 -25.625044)
		(end 291.187378 -25.626314)
		(stroke
			(width 0.2)
			(type default)
		)
		(layer "In6.Cu")
	)
	(gr_line
		(start 291.185346 -21.82495)
		(end 291.187378 -21.82622)
		(stroke
			(width 0.2)
			(type default)
		)
		(layer "In6.Cu")
	)
	(gr_line
		(start 291.185346 -14.225016)
		(end 291.187378 -14.226286)
		(stroke
			(width 0.2)
			(type default)
		)
		(layer "In6.Cu")
	)
	(gr_line
		(start 291.187378 -25.626314)
		(end 291.93744 -24.226266)
		(stroke
			(width 0.2)
			(type default)
		)
		(layer "In6.Cu")
	)
	(gr_line
		(start 291.187378 -21.82622)
		(end 291.93744 -20.426172)
		(stroke
			(width 0.2)
			(type default)
		)
		(layer "In6.Cu")
	)
	(gr_line
		(start 291.187378 -18.02638)
		(end 291.93744 -16.626586)
		(stroke
			(width 0.2)
			(type default)
		)
		(layer "In6.Cu")
	)
	(gr_line
		(start 291.187378 -14.226286)
		(end 291.93744 -12.826492)
		(stroke
			(width 0.2)
			(type default)
		)
		(layer "In6.Cu")
	)
	(gr_line
		(start 291.6936 -222.805244)
		(end 292.506146 -222.805244)
		(stroke
			(width 0.2)
			(type default)
		)
		(layer "In6.Cu")
	)
	(gr_arc
		(start 291.6936 -221.784164)
		(mid 291.18306 -222.294704)
		(end 291.6936 -222.805244)
		(stroke
			(width 0.2)
			(type default)
		)
		(layer "In6.Cu")
	)
	(gr_arc
		(start 291.935154 -16.625316)
		(mid 291.67963 -15.779496)
		(end 290.83381 -16.03502)
		(stroke
			(width 0.2)
			(type default)
		)
		(layer "In6.Cu")
	)
	(gr_arc
		(start 291.935154 -12.825222)
		(mid 291.679478 -11.979321)
		(end 290.833556 -12.23518)
		(stroke
			(width 0.2)
			(type default)
		)
		(layer "In6.Cu")
	)
	(gr_arc
		(start 291.935408 -24.224996)
		(mid 291.679376 -23.379176)
		(end 290.833556 -23.635208)
		(stroke
			(width 0.2)
			(type default)
		)
		(layer "In6.Cu")
	)
	(gr_arc
		(start 291.935408 -20.424902)
		(mid 291.679376 -19.579082)
		(end 290.833556 -19.835114)
		(stroke
			(width 0.2)
			(type default)
		)
		(layer "In6.Cu")
	)
	(gr_line
		(start 291.937186 -12.826238)
		(end 291.935154 -12.825222)
		(stroke
			(width 0.2)
			(type default)
		)
		(layer "In6.Cu")
	)
	(gr_line
		(start 291.93744 -24.226266)
		(end 291.935408 -24.224996)
		(stroke
			(width 0.2)
			(type default)
		)
		(layer "In6.Cu")
	)
	(gr_line
		(start 291.93744 -20.426172)
		(end 291.935408 -20.424902)
		(stroke
			(width 0.2)
			(type default)
		)
		(layer "In6.Cu")
	)
	(gr_line
		(start 291.93744 -16.626586)
		(end 291.935154 -16.625316)
		(stroke
			(width 0.2)
			(type default)
		)
		(layer "In6.Cu")
	)
	(gr_line
		(start 291.93744 -12.826492)
		(end 291.937186 -12.826238)
		(stroke
			(width 0.2)
			(type default)
		)
		(layer "In6.Cu")
	)
	(gr_arc
		(start 292.506146 -222.805244)
		(mid 293.01694 -222.294831)
		(end 292.5064 -221.784164)
		(stroke
			(width 0.2)
			(type default)
		)
		(layer "In6.Cu")
	)
	(gr_line
		(start 292.5064 -221.784164)
		(end 291.6936 -221.784164)
		(stroke
			(width 0.2)
			(type default)
		)
		(layer "In6.Cu")
	)
	(gr_line
		(start 293.293546 -211.406994)
		(end 294.106346 -211.406994)
		(stroke
			(width 0.2)
			(type default)
		)
		(layer "In6.Cu")
	)
	(gr_arc
		(start 293.2938 -210.385914)
		(mid 292.783006 -210.896327)
		(end 293.293546 -211.406994)
		(stroke
			(width 0.2)
			(type default)
		)
		(layer "In6.Cu")
	)
	(gr_arc
		(start 294.106346 -211.406994)
		(mid 294.616886 -210.896454)
		(end 294.106346 -210.385914)
		(stroke
			(width 0.2)
			(type default)
		)
		(layer "In6.Cu")
	)
	(gr_line
		(start 294.106346 -210.385914)
		(end 293.2938 -210.385914)
		(stroke
			(width 0.2)
			(type default)
		)
		(layer "In6.Cu")
	)
	(gr_line
		(start 294.159178 -35.69081)
		(end 294.971978 -35.69081)
		(stroke
			(width 0.2)
			(type default)
		)
		(layer "In6.Cu")
	)
	(gr_arc
		(start 294.159432 -34.66973)
		(mid 293.648638 -35.180143)
		(end 294.159178 -35.69081)
		(stroke
			(width 0.2)
			(type default)
		)
		(layer "In6.Cu")
	)
	(gr_line
		(start 294.893746 -222.805244)
		(end 295.706292 -222.805244)
		(stroke
			(width 0.2)
			(type default)
		)
		(layer "In6.Cu")
	)
	(gr_arc
		(start 294.893746 -221.784164)
		(mid 294.383206 -222.294704)
		(end 294.893746 -222.805244)
		(stroke
			(width 0.2)
			(type default)
		)
		(layer "In6.Cu")
	)
	(gr_arc
		(start 294.971978 -35.69081)
		(mid 295.482518 -35.18027)
		(end 294.971978 -34.66973)
		(stroke
			(width 0.2)
			(type default)
		)
		(layer "In6.Cu")
	)
	(gr_line
		(start 294.971978 -34.66973)
		(end 294.159432 -34.66973)
		(stroke
			(width 0.2)
			(type default)
		)
		(layer "In6.Cu")
	)
	(gr_arc
		(start 295.706292 -222.805244)
		(mid 296.217086 -222.294831)
		(end 295.706546 -221.784164)
		(stroke
			(width 0.2)
			(type default)
		)
		(layer "In6.Cu")
	)
	(gr_line
		(start 295.706546 -221.784164)
		(end 294.893746 -221.784164)
		(stroke
			(width 0.2)
			(type default)
		)
		(layer "In6.Cu")
	)
	(gr_line
		(start 296.581322 -25.033986)
		(end 296.583354 -25.035256)
		(stroke
			(width 0.2)
			(type default)
		)
		(layer "In6.Cu")
	)
	(gr_line
		(start 296.581322 -13.633704)
		(end 296.581576 -13.633958)
		(stroke
			(width 0.2)
			(type default)
		)
		(layer "In6.Cu")
	)
	(gr_line
		(start 296.581576 -13.633958)
		(end 296.583608 -13.634974)
		(stroke
			(width 0.2)
			(type default)
		)
		(layer "In6.Cu")
	)
	(gr_arc
		(start 296.583354 -25.035256)
		(mid 296.839386 -25.881076)
		(end 297.685206 -25.625044)
		(stroke
			(width 0.2)
			(type default)
		)
		(layer "In6.Cu")
	)
	(gr_arc
		(start 296.583608 -13.634974)
		(mid 296.839284 -14.480875)
		(end 297.685206 -14.225016)
		(stroke
			(width 0.2)
			(type default)
		)
		(layer "In6.Cu")
	)
	(gr_line
		(start 297.331384 -23.633938)
		(end 296.581322 -25.033986)
		(stroke
			(width 0.2)
			(type default)
		)
		(layer "In6.Cu")
	)
	(gr_line
		(start 297.331384 -12.23391)
		(end 296.581322 -13.633704)
		(stroke
			(width 0.2)
			(type default)
		)
		(layer "In6.Cu")
	)
	(gr_line
		(start 297.333416 -23.635208)
		(end 297.331384 -23.633938)
		(stroke
			(width 0.2)
			(type default)
		)
		(layer "In6.Cu")
	)
	(gr_line
		(start 297.333416 -12.23518)
		(end 297.331384 -12.23391)
		(stroke
			(width 0.2)
			(type default)
		)
		(layer "In6.Cu")
	)
	(gr_line
		(start 297.685206 -25.625044)
		(end 297.687238 -25.626314)
		(stroke
			(width 0.2)
			(type default)
		)
		(layer "In6.Cu")
	)
	(gr_line
		(start 297.685206 -14.225016)
		(end 297.687238 -14.226286)
		(stroke
			(width 0.2)
			(type default)
		)
		(layer "In6.Cu")
	)
	(gr_line
		(start 297.687238 -25.626314)
		(end 298.4373 -24.22652)
		(stroke
			(width 0.2)
			(type default)
		)
		(layer "In6.Cu")
	)
	(gr_line
		(start 297.687238 -14.226286)
		(end 298.4373 -12.826238)
		(stroke
			(width 0.2)
			(type default)
		)
		(layer "In6.Cu")
	)
	(gr_arc
		(start 298.435014 -24.22525)
		(mid 298.179338 -23.379349)
		(end 297.333416 -23.635208)
		(stroke
			(width 0.2)
			(type default)
		)
		(layer "In6.Cu")
	)
	(gr_arc
		(start 298.435268 -12.824968)
		(mid 298.179236 -11.979148)
		(end 297.333416 -12.23518)
		(stroke
			(width 0.2)
			(type default)
		)
		(layer "In6.Cu")
	)
	(gr_line
		(start 298.437046 -24.226266)
		(end 298.435014 -24.22525)
		(stroke
			(width 0.2)
			(type default)
		)
		(layer "In6.Cu")
	)
	(gr_line
		(start 298.4373 -24.22652)
		(end 298.437046 -24.226266)
		(stroke
			(width 0.2)
			(type default)
		)
		(layer "In6.Cu")
	)
	(gr_line
		(start 298.4373 -12.826238)
		(end 298.435268 -12.824968)
		(stroke
			(width 0.2)
			(type default)
		)
		(layer "In6.Cu")
	)
	(gr_line
		(start 298.831508 -17.433544)
		(end 298.831762 -17.433798)
		(stroke
			(width 0.2)
			(type default)
		)
		(layer "In6.Cu")
	)
	(gr_line
		(start 298.831762 -17.433798)
		(end 298.833794 -17.434814)
		(stroke
			(width 0.2)
			(type default)
		)
		(layer "In6.Cu")
	)
	(gr_arc
		(start 298.83354 -21.235162)
		(mid 299.089572 -22.080982)
		(end 299.935392 -21.82495)
		(stroke
			(width 0.2)
			(type default)
		)
		(layer "In6.Cu")
	)
	(gr_arc
		(start 298.833794 -17.434814)
		(mid 299.08947 -18.280715)
		(end 299.935392 -18.024856)
		(stroke
			(width 0.2)
			(type default)
		)
		(layer "In6.Cu")
	)
	(gr_arc
		(start 298.837604 -25.027636)
		(mid 299.085738 -25.879089)
		(end 299.935392 -25.625044)
		(stroke
			(width 0.2)
			(type default)
		)
		(layer "In6.Cu")
	)
	(gr_arc
		(start 298.837604 -13.627608)
		(mid 299.085738 -14.479061)
		(end 299.935392 -14.225016)
		(stroke
			(width 0.2)
			(type default)
		)
		(layer "In6.Cu")
	)
	(gr_line
		(start 298.893738 -211.406994)
		(end 299.706538 -211.406994)
		(stroke
			(width 0.2)
			(type default)
		)
		(layer "In6.Cu")
	)
	(gr_arc
		(start 298.893992 -210.385914)
		(mid 298.383198 -210.896327)
		(end 298.893738 -211.406994)
		(stroke
			(width 0.2)
			(type default)
		)
		(layer "In6.Cu")
	)
	(gr_line
		(start 299.430694 -36.699952)
		(end 300.243494 -36.699952)
		(stroke
			(width 0.2)
			(type default)
		)
		(layer "In6.Cu")
	)
	(gr_arc
		(start 299.430948 -35.678872)
		(mid 298.920154 -36.189285)
		(end 299.430694 -36.699952)
		(stroke
			(width 0.2)
			(type default)
		)
		(layer "In6.Cu")
	)
	(gr_line
		(start 299.581316 -16.034004)
		(end 298.831508 -17.433544)
		(stroke
			(width 0.2)
			(type default)
		)
		(layer "In6.Cu")
	)
	(gr_line
		(start 299.583348 -23.635208)
		(end 298.837604 -25.027636)
		(stroke
			(width 0.2)
			(type default)
		)
		(layer "In6.Cu")
	)
	(gr_line
		(start 299.583348 -19.835114)
		(end 298.83354 -21.235162)
		(stroke
			(width 0.2)
			(type default)
		)
		(layer "In6.Cu")
	)
	(gr_line
		(start 299.583348 -16.035274)
		(end 299.581316 -16.034004)
		(stroke
			(width 0.2)
			(type default)
		)
		(layer "In6.Cu")
	)
	(gr_line
		(start 299.583348 -12.23518)
		(end 298.837604 -13.627608)
		(stroke
			(width 0.2)
			(type default)
		)
		(layer "In6.Cu")
	)
	(gr_arc
		(start 299.706538 -211.406994)
		(mid 300.217078 -210.896454)
		(end 299.706538 -210.385914)
		(stroke
			(width 0.2)
			(type default)
		)
		(layer "In6.Cu")
	)
	(gr_line
		(start 299.706538 -210.385914)
		(end 298.893992 -210.385914)
		(stroke
			(width 0.2)
			(type default)
		)
		(layer "In6.Cu")
	)
	(gr_line
		(start 299.935392 -25.625044)
		(end 300.6852 -24.224996)
		(stroke
			(width 0.2)
			(type default)
		)
		(layer "In6.Cu")
	)
	(gr_line
		(start 299.935392 -21.82495)
		(end 300.681136 -20.432522)
		(stroke
			(width 0.2)
			(type default)
		)
		(layer "In6.Cu")
	)
	(gr_line
		(start 299.935392 -18.024856)
		(end 299.937424 -18.026126)
		(stroke
			(width 0.2)
			(type default)
		)
		(layer "In6.Cu")
	)
	(gr_line
		(start 299.935392 -14.225016)
		(end 300.6852 -12.824968)
		(stroke
			(width 0.2)
			(type default)
		)
		(layer "In6.Cu")
	)
	(gr_line
		(start 299.937424 -18.026126)
		(end 300.687232 -16.626332)
		(stroke
			(width 0.2)
			(type default)
		)
		(layer "In6.Cu")
	)
	(gr_arc
		(start 300.243494 -36.699952)
		(mid 300.754034 -36.189412)
		(end 300.243494 -35.678872)
		(stroke
			(width 0.2)
			(type default)
		)
		(layer "In6.Cu")
	)
	(gr_line
		(start 300.243494 -35.678872)
		(end 299.430948 -35.678872)
		(stroke
			(width 0.2)
			(type default)
		)
		(layer "In6.Cu")
	)
	(gr_line
		(start 300.493684 -222.805244)
		(end 301.30623 -222.805244)
		(stroke
			(width 0.2)
			(type default)
		)
		(layer "In6.Cu")
	)
	(gr_arc
		(start 300.493684 -221.784164)
		(mid 299.983144 -222.294704)
		(end 300.493684 -222.805244)
		(stroke
			(width 0.2)
			(type default)
		)
		(layer "In6.Cu")
	)
	(gr_arc
		(start 300.681136 -20.432522)
		(mid 300.433002 -19.581069)
		(end 299.583348 -19.835114)
		(stroke
			(width 0.2)
			(type default)
		)
		(layer "In6.Cu")
	)
	(gr_arc
		(start 300.6852 -24.224996)
		(mid 300.429168 -23.379176)
		(end 299.583348 -23.635208)
		(stroke
			(width 0.2)
			(type default)
		)
		(layer "In6.Cu")
	)
	(gr_arc
		(start 300.6852 -16.625062)
		(mid 300.429168 -15.779242)
		(end 299.583348 -16.035274)
		(stroke
			(width 0.2)
			(type default)
		)
		(layer "In6.Cu")
	)
	(gr_arc
		(start 300.6852 -12.824968)
		(mid 300.429168 -11.979148)
		(end 299.583348 -12.23518)
		(stroke
			(width 0.2)
			(type default)
		)
		(layer "In6.Cu")
	)
	(gr_line
		(start 300.687232 -16.626332)
		(end 300.6852 -16.625062)
		(stroke
			(width 0.2)
			(type default)
		)
		(layer "In6.Cu")
	)
	(gr_line
		(start 301.08144 -25.033732)
		(end 301.081694 -25.033986)
		(stroke
			(width 0.2)
			(type default)
		)
		(layer "In6.Cu")
	)
	(gr_line
		(start 301.08144 -21.233892)
		(end 301.083472 -21.235162)
		(stroke
			(width 0.2)
			(type default)
		)
		(layer "In6.Cu")
	)
	(gr_line
		(start 301.08144 -17.433544)
		(end 301.081694 -17.433798)
		(stroke
			(width 0.2)
			(type default)
		)
		(layer "In6.Cu")
	)
	(gr_line
		(start 301.08144 -13.633704)
		(end 301.081694 -13.633958)
		(stroke
			(width 0.2)
			(type default)
		)
		(layer "In6.Cu")
	)
	(gr_line
		(start 301.081694 -25.033986)
		(end 301.083726 -25.035002)
		(stroke
			(width 0.2)
			(type default)
		)
		(layer "In6.Cu")
	)
	(gr_line
		(start 301.081694 -17.433798)
		(end 301.083726 -17.434814)
		(stroke
			(width 0.2)
			(type default)
		)
		(layer "In6.Cu")
	)
	(gr_line
		(start 301.081694 -13.633958)
		(end 301.083726 -13.634974)
		(stroke
			(width 0.2)
			(type default)
		)
		(layer "In6.Cu")
	)
	(gr_arc
		(start 301.083472 -21.235162)
		(mid 301.339504 -22.080982)
		(end 302.185324 -21.82495)
		(stroke
			(width 0.2)
			(type default)
		)
		(layer "In6.Cu")
	)
	(gr_arc
		(start 301.083726 -25.035002)
		(mid 301.339402 -25.880903)
		(end 302.185324 -25.625044)
		(stroke
			(width 0.2)
			(type default)
		)
		(layer "In6.Cu")
	)
	(gr_arc
		(start 301.083726 -17.434814)
		(mid 301.33925 -18.280634)
		(end 302.18507 -18.02511)
		(stroke
			(width 0.2)
			(type default)
		)
		(layer "In6.Cu")
	)
	(gr_arc
		(start 301.083726 -13.634974)
		(mid 301.339402 -14.480875)
		(end 302.185324 -14.225016)
		(stroke
			(width 0.2)
			(type default)
		)
		(layer "In6.Cu")
	)
	(gr_arc
		(start 301.30623 -222.805244)
		(mid 301.817024 -222.294831)
		(end 301.306484 -221.784164)
		(stroke
			(width 0.2)
			(type default)
		)
		(layer "In6.Cu")
	)
	(gr_line
		(start 301.306484 -221.784164)
		(end 300.493684 -221.784164)
		(stroke
			(width 0.2)
			(type default)
		)
		(layer "In6.Cu")
	)
	(gr_line
		(start 301.65929 -35.536886)
		(end 302.471836 -35.536886)
		(stroke
			(width 0.2)
			(type default)
		)
		(layer "In6.Cu")
	)
	(gr_arc
		(start 301.65929 -34.515806)
		(mid 301.14875 -35.026346)
		(end 301.65929 -35.536886)
		(stroke
			(width 0.2)
			(type default)
		)
		(layer "In6.Cu")
	)
	(gr_line
		(start 301.831502 -23.633938)
		(end 301.08144 -25.033732)
		(stroke
			(width 0.2)
			(type default)
		)
		(layer "In6.Cu")
	)
	(gr_line
		(start 301.831502 -19.833844)
		(end 301.08144 -21.233892)
		(stroke
			(width 0.2)
			(type default)
		)
		(layer "In6.Cu")
	)
	(gr_line
		(start 301.831502 -16.03375)
		(end 301.08144 -17.433544)
		(stroke
			(width 0.2)
			(type default)
		)
		(layer "In6.Cu")
	)
	(gr_line
		(start 301.831502 -12.23391)
		(end 301.08144 -13.633704)
		(stroke
			(width 0.2)
			(type default)
		)
		(layer "In6.Cu")
	)
	(gr_line
		(start 301.833534 -23.635208)
		(end 301.831502 -23.633938)
		(stroke
			(width 0.2)
			(type default)
		)
		(layer "In6.Cu")
	)
	(gr_line
		(start 301.833534 -19.835114)
		(end 301.831502 -19.833844)
		(stroke
			(width 0.2)
			(type default)
		)
		(layer "In6.Cu")
	)
	(gr_line
		(start 301.833534 -12.23518)
		(end 301.831502 -12.23391)
		(stroke
			(width 0.2)
			(type default)
		)
		(layer "In6.Cu")
	)
	(gr_line
		(start 301.833788 -16.03502)
		(end 301.831502 -16.03375)
		(stroke
			(width 0.2)
			(type default)
		)
		(layer "In6.Cu")
	)
	(gr_line
		(start 302.09363 -211.406994)
		(end 302.90643 -211.406994)
		(stroke
			(width 0.2)
			(type default)
		)
		(layer "In6.Cu")
	)
	(gr_arc
		(start 302.093884 -210.385914)
		(mid 301.58309 -210.896327)
		(end 302.09363 -211.406994)
		(stroke
			(width 0.2)
			(type default)
		)
		(layer "In6.Cu")
	)
	(gr_line
		(start 302.18507 -18.02511)
		(end 302.187356 -18.02638)
		(stroke
			(width 0.2)
			(type default)
		)
		(layer "In6.Cu")
	)
	(gr_line
		(start 302.185324 -25.625044)
		(end 302.187356 -25.626314)
		(stroke
			(width 0.2)
			(type default)
		)
		(layer "In6.Cu")
	)
	(gr_line
		(start 302.185324 -21.82495)
		(end 302.187356 -21.82622)
		(stroke
			(width 0.2)
			(type default)
		)
		(layer "In6.Cu")
	)
	(gr_line
		(start 302.185324 -14.225016)
		(end 302.187356 -14.226286)
		(stroke
			(width 0.2)
			(type default)
		)
		(layer "In6.Cu")
	)
	(gr_line
		(start 302.187356 -25.626314)
		(end 302.937418 -24.226266)
		(stroke
			(width 0.2)
			(type default)
		)
		(layer "In6.Cu")
	)
	(gr_line
		(start 302.187356 -21.82622)
		(end 302.937418 -20.426426)
		(stroke
			(width 0.2)
			(type default)
		)
		(layer "In6.Cu")
	)
	(gr_line
		(start 302.187356 -18.02638)
		(end 302.937418 -16.626586)
		(stroke
			(width 0.2)
			(type default)
		)
		(layer "In6.Cu")
	)
	(gr_line
		(start 302.187356 -14.226286)
		(end 302.937418 -12.826238)
		(stroke
			(width 0.2)
			(type default)
		)
		(layer "In6.Cu")
	)
	(gr_arc
		(start 302.471836 -35.536886)
		(mid 302.98263 -35.026473)
		(end 302.47209 -34.515806)
		(stroke
			(width 0.2)
			(type default)
		)
		(layer "In6.Cu")
	)
	(gr_line
		(start 302.47209 -34.515806)
		(end 301.65929 -34.515806)
		(stroke
			(width 0.2)
			(type default)
		)
		(layer "In6.Cu")
	)
	(gr_arc
		(start 302.90643 -211.406994)
		(mid 303.41697 -210.896454)
		(end 302.90643 -210.385914)
		(stroke
			(width 0.2)
			(type default)
		)
		(layer "In6.Cu")
	)
	(gr_line
		(start 302.90643 -210.385914)
		(end 302.093884 -210.385914)
		(stroke
			(width 0.2)
			(type default)
		)
		(layer "In6.Cu")
	)
	(gr_arc
		(start 302.935132 -20.425156)
		(mid 302.679456 -19.579255)
		(end 301.833534 -19.835114)
		(stroke
			(width 0.2)
			(type default)
		)
		(layer "In6.Cu")
	)
	(gr_arc
		(start 302.935132 -16.625316)
		(mid 302.679608 -15.779496)
		(end 301.833788 -16.03502)
		(stroke
			(width 0.2)
			(type default)
		)
		(layer "In6.Cu")
	)
	(gr_arc
		(start 302.935386 -24.224996)
		(mid 302.679354 -23.379176)
		(end 301.833534 -23.635208)
		(stroke
			(width 0.2)
			(type default)
		)
		(layer "In6.Cu")
	)
	(gr_arc
		(start 302.935386 -12.824968)
		(mid 302.679354 -11.979148)
		(end 301.833534 -12.23518)
		(stroke
			(width 0.2)
			(type default)
		)
		(layer "In6.Cu")
	)
	(gr_line
		(start 302.937164 -20.426172)
		(end 302.935132 -20.425156)
		(stroke
			(width 0.2)
			(type default)
		)
		(layer "In6.Cu")
	)
	(gr_line
		(start 302.937418 -24.226266)
		(end 302.935386 -24.224996)
		(stroke
			(width 0.2)
			(type default)
		)
		(layer "In6.Cu")
	)
	(gr_line
		(start 302.937418 -20.426426)
		(end 302.937164 -20.426172)
		(stroke
			(width 0.2)
			(type default)
		)
		(layer "In6.Cu")
	)
	(gr_line
		(start 302.937418 -16.626586)
		(end 302.935132 -16.625316)
		(stroke
			(width 0.2)
			(type default)
		)
		(layer "In6.Cu")
	)
	(gr_line
		(start 302.937418 -12.826238)
		(end 302.935386 -12.824968)
		(stroke
			(width 0.2)
			(type default)
		)
		(layer "In6.Cu")
	)
	(gr_arc
		(start 303.717198 -219.783914)
		(mid 303.222914 -220.310202)
		(end 303.749202 -220.804486)
		(stroke
			(width 0.2)
			(type default)
		)
		(layer "In6.Cu")
	)
	(gr_line
		(start 303.717198 -219.781374)
		(end 303.717198 -219.783914)
		(stroke
			(width 0.2)
			(type default)
		)
		(layer "In6.Cu")
	)
	(gr_line
		(start 303.749202 -220.807026)
		(end 304.561748 -220.781626)
		(stroke
			(width 0.2)
			(type default)
		)
		(layer "In6.Cu")
	)
	(gr_line
		(start 303.749202 -220.804486)
		(end 303.749202 -220.807026)
		(stroke
			(width 0.2)
			(type default)
		)
		(layer "In6.Cu")
	)
	(gr_line
		(start 303.8348 -36.794694)
		(end 304.647346 -36.794694)
		(stroke
			(width 0.2)
			(type default)
		)
		(layer "In6.Cu")
	)
	(gr_arc
		(start 303.8348 -35.773614)
		(mid 303.32426 -36.284154)
		(end 303.8348 -36.794694)
		(stroke
			(width 0.2)
			(type default)
		)
		(layer "In6.Cu")
	)
	(gr_line
		(start 304.529998 -219.758514)
		(end 304.529998 -219.755974)
		(stroke
			(width 0.2)
			(type default)
		)
		(layer "In6.Cu")
	)
	(gr_line
		(start 304.529998 -219.755974)
		(end 303.717198 -219.781374)
		(stroke
			(width 0.2)
			(type default)
		)
		(layer "In6.Cu")
	)
	(gr_line
		(start 304.561748 -220.781626)
		(end 304.562002 -220.781372)
		(stroke
			(width 0.2)
			(type default)
		)
		(layer "In6.Cu")
	)
	(gr_line
		(start 304.562002 -220.781372)
		(end 304.562002 -220.779086)
		(stroke
			(width 0.2)
			(type default)
		)
		(layer "In6.Cu")
	)
	(gr_arc
		(start 304.562002 -220.779086)
		(mid 305.056286 -220.252798)
		(end 304.529998 -219.758514)
		(stroke
			(width 0.2)
			(type default)
		)
		(layer "In6.Cu")
	)
	(gr_arc
		(start 304.647346 -36.794694)
		(mid 305.15814 -36.284281)
		(end 304.6476 -35.773614)
		(stroke
			(width 0.2)
			(type default)
		)
		(layer "In6.Cu")
	)
	(gr_line
		(start 304.6476 -35.773614)
		(end 303.8348 -35.773614)
		(stroke
			(width 0.2)
			(type default)
		)
		(layer "In6.Cu")
	)
	(gr_line
		(start 305.762914 -40.31996)
		(end 306.57546 -40.31996)
		(stroke
			(width 0.2)
			(type default)
		)
		(layer "In6.Cu")
	)
	(gr_arc
		(start 305.762914 -39.29888)
		(mid 305.252374 -39.80942)
		(end 305.762914 -40.31996)
		(stroke
			(width 0.2)
			(type default)
		)
		(layer "In6.Cu")
	)
	(gr_line
		(start 306.099972 -228.000052)
		(end 260.500114 -228.000052)
		(stroke
			(width 5.08)
			(type default)
		)
		(layer "In6.Cu")
	)
	(gr_line
		(start 306.099972 -222.600012)
		(end 306.099972 -228.000052)
		(stroke
			(width 1.524)
			(type default)
		)
		(layer "In6.Cu")
	)
	(gr_arc
		(start 306.57546 -40.31996)
		(mid 307.086254 -39.809547)
		(end 306.575714 -39.29888)
		(stroke
			(width 0.2)
			(type default)
		)
		(layer "In6.Cu")
	)
	(gr_line
		(start 306.575714 -39.29888)
		(end 305.762914 -39.29888)
		(stroke
			(width 0.2)
			(type default)
		)
		(layer "In6.Cu")
	)
	(gr_arc
		(start 307.583586 -25.035256)
		(mid 307.839618 -25.881076)
		(end 308.685438 -25.625044)
		(stroke
			(width 0.2)
			(type default)
		)
		(layer "In6.Cu")
	)
	(gr_arc
		(start 307.58765 -13.627608)
		(mid 307.835784 -14.479061)
		(end 308.685438 -14.225016)
		(stroke
			(width 0.2)
			(type default)
		)
		(layer "In6.Cu")
	)
	(gr_line
		(start 308.333394 -23.635208)
		(end 307.583586 -25.035256)
		(stroke
			(width 0.2)
			(type default)
		)
		(layer "In6.Cu")
	)
	(gr_line
		(start 308.333394 -12.23518)
		(end 307.58765 -13.627608)
		(stroke
			(width 0.2)
			(type default)
		)
		(layer "In6.Cu")
	)
	(gr_line
		(start 308.500018 -228.000052)
		(end 308.500018 -222.600012)
		(stroke
			(width 1.524)
			(type default)
		)
		(layer "In6.Cu")
	)
	(gr_arc
		(start 308.500018 -222.600012)
		(mid 307.300122 -221.400116)
		(end 306.099972 -222.600012)
		(stroke
			(width 1.524)
			(type default)
		)
		(layer "In6.Cu")
	)
	(gr_line
		(start 308.685438 -25.625044)
		(end 309.431182 -24.232616)
		(stroke
			(width 0.2)
			(type default)
		)
		(layer "In6.Cu")
	)
	(gr_line
		(start 308.685438 -14.225016)
		(end 309.435246 -12.824968)
		(stroke
			(width 0.2)
			(type default)
		)
		(layer "In6.Cu")
	)
	(gr_arc
		(start 309.431182 -24.232616)
		(mid 309.183048 -23.381163)
		(end 308.333394 -23.635208)
		(stroke
			(width 0.2)
			(type default)
		)
		(layer "In6.Cu")
	)
	(gr_arc
		(start 309.435246 -12.824968)
		(mid 309.179214 -11.979148)
		(end 308.333394 -12.23518)
		(stroke
			(width 0.2)
			(type default)
		)
		(layer "In6.Cu")
	)
	(gr_line
		(start 309.831486 -25.033732)
		(end 309.83174 -25.033986)
		(stroke
			(width 0.2)
			(type default)
		)
		(layer "In6.Cu")
	)
	(gr_line
		(start 309.831486 -21.233892)
		(end 309.833518 -21.235162)
		(stroke
			(width 0.2)
			(type default)
		)
		(layer "In6.Cu")
	)
	(gr_line
		(start 309.831486 -17.433544)
		(end 309.83174 -17.433798)
		(stroke
			(width 0.2)
			(type default)
		)
		(layer "In6.Cu")
	)
	(gr_line
		(start 309.831486 -13.633704)
		(end 309.83174 -13.633958)
		(stroke
			(width 0.2)
			(type default)
		)
		(layer "In6.Cu")
	)
	(gr_line
		(start 309.83174 -25.033986)
		(end 309.833772 -25.035002)
		(stroke
			(width 0.2)
			(type default)
		)
		(layer "In6.Cu")
	)
	(gr_line
		(start 309.83174 -17.433798)
		(end 309.833772 -17.434814)
		(stroke
			(width 0.2)
			(type default)
		)
		(layer "In6.Cu")
	)
	(gr_line
		(start 309.83174 -13.633958)
		(end 309.833772 -13.634974)
		(stroke
			(width 0.2)
			(type default)
		)
		(layer "In6.Cu")
	)
	(gr_arc
		(start 309.833518 -21.235162)
		(mid 310.08955 -22.080982)
		(end 310.93537 -21.82495)
		(stroke
			(width 0.2)
			(type default)
		)
		(layer "In6.Cu")
	)
	(gr_arc
		(start 309.833772 -25.035002)
		(mid 310.089448 -25.880903)
		(end 310.93537 -25.625044)
		(stroke
			(width 0.2)
			(type default)
		)
		(layer "In6.Cu")
	)
	(gr_arc
		(start 309.833772 -17.434814)
		(mid 310.089296 -18.280634)
		(end 310.935116 -18.02511)
		(stroke
			(width 0.2)
			(type default)
		)
		(layer "In6.Cu")
	)
	(gr_arc
		(start 309.833772 -13.634974)
		(mid 310.089448 -14.480875)
		(end 310.93537 -14.225016)
		(stroke
			(width 0.2)
			(type default)
		)
		(layer "In6.Cu")
	)
	(gr_line
		(start 310.093868 -211.406994)
		(end 310.906414 -211.406994)
		(stroke
			(width 0.2)
			(type default)
		)
		(layer "In6.Cu")
	)
	(gr_arc
		(start 310.093868 -210.385914)
		(mid 309.583328 -210.896454)
		(end 310.093868 -211.406994)
		(stroke
			(width 0.2)
			(type default)
		)
		(layer "In6.Cu")
	)
	(gr_line
		(start 310.425592 -35.55238)
		(end 311.238138 -35.55238)
		(stroke
			(width 0.2)
			(type default)
		)
		(layer "In6.Cu")
	)
	(gr_arc
		(start 310.425592 -34.5313)
		(mid 309.915052 -35.04184)
		(end 310.425592 -35.55238)
		(stroke
			(width 0.2)
			(type default)
		)
		(layer "In6.Cu")
	)
	(gr_line
		(start 310.581548 -23.633938)
		(end 309.831486 -25.033732)
		(stroke
			(width 0.2)
			(type default)
		)
		(layer "In6.Cu")
	)
	(gr_line
		(start 310.581548 -19.833844)
		(end 309.831486 -21.233892)
		(stroke
			(width 0.2)
			(type default)
		)
		(layer "In6.Cu")
	)
	(gr_line
		(start 310.581548 -16.03375)
		(end 309.831486 -17.433544)
		(stroke
			(width 0.2)
			(type default)
		)
		(layer "In6.Cu")
	)
	(gr_line
		(start 310.581548 -12.23391)
		(end 309.831486 -13.633704)
		(stroke
			(width 0.2)
			(type default)
		)
		(layer "In6.Cu")
	)
	(gr_line
		(start 310.58358 -23.635208)
		(end 310.581548 -23.633938)
		(stroke
			(width 0.2)
			(type default)
		)
		(layer "In6.Cu")
	)
	(gr_line
		(start 310.58358 -19.835114)
		(end 310.581548 -19.833844)
		(stroke
			(width 0.2)
			(type default)
		)
		(layer "In6.Cu")
	)
	(gr_line
		(start 310.58358 -12.23518)
		(end 310.581548 -12.23391)
		(stroke
			(width 0.2)
			(type default)
		)
		(layer "In6.Cu")
	)
	(gr_line
		(start 310.583834 -16.03502)
		(end 310.581548 -16.03375)
		(stroke
			(width 0.2)
			(type default)
		)
		(layer "In6.Cu")
	)
	(gr_arc
		(start 310.906414 -211.406994)
		(mid 311.417208 -210.896581)
		(end 310.906668 -210.385914)
		(stroke
			(width 0.2)
			(type default)
		)
		(layer "In6.Cu")
	)
	(gr_line
		(start 310.906668 -210.385914)
		(end 310.093868 -210.385914)
		(stroke
			(width 0.2)
			(type default)
		)
		(layer "In6.Cu")
	)
	(gr_line
		(start 310.935116 -18.02511)
		(end 310.937402 -18.02638)
		(stroke
			(width 0.2)
			(type default)
		)
		(layer "In6.Cu")
	)
	(gr_line
		(start 310.93537 -25.625044)
		(end 310.937402 -25.626314)
		(stroke
			(width 0.2)
			(type default)
		)
		(layer "In6.Cu")
	)
	(gr_line
		(start 310.93537 -21.82495)
		(end 310.937402 -21.82622)
		(stroke
			(width 0.2)
			(type default)
		)
		(layer "In6.Cu")
	)
	(gr_line
		(start 310.93537 -14.225016)
		(end 310.937402 -14.226286)
		(stroke
			(width 0.2)
			(type default)
		)
		(layer "In6.Cu")
	)
	(gr_line
		(start 310.937402 -25.626314)
		(end 311.687464 -24.226266)
		(stroke
			(width 0.2)
			(type default)
		)
		(layer "In6.Cu")
	)
	(gr_line
		(start 310.937402 -21.82622)
		(end 311.687464 -20.426426)
		(stroke
			(width 0.2)
			(type default)
		)
		(layer "In6.Cu")
	)
	(gr_line
		(start 310.937402 -18.02638)
		(end 311.687464 -16.626586)
		(stroke
			(width 0.2)
			(type default)
		)
		(layer "In6.Cu")
	)
	(gr_line
		(start 310.937402 -14.226286)
		(end 311.687464 -12.826238)
		(stroke
			(width 0.2)
			(type default)
		)
		(layer "In6.Cu")
	)
	(gr_arc
		(start 311.238138 -35.55238)
		(mid 311.748932 -35.041967)
		(end 311.238392 -34.5313)
		(stroke
			(width 0.2)
			(type default)
		)
		(layer "In6.Cu")
	)
	(gr_line
		(start 311.238392 -34.5313)
		(end 310.425592 -34.5313)
		(stroke
			(width 0.2)
			(type default)
		)
		(layer "In6.Cu")
	)
	(gr_arc
		(start 311.685178 -20.425156)
		(mid 311.429502 -19.579255)
		(end 310.58358 -19.835114)
		(stroke
			(width 0.2)
			(type default)
		)
		(layer "In6.Cu")
	)
	(gr_arc
		(start 311.685178 -16.625316)
		(mid 311.429654 -15.779496)
		(end 310.583834 -16.03502)
		(stroke
			(width 0.2)
			(type default)
		)
		(layer "In6.Cu")
	)
	(gr_arc
		(start 311.685432 -24.224996)
		(mid 311.4294 -23.379176)
		(end 310.58358 -23.635208)
		(stroke
			(width 0.2)
			(type default)
		)
		(layer "In6.Cu")
	)
	(gr_arc
		(start 311.685432 -12.824968)
		(mid 311.4294 -11.979148)
		(end 310.58358 -12.23518)
		(stroke
			(width 0.2)
			(type default)
		)
		(layer "In6.Cu")
	)
	(gr_line
		(start 311.68721 -20.426172)
		(end 311.685178 -20.425156)
		(stroke
			(width 0.2)
			(type default)
		)
		(layer "In6.Cu")
	)
	(gr_line
		(start 311.687464 -24.226266)
		(end 311.685432 -24.224996)
		(stroke
			(width 0.2)
			(type default)
		)
		(layer "In6.Cu")
	)
	(gr_line
		(start 311.687464 -20.426426)
		(end 311.68721 -20.426172)
		(stroke
			(width 0.2)
			(type default)
		)
		(layer "In6.Cu")
	)
	(gr_line
		(start 311.687464 -16.626586)
		(end 311.685178 -16.625316)
		(stroke
			(width 0.2)
			(type default)
		)
		(layer "In6.Cu")
	)
	(gr_line
		(start 311.687464 -12.826238)
		(end 311.685432 -12.824968)
		(stroke
			(width 0.2)
			(type default)
		)
		(layer "In6.Cu")
	)
	(gr_line
		(start 311.69356 -222.805244)
		(end 312.506106 -222.805244)
		(stroke
			(width 0.2)
			(type default)
		)
		(layer "In6.Cu")
	)
	(gr_arc
		(start 311.69356 -221.784164)
		(mid 311.18302 -222.294704)
		(end 311.69356 -222.805244)
		(stroke
			(width 0.2)
			(type default)
		)
		(layer "In6.Cu")
	)
	(gr_line
		(start 312.081418 -25.033732)
		(end 312.081672 -25.033986)
		(stroke
			(width 0.2)
			(type default)
		)
		(layer "In6.Cu")
	)
	(gr_line
		(start 312.081418 -21.233892)
		(end 312.08345 -21.235162)
		(stroke
			(width 0.2)
			(type default)
		)
		(layer "In6.Cu")
	)
	(gr_line
		(start 312.081418 -17.433544)
		(end 312.081672 -17.433798)
		(stroke
			(width 0.2)
			(type default)
		)
		(layer "In6.Cu")
	)
	(gr_line
		(start 312.081418 -13.633704)
		(end 312.081672 -13.633958)
		(stroke
			(width 0.2)
			(type default)
		)
		(layer "In6.Cu")
	)
	(gr_line
		(start 312.081672 -25.033986)
		(end 312.083704 -25.035002)
		(stroke
			(width 0.2)
			(type default)
		)
		(layer "In6.Cu")
	)
	(gr_line
		(start 312.081672 -17.433798)
		(end 312.083704 -17.434814)
		(stroke
			(width 0.2)
			(type default)
		)
		(layer "In6.Cu")
	)
	(gr_line
		(start 312.081672 -13.633958)
		(end 312.083704 -13.634974)
		(stroke
			(width 0.2)
			(type default)
		)
		(layer "In6.Cu")
	)
	(gr_arc
		(start 312.08345 -21.235162)
		(mid 312.339482 -22.080982)
		(end 313.185302 -21.82495)
		(stroke
			(width 0.2)
			(type default)
		)
		(layer "In6.Cu")
	)
	(gr_arc
		(start 312.083704 -25.035002)
		(mid 312.33938 -25.880903)
		(end 313.185302 -25.625044)
		(stroke
			(width 0.2)
			(type default)
		)
		(layer "In6.Cu")
	)
	(gr_arc
		(start 312.083704 -17.434814)
		(mid 312.339228 -18.280634)
		(end 313.185048 -18.02511)
		(stroke
			(width 0.2)
			(type default)
		)
		(layer "In6.Cu")
	)
	(gr_arc
		(start 312.083704 -13.634974)
		(mid 312.33938 -14.480875)
		(end 313.185302 -14.225016)
		(stroke
			(width 0.2)
			(type default)
		)
		(layer "In6.Cu")
	)
	(gr_arc
		(start 312.506106 -222.805244)
		(mid 313.0169 -222.294831)
		(end 312.50636 -221.784164)
		(stroke
			(width 0.2)
			(type default)
		)
		(layer "In6.Cu")
	)
	(gr_line
		(start 312.50636 -221.784164)
		(end 311.69356 -221.784164)
		(stroke
			(width 0.2)
			(type default)
		)
		(layer "In6.Cu")
	)
	(gr_line
		(start 312.676286 -36.696142)
		(end 313.489086 -36.696142)
		(stroke
			(width 0.2)
			(type default)
		)
		(layer "In6.Cu")
	)
	(gr_arc
		(start 312.67654 -35.675062)
		(mid 312.165746 -36.185475)
		(end 312.676286 -36.696142)
		(stroke
			(width 0.2)
			(type default)
		)
		(layer "In6.Cu")
	)
	(gr_line
		(start 312.83148 -23.633938)
		(end 312.081418 -25.033732)
		(stroke
			(width 0.2)
			(type default)
		)
		(layer "In6.Cu")
	)
	(gr_line
		(start 312.83148 -19.833844)
		(end 312.081418 -21.233892)
		(stroke
			(width 0.2)
			(type default)
		)
		(layer "In6.Cu")
	)
	(gr_line
		(start 312.83148 -16.03375)
		(end 312.081418 -17.433544)
		(stroke
			(width 0.2)
			(type default)
		)
		(layer "In6.Cu")
	)
	(gr_line
		(start 312.83148 -12.23391)
		(end 312.081418 -13.633704)
		(stroke
			(width 0.2)
			(type default)
		)
		(layer "In6.Cu")
	)
	(gr_line
		(start 312.833512 -23.635208)
		(end 312.83148 -23.633938)
		(stroke
			(width 0.2)
			(type default)
		)
		(layer "In6.Cu")
	)
	(gr_line
		(start 312.833512 -19.835114)
		(end 312.83148 -19.833844)
		(stroke
			(width 0.2)
			(type default)
		)
		(layer "In6.Cu")
	)
	(gr_line
		(start 312.833512 -12.23518)
		(end 312.83148 -12.23391)
		(stroke
			(width 0.2)
			(type default)
		)
		(layer "In6.Cu")
	)
	(gr_line
		(start 312.833766 -16.03502)
		(end 312.83148 -16.03375)
		(stroke
			(width 0.2)
			(type default)
		)
		(layer "In6.Cu")
	)
	(gr_line
		(start 313.185048 -18.02511)
		(end 313.187334 -18.02638)
		(stroke
			(width 0.2)
			(type default)
		)
		(layer "In6.Cu")
	)
	(gr_line
		(start 313.185302 -25.625044)
		(end 313.187334 -25.626314)
		(stroke
			(width 0.2)
			(type default)
		)
		(layer "In6.Cu")
	)
	(gr_line
		(start 313.185302 -21.82495)
		(end 313.187334 -21.82622)
		(stroke
			(width 0.2)
			(type default)
		)
		(layer "In6.Cu")
	)
	(gr_line
		(start 313.185302 -14.225016)
		(end 313.187334 -14.226286)
		(stroke
			(width 0.2)
			(type default)
		)
		(layer "In6.Cu")
	)
	(gr_line
		(start 313.187334 -25.626314)
		(end 313.937396 -24.226266)
		(stroke
			(width 0.2)
			(type default)
		)
		(layer "In6.Cu")
	)
	(gr_line
		(start 313.187334 -21.82622)
		(end 313.937396 -20.426426)
		(stroke
			(width 0.2)
			(type default)
		)
		(layer "In6.Cu")
	)
	(gr_line
		(start 313.187334 -18.02638)
		(end 313.937396 -16.626586)
		(stroke
			(width 0.2)
			(type default)
		)
		(layer "In6.Cu")
	)
	(gr_line
		(start 313.187334 -14.226286)
		(end 313.937396 -12.826238)
		(stroke
			(width 0.2)
			(type default)
		)
		(layer "In6.Cu")
	)
	(gr_line
		(start 313.29376 -211.406994)
		(end 314.10656 -211.406994)
		(stroke
			(width 0.2)
			(type default)
		)
		(layer "In6.Cu")
	)
	(gr_arc
		(start 313.294014 -210.385914)
		(mid 312.78322 -210.896327)
		(end 313.29376 -211.406994)
		(stroke
			(width 0.2)
			(type default)
		)
		(layer "In6.Cu")
	)
	(gr_arc
		(start 313.489086 -36.696142)
		(mid 313.999626 -36.185602)
		(end 313.489086 -35.675062)
		(stroke
			(width 0.2)
			(type default)
		)
		(layer "In6.Cu")
	)
	(gr_line
		(start 313.489086 -35.675062)
		(end 312.67654 -35.675062)
		(stroke
			(width 0.2)
			(type default)
		)
		(layer "In6.Cu")
	)
	(gr_arc
		(start 313.93511 -20.425156)
		(mid 313.679434 -19.579255)
		(end 312.833512 -19.835114)
		(stroke
			(width 0.2)
			(type default)
		)
		(layer "In6.Cu")
	)
	(gr_arc
		(start 313.93511 -16.625316)
		(mid 313.679586 -15.779496)
		(end 312.833766 -16.03502)
		(stroke
			(width 0.2)
			(type default)
		)
		(layer "In6.Cu")
	)
	(gr_arc
		(start 313.935364 -24.224996)
		(mid 313.679332 -23.379176)
		(end 312.833512 -23.635208)
		(stroke
			(width 0.2)
			(type default)
		)
		(layer "In6.Cu")
	)
	(gr_arc
		(start 313.935364 -12.824968)
		(mid 313.679332 -11.979148)
		(end 312.833512 -12.23518)
		(stroke
			(width 0.2)
			(type default)
		)
		(layer "In6.Cu")
	)
	(gr_line
		(start 313.937142 -20.426172)
		(end 313.93511 -20.425156)
		(stroke
			(width 0.2)
			(type default)
		)
		(layer "In6.Cu")
	)
	(gr_line
		(start 313.937396 -24.226266)
		(end 313.935364 -24.224996)
		(stroke
			(width 0.2)
			(type default)
		)
		(layer "In6.Cu")
	)
	(gr_line
		(start 313.937396 -20.426426)
		(end 313.937142 -20.426172)
		(stroke
			(width 0.2)
			(type default)
		)
		(layer "In6.Cu")
	)
	(gr_line
		(start 313.937396 -16.626586)
		(end 313.93511 -16.625316)
		(stroke
			(width 0.2)
			(type default)
		)
		(layer "In6.Cu")
	)
	(gr_line
		(start 313.937396 -12.826238)
		(end 313.935364 -12.824968)
		(stroke
			(width 0.2)
			(type default)
		)
		(layer "In6.Cu")
	)
	(gr_arc
		(start 314.10656 -211.406994)
		(mid 314.6171 -210.896454)
		(end 314.10656 -210.385914)
		(stroke
			(width 0.2)
			(type default)
		)
		(layer "In6.Cu")
	)
	(gr_line
		(start 314.10656 -210.385914)
		(end 313.294014 -210.385914)
		(stroke
			(width 0.2)
			(type default)
		)
		(layer "In6.Cu")
	)
	(gr_line
		(start 314.8838 -35.524694)
		(end 315.696346 -35.524694)
		(stroke
			(width 0.2)
			(type default)
		)
		(layer "In6.Cu")
	)
	(gr_arc
		(start 314.8838 -34.503614)
		(mid 314.37326 -35.014154)
		(end 314.8838 -35.524694)
		(stroke
			(width 0.2)
			(type default)
		)
		(layer "In6.Cu")
	)
	(gr_line
		(start 314.893706 -222.805244)
		(end 315.706252 -222.805244)
		(stroke
			(width 0.2)
			(type default)
		)
		(layer "In6.Cu")
	)
	(gr_arc
		(start 314.893706 -221.784164)
		(mid 314.383166 -222.294704)
		(end 314.893706 -222.805244)
		(stroke
			(width 0.2)
			(type default)
		)
		(layer "In6.Cu")
	)
	(gr_arc
		(start 315.696346 -35.524694)
		(mid 316.20714 -35.014281)
		(end 315.6966 -34.503614)
		(stroke
			(width 0.2)
			(type default)
		)
		(layer "In6.Cu")
	)
	(gr_line
		(start 315.6966 -34.503614)
		(end 314.8838 -34.503614)
		(stroke
			(width 0.2)
			(type default)
		)
		(layer "In6.Cu")
	)
	(gr_arc
		(start 315.706252 -222.805244)
		(mid 316.217046 -222.294831)
		(end 315.706506 -221.784164)
		(stroke
			(width 0.2)
			(type default)
		)
		(layer "In6.Cu")
	)
	(gr_line
		(start 315.706506 -221.784164)
		(end 314.893706 -221.784164)
		(stroke
			(width 0.2)
			(type default)
		)
		(layer "In6.Cu")
	)
	(gr_line
		(start 316.493906 -211.406994)
		(end 317.306706 -211.406994)
		(stroke
			(width 0.2)
			(type default)
		)
		(layer "In6.Cu")
	)
	(gr_arc
		(start 316.49416 -210.385914)
		(mid 315.983366 -210.896327)
		(end 316.493906 -211.406994)
		(stroke
			(width 0.2)
			(type default)
		)
		(layer "In6.Cu")
	)
	(gr_arc
		(start 317.306706 -211.406994)
		(mid 317.817246 -210.896454)
		(end 317.306706 -210.385914)
		(stroke
			(width 0.2)
			(type default)
		)
		(layer "In6.Cu")
	)
	(gr_line
		(start 317.306706 -210.385914)
		(end 316.49416 -210.385914)
		(stroke
			(width 0.2)
			(type default)
		)
		(layer "In6.Cu")
	)
	(gr_line
		(start 318.093598 -222.805244)
		(end 318.906144 -222.805244)
		(stroke
			(width 0.2)
			(type default)
		)
		(layer "In6.Cu")
	)
	(gr_arc
		(start 318.093598 -221.784164)
		(mid 317.583058 -222.294704)
		(end 318.093598 -222.805244)
		(stroke
			(width 0.2)
			(type default)
		)
		(layer "In6.Cu")
	)
	(gr_arc
		(start 318.583564 -25.035256)
		(mid 318.839596 -25.881076)
		(end 319.685416 -25.625044)
		(stroke
			(width 0.2)
			(type default)
		)
		(layer "In6.Cu")
	)
	(gr_arc
		(start 318.587628 -13.627608)
		(mid 318.835762 -14.479061)
		(end 319.685416 -14.225016)
		(stroke
			(width 0.2)
			(type default)
		)
		(layer "In6.Cu")
	)
	(gr_arc
		(start 318.906144 -222.805244)
		(mid 319.416938 -222.294831)
		(end 318.906398 -221.784164)
		(stroke
			(width 0.2)
			(type default)
		)
		(layer "In6.Cu")
	)
	(gr_line
		(start 318.906398 -221.784164)
		(end 318.093598 -221.784164)
		(stroke
			(width 0.2)
			(type default)
		)
		(layer "In6.Cu")
	)
	(gr_line
		(start 319.333372 -23.635208)
		(end 318.583564 -25.035256)
		(stroke
			(width 0.2)
			(type default)
		)
		(layer "In6.Cu")
	)
	(gr_line
		(start 319.333372 -12.23518)
		(end 318.587628 -13.627608)
		(stroke
			(width 0.2)
			(type default)
		)
		(layer "In6.Cu")
	)
	(gr_line
		(start 319.685416 -25.625044)
		(end 320.43116 -24.232616)
		(stroke
			(width 0.2)
			(type default)
		)
		(layer "In6.Cu")
	)
	(gr_line
		(start 319.685416 -14.225016)
		(end 320.435224 -12.824968)
		(stroke
			(width 0.2)
			(type default)
		)
		(layer "In6.Cu")
	)
	(gr_line
		(start 319.693798 -211.406994)
		(end 320.506598 -211.406994)
		(stroke
			(width 0.2)
			(type default)
		)
		(layer "In6.Cu")
	)
	(gr_arc
		(start 319.694052 -210.385914)
		(mid 319.183258 -210.896327)
		(end 319.693798 -211.406994)
		(stroke
			(width 0.2)
			(type default)
		)
		(layer "In6.Cu")
	)
	(gr_line
		(start 319.720976 -37.53612)
		(end 320.533522 -37.53612)
		(stroke
			(width 0.2)
			(type default)
		)
		(layer "In6.Cu")
	)
	(gr_line
		(start 319.720976 -37.53612)
		(end 320.533776 -37.53612)
		(stroke
			(width 0.2)
			(type default)
		)
		(layer "In6.Cu")
	)
	(gr_arc
		(start 319.720976 -36.51504)
		(mid 319.210436 -37.02558)
		(end 319.720976 -37.53612)
		(stroke
			(width 0.2)
			(type default)
		)
		(layer "In6.Cu")
	)
	(gr_arc
		(start 319.72123 -36.51504)
		(mid 319.210436 -37.025453)
		(end 319.720976 -37.53612)
		(stroke
			(width 0.2)
			(type default)
		)
		(layer "In6.Cu")
	)
	(gr_arc
		(start 320.43116 -24.232616)
		(mid 320.183026 -23.381163)
		(end 319.333372 -23.635208)
		(stroke
			(width 0.2)
			(type default)
		)
		(layer "In6.Cu")
	)
	(gr_arc
		(start 320.435224 -12.824968)
		(mid 320.179192 -11.979148)
		(end 319.333372 -12.23518)
		(stroke
			(width 0.2)
			(type default)
		)
		(layer "In6.Cu")
	)
	(gr_arc
		(start 320.506598 -211.406994)
		(mid 321.017138 -210.896454)
		(end 320.506598 -210.385914)
		(stroke
			(width 0.2)
			(type default)
		)
		(layer "In6.Cu")
	)
	(gr_line
		(start 320.506598 -210.385914)
		(end 319.694052 -210.385914)
		(stroke
			(width 0.2)
			(type default)
		)
		(layer "In6.Cu")
	)
	(gr_arc
		(start 320.533522 -37.53612)
		(mid 321.044316 -37.025707)
		(end 320.533776 -36.51504)
		(stroke
			(width 0.2)
			(type default)
		)
		(layer "In6.Cu")
	)
	(gr_arc
		(start 320.533776 -37.53612)
		(mid 321.044316 -37.02558)
		(end 320.533776 -36.51504)
		(stroke
			(width 0.2)
			(type default)
		)
		(layer "In6.Cu")
	)
	(gr_line
		(start 320.533776 -36.51504)
		(end 319.720976 -36.51504)
		(stroke
			(width 0.2)
			(type default)
		)
		(layer "In6.Cu")
	)
	(gr_line
		(start 320.533776 -36.51504)
		(end 319.72123 -36.51504)
		(stroke
			(width 0.2)
			(type default)
		)
		(layer "In6.Cu")
	)
	(gr_line
		(start 320.831464 -25.033732)
		(end 320.831718 -25.033986)
		(stroke
			(width 0.2)
			(type default)
		)
		(layer "In6.Cu")
	)
	(gr_line
		(start 320.831464 -21.233892)
		(end 320.833496 -21.235162)
		(stroke
			(width 0.2)
			(type default)
		)
		(layer "In6.Cu")
	)
	(gr_line
		(start 320.831464 -17.433544)
		(end 320.831718 -17.433798)
		(stroke
			(width 0.2)
			(type default)
		)
		(layer "In6.Cu")
	)
	(gr_line
		(start 320.831464 -13.633704)
		(end 320.831718 -13.633958)
		(stroke
			(width 0.2)
			(type default)
		)
		(layer "In6.Cu")
	)
	(gr_line
		(start 320.831718 -25.033986)
		(end 320.83375 -25.035002)
		(stroke
			(width 0.2)
			(type default)
		)
		(layer "In6.Cu")
	)
	(gr_line
		(start 320.831718 -17.433798)
		(end 320.83375 -17.434814)
		(stroke
			(width 0.2)
			(type default)
		)
		(layer "In6.Cu")
	)
	(gr_line
		(start 320.831718 -13.633958)
		(end 320.83375 -13.634974)
		(stroke
			(width 0.2)
			(type default)
		)
		(layer "In6.Cu")
	)
	(gr_arc
		(start 320.833496 -21.235162)
		(mid 321.089528 -22.080982)
		(end 321.935348 -21.82495)
		(stroke
			(width 0.2)
			(type default)
		)
		(layer "In6.Cu")
	)
	(gr_arc
		(start 320.83375 -25.035002)
		(mid 321.089426 -25.880903)
		(end 321.935348 -25.625044)
		(stroke
			(width 0.2)
			(type default)
		)
		(layer "In6.Cu")
	)
	(gr_arc
		(start 320.83375 -17.434814)
		(mid 321.089274 -18.280634)
		(end 321.935094 -18.02511)
		(stroke
			(width 0.2)
			(type default)
		)
		(layer "In6.Cu")
	)
	(gr_arc
		(start 320.83375 -13.634974)
		(mid 321.089426 -14.480875)
		(end 321.935348 -14.225016)
		(stroke
			(width 0.2)
			(type default)
		)
		(layer "In6.Cu")
	)
	(gr_line
		(start 321.293744 -222.805244)
		(end 322.10629 -222.805244)
		(stroke
			(width 0.2)
			(type default)
		)
		(layer "In6.Cu")
	)
	(gr_arc
		(start 321.293744 -221.784164)
		(mid 320.783204 -222.294704)
		(end 321.293744 -222.805244)
		(stroke
			(width 0.2)
			(type default)
		)
		(layer "In6.Cu")
	)
	(gr_line
		(start 321.581526 -23.633938)
		(end 320.831464 -25.033732)
		(stroke
			(width 0.2)
			(type default)
		)
		(layer "In6.Cu")
	)
	(gr_line
		(start 321.581526 -19.833844)
		(end 320.831464 -21.233892)
		(stroke
			(width 0.2)
			(type default)
		)
		(layer "In6.Cu")
	)
	(gr_line
		(start 321.581526 -16.03375)
		(end 320.831464 -17.433544)
		(stroke
			(width 0.2)
			(type default)
		)
		(layer "In6.Cu")
	)
	(gr_line
		(start 321.581526 -12.23391)
		(end 320.831464 -13.633704)
		(stroke
			(width 0.2)
			(type default)
		)
		(layer "In6.Cu")
	)
	(gr_line
		(start 321.583558 -23.635208)
		(end 321.581526 -23.633938)
		(stroke
			(width 0.2)
			(type default)
		)
		(layer "In6.Cu")
	)
	(gr_line
		(start 321.583558 -19.835114)
		(end 321.581526 -19.833844)
		(stroke
			(width 0.2)
			(type default)
		)
		(layer "In6.Cu")
	)
	(gr_line
		(start 321.583558 -12.23518)
		(end 321.581526 -12.23391)
		(stroke
			(width 0.2)
			(type default)
		)
		(layer "In6.Cu")
	)
	(gr_line
		(start 321.583812 -16.03502)
		(end 321.581526 -16.03375)
		(stroke
			(width 0.2)
			(type default)
		)
		(layer "In6.Cu")
	)
	(gr_line
		(start 321.935094 -18.02511)
		(end 321.93738 -18.02638)
		(stroke
			(width 0.2)
			(type default)
		)
		(layer "In6.Cu")
	)
	(gr_line
		(start 321.935348 -25.625044)
		(end 321.93738 -25.626314)
		(stroke
			(width 0.2)
			(type default)
		)
		(layer "In6.Cu")
	)
	(gr_line
		(start 321.935348 -21.82495)
		(end 321.93738 -21.82622)
		(stroke
			(width 0.2)
			(type default)
		)
		(layer "In6.Cu")
	)
	(gr_line
		(start 321.935348 -14.225016)
		(end 321.93738 -14.226286)
		(stroke
			(width 0.2)
			(type default)
		)
		(layer "In6.Cu")
	)
	(gr_line
		(start 321.93738 -25.626314)
		(end 322.687442 -24.226266)
		(stroke
			(width 0.2)
			(type default)
		)
		(layer "In6.Cu")
	)
	(gr_line
		(start 321.93738 -21.82622)
		(end 322.687442 -20.426426)
		(stroke
			(width 0.2)
			(type default)
		)
		(layer "In6.Cu")
	)
	(gr_line
		(start 321.93738 -18.02638)
		(end 322.687442 -16.626586)
		(stroke
			(width 0.2)
			(type default)
		)
		(layer "In6.Cu")
	)
	(gr_line
		(start 321.93738 -14.226286)
		(end 322.687442 -12.826238)
		(stroke
			(width 0.2)
			(type default)
		)
		(layer "In6.Cu")
	)
	(gr_arc
		(start 322.10629 -222.805244)
		(mid 322.617084 -222.294831)
		(end 322.106544 -221.784164)
		(stroke
			(width 0.2)
			(type default)
		)
		(layer "In6.Cu")
	)
	(gr_line
		(start 322.106544 -221.784164)
		(end 321.293744 -221.784164)
		(stroke
			(width 0.2)
			(type default)
		)
		(layer "In6.Cu")
	)
	(gr_arc
		(start 322.685156 -20.425156)
		(mid 322.42948 -19.579255)
		(end 321.583558 -19.835114)
		(stroke
			(width 0.2)
			(type default)
		)
		(layer "In6.Cu")
	)
	(gr_arc
		(start 322.685156 -16.625316)
		(mid 322.429632 -15.779496)
		(end 321.583812 -16.03502)
		(stroke
			(width 0.2)
			(type default)
		)
		(layer "In6.Cu")
	)
	(gr_arc
		(start 322.68541 -24.224996)
		(mid 322.429378 -23.379176)
		(end 321.583558 -23.635208)
		(stroke
			(width 0.2)
			(type default)
		)
		(layer "In6.Cu")
	)
	(gr_arc
		(start 322.68541 -12.824968)
		(mid 322.429378 -11.979148)
		(end 321.583558 -12.23518)
		(stroke
			(width 0.2)
			(type default)
		)
		(layer "In6.Cu")
	)
	(gr_line
		(start 322.687188 -20.426172)
		(end 322.685156 -20.425156)
		(stroke
			(width 0.2)
			(type default)
		)
		(layer "In6.Cu")
	)
	(gr_line
		(start 322.687442 -24.226266)
		(end 322.68541 -24.224996)
		(stroke
			(width 0.2)
			(type default)
		)
		(layer "In6.Cu")
	)
	(gr_line
		(start 322.687442 -20.426426)
		(end 322.687188 -20.426172)
		(stroke
			(width 0.2)
			(type default)
		)
		(layer "In6.Cu")
	)
	(gr_line
		(start 322.687442 -16.626586)
		(end 322.685156 -16.625316)
		(stroke
			(width 0.2)
			(type default)
		)
		(layer "In6.Cu")
	)
	(gr_line
		(start 322.687442 -12.826238)
		(end 322.68541 -12.824968)
		(stroke
			(width 0.2)
			(type default)
		)
		(layer "In6.Cu")
	)
	(gr_line
		(start 322.89369 -211.406994)
		(end 323.70649 -211.406994)
		(stroke
			(width 0.2)
			(type default)
		)
		(layer "In6.Cu")
	)
	(gr_arc
		(start 322.893944 -210.385914)
		(mid 322.38315 -210.896327)
		(end 322.89369 -211.406994)
		(stroke
			(width 0.2)
			(type default)
		)
		(layer "In6.Cu")
	)
	(gr_line
		(start 323.081396 -25.033732)
		(end 323.08165 -25.033986)
		(stroke
			(width 0.2)
			(type default)
		)
		(layer "In6.Cu")
	)
	(gr_line
		(start 323.081396 -21.233892)
		(end 323.083428 -21.235162)
		(stroke
			(width 0.2)
			(type default)
		)
		(layer "In6.Cu")
	)
	(gr_line
		(start 323.081396 -17.433544)
		(end 323.08165 -17.433798)
		(stroke
			(width 0.2)
			(type default)
		)
		(layer "In6.Cu")
	)
	(gr_line
		(start 323.081396 -13.633704)
		(end 323.08165 -13.633958)
		(stroke
			(width 0.2)
			(type default)
		)
		(layer "In6.Cu")
	)
	(gr_line
		(start 323.08165 -25.033986)
		(end 323.083682 -25.035002)
		(stroke
			(width 0.2)
			(type default)
		)
		(layer "In6.Cu")
	)
	(gr_line
		(start 323.08165 -17.433798)
		(end 323.083682 -17.434814)
		(stroke
			(width 0.2)
			(type default)
		)
		(layer "In6.Cu")
	)
	(gr_line
		(start 323.08165 -13.633958)
		(end 323.083682 -13.634974)
		(stroke
			(width 0.2)
			(type default)
		)
		(layer "In6.Cu")
	)
	(gr_arc
		(start 323.083428 -21.235162)
		(mid 323.33946 -22.080982)
		(end 324.18528 -21.82495)
		(stroke
			(width 0.2)
			(type default)
		)
		(layer "In6.Cu")
	)
	(gr_arc
		(start 323.083682 -25.035002)
		(mid 323.339358 -25.880903)
		(end 324.18528 -25.625044)
		(stroke
			(width 0.2)
			(type default)
		)
		(layer "In6.Cu")
	)
	(gr_arc
		(start 323.083682 -17.434814)
		(mid 323.339206 -18.280634)
		(end 324.185026 -18.02511)
		(stroke
			(width 0.2)
			(type default)
		)
		(layer "In6.Cu")
	)
	(gr_arc
		(start 323.083682 -13.634974)
		(mid 323.339358 -14.480875)
		(end 324.18528 -14.225016)
		(stroke
			(width 0.2)
			(type default)
		)
		(layer "In6.Cu")
	)
	(gr_line
		(start 323.61251 -35.479482)
		(end 324.425056 -35.479482)
		(stroke
			(width 0.2)
			(type default)
		)
		(layer "In6.Cu")
	)
	(gr_line
		(start 323.61251 -35.479482)
		(end 324.42531 -35.479482)
		(stroke
			(width 0.2)
			(type default)
		)
		(layer "In6.Cu")
	)
	(gr_arc
		(start 323.61251 -34.458402)
		(mid 323.10197 -34.968942)
		(end 323.61251 -35.479482)
		(stroke
			(width 0.2)
			(type default)
		)
		(layer "In6.Cu")
	)
	(gr_arc
		(start 323.612764 -34.458402)
		(mid 323.10197 -34.968815)
		(end 323.61251 -35.479482)
		(stroke
			(width 0.2)
			(type default)
		)
		(layer "In6.Cu")
	)
	(gr_arc
		(start 323.70649 -211.406994)
		(mid 324.21703 -210.896454)
		(end 323.70649 -210.385914)
		(stroke
			(width 0.2)
			(type default)
		)
		(layer "In6.Cu")
	)
	(gr_line
		(start 323.70649 -210.385914)
		(end 322.893944 -210.385914)
		(stroke
			(width 0.2)
			(type default)
		)
		(layer "In6.Cu")
	)
	(gr_line
		(start 323.831458 -23.633938)
		(end 323.081396 -25.033732)
		(stroke
			(width 0.2)
			(type default)
		)
		(layer "In6.Cu")
	)
	(gr_line
		(start 323.831458 -19.833844)
		(end 323.081396 -21.233892)
		(stroke
			(width 0.2)
			(type default)
		)
		(layer "In6.Cu")
	)
	(gr_line
		(start 323.831458 -16.03375)
		(end 323.081396 -17.433544)
		(stroke
			(width 0.2)
			(type default)
		)
		(layer "In6.Cu")
	)
	(gr_line
		(start 323.831458 -12.23391)
		(end 323.081396 -13.633704)
		(stroke
			(width 0.2)
			(type default)
		)
		(layer "In6.Cu")
	)
	(gr_line
		(start 323.83349 -23.635208)
		(end 323.831458 -23.633938)
		(stroke
			(width 0.2)
			(type default)
		)
		(layer "In6.Cu")
	)
	(gr_line
		(start 323.83349 -19.835114)
		(end 323.831458 -19.833844)
		(stroke
			(width 0.2)
			(type default)
		)
		(layer "In6.Cu")
	)
	(gr_line
		(start 323.83349 -12.23518)
		(end 323.831458 -12.23391)
		(stroke
			(width 0.2)
			(type default)
		)
		(layer "In6.Cu")
	)
	(gr_line
		(start 323.833744 -16.03502)
		(end 323.831458 -16.03375)
		(stroke
			(width 0.2)
			(type default)
		)
		(layer "In6.Cu")
	)
	(gr_line
		(start 324.185026 -18.02511)
		(end 324.187312 -18.02638)
		(stroke
			(width 0.2)
			(type default)
		)
		(layer "In6.Cu")
	)
	(gr_line
		(start 324.18528 -25.625044)
		(end 324.187312 -25.626314)
		(stroke
			(width 0.2)
			(type default)
		)
		(layer "In6.Cu")
	)
	(gr_line
		(start 324.18528 -21.82495)
		(end 324.187312 -21.82622)
		(stroke
			(width 0.2)
			(type default)
		)
		(layer "In6.Cu")
	)
	(gr_line
		(start 324.18528 -14.225016)
		(end 324.187312 -14.226286)
		(stroke
			(width 0.2)
			(type default)
		)
		(layer "In6.Cu")
	)
	(gr_line
		(start 324.187312 -25.626314)
		(end 324.937374 -24.226266)
		(stroke
			(width 0.2)
			(type default)
		)
		(layer "In6.Cu")
	)
	(gr_line
		(start 324.187312 -21.82622)
		(end 324.937374 -20.426426)
		(stroke
			(width 0.2)
			(type default)
		)
		(layer "In6.Cu")
	)
	(gr_line
		(start 324.187312 -18.02638)
		(end 324.937374 -16.626586)
		(stroke
			(width 0.2)
			(type default)
		)
		(layer "In6.Cu")
	)
	(gr_line
		(start 324.187312 -14.226286)
		(end 324.937374 -12.826238)
		(stroke
			(width 0.2)
			(type default)
		)
		(layer "In6.Cu")
	)
	(gr_arc
		(start 324.425056 -35.479482)
		(mid 324.93585 -34.969069)
		(end 324.42531 -34.458402)
		(stroke
			(width 0.2)
			(type default)
		)
		(layer "In6.Cu")
	)
	(gr_arc
		(start 324.42531 -35.479482)
		(mid 324.93585 -34.968942)
		(end 324.42531 -34.458402)
		(stroke
			(width 0.2)
			(type default)
		)
		(layer "In6.Cu")
	)
	(gr_line
		(start 324.42531 -34.458402)
		(end 323.61251 -34.458402)
		(stroke
			(width 0.2)
			(type default)
		)
		(layer "In6.Cu")
	)
	(gr_line
		(start 324.42531 -34.458402)
		(end 323.612764 -34.458402)
		(stroke
			(width 0.2)
			(type default)
		)
		(layer "In6.Cu")
	)
	(gr_line
		(start 324.493636 -222.805244)
		(end 325.306182 -222.805244)
		(stroke
			(width 0.2)
			(type default)
		)
		(layer "In6.Cu")
	)
	(gr_arc
		(start 324.493636 -221.784164)
		(mid 323.983096 -222.294704)
		(end 324.493636 -222.805244)
		(stroke
			(width 0.2)
			(type default)
		)
		(layer "In6.Cu")
	)
	(gr_arc
		(start 324.935088 -20.425156)
		(mid 324.679412 -19.579255)
		(end 323.83349 -19.835114)
		(stroke
			(width 0.2)
			(type default)
		)
		(layer "In6.Cu")
	)
	(gr_arc
		(start 324.935088 -16.625316)
		(mid 324.679564 -15.779496)
		(end 323.833744 -16.03502)
		(stroke
			(width 0.2)
			(type default)
		)
		(layer "In6.Cu")
	)
	(gr_arc
		(start 324.935342 -24.224996)
		(mid 324.67931 -23.379176)
		(end 323.83349 -23.635208)
		(stroke
			(width 0.2)
			(type default)
		)
		(layer "In6.Cu")
	)
	(gr_arc
		(start 324.935342 -12.824968)
		(mid 324.67931 -11.979148)
		(end 323.83349 -12.23518)
		(stroke
			(width 0.2)
			(type default)
		)
		(layer "In6.Cu")
	)
	(gr_line
		(start 324.93712 -20.426172)
		(end 324.935088 -20.425156)
		(stroke
			(width 0.2)
			(type default)
		)
		(layer "In6.Cu")
	)
	(gr_line
		(start 324.937374 -24.226266)
		(end 324.935342 -24.224996)
		(stroke
			(width 0.2)
			(type default)
		)
		(layer "In6.Cu")
	)
	(gr_line
		(start 324.937374 -20.426426)
		(end 324.93712 -20.426172)
		(stroke
			(width 0.2)
			(type default)
		)
		(layer "In6.Cu")
	)
	(gr_line
		(start 324.937374 -16.626586)
		(end 324.935088 -16.625316)
		(stroke
			(width 0.2)
			(type default)
		)
		(layer "In6.Cu")
	)
	(gr_line
		(start 324.937374 -12.826238)
		(end 324.935342 -12.824968)
		(stroke
			(width 0.2)
			(type default)
		)
		(layer "In6.Cu")
	)
	(gr_arc
		(start 325.306182 -222.805244)
		(mid 325.816976 -222.294831)
		(end 325.306436 -221.784164)
		(stroke
			(width 0.2)
			(type default)
		)
		(layer "In6.Cu")
	)
	(gr_line
		(start 325.306436 -221.784164)
		(end 324.493636 -221.784164)
		(stroke
			(width 0.2)
			(type default)
		)
		(layer "In6.Cu")
	)
	(gr_line
		(start 325.969122 -36.472114)
		(end 326.781668 -36.472114)
		(stroke
			(width 0.2)
			(type default)
		)
		(layer "In6.Cu")
	)
	(gr_arc
		(start 325.969122 -35.451034)
		(mid 325.458582 -35.961574)
		(end 325.969122 -36.472114)
		(stroke
			(width 0.2)
			(type default)
		)
		(layer "In6.Cu")
	)
	(gr_line
		(start 326.093582 -211.406994)
		(end 326.906382 -211.406994)
		(stroke
			(width 0.2)
			(type default)
		)
		(layer "In6.Cu")
	)
	(gr_arc
		(start 326.093836 -210.385914)
		(mid 325.583042 -210.896327)
		(end 326.093582 -211.406994)
		(stroke
			(width 0.2)
			(type default)
		)
		(layer "In6.Cu")
	)
	(gr_arc
		(start 326.781668 -36.472114)
		(mid 327.292462 -35.961701)
		(end 326.781922 -35.451034)
		(stroke
			(width 0.2)
			(type default)
		)
		(layer "In6.Cu")
	)
	(gr_line
		(start 326.781922 -35.451034)
		(end 325.969122 -35.451034)
		(stroke
			(width 0.2)
			(type default)
		)
		(layer "In6.Cu")
	)
	(gr_arc
		(start 326.906382 -211.406994)
		(mid 327.416922 -210.896454)
		(end 326.906382 -210.385914)
		(stroke
			(width 0.2)
			(type default)
		)
		(layer "In6.Cu")
	)
	(gr_line
		(start 326.906382 -210.385914)
		(end 326.093836 -210.385914)
		(stroke
			(width 0.2)
			(type default)
		)
		(layer "In6.Cu")
	)
	(gr_line
		(start 327.693782 -222.805244)
		(end 328.506328 -222.805244)
		(stroke
			(width 0.2)
			(type default)
		)
		(layer "In6.Cu")
	)
	(gr_arc
		(start 327.693782 -221.784164)
		(mid 327.183242 -222.294704)
		(end 327.693782 -222.805244)
		(stroke
			(width 0.2)
			(type default)
		)
		(layer "In6.Cu")
	)
	(gr_line
		(start 328.375518 -35.429952)
		(end 329.188064 -35.429952)
		(stroke
			(width 0.2)
			(type default)
		)
		(layer "In6.Cu")
	)
	(gr_arc
		(start 328.375518 -34.408872)
		(mid 327.864978 -34.919412)
		(end 328.375518 -35.429952)
		(stroke
			(width 0.2)
			(type default)
		)
		(layer "In6.Cu")
	)
	(gr_arc
		(start 328.506328 -222.805244)
		(mid 329.017122 -222.294831)
		(end 328.506582 -221.784164)
		(stroke
			(width 0.2)
			(type default)
		)
		(layer "In6.Cu")
	)
	(gr_line
		(start 328.506582 -221.784164)
		(end 327.693782 -221.784164)
		(stroke
			(width 0.2)
			(type default)
		)
		(layer "In6.Cu")
	)
	(gr_arc
		(start 329.188064 -35.429952)
		(mid 329.698858 -34.919539)
		(end 329.188318 -34.408872)
		(stroke
			(width 0.2)
			(type default)
		)
		(layer "In6.Cu")
	)
	(gr_line
		(start 329.188318 -34.408872)
		(end 328.375518 -34.408872)
		(stroke
			(width 0.2)
			(type default)
		)
		(layer "In6.Cu")
	)
	(gr_line
		(start 330.893674 -222.805244)
		(end 331.70622 -222.805244)
		(stroke
			(width 0.2)
			(type default)
		)
		(layer "In6.Cu")
	)
	(gr_arc
		(start 330.893674 -221.784164)
		(mid 330.383134 -222.294704)
		(end 330.893674 -222.805244)
		(stroke
			(width 0.2)
			(type default)
		)
		(layer "In6.Cu")
	)
	(gr_arc
		(start 331.70622 -222.805244)
		(mid 332.217014 -222.294831)
		(end 331.706474 -221.784164)
		(stroke
			(width 0.2)
			(type default)
		)
		(layer "In6.Cu")
	)
	(gr_line
		(start 331.706474 -221.784164)
		(end 330.893674 -221.784164)
		(stroke
			(width 0.2)
			(type default)
		)
		(layer "In6.Cu")
	)
	(gr_arc
		(start 331.749908 0.999998)
		(mid 332.042801 0.292893)
		(end 332.749906 0)
		(stroke
			(width 1.524)
			(type default)
		)
		(layer "In6.Cu")
	)
	(gr_arc
		(start 331.749908 3.999992)
		(mid 331.457019 4.707106)
		(end 330.74991 4.99999)
		(stroke
			(width 1.524)
			(type default)
		)
		(layer "In6.Cu")
	)
	(gr_line
		(start 331.749908 3.999992)
		(end 331.749908 0.999998)
		(stroke
			(width 1.524)
			(type default)
		)
		(layer "In6.Cu")
	)
	(gr_line
		(start 332.493874 -211.406994)
		(end 333.306674 -211.406994)
		(stroke
			(width 0.2)
			(type default)
		)
		(layer "In6.Cu")
	)
	(gr_arc
		(start 332.494128 -210.385914)
		(mid 331.983334 -210.896327)
		(end 332.493874 -211.406994)
		(stroke
			(width 0.2)
			(type default)
		)
		(layer "In6.Cu")
	)
	(gr_line
		(start 332.749906 0)
		(end 354.600002 0)
		(stroke
			(width 1.524)
			(type default)
		)
		(layer "In6.Cu")
	)
	(gr_arc
		(start 333.306674 -211.406994)
		(mid 333.817214 -210.896454)
		(end 333.306674 -210.385914)
		(stroke
			(width 0.2)
			(type default)
		)
		(layer "In6.Cu")
	)
	(gr_line
		(start 333.306674 -210.385914)
		(end 332.494128 -210.385914)
		(stroke
			(width 0.2)
			(type default)
		)
		(layer "In6.Cu")
	)
	(gr_line
		(start 334.093566 -222.805244)
		(end 334.906112 -222.805244)
		(stroke
			(width 0.2)
			(type default)
		)
		(layer "In6.Cu")
	)
	(gr_arc
		(start 334.093566 -221.784164)
		(mid 333.583026 -222.294704)
		(end 334.093566 -222.805244)
		(stroke
			(width 0.2)
			(type default)
		)
		(layer "In6.Cu")
	)
	(gr_arc
		(start 334.906112 -222.805244)
		(mid 335.416906 -222.294831)
		(end 334.906366 -221.784164)
		(stroke
			(width 0.2)
			(type default)
		)
		(layer "In6.Cu")
	)
	(gr_line
		(start 334.906366 -221.784164)
		(end 334.093566 -221.784164)
		(stroke
			(width 0.2)
			(type default)
		)
		(layer "In6.Cu")
	)
	(gr_line
		(start 335.693766 -211.406994)
		(end 336.506566 -211.406994)
		(stroke
			(width 0.2)
			(type default)
		)
		(layer "In6.Cu")
	)
	(gr_arc
		(start 335.69402 -210.385914)
		(mid 335.183226 -210.896327)
		(end 335.693766 -211.406994)
		(stroke
			(width 0.2)
			(type default)
		)
		(layer "In6.Cu")
	)
	(gr_arc
		(start 336.506566 -211.406994)
		(mid 337.017106 -210.896454)
		(end 336.506566 -210.385914)
		(stroke
			(width 0.2)
			(type default)
		)
		(layer "In6.Cu")
	)
	(gr_line
		(start 336.506566 -210.385914)
		(end 335.69402 -210.385914)
		(stroke
			(width 0.2)
			(type default)
		)
		(layer "In6.Cu")
	)
	(gr_line
		(start 337.293712 -222.805244)
		(end 338.106258 -222.805244)
		(stroke
			(width 0.2)
			(type default)
		)
		(layer "In6.Cu")
	)
	(gr_arc
		(start 337.293712 -221.784164)
		(mid 336.783172 -222.294704)
		(end 337.293712 -222.805244)
		(stroke
			(width 0.2)
			(type default)
		)
		(layer "In6.Cu")
	)
	(gr_arc
		(start 338.106258 -222.805244)
		(mid 338.617052 -222.294831)
		(end 338.106512 -221.784164)
		(stroke
			(width 0.2)
			(type default)
		)
		(layer "In6.Cu")
	)
	(gr_line
		(start 338.106512 -221.784164)
		(end 337.293712 -221.784164)
		(stroke
			(width 0.2)
			(type default)
		)
		(layer "In6.Cu")
	)
	(gr_line
		(start 338.893658 -211.406994)
		(end 339.706204 -211.406994)
		(stroke
			(width 0.2)
			(type default)
		)
		(layer "In6.Cu")
	)
	(gr_arc
		(start 338.893658 -210.385914)
		(mid 338.383118 -210.896454)
		(end 338.893658 -211.406994)
		(stroke
			(width 0.2)
			(type default)
		)
		(layer "In6.Cu")
	)
	(gr_arc
		(start 339.706204 -211.406994)
		(mid 340.216998 -210.896581)
		(end 339.706458 -210.385914)
		(stroke
			(width 0.2)
			(type default)
		)
		(layer "In6.Cu")
	)
	(gr_line
		(start 339.706458 -210.385914)
		(end 338.893658 -210.385914)
		(stroke
			(width 0.2)
			(type default)
		)
		(layer "In6.Cu")
	)
	(gr_line
		(start 340.493604 -222.805244)
		(end 341.306404 -222.805244)
		(stroke
			(width 0.2)
			(type default)
		)
		(layer "In6.Cu")
	)
	(gr_arc
		(start 340.493858 -221.784164)
		(mid 339.983064 -222.294577)
		(end 340.493604 -222.805244)
		(stroke
			(width 0.2)
			(type default)
		)
		(layer "In6.Cu")
	)
	(gr_arc
		(start 341.306404 -222.805244)
		(mid 341.816944 -222.294704)
		(end 341.306404 -221.784164)
		(stroke
			(width 0.2)
			(type default)
		)
		(layer "In6.Cu")
	)
	(gr_line
		(start 341.306404 -221.784164)
		(end 340.493858 -221.784164)
		(stroke
			(width 0.2)
			(type default)
		)
		(layer "In6.Cu")
	)
	(gr_line
		(start 342.09355 -211.406994)
		(end 342.906096 -211.406994)
		(stroke
			(width 0.2)
			(type default)
		)
		(layer "In6.Cu")
	)
	(gr_arc
		(start 342.09355 -210.385914)
		(mid 341.58301 -210.896454)
		(end 342.09355 -211.406994)
		(stroke
			(width 0.2)
			(type default)
		)
		(layer "In6.Cu")
	)
	(gr_arc
		(start 342.906096 -211.406994)
		(mid 343.41689 -210.896581)
		(end 342.90635 -210.385914)
		(stroke
			(width 0.2)
			(type default)
		)
		(layer "In6.Cu")
	)
	(gr_line
		(start 342.90635 -210.385914)
		(end 342.09355 -210.385914)
		(stroke
			(width 0.2)
			(type default)
		)
		(layer "In6.Cu")
	)
	(gr_line
		(start 344.499946 -228.000052)
		(end 308.500018 -228.000052)
		(stroke
			(width 5.08)
			(type default)
		)
		(layer "In6.Cu")
	)
	(gr_line
		(start 344.499946 -222.400114)
		(end 344.499946 -228.000052)
		(stroke
			(width 1.524)
			(type default)
		)
		(layer "In6.Cu")
	)
	(gr_arc
		(start 345.000072 -221.899988)
		(mid 344.64643 -222.046472)
		(end 344.499946 -222.400114)
		(stroke
			(width 1.524)
			(type default)
		)
		(layer "In6.Cu")
	)
	(gr_line
		(start 345.799918 -221.899988)
		(end 345.000072 -221.899988)
		(stroke
			(width 1.524)
			(type default)
		)
		(layer "In6.Cu")
	)
	(gr_arc
		(start 345.799918 -221.899988)
		(mid 346.153446 -221.753586)
		(end 346.300044 -221.400116)
		(stroke
			(width 1.524)
			(type default)
		)
		(layer "In6.Cu")
	)
	(gr_line
		(start 346.300044 -214.799926)
		(end 346.300044 -221.400116)
		(stroke
			(width 1.524)
			(type default)
		)
		(layer "In6.Cu")
	)
	(gr_arc
		(start 347.600016 -213.499954)
		(mid 346.680797 -213.880707)
		(end 346.300044 -214.799926)
		(stroke
			(width 1.524)
			(type default)
		)
		(layer "In6.Cu")
	)
	(gr_arc
		(start 354.24999 -18.200116)
		(mid 354.396563 -18.553594)
		(end 354.750116 -18.699988)
		(stroke
			(width 1.524)
			(type default)
		)
		(layer "In6.Cu")
	)
	(gr_line
		(start 354.24999 -10.199878)
		(end 354.24999 -18.200116)
		(stroke
			(width 1.524)
			(type default)
		)
		(layer "In6.Cu")
	)
	(gr_line
		(start 354.600002 -213.499954)
		(end 347.600016 -213.499954)
		(stroke
			(width 1.524)
			(type default)
		)
		(layer "In6.Cu")
	)
	(gr_arc
		(start 354.600002 -213.499954)
		(mid 355.307091 -213.207058)
		(end 355.6 -212.499956)
		(stroke
			(width 1.524)
			(type default)
		)
		(layer "In6.Cu")
	)
	(gr_line
		(start 354.750116 -18.699988)
		(end 355.099874 -18.699988)
		(stroke
			(width 1.524)
			(type default)
		)
		(layer "In6.Cu")
	)
	(gr_arc
		(start 354.750116 -9.700006)
		(mid 354.396563 -9.8464)
		(end 354.24999 -10.199878)
		(stroke
			(width 1.524)
			(type default)
		)
		(layer "In6.Cu")
	)
	(gr_line
		(start 355.099874 -9.700006)
		(end 354.750116 -9.700006)
		(stroke
			(width 1.524)
			(type default)
		)
		(layer "In6.Cu")
	)
	(gr_arc
		(start 355.099874 -9.700006)
		(mid 355.453526 -9.55353)
		(end 355.6 -9.19988)
		(stroke
			(width 1.524)
			(type default)
		)
		(layer "In6.Cu")
	)
	(gr_arc
		(start 355.6 -19.200114)
		(mid 355.45352 -18.846472)
		(end 355.099874 -18.699988)
		(stroke
			(width 1.524)
			(type default)
		)
		(layer "In6.Cu")
	)
	(gr_line
		(start 355.6 -19.200114)
		(end 355.6 -212.499956)
		(stroke
			(width 1.524)
			(type default)
		)
		(layer "In6.Cu")
	)
	(gr_arc
		(start 355.6 -0.999998)
		(mid 355.307107 -0.292893)
		(end 354.600002 0)
		(stroke
			(width 1.524)
			(type default)
		)
		(layer "In6.Cu")
	)
	(gr_line
		(start 355.6 -0.999998)
		(end 355.6 -9.19988)
		(stroke
			(width 1.524)
			(type default)
		)
		(layer "In6.Cu")
	)
	(gr_arc
		(start 0 -212.499956)
		(mid 0.292893 -213.207061)
		(end 0.999998 -213.499954)
		(stroke
			(width 0.05)
			(type default)
		)
		(layer "Edge.Cuts")
	)
	(gr_line
		(start 0 -28.010104)
		(end 0 -212.499956)
		(stroke
			(width 0.05)
			(type default)
		)
		(layer "Edge.Cuts")
	)
	(gr_line
		(start 0.999998 -213.499954)
		(end 25.4 -213.499954)
		(stroke
			(width 0.05)
			(type default)
		)
		(layer "Edge.Cuts")
	)
	(gr_arc
		(start 1.999996 -26.010108)
		(mid 0.585785 -26.595893)
		(end 0 -28.010104)
		(stroke
			(width 0.05)
			(type default)
		)
		(layer "Edge.Cuts")
	)
	(gr_arc
		(start 8.10006 -203.499974)
		(mid 9.99998 -205.399894)
		(end 11.8999 -203.499974)
		(stroke
			(width 0.05)
			(type default)
		)
		(layer "Edge.Cuts")
	)
	(gr_arc
		(start 11.712194 -60.300108)
		(mid 13.812266 -62.40018)
		(end 15.912084 -60.300108)
		(stroke
			(width 0.05)
			(type default)
		)
		(layer "Edge.Cuts")
	)
	(gr_arc
		(start 11.8999 -203.499974)
		(mid 9.99998 -201.600054)
		(end 8.10006 -203.499974)
		(stroke
			(width 0.05)
			(type default)
		)
		(layer "Edge.Cuts")
	)
	(gr_arc
		(start 15.912084 -60.300108)
		(mid 13.812266 -58.20029)
		(end 11.712194 -60.300108)
		(stroke
			(width 0.05)
			(type default)
		)
		(layer "Edge.Cuts")
	)
	(gr_arc
		(start 26.699972 -221.400116)
		(mid 26.846545 -221.753594)
		(end 27.200098 -221.899988)
		(stroke
			(width 0.05)
			(type default)
		)
		(layer "Edge.Cuts")
	)
	(gr_arc
		(start 26.699972 -214.799926)
		(mid 26.319228 -213.88069)
		(end 25.4 -213.499954)
		(stroke
			(width 0.05)
			(type default)
		)
		(layer "Edge.Cuts")
	)
	(gr_line
		(start 26.699972 -214.799926)
		(end 26.699972 -221.400116)
		(stroke
			(width 0.05)
			(type default)
		)
		(layer "Edge.Cuts")
	)
	(gr_line
		(start 27.200098 -221.899988)
		(end 27.999944 -221.899988)
		(stroke
			(width 0.05)
			(type default)
		)
		(layer "Edge.Cuts")
	)
	(gr_line
		(start 28.50007 -226.70008)
		(end 29.500068 -227.999798)
		(stroke
			(width 0.05)
			(type default)
		)
		(layer "Edge.Cuts")
	)
	(gr_arc
		(start 28.50007 -222.400114)
		(mid 28.353594 -222.046447)
		(end 27.999944 -221.899988)
		(stroke
			(width 0.05)
			(type default)
		)
		(layer "Edge.Cuts")
	)
	(gr_line
		(start 28.50007 -222.400114)
		(end 28.50007 -226.70008)
		(stroke
			(width 0.05)
			(type default)
		)
		(layer "Edge.Cuts")
	)
	(gr_line
		(start 29.500068 -227.999798)
		(end 73.200006 -227.999798)
		(stroke
			(width 0.05)
			(type default)
		)
		(layer "Edge.Cuts")
	)
	(gr_line
		(start 49.950116 -26.010108)
		(end 1.999996 -26.010108)
		(stroke
			(width 0.05)
			(type default)
		)
		(layer "Edge.Cuts")
	)
	(gr_arc
		(start 49.950116 -26.010108)
		(mid 51.364321 -25.424318)
		(end 51.950112 -24.010112)
		(stroke
			(width 0.05)
			(type default)
		)
		(layer "Edge.Cuts")
	)
	(gr_line
		(start 51.950112 -1.999996)
		(end 51.950112 -24.010112)
		(stroke
			(width 0.05)
			(type default)
		)
		(layer "Edge.Cuts")
	)
	(gr_arc
		(start 53.950108 0)
		(mid 52.535897 -0.585785)
		(end 51.950112 -1.999996)
		(stroke
			(width 0.05)
			(type default)
		)
		(layer "Edge.Cuts")
	)
	(gr_arc
		(start 72.849994 -14.200124)
		(mid 74.44994 -15.80007)
		(end 76.049886 -14.200124)
		(stroke
			(width 0.05)
			(type default)
		)
		(layer "Edge.Cuts")
	)
	(gr_line
		(start 73.200006 -227.999798)
		(end 74.200004 -226.70008)
		(stroke
			(width 0.05)
			(type default)
		)
		(layer "Edge.Cuts")
	)
	(gr_line
		(start 74.200004 -226.70008)
		(end 74.200004 -222.499936)
		(stroke
			(width 0.05)
			(type default)
		)
		(layer "Edge.Cuts")
	)
	(gr_arc
		(start 76.049886 -14.200124)
		(mid 74.44994 -12.600178)
		(end 72.849994 -14.200124)
		(stroke
			(width 0.05)
			(type default)
		)
		(layer "Edge.Cuts")
	)
	(gr_line
		(start 76.399898 -226.70008)
		(end 77.40015 -227.999798)
		(stroke
			(width 0.05)
			(type default)
		)
		(layer "Edge.Cuts")
	)
	(gr_arc
		(start 76.399898 -222.499936)
		(mid 75.299951 -221.399862)
		(end 74.200004 -222.499936)
		(stroke
			(width 0.05)
			(type default)
		)
		(layer "Edge.Cuts")
	)
	(gr_line
		(start 76.399898 -222.499936)
		(end 76.399898 -226.70008)
		(stroke
			(width 0.05)
			(type default)
		)
		(layer "Edge.Cuts")
	)
	(gr_line
		(start 77.40015 -227.999798)
		(end 111.500158 -227.999798)
		(stroke
			(width 0.05)
			(type default)
		)
		(layer "Edge.Cuts")
	)
	(gr_arc
		(start 83.849972 -22.999954)
		(mid 85.450172 -24.600154)
		(end 87.050118 -22.999954)
		(stroke
			(width 0.05)
			(type default)
		)
		(layer "Edge.Cuts")
	)
	(gr_arc
		(start 83.849972 -5.40004)
		(mid 85.450172 -7.00024)
		(end 87.050118 -5.40004)
		(stroke
			(width 0.05)
			(type default)
		)
		(layer "Edge.Cuts")
	)
	(gr_arc
		(start 87.050118 -22.999954)
		(mid 85.450172 -21.400008)
		(end 83.849972 -22.999954)
		(stroke
			(width 0.05)
			(type default)
		)
		(layer "Edge.Cuts")
	)
	(gr_arc
		(start 87.050118 -5.40004)
		(mid 85.450172 -3.800094)
		(end 83.849972 -5.40004)
		(stroke
			(width 0.05)
			(type default)
		)
		(layer "Edge.Cuts")
	)
	(gr_arc
		(start 89.950036 -18.200116)
		(mid 90.096445 -18.553579)
		(end 90.449908 -18.699988)
		(stroke
			(width 0.05)
			(type default)
		)
		(layer "Edge.Cuts")
	)
	(gr_line
		(start 89.950036 -10.199878)
		(end 89.950036 -18.200116)
		(stroke
			(width 0.05)
			(type default)
		)
		(layer "Edge.Cuts")
	)
	(gr_line
		(start 90.449908 -18.699988)
		(end 92.95003 -18.699988)
		(stroke
			(width 0.05)
			(type default)
		)
		(layer "Edge.Cuts")
	)
	(gr_arc
		(start 90.449908 -9.700006)
		(mid 90.096445 -9.846415)
		(end 89.950036 -10.199878)
		(stroke
			(width 0.05)
			(type default)
		)
		(layer "Edge.Cuts")
	)
	(gr_arc
		(start 92.95003 -18.699988)
		(mid 93.303493 -18.553579)
		(end 93.449902 -18.200116)
		(stroke
			(width 0.05)
			(type default)
		)
		(layer "Edge.Cuts")
	)
	(gr_line
		(start 92.95003 -9.700006)
		(end 90.449908 -9.700006)
		(stroke
			(width 0.05)
			(type default)
		)
		(layer "Edge.Cuts")
	)
	(gr_line
		(start 93.449902 -18.200116)
		(end 93.449902 -10.199878)
		(stroke
			(width 0.05)
			(type default)
		)
		(layer "Edge.Cuts")
	)
	(gr_arc
		(start 93.449902 -10.199878)
		(mid 93.303493 -9.846415)
		(end 92.95003 -9.700006)
		(stroke
			(width 0.05)
			(type default)
		)
		(layer "Edge.Cuts")
	)
	(gr_line
		(start 111.500158 -227.999798)
		(end 112.499902 -226.70008)
		(stroke
			(width 0.05)
			(type default)
		)
		(layer "Edge.Cuts")
	)
	(gr_line
		(start 112.499902 -226.70008)
		(end 112.499902 -222.400114)
		(stroke
			(width 0.05)
			(type default)
		)
		(layer "Edge.Cuts")
	)
	(gr_arc
		(start 113.000028 -221.899988)
		(mid 112.646372 -222.046462)
		(end 112.499902 -222.400114)
		(stroke
			(width 0.05)
			(type default)
		)
		(layer "Edge.Cuts")
	)
	(gr_line
		(start 113.000028 -221.899988)
		(end 113.799874 -221.899988)
		(stroke
			(width 0.05)
			(type default)
		)
		(layer "Edge.Cuts")
	)
	(gr_arc
		(start 113.799874 -221.899988)
		(mid 114.153501 -221.753669)
		(end 114.3 -221.400116)
		(stroke
			(width 0.05)
			(type default)
		)
		(layer "Edge.Cuts")
	)
	(gr_line
		(start 114.3 -221.400116)
		(end 114.3 -214.799926)
		(stroke
			(width 0.05)
			(type default)
		)
		(layer "Edge.Cuts")
	)
	(gr_arc
		(start 115.599972 -213.499954)
		(mid 114.68078 -213.880718)
		(end 114.3 -214.799926)
		(stroke
			(width 0.05)
			(type default)
		)
		(layer "Edge.Cuts")
	)
	(gr_line
		(start 115.599972 -213.499954)
		(end 131.400042 -213.499954)
		(stroke
			(width 0.05)
			(type default)
		)
		(layer "Edge.Cuts")
	)
	(gr_line
		(start 119.637556 0)
		(end 53.950108 0)
		(stroke
			(width 0.05)
			(type default)
		)
		(layer "Edge.Cuts")
	)
	(gr_arc
		(start 119.637556 0)
		(mid 121.051797 0.585769)
		(end 121.637552 1.999996)
		(stroke
			(width 0.05)
			(type default)
		)
		(layer "Edge.Cuts")
	)
	(gr_line
		(start 121.637552 2.999994)
		(end 121.637552 1.999996)
		(stroke
			(width 0.05)
			(type default)
		)
		(layer "Edge.Cuts")
	)
	(gr_arc
		(start 123.637548 4.99999)
		(mid 122.223337 4.414205)
		(end 121.637552 2.999994)
		(stroke
			(width 0.05)
			(type default)
		)
		(layer "Edge.Cuts")
	)
	(gr_arc
		(start 132.700014 -221.400116)
		(mid 132.846423 -221.753579)
		(end 133.199886 -221.899988)
		(stroke
			(width 0.05)
			(type default)
		)
		(layer "Edge.Cuts")
	)
	(gr_arc
		(start 132.700014 -214.799926)
		(mid 132.319273 -213.880675)
		(end 131.400042 -213.499954)
		(stroke
			(width 0.05)
			(type default)
		)
		(layer "Edge.Cuts")
	)
	(gr_line
		(start 132.700014 -214.799926)
		(end 132.700014 -221.400116)
		(stroke
			(width 0.05)
			(type default)
		)
		(layer "Edge.Cuts")
	)
	(gr_line
		(start 133.199886 -221.899988)
		(end 133.999986 -221.899988)
		(stroke
			(width 0.05)
			(type default)
		)
		(layer "Edge.Cuts")
	)
	(gr_line
		(start 134.500112 -226.70008)
		(end 135.50011 -227.999798)
		(stroke
			(width 0.05)
			(type default)
		)
		(layer "Edge.Cuts")
	)
	(gr_arc
		(start 134.500112 -222.400114)
		(mid 134.353633 -222.046467)
		(end 133.999986 -221.899988)
		(stroke
			(width 0.05)
			(type default)
		)
		(layer "Edge.Cuts")
	)
	(gr_line
		(start 134.500112 -222.400114)
		(end 134.500112 -226.70008)
		(stroke
			(width 0.05)
			(type default)
		)
		(layer "Edge.Cuts")
	)
	(gr_arc
		(start 135.037576 -9.53008)
		(mid 136.13765 -10.630154)
		(end 137.23747 -9.53008)
		(stroke
			(width 0.05)
			(type default)
		)
		(layer "Edge.Cuts")
	)
	(gr_line
		(start 135.50011 -227.999798)
		(end 179.200048 -227.999798)
		(stroke
			(width 0.05)
			(type default)
		)
		(layer "Edge.Cuts")
	)
	(gr_arc
		(start 137.23747 -9.53008)
		(mid 136.13765 -8.43026)
		(end 135.037576 -9.53008)
		(stroke
			(width 0.05)
			(type default)
		)
		(layer "Edge.Cuts")
	)
	(gr_arc
		(start 146.037554 -9.53008)
		(mid 147.137628 -10.630154)
		(end 148.237448 -9.53008)
		(stroke
			(width 0.05)
			(type default)
		)
		(layer "Edge.Cuts")
	)
	(gr_arc
		(start 148.237448 -9.53008)
		(mid 147.137628 -8.43026)
		(end 146.037554 -9.53008)
		(stroke
			(width 0.05)
			(type default)
		)
		(layer "Edge.Cuts")
	)
	(gr_arc
		(start 157.037532 -9.53008)
		(mid 158.137606 -10.630154)
		(end 159.237426 -9.53008)
		(stroke
			(width 0.05)
			(type default)
		)
		(layer "Edge.Cuts")
	)
	(gr_arc
		(start 159.237426 -9.53008)
		(mid 158.137606 -8.43026)
		(end 157.037532 -9.53008)
		(stroke
			(width 0.05)
			(type default)
		)
		(layer "Edge.Cuts")
	)
	(gr_arc
		(start 168.03751 -9.53008)
		(mid 169.137584 -10.630154)
		(end 170.237404 -9.53008)
		(stroke
			(width 0.05)
			(type default)
		)
		(layer "Edge.Cuts")
	)
	(gr_arc
		(start 170.237404 -9.53008)
		(mid 169.137584 -8.43026)
		(end 168.03751 -9.53008)
		(stroke
			(width 0.05)
			(type default)
		)
		(layer "Edge.Cuts")
	)
	(gr_line
		(start 179.200048 -227.999798)
		(end 180.200046 -226.70008)
		(stroke
			(width 0.05)
			(type default)
		)
		(layer "Edge.Cuts")
	)
	(gr_line
		(start 180.200046 -226.70008)
		(end 180.200046 -222.499936)
		(stroke
			(width 0.05)
			(type default)
		)
		(layer "Edge.Cuts")
	)
	(gr_line
		(start 182.39994 -226.70008)
		(end 183.399938 -227.999798)
		(stroke
			(width 0.05)
			(type default)
		)
		(layer "Edge.Cuts")
	)
	(gr_arc
		(start 182.39994 -222.499936)
		(mid 181.299993 -221.399862)
		(end 180.200046 -222.499936)
		(stroke
			(width 0.05)
			(type default)
		)
		(layer "Edge.Cuts")
	)
	(gr_line
		(start 182.39994 -222.499936)
		(end 182.39994 -226.70008)
		(stroke
			(width 0.05)
			(type default)
		)
		(layer "Edge.Cuts")
	)
	(gr_line
		(start 183.399938 -227.999798)
		(end 217.499946 -227.999798)
		(stroke
			(width 0.05)
			(type default)
		)
		(layer "Edge.Cuts")
	)
	(gr_arc
		(start 199.021954 -72.00011)
		(mid 200.622154 -73.60031)
		(end 202.2221 -72.00011)
		(stroke
			(width 0.05)
			(type default)
		)
		(layer "Edge.Cuts")
	)
	(gr_arc
		(start 199.021954 -59.99988)
		(mid 200.622154 -61.60008)
		(end 202.2221 -59.99988)
		(stroke
			(width 0.05)
			(type default)
		)
		(layer "Edge.Cuts")
	)
	(gr_arc
		(start 202.2221 -72.00011)
		(mid 200.622154 -70.400164)
		(end 199.021954 -72.00011)
		(stroke
			(width 0.05)
			(type default)
		)
		(layer "Edge.Cuts")
	)
	(gr_arc
		(start 202.2221 -59.99988)
		(mid 200.622154 -58.399934)
		(end 199.021954 -59.99988)
		(stroke
			(width 0.05)
			(type default)
		)
		(layer "Edge.Cuts")
	)
	(gr_line
		(start 217.499946 -227.999798)
		(end 218.499944 -226.70008)
		(stroke
			(width 0.05)
			(type default)
		)
		(layer "Edge.Cuts")
	)
	(gr_line
		(start 218.499944 -226.70008)
		(end 218.499944 -222.400114)
		(stroke
			(width 0.05)
			(type default)
		)
		(layer "Edge.Cuts")
	)
	(gr_arc
		(start 219.00007 -221.899988)
		(mid 218.646452 -222.046483)
		(end 218.499944 -222.400114)
		(stroke
			(width 0.05)
			(type default)
		)
		(layer "Edge.Cuts")
	)
	(gr_line
		(start 219.00007 -221.899988)
		(end 219.799916 -221.899988)
		(stroke
			(width 0.05)
			(type default)
		)
		(layer "Edge.Cuts")
	)
	(gr_arc
		(start 219.799916 -221.899988)
		(mid 220.153469 -221.753594)
		(end 220.300042 -221.400116)
		(stroke
			(width 0.05)
			(type default)
		)
		(layer "Edge.Cuts")
	)
	(gr_line
		(start 220.300042 -221.400116)
		(end 220.300042 -214.799926)
		(stroke
			(width 0.05)
			(type default)
		)
		(layer "Edge.Cuts")
	)
	(gr_arc
		(start 221.600014 -213.499954)
		(mid 220.680795 -213.880704)
		(end 220.300042 -214.799926)
		(stroke
			(width 0.05)
			(type default)
		)
		(layer "Edge.Cuts")
	)
	(gr_line
		(start 221.600014 -213.499954)
		(end 229.142036 -213.499954)
		(stroke
			(width 0.05)
			(type default)
		)
		(layer "Edge.Cuts")
	)
	(gr_arc
		(start 229.142036 -213.499954)
		(mid 232.677563 -212.035491)
		(end 234.142026 -208.499964)
		(stroke
			(width 0.05)
			(type default)
		)
		(layer "Edge.Cuts")
	)
	(gr_line
		(start 234.142026 -208.499964)
		(end 234.142026 -165.269926)
		(stroke
			(width 0.05)
			(type default)
		)
		(layer "Edge.Cuts")
	)
	(gr_arc
		(start 235.412026 -163.999926)
		(mid 234.513993 -164.371893)
		(end 234.142026 -165.269926)
		(stroke
			(width 0.05)
			(type default)
		)
		(layer "Edge.Cuts")
	)
	(gr_line
		(start 235.412026 -163.999926)
		(end 249.871992 -163.999926)
		(stroke
			(width 0.05)
			(type default)
		)
		(layer "Edge.Cuts")
	)
	(gr_arc
		(start 251.141992 -208.499964)
		(mid 252.606455 -212.035491)
		(end 256.141982 -213.499954)
		(stroke
			(width 0.05)
			(type default)
		)
		(layer "Edge.Cuts")
	)
	(gr_arc
		(start 251.141992 -165.269926)
		(mid 250.770026 -164.371886)
		(end 249.871992 -163.999926)
		(stroke
			(width 0.05)
			(type default)
		)
		(layer "Edge.Cuts")
	)
	(gr_line
		(start 251.141992 -165.269926)
		(end 251.141992 -208.499964)
		(stroke
			(width 0.05)
			(type default)
		)
		(layer "Edge.Cuts")
	)
	(gr_line
		(start 256.141982 -213.499954)
		(end 257.400044 -213.499954)
		(stroke
			(width 0.05)
			(type default)
		)
		(layer "Edge.Cuts")
	)
	(gr_arc
		(start 258.700016 -221.400116)
		(mid 258.846425 -221.753579)
		(end 259.199888 -221.899988)
		(stroke
			(width 0.05)
			(type default)
		)
		(layer "Edge.Cuts")
	)
	(gr_arc
		(start 258.700016 -214.799926)
		(mid 258.319275 -213.880675)
		(end 257.400044 -213.499954)
		(stroke
			(width 0.05)
			(type default)
		)
		(layer "Edge.Cuts")
	)
	(gr_line
		(start 258.700016 -214.799926)
		(end 258.700016 -221.400116)
		(stroke
			(width 0.05)
			(type default)
		)
		(layer "Edge.Cuts")
	)
	(gr_line
		(start 259.199888 -221.899988)
		(end 259.999988 -221.899988)
		(stroke
			(width 0.05)
			(type default)
		)
		(layer "Edge.Cuts")
	)
	(gr_line
		(start 260.500114 -226.70008)
		(end 261.500112 -227.999798)
		(stroke
			(width 0.05)
			(type default)
		)
		(layer "Edge.Cuts")
	)
	(gr_arc
		(start 260.500114 -222.400114)
		(mid 260.353635 -222.046467)
		(end 259.999988 -221.899988)
		(stroke
			(width 0.05)
			(type default)
		)
		(layer "Edge.Cuts")
	)
	(gr_line
		(start 260.500114 -222.400114)
		(end 260.500114 -226.70008)
		(stroke
			(width 0.05)
			(type default)
		)
		(layer "Edge.Cuts")
	)
	(gr_line
		(start 261.500112 -227.999798)
		(end 305.20005 -227.999798)
		(stroke
			(width 0.05)
			(type default)
		)
		(layer "Edge.Cuts")
	)
	(gr_arc
		(start 288.037524 -9.53008)
		(mid 289.137598 -10.630154)
		(end 290.237418 -9.53008)
		(stroke
			(width 0.05)
			(type default)
		)
		(layer "Edge.Cuts")
	)
	(gr_arc
		(start 290.237418 -9.53008)
		(mid 289.137598 -8.43026)
		(end 288.037524 -9.53008)
		(stroke
			(width 0.05)
			(type default)
		)
		(layer "Edge.Cuts")
	)
	(gr_arc
		(start 299.037502 -9.53008)
		(mid 300.137576 -10.630154)
		(end 301.237396 -9.53008)
		(stroke
			(width 0.05)
			(type default)
		)
		(layer "Edge.Cuts")
	)
	(gr_arc
		(start 301.237396 -9.53008)
		(mid 300.137576 -8.43026)
		(end 299.037502 -9.53008)
		(stroke
			(width 0.05)
			(type default)
		)
		(layer "Edge.Cuts")
	)
	(gr_line
		(start 305.20005 -227.999798)
		(end 306.200048 -226.70008)
		(stroke
			(width 0.05)
			(type default)
		)
		(layer "Edge.Cuts")
	)
	(gr_line
		(start 306.200048 -226.70008)
		(end 306.200048 -222.499936)
		(stroke
			(width 0.05)
			(type default)
		)
		(layer "Edge.Cuts")
	)
	(gr_line
		(start 308.399942 -226.70008)
		(end 309.39994 -227.999798)
		(stroke
			(width 0.05)
			(type default)
		)
		(layer "Edge.Cuts")
	)
	(gr_arc
		(start 308.399942 -222.499936)
		(mid 307.299995 -221.399862)
		(end 306.200048 -222.499936)
		(stroke
			(width 0.05)
			(type default)
		)
		(layer "Edge.Cuts")
	)
	(gr_line
		(start 308.399942 -222.499936)
		(end 308.399942 -226.70008)
		(stroke
			(width 0.05)
			(type default)
		)
		(layer "Edge.Cuts")
	)
	(gr_line
		(start 309.39994 -227.999798)
		(end 343.499948 -227.999798)
		(stroke
			(width 0.05)
			(type default)
		)
		(layer "Edge.Cuts")
	)
	(gr_arc
		(start 310.03748 -9.53008)
		(mid 311.137554 -10.630154)
		(end 312.237374 -9.53008)
		(stroke
			(width 0.05)
			(type default)
		)
		(layer "Edge.Cuts")
	)
	(gr_arc
		(start 312.237374 -9.53008)
		(mid 311.137554 -8.43026)
		(end 310.03748 -9.53008)
		(stroke
			(width 0.05)
			(type default)
		)
		(layer "Edge.Cuts")
	)
	(gr_arc
		(start 321.037458 -9.53008)
		(mid 322.137532 -10.630154)
		(end 323.237606 -9.53008)
		(stroke
			(width 0.05)
			(type default)
		)
		(layer "Edge.Cuts")
	)
	(gr_arc
		(start 323.237606 -9.53008)
		(mid 322.137532 -8.430006)
		(end 321.037458 -9.53008)
		(stroke
			(width 0.05)
			(type default)
		)
		(layer "Edge.Cuts")
	)
	(gr_line
		(start 330.74991 4.99999)
		(end 123.637548 4.99999)
		(stroke
			(width 0.05)
			(type default)
		)
		(layer "Edge.Cuts")
	)
	(gr_line
		(start 331.749908 0.999998)
		(end 331.749908 3.999992)
		(stroke
			(width 0.05)
			(type default)
		)
		(layer "Edge.Cuts")
	)
	(gr_arc
		(start 331.749908 0.999998)
		(mid 332.042802 0.292896)
		(end 332.749906 0)
		(stroke
			(width 0.05)
			(type default)
		)
		(layer "Edge.Cuts")
	)
	(gr_arc
		(start 331.749908 3.999992)
		(mid 331.457015 4.707097)
		(end 330.74991 4.99999)
		(stroke
			(width 0.05)
			(type default)
		)
		(layer "Edge.Cuts")
	)
	(gr_arc
		(start 337.149948 -14.200124)
		(mid 338.750148 -15.800324)
		(end 340.350094 -14.200124)
		(stroke
			(width 0.05)
			(type default)
		)
		(layer "Edge.Cuts")
	)
	(gr_arc
		(start 340.350094 -14.200124)
		(mid 338.750148 -12.600178)
		(end 337.149948 -14.200124)
		(stroke
			(width 0.05)
			(type default)
		)
		(layer "Edge.Cuts")
	)
	(gr_line
		(start 343.499948 -227.999798)
		(end 344.499946 -226.70008)
		(stroke
			(width 0.05)
			(type default)
		)
		(layer "Edge.Cuts")
	)
	(gr_arc
		(start 343.7001 -203.499974)
		(mid 345.60002 -205.399894)
		(end 347.49994 -203.499974)
		(stroke
			(width 0.05)
			(type default)
		)
		(layer "Edge.Cuts")
	)
	(gr_arc
		(start 343.7001 -34.500058)
		(mid 345.60002 -36.399978)
		(end 347.49994 -34.500058)
		(stroke
			(width 0.05)
			(type default)
		)
		(layer "Edge.Cuts")
	)
	(gr_line
		(start 344.499946 -226.70008)
		(end 344.499946 -222.400114)
		(stroke
			(width 0.05)
			(type default)
		)
		(layer "Edge.Cuts")
	)
	(gr_arc
		(start 345.000072 -221.899988)
		(mid 344.646453 -222.046482)
		(end 344.499946 -222.400114)
		(stroke
			(width 0.05)
			(type default)
		)
		(layer "Edge.Cuts")
	)
	(gr_line
		(start 345.000072 -221.899988)
		(end 345.799918 -221.899988)
		(stroke
			(width 0.05)
			(type default)
		)
		(layer "Edge.Cuts")
	)
	(gr_arc
		(start 345.799918 -221.899988)
		(mid 346.153471 -221.753594)
		(end 346.300044 -221.400116)
		(stroke
			(width 0.05)
			(type default)
		)
		(layer "Edge.Cuts")
	)
	(gr_line
		(start 346.300044 -221.400116)
		(end 346.300044 -214.799926)
		(stroke
			(width 0.05)
			(type default)
		)
		(layer "Edge.Cuts")
	)
	(gr_arc
		(start 347.49994 -203.499974)
		(mid 345.60002 -201.600054)
		(end 343.7001 -203.499974)
		(stroke
			(width 0.05)
			(type default)
		)
		(layer "Edge.Cuts")
	)
	(gr_arc
		(start 347.49994 -34.500058)
		(mid 345.60002 -32.600138)
		(end 343.7001 -34.500058)
		(stroke
			(width 0.05)
			(type default)
		)
		(layer "Edge.Cuts")
	)
	(gr_arc
		(start 347.600016 -213.499954)
		(mid 346.680796 -213.880703)
		(end 346.300044 -214.799926)
		(stroke
			(width 0.05)
			(type default)
		)
		(layer "Edge.Cuts")
	)
	(gr_line
		(start 347.600016 -213.499954)
		(end 354.600002 -213.499954)
		(stroke
			(width 0.05)
			(type default)
		)
		(layer "Edge.Cuts")
	)
	(gr_arc
		(start 348.149926 -22.999954)
		(mid 349.750126 -24.600154)
		(end 351.350072 -22.999954)
		(stroke
			(width 0.05)
			(type default)
		)
		(layer "Edge.Cuts")
	)
	(gr_arc
		(start 348.149926 -5.40004)
		(mid 349.750126 -7.00024)
		(end 351.350072 -5.40004)
		(stroke
			(width 0.05)
			(type default)
		)
		(layer "Edge.Cuts")
	)
	(gr_arc
		(start 351.350072 -22.999954)
		(mid 349.750126 -21.400008)
		(end 348.149926 -22.999954)
		(stroke
			(width 0.05)
			(type default)
		)
		(layer "Edge.Cuts")
	)
	(gr_arc
		(start 351.350072 -5.40004)
		(mid 349.750126 -3.800094)
		(end 348.149926 -5.40004)
		(stroke
			(width 0.05)
			(type default)
		)
		(layer "Edge.Cuts")
	)
	(gr_line
		(start 354.24999 -18.200116)
		(end 354.24999 -10.199878)
		(stroke
			(width 0.05)
			(type default)
		)
		(layer "Edge.Cuts")
	)
	(gr_arc
		(start 354.24999 -18.200116)
		(mid 354.396492 -18.553672)
		(end 354.750116 -18.699988)
		(stroke
			(width 0.05)
			(type default)
		)
		(layer "Edge.Cuts")
	)
	(gr_arc
		(start 354.600002 -213.499954)
		(mid 355.307107 -213.207061)
		(end 355.6 -212.499956)
		(stroke
			(width 0.05)
			(type default)
		)
		(layer "Edge.Cuts")
	)
	(gr_line
		(start 354.600002 0)
		(end 332.749906 0)
		(stroke
			(width 0.05)
			(type default)
		)
		(layer "Edge.Cuts")
	)
	(gr_arc
		(start 354.750116 -9.700006)
		(mid 354.396564 -9.846396)
		(end 354.24999 -10.199878)
		(stroke
			(width 0.05)
			(type default)
		)
		(layer "Edge.Cuts")
	)
	(gr_line
		(start 354.750116 -9.700006)
		(end 355.099874 -9.700006)
		(stroke
			(width 0.05)
			(type default)
		)
		(layer "Edge.Cuts")
	)
	(gr_line
		(start 355.099874 -18.699988)
		(end 354.750116 -18.699988)
		(stroke
			(width 0.05)
			(type default)
		)
		(layer "Edge.Cuts")
	)
	(gr_arc
		(start 355.099874 -9.700006)
		(mid 355.453516 -9.553522)
		(end 355.6 -9.19988)
		(stroke
			(width 0.05)
			(type default)
		)
		(layer "Edge.Cuts")
	)
	(gr_line
		(start 355.6 -212.499956)
		(end 355.6 -19.200114)
		(stroke
			(width 0.05)
			(type default)
		)
		(layer "Edge.Cuts")
	)
	(gr_arc
		(start 355.6 -19.200114)
		(mid 355.453516 -18.846472)
		(end 355.099874 -18.699988)
		(stroke
			(width 0.05)
			(type default)
		)
		(layer "Edge.Cuts")
	)
	(gr_line
		(start 355.6 -9.19988)
		(end 355.6 -0.999998)
		(stroke
			(width 0.05)
			(type default)
		)
		(layer "Edge.Cuts")
	)
	(gr_arc
		(start 355.6 -0.999998)
		(mid 355.307107 -0.292893)
		(end 354.600002 0)
		(stroke
			(width 0.05)
			(type default)
		)
		(layer "Edge.Cuts")
	)
	(segment
		(start 17.505934 -118.857522)
		(end 17.427702 -118.455186)
		(width 0.136652)
		(layer "F.Cu")
		(net "BMC_REFCLK_P")
	)
	(segment
		(start 22.331172 -125.630178)
		(end 21.233638 -124.911866)
		(width 0.136652)
		(layer "F.Cu")
		(net "BMC_REFCLK_P")
	)
	(segment
		(start 23.319232 -125.46203)
		(end 22.909276 -125.46203)
		(width 0.136652)
		(layer "F.Cu")
		(net "BMC_REFCLK_P")
	)
	(segment
		(start 20.25015 -124.26823)
		(end 20.201382 -124.035312)
		(width 0.136652)
		(layer "F.Cu")
		(net "BMC_REFCLK_P")
	)
	(segment
		(start 25.042368 -109.015784)
		(end 25.419304 -109.39272)
		(width 0.136652)
		(layer "F.Cu")
		(net "BMC_REFCLK_P")
	)
	(segment
		(start 19.656552 -112.909858)
		(end 19.610832 -112.676432)
		(width 0.136652)
		(layer "F.Cu")
		(net "BMC_REFCLK_P")
	)
	(segment
		(start 18.26006 -115.348004)
		(end 18.13052 -115.148614)
		(width 0.136652)
		(layer "F.Cu")
		(net "BMC_REFCLK_P")
	)
	(segment
		(start 24.47544 -125.630178)
		(end 23.48738 -125.630178)
		(width 0.136652)
		(layer "F.Cu")
		(net "BMC_REFCLK_P")
	)
	(segment
		(start 20.84197 -124.454666)
		(end 20.609306 -124.50318)
		(width 0.136652)
		(layer "F.Cu")
		(net "BMC_REFCLK_P")
	)
	(segment
		(start 20.948396 -110.99165)
		(end 20.902676 -110.758224)
		(width 0.136652)
		(layer "F.Cu")
		(net "BMC_REFCLK_P")
	)
	(segment
		(start 26.144728 -109.02696)
		(end 26.444448 -109.32668)
		(width 0.136652)
		(layer "F.Cu")
		(net "BMC_REFCLK_P")
	)
	(segment
		(start 22.741128 -125.630178)
		(end 22.331172 -125.630178)
		(width 0.136652)
		(layer "F.Cu")
		(net "BMC_REFCLK_P")
	)
	(segment
		(start 18.091658 -121.868946)
		(end 17.869154 -120.72493)
		(width 0.136652)
		(layer "F.Cu")
		(net "BMC_REFCLK_P")
	)
	(segment
		(start 17.934432 -116.880132)
		(end 18.019776 -116.479066)
		(width 0.136652)
		(layer "F.Cu")
		(net "BMC_REFCLK_P")
	)
	(segment
		(start 19.194018 -113.295176)
		(end 19.427444 -113.24971)
		(width 0.136652)
		(layer "F.Cu")
		(net "BMC_REFCLK_P")
	)
	(segment
		(start 20.609306 -124.50318)
		(end 20.25015 -124.26823)
		(width 0.136652)
		(layer "F.Cu")
		(net "BMC_REFCLK_P")
	)
	(segment
		(start 25.785064 -109.02696)
		(end 26.144728 -109.02696)
		(width 0.136652)
		(layer "F.Cu")
		(net "BMC_REFCLK_P")
	)
	(segment
		(start 29.315664 -127.046736)
		(end 28.890468 -127.046736)
		(width 0.1016)
		(layer "F.Cu")
		(net "BMC_REFCLK_P")
	)
	(segment
		(start 29.704792 -126.884938)
		(end 29.703776 -126.885954)
		(width 0.1016)
		(layer "F.Cu")
		(net "BMC_REFCLK_P")
	)
	(segment
		(start 20.485862 -111.377222)
		(end 20.719288 -111.331502)
		(width 0.136652)
		(layer "F.Cu")
		(net "BMC_REFCLK_P")
	)
	(segment
		(start 20.201382 -124.035312)
		(end 19.858482 -123.810776)
		(width 0.136652)
		(layer "F.Cu")
		(net "BMC_REFCLK_P")
	)
	(segment
		(start 21.243036 -110.30712)
		(end 21.583396 -110.078774)
		(width 0.136652)
		(layer "F.Cu")
		(net "BMC_REFCLK_P")
	)
	(segment
		(start 22.157182 -109.896148)
		(end 22.203156 -109.662722)
		(width 0.136652)
		(layer "F.Cu")
		(net "BMC_REFCLK_P")
	)
	(segment
		(start 18.215864 -114.747548)
		(end 18.548096 -114.25428)
		(width 0.136652)
		(layer "F.Cu")
		(net "BMC_REFCLK_P")
	)
	(segment
		(start 17.923764 -120.12549)
		(end 17.72666 -119.992394)
		(width 0.136652)
		(layer "F.Cu")
		(net "BMC_REFCLK_P")
	)
	(segment
		(start 18.13052 -115.148614)
		(end 18.215864 -114.747548)
		(width 0.136652)
		(layer "F.Cu")
		(net "BMC_REFCLK_P")
	)
	(segment
		(start 19.01063 -113.868708)
		(end 18.96491 -113.635282)
		(width 0.136652)
		(layer "F.Cu")
		(net "BMC_REFCLK_P")
	)
	(segment
		(start 25.03678 -125.680978)
		(end 24.78024 -125.680978)
		(width 0.1016)
		(layer "F.Cu")
		(net "BMC_REFCLK_P")
	)
	(segment
		(start 18.17497 -115.74907)
		(end 18.26006 -115.348004)
		(width 0.136652)
		(layer "F.Cu")
		(net "BMC_REFCLK_P")
	)
	(segment
		(start 17.869154 -120.72493)
		(end 18.001996 -120.527826)
		(width 0.136652)
		(layer "F.Cu")
		(net "BMC_REFCLK_P")
	)
	(segment
		(start 22.203156 -109.662722)
		(end 23.02002 -109.114336)
		(width 0.136652)
		(layer "F.Cu")
		(net "BMC_REFCLK_P")
	)
	(segment
		(start 26.369264 -125.439678)
		(end 26.267664 -125.338078)
		(width 0.1016)
		(layer "F.Cu")
		(net "BMC_REFCLK_P")
	)
	(segment
		(start 21.233638 -124.911866)
		(end 21.185124 -124.679202)
		(width 0.136652)
		(layer "F.Cu")
		(net "BMC_REFCLK_P")
	)
	(segment
		(start 20.902676 -110.758224)
		(end 21.131784 -110.418118)
		(width 0.136652)
		(layer "F.Cu")
		(net "BMC_REFCLK_P")
	)
	(segment
		(start 18.019776 -116.479066)
		(end 17.890236 -116.279676)
		(width 0.136652)
		(layer "F.Cu")
		(net "BMC_REFCLK_P")
	)
	(segment
		(start 18.548096 -114.25428)
		(end 18.781522 -114.20856)
		(width 0.136652)
		(layer "F.Cu")
		(net "BMC_REFCLK_P")
	)
	(segment
		(start 18.001996 -120.527826)
		(end 17.923764 -120.12549)
		(width 0.136652)
		(layer "F.Cu")
		(net "BMC_REFCLK_P")
	)
	(segment
		(start 18.96491 -113.635282)
		(end 19.194018 -113.295176)
		(width 0.136652)
		(layer "F.Cu")
		(net "BMC_REFCLK_P")
	)
	(segment
		(start 24.60244 -125.503178)
		(end 24.47544 -125.630178)
		(width 0.136652)
		(layer "F.Cu")
		(net "BMC_REFCLK_P")
	)
	(segment
		(start 19.610832 -112.676432)
		(end 19.83994 -112.336326)
		(width 0.136652)
		(layer "F.Cu")
		(net "BMC_REFCLK_P")
	)
	(segment
		(start 21.185124 -124.679202)
		(end 20.84197 -124.454666)
		(width 0.136652)
		(layer "F.Cu")
		(net "BMC_REFCLK_P")
	)
	(segment
		(start 22.909276 -125.46203)
		(end 22.741128 -125.630178)
		(width 0.136652)
		(layer "F.Cu")
		(net "BMC_REFCLK_P")
	)
	(segment
		(start 20.302474 -111.950754)
		(end 20.256754 -111.717328)
		(width 0.136652)
		(layer "F.Cu")
		(net "BMC_REFCLK_P")
	)
	(segment
		(start 17.648428 -119.590058)
		(end 17.78127 -119.392954)
		(width 0.136652)
		(layer "F.Cu")
		(net "BMC_REFCLK_P")
	)
	(segment
		(start 19.427444 -113.24971)
		(end 19.656552 -112.909858)
		(width 0.136652)
		(layer "F.Cu")
		(net "BMC_REFCLK_P")
	)
	(segment
		(start 23.22957 -109.050582)
		(end 24.049482 -109.050582)
		(width 0.136652)
		(layer "F.Cu")
		(net "BMC_REFCLK_P")
	)
	(segment
		(start 25.419304 -109.39272)
		(end 25.785064 -109.02696)
		(width 0.136652)
		(layer "F.Cu")
		(net "BMC_REFCLK_P")
	)
	(segment
		(start 17.78127 -119.392954)
		(end 17.703038 -118.990618)
		(width 0.136652)
		(layer "F.Cu")
		(net "BMC_REFCLK_P")
	)
	(segment
		(start 24.049482 -109.050582)
		(end 24.394922 -109.396022)
		(width 0.136652)
		(layer "F.Cu")
		(net "BMC_REFCLK_P")
	)
	(segment
		(start 20.256754 -111.717328)
		(end 20.485862 -111.377222)
		(width 0.136652)
		(layer "F.Cu")
		(net "BMC_REFCLK_P")
	)
	(segment
		(start 17.735042 -117.009418)
		(end 17.934432 -116.880132)
		(width 0.136652)
		(layer "F.Cu")
		(net "BMC_REFCLK_P")
	)
	(segment
		(start 17.427702 -118.455186)
		(end 17.735042 -117.009418)
		(width 0.136652)
		(layer "F.Cu")
		(net "BMC_REFCLK_P")
	)
	(segment
		(start 26.674064 -125.439678)
		(end 26.369264 -125.439678)
		(width 0.1016)
		(layer "F.Cu")
		(net "BMC_REFCLK_P")
	)
	(segment
		(start 24.77516 -109.015784)
		(end 25.042368 -109.015784)
		(width 0.136652)
		(layer "F.Cu")
		(net "BMC_REFCLK_P")
	)
	(segment
		(start 23.48738 -125.630178)
		(end 23.319232 -125.46203)
		(width 0.136652)
		(layer "F.Cu")
		(net "BMC_REFCLK_P")
	)
	(segment
		(start 18.781522 -114.20856)
		(end 19.01063 -113.868708)
		(width 0.136652)
		(layer "F.Cu")
		(net "BMC_REFCLK_P")
	)
	(segment
		(start 21.816822 -110.124494)
		(end 22.157182 -109.896148)
		(width 0.136652)
		(layer "F.Cu")
		(net "BMC_REFCLK_P")
	)
	(segment
		(start 24.394922 -109.396022)
		(end 24.77516 -109.015784)
		(width 0.136652)
		(layer "F.Cu")
		(net "BMC_REFCLK_P")
	)
	(segment
		(start 24.78024 -125.680978)
		(end 24.60244 -125.503178)
		(width 0.1016)
		(layer "F.Cu")
		(net "BMC_REFCLK_P")
	)
	(segment
		(start 19.83994 -112.336326)
		(end 20.073366 -112.290606)
		(width 0.136652)
		(layer "F.Cu")
		(net "BMC_REFCLK_P")
	)
	(segment
		(start 17.890236 -116.279676)
		(end 17.97558 -115.87861)
		(width 0.136652)
		(layer "F.Cu")
		(net "BMC_REFCLK_P")
	)
	(segment
		(start 20.073366 -112.290606)
		(end 20.302474 -111.950754)
		(width 0.136652)
		(layer "F.Cu")
		(net "BMC_REFCLK_P")
	)
	(segment
		(start 17.703038 -118.990618)
		(end 17.505934 -118.857522)
		(width 0.136652)
		(layer "F.Cu")
		(net "BMC_REFCLK_P")
	)
	(segment
		(start 21.583396 -110.078774)
		(end 21.816822 -110.124494)
		(width 0.136652)
		(layer "F.Cu")
		(net "BMC_REFCLK_P")
	)
	(segment
		(start 25.962864 -125.338078)
		(end 25.861264 -125.439678)
		(width 0.1016)
		(layer "F.Cu")
		(net "BMC_REFCLK_P")
	)
	(segment
		(start 19.858482 -123.810776)
		(end 19.625564 -123.859544)
		(width 0.136652)
		(layer "F.Cu")
		(net "BMC_REFCLK_P")
	)
	(segment
		(start 19.625564 -123.859544)
		(end 19.282664 -123.635008)
		(width 0.136652)
		(layer "F.Cu")
		(net "BMC_REFCLK_P")
	)
	(segment
		(start 20.719288 -111.331502)
		(end 20.948396 -110.99165)
		(width 0.136652)
		(layer "F.Cu")
		(net "BMC_REFCLK_P")
	)
	(segment
		(start 19.282664 -123.635008)
		(end 18.091658 -121.868946)
		(width 0.136652)
		(layer "F.Cu")
		(net "BMC_REFCLK_P")
	)
	(segment
		(start 17.97558 -115.87861)
		(end 18.17497 -115.74907)
		(width 0.136652)
		(layer "F.Cu")
		(net "BMC_REFCLK_P")
	)
	(segment
		(start 17.72666 -119.992394)
		(end 17.648428 -119.590058)
		(width 0.136652)
		(layer "F.Cu")
		(net "BMC_REFCLK_P")
	)
	(segment
		(start 26.267664 -125.338078)
		(end 25.962864 -125.338078)
		(width 0.1016)
		(layer "F.Cu")
		(net "BMC_REFCLK_P")
	)
	(segment
		(start 25.861264 -125.439678)
		(end 25.663906 -125.439678)
		(width 0.1016)
		(layer "F.Cu")
		(net "BMC_REFCLK_P")
	)
	(segment
		(start 28.483052 -126.901956)
		(end 27.265884 -125.684788)
		(width 0.1016)
		(layer "F.Cu")
		(net "BMC_REFCLK_P")
	)
	(arc
		(start 25.277318 -125.59284)
		(mid 25.16484 -125.658174)
		(end 25.03678 -125.680978)
		(width 0.1016)
		(layer "F.Cu")
		(net "BMC_REFCLK_P")
	)
	(arc
		(start 21.131784 -110.418118)
		(mid 21.182031 -110.357228)
		(end 21.243036 -110.30712)
		(width 0.136652)
		(layer "F.Cu")
		(net "BMC_REFCLK_P")
	)
	(arc
		(start 28.890468 -127.046736)
		(mid 28.674279 -127.009467)
		(end 28.483052 -126.901956)
		(width 0.1016)
		(layer "F.Cu")
		(net "BMC_REFCLK_P")
	)
	(arc
		(start 23.02002 -109.114336)
		(mid 23.120051 -109.066863)
		(end 23.22957 -109.050582)
		(width 0.136652)
		(layer "F.Cu")
		(net "BMC_REFCLK_P")
	)
	(arc
		(start 29.626052 -126.95047)
		(mid 29.478148 -127.022102)
		(end 29.315664 -127.046736)
		(width 0.1016)
		(layer "F.Cu")
		(net "BMC_REFCLK_P")
	)
	(arc
		(start 29.703776 -126.885954)
		(mid 29.666404 -126.920008)
		(end 29.626052 -126.95047)
		(width 0.1016)
		(layer "F.Cu")
		(net "BMC_REFCLK_P")
	)
	(arc
		(start 27.265884 -125.684788)
		(mid 26.994354 -125.503387)
		(end 26.674064 -125.439678)
		(width 0.1016)
		(layer "F.Cu")
		(net "BMC_REFCLK_P")
	)
	(arc
		(start 25.663906 -125.439678)
		(mid 25.455949 -125.479263)
		(end 25.277318 -125.59284)
		(width 0.1016)
		(layer "F.Cu")
		(net "BMC_REFCLK_P")
	)
	(segment
		(start 24.704548 -108.710984)
		(end 25.1079 -108.710984)
		(width 0.136652)
		(layer "F.Cu")
		(net "BMC_REFCLK_N")
	)
	(segment
		(start 24.395176 -108.401612)
		(end 24.395684 -108.40212)
		(width 0.136652)
		(layer "F.Cu")
		(net "BMC_REFCLK_N")
	)
	(segment
		(start 24.78024 -125.884178)
		(end 24.60244 -126.061978)
		(width 0.1016)
		(layer "F.Cu")
		(net "BMC_REFCLK_N")
	)
	(segment
		(start 19.064224 -123.856496)
		(end 17.80413 -121.988072)
		(width 0.136652)
		(layer "F.Cu")
		(net "BMC_REFCLK_N")
	)
	(segment
		(start 17.92986 -114.626136)
		(end 20.879054 -110.247684)
		(width 0.136652)
		(layer "F.Cu")
		(net "BMC_REFCLK_N")
	)
	(segment
		(start 24.050752 -108.745782)
		(end 24.395176 -108.401612)
		(width 0.136652)
		(layer "F.Cu")
		(net "BMC_REFCLK_N")
	)
	(segment
		(start 17.929606 -114.626644)
		(end 17.92986 -114.626136)
		(width 0.136652)
		(layer "F.Cu")
		(net "BMC_REFCLK_N")
	)
	(segment
		(start 17.116552 -118.452392)
		(end 17.92986 -114.626644)
		(width 0.136652)
		(layer "F.Cu")
		(net "BMC_REFCLK_N")
	)
	(segment
		(start 29.623766 -127.249936)
		(end 28.890468 -127.249936)
		(width 0.1016)
		(layer "F.Cu")
		(net "BMC_REFCLK_N")
	)
	(segment
		(start 26.674064 -125.642878)
		(end 25.663906 -125.642878)
		(width 0.1016)
		(layer "F.Cu")
		(net "BMC_REFCLK_N")
	)
	(segment
		(start 22.24024 -125.934978)
		(end 19.064224 -123.856496)
		(width 0.136652)
		(layer "F.Cu")
		(net "BMC_REFCLK_N")
	)
	(segment
		(start 25.1079 -108.710984)
		(end 25.420066 -108.398818)
		(width 0.136652)
		(layer "F.Cu")
		(net "BMC_REFCLK_N")
	)
	(segment
		(start 25.420066 -108.398818)
		(end 25.743408 -108.72216)
		(width 0.136652)
		(layer "F.Cu")
		(net "BMC_REFCLK_N")
	)
	(segment
		(start 24.395684 -108.40212)
		(end 24.704548 -108.710984)
		(width 0.136652)
		(layer "F.Cu")
		(net "BMC_REFCLK_N")
	)
	(segment
		(start 28.334716 -127.041148)
		(end 27.12212 -125.828552)
		(width 0.1016)
		(layer "F.Cu")
		(net "BMC_REFCLK_N")
	)
	(segment
		(start 26.180288 -108.72216)
		(end 26.443432 -108.459016)
		(width 0.136652)
		(layer "F.Cu")
		(net "BMC_REFCLK_N")
	)
	(segment
		(start 25.743408 -108.72216)
		(end 26.180288 -108.72216)
		(width 0.136652)
		(layer "F.Cu")
		(net "BMC_REFCLK_N")
	)
	(segment
		(start 23.22957 -108.745782)
		(end 24.050752 -108.745782)
		(width 0.136652)
		(layer "F.Cu")
		(net "BMC_REFCLK_N")
	)
	(segment
		(start 24.60244 -126.061978)
		(end 24.47544 -125.934978)
		(width 0.136652)
		(layer "F.Cu")
		(net "BMC_REFCLK_N")
	)
	(segment
		(start 21.07311 -110.053882)
		(end 22.850094 -108.861098)
		(width 0.136652)
		(layer "F.Cu")
		(net "BMC_REFCLK_N")
	)
	(segment
		(start 17.92986 -114.626644)
		(end 17.929606 -114.626644)
		(width 0.136652)
		(layer "F.Cu")
		(net "BMC_REFCLK_N")
	)
	(segment
		(start 25.036526 -125.884178)
		(end 24.78024 -125.884178)
		(width 0.1016)
		(layer "F.Cu")
		(net "BMC_REFCLK_N")
	)
	(segment
		(start 17.80413 -121.988072)
		(end 17.116552 -118.452392)
		(width 0.136652)
		(layer "F.Cu")
		(net "BMC_REFCLK_N")
	)
	(segment
		(start 24.47544 -125.934978)
		(end 22.24024 -125.934978)
		(width 0.136652)
		(layer "F.Cu")
		(net "BMC_REFCLK_N")
	)
	(arc
		(start 29.820616 -127.234188)
		(mid 29.722503 -127.245958)
		(end 29.623766 -127.249936)
		(width 0.1016)
		(layer "F.Cu")
		(net "BMC_REFCLK_N")
	)
	(arc
		(start 27.12212 -125.828552)
		(mid 26.916564 -125.691141)
		(end 26.674064 -125.642878)
		(width 0.1016)
		(layer "F.Cu")
		(net "BMC_REFCLK_N")
	)
	(arc
		(start 28.890468 -127.249936)
		(mid 28.60621 -127.201017)
		(end 28.354782 -127.05969)
		(width 0.1016)
		(layer "F.Cu")
		(net "BMC_REFCLK_N")
	)
	(arc
		(start 20.879054 -110.247684)
		(mid 20.966691 -110.141379)
		(end 21.07311 -110.053882)
		(width 0.136652)
		(layer "F.Cu")
		(net "BMC_REFCLK_N")
	)
	(arc
		(start 28.354782 -127.05969)
		(mid 28.344458 -127.050735)
		(end 28.334716 -127.041148)
		(width 0.1016)
		(layer "F.Cu")
		(net "BMC_REFCLK_N")
	)
	(arc
		(start 25.413716 -125.74397)
		(mid 25.237732 -125.847981)
		(end 25.036526 -125.884178)
		(width 0.1016)
		(layer "F.Cu")
		(net "BMC_REFCLK_N")
	)
	(arc
		(start 22.850094 -108.861098)
		(mid 23.031254 -108.775215)
		(end 23.22957 -108.745782)
		(width 0.136652)
		(layer "F.Cu")
		(net "BMC_REFCLK_N")
	)
	(arc
		(start 25.663906 -125.642878)
		(mid 25.528983 -125.669104)
		(end 25.413716 -125.74397)
		(width 0.1016)
		(layer "F.Cu")
		(net "BMC_REFCLK_N")
	)
	(arc
		(start 30.504892 -126.884938)
		(mid 30.190354 -127.113652)
		(end 29.820616 -127.234188)
		(width 0.1016)
		(layer "F.Cu")
		(net "BMC_REFCLK_N")
	)
	(segment
		(start 19.365214 -92.72905)
		(end 18.965418 -93.128846)
		(width 0.12065)
		(layer "F.Cu")
		(net "BMC_TPM_RST")
	)
	(segment
		(start 16.75511 -91.5924)
		(end 16.103092 -90.940382)
		(width 0.12065)
		(layer "F.Cu")
		(net "BMC_TPM_RST")
	)
	(segment
		(start 16.75511 -93.321632)
		(end 17.737328 -93.321632)
		(width 0.12065)
		(layer "F.Cu")
		(net "BMC_TPM_RST")
	)
	(segment
		(start 16.75511 -93.321632)
		(end 16.75511 -92.160852)
		(width 0.12065)
		(layer "F.Cu")
		(net "BMC_TPM_RST")
	)
	(segment
		(start 18.965418 -93.128846)
		(end 17.930114 -93.128846)
		(width 0.12065)
		(layer "F.Cu")
		(net "BMC_TPM_RST")
	)
	(segment
		(start 17.737328 -93.321632)
		(end 17.930114 -93.128846)
		(width 0.12065)
		(layer "F.Cu")
		(net "BMC_TPM_RST")
	)
	(segment
		(start 16.103092 -90.940382)
		(end 15.1257 -90.940382)
		(width 0.12065)
		(layer "F.Cu")
		(net "BMC_TPM_RST")
	)
	(segment
		(start 16.75511 -92.160852)
		(end 16.75511 -91.5924)
		(width 0.12065)
		(layer "F.Cu")
		(net "BMC_TPM_RST")
	)
	(via
		(at 16.75511 -92.160852)
		(size 0.7112)
		(drill 0.3556)
		(layers "F.Cu" "B.Cu")
		(net "BMC_TPM_RST")
	)
	(segment
		(start 215.532716 -5.777484)
		(end 215.852248 -5.777484)
		(width 0.12065)
		(layer "F.Cu")
		(net "Q3202_D")
	)
	(segment
		(start 216.295732 -5.334)
		(end 216.929208 -5.334)
		(width 0.12065)
		(layer "F.Cu")
		(net "Q3202_D")
	)
	(segment
		(start 217.0176 -4.5085)
		(end 217.0176 -5.245608)
		(width 0.12065)
		(layer "F.Cu")
		(net "Q3202_D")
	)
	(segment
		(start 215.852248 -5.777484)
		(end 216.295732 -5.334)
		(width 0.12065)
		(layer "F.Cu")
		(net "Q3202_D")
	)
	(segment
		(start 216.929208 -5.334)
		(end 216.980008 -5.2832)
		(width 0.12065)
		(layer "F.Cu")
		(net "Q3202_D")
	)
	(segment
		(start 217.0176 -5.245608)
		(end 216.980008 -5.2832)
		(width 0.12065)
		(layer "F.Cu")
		(net "Q3202_D")
	)
	(segment
		(start 214.823548 -7.4676)
		(end 214.823548 -6.486652)
		(width 0.12065)
		(layer "F.Cu")
		(net "Q3202_D")
	)
	(segment
		(start 214.823548 -6.486652)
		(end 215.532716 -5.777484)
		(width 0.12065)
		(layer "F.Cu")
		(net "Q3202_D")
	)
	(via
		(at 216.1286 -4.1148)
		(size 0.7112)
		(drill 0.3556)
		(layers "F.Cu" "B.Cu")
		(net "Q3202_D")
	)
	(via
		(at 216.980008 -5.2832)
		(size 0.508)
		(drill 0.254)
		(layers "F.Cu" "B.Cu")
		(net "Q3202_D")
	)
	(segment
		(start 216.1286 -4.1148)
		(end 216.1286 -4.431792)
		(width 0.12065)
		(layer "B.Cu")
		(net "Q3202_D")
	)
	(segment
		(start 216.1286 -4.431792)
		(end 216.980008 -5.2832)
		(width 0.12065)
		(layer "B.Cu")
		(net "Q3202_D")
	)
	(segment
		(start 217.5891 -4.1148)
		(end 216.1286 -4.1148)
		(width 0.12065)
		(layer "B.Cu")
		(net "Q3202_D")
	)
	(segment
		(start 242.374928 -16.13535)
		(end 241.33048 -16.13535)
		(width 0.12065)
		(layer "F.Cu")
		(net "Q22_G")
	)
	(segment
		(start 241.33048 -16.13535)
		(end 239.4839 -16.13535)
		(width 0.12065)
		(layer "F.Cu")
		(net "Q22_G")
	)
	(segment
		(start 242.654074 -16.414496)
		(end 242.374928 -16.13535)
		(width 0.12065)
		(layer "F.Cu")
		(net "Q22_G")
	)
	(via
		(at 241.33048 -16.13535)
		(size 0.7112)
		(drill 0.3556)
		(layers "F.Cu" "B.Cu")
		(net "Q22_G")
	)
	(segment
		(start 267.570712 -12.705588)
		(end 267.9065 -12.3698)
		(width 0.12065)
		(layer "F.Cu")
		(net "PM8536_RST#_LS_R")
	)
	(segment
		(start 268.3891 -9.1948)
		(end 268.3891 -9.652)
		(width 0.12065)
		(layer "F.Cu")
		(net "PM8536_RST#_LS_R")
	)
	(segment
		(start 267.45565 -11.80465)
		(end 268.24305 -11.80465)
		(width 0.12065)
		(layer "F.Cu")
		(net "PM8536_RST#_LS_R")
	)
	(segment
		(start 266.754864 -12.505436)
		(end 267.45565 -11.80465)
		(width 0.12065)
		(layer "F.Cu")
		(net "PM8536_RST#_LS_R")
	)
	(segment
		(start 268.24305 -11.80465)
		(end 268.7701 -11.2776)
		(width 0.12065)
		(layer "F.Cu")
		(net "PM8536_RST#_LS_R")
	)
	(segment
		(start 268.7701 -10.033)
		(end 268.7701 -11.2776)
		(width 0.12065)
		(layer "F.Cu")
		(net "PM8536_RST#_LS_R")
	)
	(segment
		(start 266.754864 -12.705588)
		(end 266.754864 -12.505436)
		(width 0.12065)
		(layer "F.Cu")
		(net "PM8536_RST#_LS_R")
	)
	(segment
		(start 266.754864 -12.705588)
		(end 267.570712 -12.705588)
		(width 0.12065)
		(layer "F.Cu")
		(net "PM8536_RST#_LS_R")
	)
	(segment
		(start 268.3891 -9.652)
		(end 268.7701 -10.033)
		(width 0.12065)
		(layer "F.Cu")
		(net "PM8536_RST#_LS_R")
	)
	(via
		(at 266.754864 -12.705588)
		(size 0.7112)
		(drill 0.3556)
		(layers "F.Cu" "B.Cu")
		(net "PM8536_RST#_LS_R")
	)
	(segment
		(start 19.91106 -80.869282)
		(end 19.91106 -80.090518)
		(width 0.136652)
		(layer "F.Cu")
		(net "PCIE_RX_CAP_P78")
	)
	(segment
		(start 20.92198 -82.231992)
		(end 19.99996 -81.309972)
		(width 0.136652)
		(layer "F.Cu")
		(net "PCIE_RX_CAP_P78")
	)
	(segment
		(start 19.99996 -80.958182)
		(end 19.91106 -80.869282)
		(width 0.136652)
		(layer "F.Cu")
		(net "PCIE_RX_CAP_P78")
	)
	(segment
		(start 20.6502 -83.3755)
		(end 20.92198 -83.10372)
		(width 0.136652)
		(layer "F.Cu")
		(net "PCIE_RX_CAP_P78")
	)
	(segment
		(start 20.92198 -83.10372)
		(end 20.92198 -82.231992)
		(width 0.136652)
		(layer "F.Cu")
		(net "PCIE_RX_CAP_P78")
	)
	(segment
		(start 19.99996 -81.309972)
		(end 19.99996 -80.958182)
		(width 0.136652)
		(layer "F.Cu")
		(net "PCIE_RX_CAP_P78")
	)
	(segment
		(start 21.5138 -83.3755)
		(end 21.22678 -83.08848)
		(width 0.136652)
		(layer "F.Cu")
		(net "PCIE_RX_CAP_N78")
	)
	(segment
		(start 20.410932 -80.869282)
		(end 20.410932 -80.090518)
		(width 0.136652)
		(layer "F.Cu")
		(net "PCIE_RX_CAP_N78")
	)
	(segment
		(start 20.30476 -81.18348)
		(end 20.30476 -80.975454)
		(width 0.136652)
		(layer "F.Cu")
		(net "PCIE_RX_CAP_N78")
	)
	(segment
		(start 21.22678 -82.1055)
		(end 20.30476 -81.18348)
		(width 0.136652)
		(layer "F.Cu")
		(net "PCIE_RX_CAP_N78")
	)
	(segment
		(start 21.22678 -83.08848)
		(end 21.22678 -82.1055)
		(width 0.136652)
		(layer "F.Cu")
		(net "PCIE_RX_CAP_N78")
	)
	(segment
		(start 20.30476 -80.975454)
		(end 20.410932 -80.869282)
		(width 0.136652)
		(layer "F.Cu")
		(net "PCIE_RX_CAP_N78")
	)
	(segment
		(start 32.904938 -127.684784)
		(end 32.505142 -127.284988)
		(width 0.12065)
		(layer "F.Cu")
		(net "TP_GPIOB2")
	)
	(via
		(at 32.505142 -127.284988)
		(size 0.4572)
		(drill 0.2032)
		(layers "F.Cu" "B.Cu")
		(net "TP_GPIOB2")
	)
	(segment
		(start 34.9504 -127.339852)
		(end 34.706052 -127.5842)
		(width 0.12065)
		(layer "B.Cu")
		(net "TP_GPIOB2")
	)
	(segment
		(start 34.706052 -127.5842)
		(end 32.8168 -127.5842)
		(width 0.12065)
		(layer "B.Cu")
		(net "TP_GPIOB2")
	)
	(segment
		(start 32.517588 -127.284988)
		(end 32.505142 -127.284988)
		(width 0.12065)
		(layer "B.Cu")
		(net "TP_GPIOB2")
	)
	(segment
		(start 32.8168 -127.5842)
		(end 32.517588 -127.284988)
		(width 0.12065)
		(layer "B.Cu")
		(net "TP_GPIOB2")
	)
	(segment
		(start 32.904938 -126.084838)
		(end 33.304734 -125.685042)
		(width 0.12065)
		(layer "F.Cu")
		(net "LAN_SMB_ALERT_N_R")
	)
	(segment
		(start 30.544008 -113.201704)
		(end 30.544008 -112.725708)
		(width 0.12065)
		(layer "F.Cu")
		(net "LAN_SMB_ALERT_N_R")
	)
	(segment
		(start 31.418784 -115.430808)
		(end 31.091124 -115.103148)
		(width 0.12065)
		(layer "F.Cu")
		(net "LAN_SMB_ALERT_N_R")
	)
	(segment
		(start 31.091124 -113.74882)
		(end 30.544008 -113.201704)
		(width 0.12065)
		(layer "F.Cu")
		(net "LAN_SMB_ALERT_N_R")
	)
	(segment
		(start 31.091124 -115.103148)
		(end 31.091124 -113.74882)
		(width 0.12065)
		(layer "F.Cu")
		(net "LAN_SMB_ALERT_N_R")
	)
	(via
		(at 33.304734 -125.685042)
		(size 0.4572)
		(drill 0.2032)
		(layers "F.Cu" "B.Cu")
		(net "LAN_SMB_ALERT_N_R")
	)
	(via
		(at 31.418784 -115.430808)
		(size 0.508)
		(drill 0.254)
		(layers "F.Cu" "B.Cu")
		(net "LAN_SMB_ALERT_N_R")
	)
	(via
		(at 31.091124 -113.74882)
		(size 0.7112)
		(drill 0.3556)
		(layers "F.Cu" "B.Cu")
		(net "LAN_SMB_ALERT_N_R")
	)
	(segment
		(start 31.418784 -115.430808)
		(end 32.098742 -116.110766)
		(width 0.127)
		(layer "In2.Cu")
		(net "LAN_SMB_ALERT_N_R")
	)
	(segment
		(start 32.91078 -121.92254)
		(end 32.91078 -125.291088)
		(width 0.127)
		(layer "In2.Cu")
		(net "LAN_SMB_ALERT_N_R")
	)
	(segment
		(start 32.098742 -116.110766)
		(end 32.098742 -121.110502)
		(width 0.127)
		(layer "In2.Cu")
		(net "LAN_SMB_ALERT_N_R")
	)
	(segment
		(start 32.098742 -121.110502)
		(end 32.91078 -121.92254)
		(width 0.127)
		(layer "In2.Cu")
		(net "LAN_SMB_ALERT_N_R")
	)
	(segment
		(start 32.91078 -125.291088)
		(end 33.304734 -125.685042)
		(width 0.127)
		(layer "In2.Cu")
		(net "LAN_SMB_ALERT_N_R")
	)
	(segment
		(start 203.174092 -24.177498)
		(end 203.09459 -24.257)
		(width 0.12065)
		(layer "F.Cu")
		(net "U56_SDA")
	)
	(segment
		(start 203.09459 -24.257)
		(end 202.142852 -24.257)
		(width 0.12065)
		(layer "F.Cu")
		(net "U56_SDA")
	)
	(segment
		(start 204.62875 -24.75865)
		(end 204.104748 -24.75865)
		(width 0.12065)
		(layer "F.Cu")
		(net "U56_SDA")
	)
	(segment
		(start 204.104748 -24.75865)
		(end 203.523596 -24.177498)
		(width 0.12065)
		(layer "F.Cu")
		(net "U56_SDA")
	)
	(segment
		(start 204.9399 -25.0698)
		(end 204.62875 -24.75865)
		(width 0.12065)
		(layer "F.Cu")
		(net "U56_SDA")
	)
	(segment
		(start 203.523596 -24.177498)
		(end 203.174092 -24.177498)
		(width 0.12065)
		(layer "F.Cu")
		(net "U56_SDA")
	)
	(segment
		(start 204.7113 -24.257)
		(end 204.9399 -24.0284)
		(width 0.12065)
		(layer "F.Cu")
		(net "U56_SCL")
	)
	(segment
		(start 204.312774 -24.257)
		(end 204.7113 -24.257)
		(width 0.12065)
		(layer "F.Cu")
		(net "U56_SCL")
	)
	(segment
		(start 202.142852 -23.60676)
		(end 203.105004 -23.60676)
		(width 0.12065)
		(layer "F.Cu")
		(net "U56_SCL")
	)
	(segment
		(start 203.105004 -23.60676)
		(end 203.174092 -23.675848)
		(width 0.12065)
		(layer "F.Cu")
		(net "U56_SCL")
	)
	(segment
		(start 203.174092 -23.675848)
		(end 203.731622 -23.675848)
		(width 0.12065)
		(layer "F.Cu")
		(net "U56_SCL")
	)
	(segment
		(start 203.731622 -23.675848)
		(end 204.312774 -24.257)
		(width 0.12065)
		(layer "F.Cu")
		(net "U56_SCL")
	)
	(segment
		(start 204.9145 -23.0124)
		(end 204.9145 -21.971)
		(width 0.12065)
		(layer "F.Cu")
		(net "U56_INT_N")
	)
	(segment
		(start 202.142852 -22.95652)
		(end 203.63688 -22.95652)
		(width 0.12065)
		(layer "F.Cu")
		(net "U56_INT_N")
	)
	(segment
		(start 204.9145 -23.0124)
		(end 204.1398 -23.0124)
		(width 0.12065)
		(layer "F.Cu")
		(net "U56_INT_N")
	)
	(segment
		(start 204.1398 -23.0124)
		(end 203.8604 -22.733)
		(width 0.12065)
		(layer "F.Cu")
		(net "U56_INT_N")
	)
	(segment
		(start 203.63688 -22.95652)
		(end 203.8604 -22.733)
		(width 0.12065)
		(layer "F.Cu")
		(net "U56_INT_N")
	)
	(via
		(at 203.8604 -22.733)
		(size 0.7112)
		(drill 0.3556)
		(layers "F.Cu" "B.Cu")
		(net "U56_INT_N")
	)
	(segment
		(start 196.504052 -23.60676)
		(end 194.93484 -23.60676)
		(width 0.12065)
		(layer "F.Cu")
		(net "U56_A2")
	)
	(segment
		(start 193.3829 -24.0538)
		(end 193.3829 -23.0124)
		(width 0.12065)
		(layer "F.Cu")
		(net "U56_A2")
	)
	(segment
		(start 194.93484 -23.60676)
		(end 194.564 -23.9776)
		(width 0.12065)
		(layer "F.Cu")
		(net "U56_A2")
	)
	(segment
		(start 194.4878 -24.0538)
		(end 194.564 -23.9776)
		(width 0.12065)
		(layer "F.Cu")
		(net "U56_A2")
	)
	(segment
		(start 193.3829 -24.0538)
		(end 194.4878 -24.0538)
		(width 0.12065)
		(layer "F.Cu")
		(net "U56_A2")
	)
	(via
		(at 194.564 -23.9776)
		(size 0.7112)
		(drill 0.3556)
		(layers "F.Cu" "B.Cu")
		(net "U56_A2")
	)
	(segment
		(start 195.774564 -24.257)
		(end 194.737482 -25.294082)
		(width 0.12065)
		(layer "F.Cu")
		(net "U56_A1")
	)
	(segment
		(start 193.3829 -25.0952)
		(end 194.5386 -25.0952)
		(width 0.12065)
		(layer "F.Cu")
		(net "U56_A1")
	)
	(segment
		(start 193.3829 -26.1366)
		(end 193.3829 -25.0952)
		(width 0.12065)
		(layer "F.Cu")
		(net "U56_A1")
	)
	(segment
		(start 194.5386 -25.0952)
		(end 194.737482 -25.294082)
		(width 0.12065)
		(layer "F.Cu")
		(net "U56_A1")
	)
	(segment
		(start 196.504052 -24.257)
		(end 195.774564 -24.257)
		(width 0.12065)
		(layer "F.Cu")
		(net "U56_A1")
	)
	(via
		(at 194.737482 -25.294082)
		(size 0.7112)
		(drill 0.3556)
		(layers "F.Cu" "B.Cu")
		(net "U56_A1")
	)
	(segment
		(start 195.575174 -26.601674)
		(end 195.4276 -26.4541)
		(width 0.12065)
		(layer "F.Cu")
		(net "U56_A0")
	)
	(segment
		(start 196.469 -26.571956)
		(end 196.498718 -26.601674)
		(width 0.12065)
		(layer "F.Cu")
		(net "U56_A0")
	)
	(segment
		(start 194.3862 -26.4541)
		(end 195.4276 -26.4541)
		(width 0.12065)
		(layer "F.Cu")
		(net "U56_A0")
	)
	(segment
		(start 196.498718 -26.601674)
		(end 195.575174 -26.601674)
		(width 0.12065)
		(layer "F.Cu")
		(net "U56_A0")
	)
	(segment
		(start 196.504052 -24.90724)
		(end 196.469 -24.942292)
		(width 0.12065)
		(layer "F.Cu")
		(net "U56_A0")
	)
	(segment
		(start 196.469 -24.942292)
		(end 196.469 -26.571956)
		(width 0.12065)
		(layer "F.Cu")
		(net "U56_A0")
	)
	(via
		(at 196.498718 -26.601674)
		(size 0.7112)
		(drill 0.3556)
		(layers "F.Cu" "B.Cu")
		(net "U56_A0")
	)
	(segment
		(start 45.70476 -123.684792)
		(end 46.104556 -123.284996)
		(width 0.12065)
		(layer "F.Cu")
		(net "BMC0_SMB3_DAT")
	)
	(via
		(at 53.550312 -119.228362)
		(size 0.7112)
		(drill 0.3556)
		(layers "F.Cu" "B.Cu")
		(net "BMC0_SMB3_DAT")
	)
	(via
		(at 46.104556 -123.284996)
		(size 0.4572)
		(drill 0.2032)
		(layers "F.Cu" "B.Cu")
		(net "BMC0_SMB3_DAT")
	)
	(segment
		(start 55.299356 -118.843044)
		(end 55.959502 -118.182898)
		(width 0.12065)
		(layer "B.Cu")
		(net "BMC0_SMB3_DAT")
	)
	(segment
		(start 49.279302 -122.460512)
		(end 49.549558 -122.190256)
		(width 0.120396)
		(layer "B.Cu")
		(net "BMC0_SMB3_DAT")
	)
	(segment
		(start 56.33085 -118.182898)
		(end 56.588152 -118.4402)
		(width 0.12065)
		(layer "B.Cu")
		(net "BMC0_SMB3_DAT")
	)
	(segment
		(start 49.549558 -122.190256)
		(end 52.89677 -118.843044)
		(width 0.12065)
		(layer "B.Cu")
		(net "BMC0_SMB3_DAT")
	)
	(segment
		(start 53.550312 -118.843044)
		(end 53.550312 -119.228362)
		(width 0.12065)
		(layer "B.Cu")
		(net "BMC0_SMB3_DAT")
	)
	(segment
		(start 49.082198 -122.460512)
		(end 49.279302 -122.460512)
		(width 0.120396)
		(layer "B.Cu")
		(net "BMC0_SMB3_DAT")
	)
	(segment
		(start 46.104556 -123.284996)
		(end 46.104556 -123.005596)
		(width 0.120396)
		(layer "B.Cu")
		(net "BMC0_SMB3_DAT")
	)
	(segment
		(start 55.959502 -118.182898)
		(end 56.33085 -118.182898)
		(width 0.12065)
		(layer "B.Cu")
		(net "BMC0_SMB3_DAT")
	)
	(segment
		(start 48.65243 -122.89028)
		(end 49.082198 -122.460512)
		(width 0.120396)
		(layer "B.Cu")
		(net "BMC0_SMB3_DAT")
	)
	(segment
		(start 53.550312 -118.843044)
		(end 55.299356 -118.843044)
		(width 0.12065)
		(layer "B.Cu")
		(net "BMC0_SMB3_DAT")
	)
	(segment
		(start 52.89677 -118.843044)
		(end 53.550312 -118.843044)
		(width 0.12065)
		(layer "B.Cu")
		(net "BMC0_SMB3_DAT")
	)
	(segment
		(start 46.104556 -123.005596)
		(end 46.219872 -122.89028)
		(width 0.120396)
		(layer "B.Cu")
		(net "BMC0_SMB3_DAT")
	)
	(segment
		(start 46.219872 -122.89028)
		(end 48.65243 -122.89028)
		(width 0.120396)
		(layer "B.Cu")
		(net "BMC0_SMB3_DAT")
	)
	(segment
		(start 44.904914 -124.484892)
		(end 45.30471 -124.085096)
		(width 0.12065)
		(layer "F.Cu")
		(net "BMC0_SMB3_CLK")
	)
	(via
		(at 56.726836 -116.460016)
		(size 0.7112)
		(drill 0.3556)
		(layers "F.Cu" "B.Cu")
		(net "BMC0_SMB3_CLK")
	)
	(via
		(at 45.30471 -124.085096)
		(size 0.4572)
		(drill 0.2032)
		(layers "F.Cu" "B.Cu")
		(net "BMC0_SMB3_CLK")
	)
	(segment
		(start 56.588152 -116.5987)
		(end 56.726836 -116.460016)
		(width 0.12065)
		(layer "B.Cu")
		(net "BMC0_SMB3_CLK")
	)
	(segment
		(start 45.30471 -124.085096)
		(end 45.30471 -123.837192)
		(width 0.120396)
		(layer "B.Cu")
		(net "BMC0_SMB3_CLK")
	)
	(segment
		(start 45.30471 -123.837192)
		(end 45.714158 -123.427744)
		(width 0.120396)
		(layer "B.Cu")
		(net "BMC0_SMB3_CLK")
	)
	(segment
		(start 46.10862 -122.668284)
		(end 48.559974 -122.668284)
		(width 0.120396)
		(layer "B.Cu")
		(net "BMC0_SMB3_CLK")
	)
	(segment
		(start 45.714158 -123.427744)
		(end 45.714158 -123.062746)
		(width 0.120396)
		(layer "B.Cu")
		(net "BMC0_SMB3_CLK")
	)
	(segment
		(start 55.09133 -118.341394)
		(end 55.751476 -117.681248)
		(width 0.12065)
		(layer "B.Cu")
		(net "BMC0_SMB3_CLK")
	)
	(segment
		(start 49.050448 -122.17781)
		(end 49.050448 -121.97969)
		(width 0.120396)
		(layer "B.Cu")
		(net "BMC0_SMB3_CLK")
	)
	(segment
		(start 56.588152 -117.4242)
		(end 56.588152 -116.5987)
		(width 0.12065)
		(layer "B.Cu")
		(net "BMC0_SMB3_CLK")
	)
	(segment
		(start 49.07153 -121.958608)
		(end 52.688744 -118.341394)
		(width 0.12065)
		(layer "B.Cu")
		(net "BMC0_SMB3_CLK")
	)
	(segment
		(start 45.714158 -123.062746)
		(end 46.10862 -122.668284)
		(width 0.120396)
		(layer "B.Cu")
		(net "BMC0_SMB3_CLK")
	)
	(segment
		(start 49.050448 -121.97969)
		(end 49.07153 -121.958608)
		(width 0.120396)
		(layer "B.Cu")
		(net "BMC0_SMB3_CLK")
	)
	(segment
		(start 55.751476 -117.681248)
		(end 56.331104 -117.681248)
		(width 0.12065)
		(layer "B.Cu")
		(net "BMC0_SMB3_CLK")
	)
	(segment
		(start 56.331104 -117.681248)
		(end 56.588152 -117.4242)
		(width 0.12065)
		(layer "B.Cu")
		(net "BMC0_SMB3_CLK")
	)
	(segment
		(start 48.559974 -122.668284)
		(end 49.050448 -122.17781)
		(width 0.120396)
		(layer "B.Cu")
		(net "BMC0_SMB3_CLK")
	)
	(segment
		(start 52.688744 -118.341394)
		(end 55.09133 -118.341394)
		(width 0.12065)
		(layer "B.Cu")
		(net "BMC0_SMB3_CLK")
	)
	(segment
		(start 44.904914 -123.684792)
		(end 45.30471 -123.284996)
		(width 0.12065)
		(layer "F.Cu")
		(net "BMC0_SDA12_R")
	)
	(via
		(at 55.47995 -116.2177)
		(size 0.7112)
		(drill 0.3556)
		(layers "F.Cu" "B.Cu")
		(net "BMC0_SDA12_R")
	)
	(via
		(at 45.30471 -123.284996)
		(size 0.4572)
		(drill 0.2032)
		(layers "F.Cu" "B.Cu")
		(net "BMC0_SDA12_R")
	)
	(segment
		(start 47.930816 -122.298968)
		(end 48.761396 -121.468388)
		(width 0.1016)
		(layer "B.Cu")
		(net "BMC0_SDA12_R")
	)
	(segment
		(start 48.761396 -121.468388)
		(end 48.972724 -121.468388)
		(width 0.1016)
		(layer "B.Cu")
		(net "BMC0_SDA12_R")
	)
	(segment
		(start 48.990504 -121.450608)
		(end 52.804314 -117.636798)
		(width 0.12065)
		(layer "B.Cu")
		(net "BMC0_SDA12_R")
	)
	(segment
		(start 45.819314 -122.298968)
		(end 47.930816 -122.298968)
		(width 0.1016)
		(layer "B.Cu")
		(net "BMC0_SDA12_R")
	)
	(segment
		(start 48.972724 -121.468388)
		(end 48.990504 -121.450608)
		(width 0.1016)
		(layer "B.Cu")
		(net "BMC0_SDA12_R")
	)
	(segment
		(start 52.804314 -117.636798)
		(end 53.760624 -117.636798)
		(width 0.12065)
		(layer "B.Cu")
		(net "BMC0_SDA12_R")
	)
	(segment
		(start 45.442124 -123.147582)
		(end 45.442124 -122.676158)
		(width 0.1016)
		(layer "B.Cu")
		(net "BMC0_SDA12_R")
	)
	(segment
		(start 54.174898 -116.475002)
		(end 54.4322 -116.2177)
		(width 0.12065)
		(layer "B.Cu")
		(net "BMC0_SDA12_R")
	)
	(segment
		(start 45.442124 -122.676158)
		(end 45.819314 -122.298968)
		(width 0.1016)
		(layer "B.Cu")
		(net "BMC0_SDA12_R")
	)
	(segment
		(start 54.4322 -116.2177)
		(end 55.47995 -116.2177)
		(width 0.12065)
		(layer "B.Cu")
		(net "BMC0_SDA12_R")
	)
	(segment
		(start 53.760624 -117.636798)
		(end 54.174898 -117.222524)
		(width 0.12065)
		(layer "B.Cu")
		(net "BMC0_SDA12_R")
	)
	(segment
		(start 45.30471 -123.284996)
		(end 45.442124 -123.147582)
		(width 0.1016)
		(layer "B.Cu")
		(net "BMC0_SDA12_R")
	)
	(segment
		(start 54.174898 -117.222524)
		(end 54.174898 -116.475002)
		(width 0.12065)
		(layer "B.Cu")
		(net "BMC0_SDA12_R")
	)
	(segment
		(start 44.104814 -124.484892)
		(end 44.504864 -124.084842)
		(width 0.12065)
		(layer "F.Cu")
		(net "BMC0_SCL12_R")
	)
	(via
		(at 44.504864 -124.084842)
		(size 0.4572)
		(drill 0.2032)
		(layers "F.Cu" "B.Cu")
		(net "BMC0_SCL12_R")
	)
	(via
		(at 52.39639 -116.2177)
		(size 0.7112)
		(drill 0.3556)
		(layers "F.Cu" "B.Cu")
		(net "BMC0_SCL12_R")
	)
	(segment
		(start 53.673248 -116.4717)
		(end 53.673248 -117.014498)
		(width 0.12065)
		(layer "B.Cu")
		(net "BMC0_SCL12_R")
	)
	(segment
		(start 45.734986 -122.095768)
		(end 45.238924 -122.59183)
		(width 0.1016)
		(layer "B.Cu")
		(net "BMC0_SCL12_R")
	)
	(segment
		(start 53.673248 -117.014498)
		(end 53.552598 -117.135148)
		(width 0.12065)
		(layer "B.Cu")
		(net "BMC0_SCL12_R")
	)
	(segment
		(start 45.238924 -122.59183)
		(end 45.238924 -122.811794)
		(width 0.1016)
		(layer "B.Cu")
		(net "BMC0_SCL12_R")
	)
	(segment
		(start 44.92371 -123.127008)
		(end 44.92371 -123.665996)
		(width 0.1016)
		(layer "B.Cu")
		(net "BMC0_SCL12_R")
	)
	(segment
		(start 53.552598 -117.135148)
		(end 52.596288 -117.135148)
		(width 0.12065)
		(layer "B.Cu")
		(net "BMC0_SCL12_R")
	)
	(segment
		(start 48.617886 -121.11355)
		(end 48.617886 -121.32437)
		(width 0.1016)
		(layer "B.Cu")
		(net "BMC0_SCL12_R")
	)
	(segment
		(start 48.635666 -121.09577)
		(end 48.617886 -121.11355)
		(width 0.1016)
		(layer "B.Cu")
		(net "BMC0_SCL12_R")
	)
	(segment
		(start 52.596288 -117.135148)
		(end 48.635666 -121.09577)
		(width 0.12065)
		(layer "B.Cu")
		(net "BMC0_SCL12_R")
	)
	(segment
		(start 53.419248 -116.2177)
		(end 53.673248 -116.4717)
		(width 0.12065)
		(layer "B.Cu")
		(net "BMC0_SCL12_R")
	)
	(segment
		(start 53.4162 -116.2177)
		(end 53.419248 -116.2177)
		(width 0.12065)
		(layer "B.Cu")
		(net "BMC0_SCL12_R")
	)
	(segment
		(start 44.92371 -123.665996)
		(end 44.504864 -124.084842)
		(width 0.1016)
		(layer "B.Cu")
		(net "BMC0_SCL12_R")
	)
	(segment
		(start 53.4162 -116.2177)
		(end 52.39639 -116.2177)
		(width 0.12065)
		(layer "B.Cu")
		(net "BMC0_SCL12_R")
	)
	(segment
		(start 45.238924 -122.811794)
		(end 44.92371 -123.127008)
		(width 0.1016)
		(layer "B.Cu")
		(net "BMC0_SCL12_R")
	)
	(segment
		(start 47.846488 -122.095768)
		(end 45.734986 -122.095768)
		(width 0.1016)
		(layer "B.Cu")
		(net "BMC0_SCL12_R")
	)
	(segment
		(start 48.617886 -121.32437)
		(end 47.846488 -122.095768)
		(width 0.1016)
		(layer "B.Cu")
		(net "BMC0_SCL12_R")
	)
	(segment
		(start 205.181454 -32.169354)
		(end 205.181454 -32.483806)
		(width 0.12065)
		(layer "F.Cu")
		(net "U55_SDA")
	)
	(segment
		(start 205.181454 -32.169354)
		(end 203.903072 -32.169354)
		(width 0.12065)
		(layer "F.Cu")
		(net "U55_SDA")
	)
	(segment
		(start 205.91653 -32.169354)
		(end 205.181454 -32.169354)
		(width 0.12065)
		(layer "F.Cu")
		(net "U55_SDA")
	)
	(segment
		(start 203.903072 -32.169354)
		(end 203.839826 -32.2326)
		(width 0.12065)
		(layer "F.Cu")
		(net "U55_SDA")
	)
	(segment
		(start 203.839826 -32.2326)
		(end 202.879452 -32.2326)
		(width 0.12065)
		(layer "F.Cu")
		(net "U55_SDA")
	)
	(segment
		(start 206.16545 -32.418274)
		(end 205.91653 -32.169354)
		(width 0.12065)
		(layer "F.Cu")
		(net "U55_SDA")
	)
	(via
		(at 205.181454 -32.483806)
		(size 0.7112)
		(drill 0.3556)
		(layers "F.Cu" "B.Cu")
		(net "U55_SDA")
	)
	(segment
		(start 205.90002 -31.667704)
		(end 206.16545 -31.402274)
		(width 0.12065)
		(layer "F.Cu")
		(net "U55_SCL")
	)
	(segment
		(start 204.532738 -31.667704)
		(end 203.925424 -31.667704)
		(width 0.12065)
		(layer "F.Cu")
		(net "U55_SCL")
	)
	(segment
		(start 203.84008 -31.58236)
		(end 202.879452 -31.58236)
		(width 0.12065)
		(layer "F.Cu")
		(net "U55_SCL")
	)
	(segment
		(start 204.532738 -31.297372)
		(end 204.532738 -31.667704)
		(width 0.12065)
		(layer "F.Cu")
		(net "U55_SCL")
	)
	(segment
		(start 204.532738 -31.667704)
		(end 205.90002 -31.667704)
		(width 0.12065)
		(layer "F.Cu")
		(net "U55_SCL")
	)
	(segment
		(start 203.925424 -31.667704)
		(end 203.84008 -31.58236)
		(width 0.12065)
		(layer "F.Cu")
		(net "U55_SCL")
	)
	(via
		(at 204.532738 -31.297372)
		(size 0.7112)
		(drill 0.3556)
		(layers "F.Cu" "B.Cu")
		(net "U55_SCL")
	)
	(segment
		(start 196.0372 -30.4038)
		(end 196.0372 -29.6672)
		(width 0.12065)
		(layer "F.Cu")
		(net "U55_P0")
	)
	(segment
		(start 190.8302 -29.21)
		(end 191.135 -29.5148)
		(width 0.12065)
		(layer "F.Cu")
		(net "U55_P0")
	)
	(segment
		(start 196.56552 -30.93212)
		(end 196.0372 -30.4038)
		(width 0.12065)
		(layer "F.Cu")
		(net "U55_P0")
	)
	(segment
		(start 195.621148 -29.251148)
		(end 193.773552 -29.251148)
		(width 0.12065)
		(layer "F.Cu")
		(net "U55_P0")
	)
	(segment
		(start 196.0372 -29.6672)
		(end 195.621148 -29.251148)
		(width 0.12065)
		(layer "F.Cu")
		(net "U55_P0")
	)
	(segment
		(start 193.773552 -29.251148)
		(end 192.8495 -30.1752)
		(width 0.12065)
		(layer "F.Cu")
		(net "U55_P0")
	)
	(segment
		(start 192.5066 -29.5148)
		(end 192.8495 -29.8577)
		(width 0.12065)
		(layer "F.Cu")
		(net "U55_P0")
	)
	(segment
		(start 191.135 -29.5148)
		(end 192.5066 -29.5148)
		(width 0.12065)
		(layer "F.Cu")
		(net "U55_P0")
	)
	(segment
		(start 197.240652 -30.93212)
		(end 196.56552 -30.93212)
		(width 0.12065)
		(layer "F.Cu")
		(net "U55_P0")
	)
	(segment
		(start 192.8495 -29.8577)
		(end 192.8495 -30.1752)
		(width 0.12065)
		(layer "F.Cu")
		(net "U55_P0")
	)
	(via
		(at 190.8302 -29.21)
		(size 0.7112)
		(drill 0.3556)
		(layers "F.Cu" "B.Cu")
		(net "U55_P0")
	)
	(segment
		(start 205.400402 -30.200092)
		(end 205.400402 -29.353002)
		(width 0.12065)
		(layer "F.Cu")
		(net "U55_INT_N")
	)
	(segment
		(start 205.400402 -30.200092)
		(end 204.826108 -30.200092)
		(width 0.12065)
		(layer "F.Cu")
		(net "U55_INT_N")
	)
	(segment
		(start 205.400402 -29.353002)
		(end 205.2066 -29.1592)
		(width 0.12065)
		(layer "F.Cu")
		(net "U55_INT_N")
	)
	(segment
		(start 204.09408 -30.93212)
		(end 202.879452 -30.93212)
		(width 0.12065)
		(layer "F.Cu")
		(net "U55_INT_N")
	)
	(segment
		(start 204.826108 -30.200092)
		(end 204.09408 -30.93212)
		(width 0.12065)
		(layer "F.Cu")
		(net "U55_INT_N")
	)
	(via
		(at 205.2066 -29.1592)
		(size 0.7112)
		(drill 0.3556)
		(layers "F.Cu" "B.Cu")
		(net "U55_INT_N")
	)
	(segment
		(start 195.55714 -31.58236)
		(end 195.3133 -31.8262)
		(width 0.12065)
		(layer "F.Cu")
		(net "U55_A2")
	)
	(segment
		(start 195.3133 -30.1625)
		(end 194.9704 -29.8196)
		(width 0.12065)
		(layer "F.Cu")
		(net "U55_A2")
	)
	(segment
		(start 195.3133 -30.7848)
		(end 195.3133 -30.1625)
		(width 0.12065)
		(layer "F.Cu")
		(net "U55_A2")
	)
	(segment
		(start 195.3133 -31.8262)
		(end 195.3133 -30.7848)
		(width 0.12065)
		(layer "F.Cu")
		(net "U55_A2")
	)
	(segment
		(start 197.240652 -31.58236)
		(end 195.55714 -31.58236)
		(width 0.12065)
		(layer "F.Cu")
		(net "U55_A2")
	)
	(via
		(at 194.9704 -29.8196)
		(size 0.7112)
		(drill 0.3556)
		(layers "F.Cu" "B.Cu")
		(net "U55_A2")
	)
	(segment
		(start 195.9483 -32.2326)
		(end 195.3133 -32.8676)
		(width 0.12065)
		(layer "F.Cu")
		(net "U55_A1")
	)
	(segment
		(start 197.240652 -32.2326)
		(end 195.9483 -32.2326)
		(width 0.12065)
		(layer "F.Cu")
		(net "U55_A1")
	)
	(segment
		(start 195.3133 -33.909)
		(end 195.3133 -35.2679)
		(width 0.12065)
		(layer "F.Cu")
		(net "U55_A1")
	)
	(segment
		(start 195.3133 -35.2679)
		(end 195.2498 -35.3314)
		(width 0.12065)
		(layer "F.Cu")
		(net "U55_A1")
	)
	(segment
		(start 195.3133 -32.8676)
		(end 195.3133 -33.909)
		(width 0.12065)
		(layer "F.Cu")
		(net "U55_A1")
	)
	(via
		(at 195.2498 -35.3314)
		(size 0.7112)
		(drill 0.3556)
		(layers "F.Cu" "B.Cu")
		(net "U55_A1")
	)
	(segment
		(start 199.4281 -34.3281)
		(end 199.6948 -34.5948)
		(width 0.12065)
		(layer "F.Cu")
		(net "U55_A0")
	)
	(segment
		(start 198.3867 -34.3408)
		(end 198.3994 -34.3281)
		(width 0.12065)
		(layer "F.Cu")
		(net "U55_A0")
	)
	(segment
		(start 197.3707 -34.3408)
		(end 198.3867 -34.3408)
		(width 0.12065)
		(layer "F.Cu")
		(net "U55_A0")
	)
	(segment
		(start 197.240652 -32.88284)
		(end 197.240652 -34.210752)
		(width 0.12065)
		(layer "F.Cu")
		(net "U55_A0")
	)
	(segment
		(start 197.240652 -34.210752)
		(end 197.3707 -34.3408)
		(width 0.12065)
		(layer "F.Cu")
		(net "U55_A0")
	)
	(segment
		(start 198.3994 -34.3281)
		(end 199.4281 -34.3281)
		(width 0.12065)
		(layer "F.Cu")
		(net "U55_A0")
	)
	(via
		(at 199.6948 -34.5948)
		(size 0.7112)
		(drill 0.3556)
		(layers "F.Cu" "B.Cu")
		(net "U55_A0")
	)
	(segment
		(start 227.33 -7.874)
		(end 228.346 -7.874)
		(width 0.12065)
		(layer "F.Cu")
		(net "TWI_SDA2_R")
	)
	(segment
		(start 228.346 -7.874)
		(end 228.854 -7.366)
		(width 0.12065)
		(layer "F.Cu")
		(net "TWI_SDA2_R")
	)
	(segment
		(start 229.8065 -7.366)
		(end 228.854 -7.366)
		(width 0.12065)
		(layer "F.Cu")
		(net "TWI_SDA2_R")
	)
	(via
		(at 228.854 -7.366)
		(size 0.7112)
		(drill 0.3556)
		(layers "F.Cu" "B.Cu")
		(net "TWI_SDA2_R")
	)
	(segment
		(start 229.8065 -8.382)
		(end 229.108 -8.382)
		(width 0.12065)
		(layer "F.Cu")
		(net "TWI_SCL2_R")
	)
	(segment
		(start 228.346 -9.144)
		(end 228.854 -8.636)
		(width 0.12065)
		(layer "F.Cu")
		(net "TWI_SCL2_R")
	)
	(segment
		(start 229.108 -8.382)
		(end 228.854 -8.636)
		(width 0.12065)
		(layer "F.Cu")
		(net "TWI_SCL2_R")
	)
	(segment
		(start 227.33 -9.144)
		(end 228.346 -9.144)
		(width 0.12065)
		(layer "F.Cu")
		(net "TWI_SCL2_R")
	)
	(via
		(at 228.854 -8.636)
		(size 0.7112)
		(drill 0.3556)
		(layers "F.Cu" "B.Cu")
		(net "TWI_SCL2_R")
	)
	(segment
		(start 14.52245 -174.35195)
		(end 14.5288 -174.3583)
		(width 0.12065)
		(layer "F.Cu")
		(net "TRAY_MBP_CTRL_EN_N")
	)
	(segment
		(start 13.0683 -174.35195)
		(end 14.52245 -174.35195)
		(width 0.12065)
		(layer "F.Cu")
		(net "TRAY_MBP_CTRL_EN_N")
	)
	(segment
		(start 15.21079 -175.25492)
		(end 15.06601 -175.3997)
		(width 0.12065)
		(layer "F.Cu")
		(net "TRAY_MBP_CTRL_EN_N")
	)
	(segment
		(start 15.06601 -175.3997)
		(end 14.5288 -175.3997)
		(width 0.12065)
		(layer "F.Cu")
		(net "TRAY_MBP_CTRL_EN_N")
	)
	(segment
		(start 64.510412 -31.700216)
		(end 64.62014 -31.700216)
		(width 0.12065)
		(layer "F.Cu")
		(net "TRAY_MBP_CTRL_EN_N")
	)
	(segment
		(start 64.62014 -31.700216)
		(end 65.385188 -30.935168)
		(width 0.12065)
		(layer "F.Cu")
		(net "TRAY_MBP_CTRL_EN_N")
	)
	(segment
		(start 15.62227 -175.25492)
		(end 15.21079 -175.25492)
		(width 0.12065)
		(layer "F.Cu")
		(net "TRAY_MBP_CTRL_EN_N")
	)
	(segment
		(start 14.5288 -174.3583)
		(end 14.5288 -175.3997)
		(width 0.12065)
		(layer "F.Cu")
		(net "TRAY_MBP_CTRL_EN_N")
	)
	(segment
		(start 16.503396 -175.25492)
		(end 16.5989 -175.350424)
		(width 0.12065)
		(layer "F.Cu")
		(net "TRAY_MBP_CTRL_EN_N")
	)
	(segment
		(start 15.62227 -175.25492)
		(end 16.503396 -175.25492)
		(width 0.12065)
		(layer "F.Cu")
		(net "TRAY_MBP_CTRL_EN_N")
	)
	(via
		(at 15.62227 -175.25492)
		(size 0.7112)
		(drill 0.3556)
		(layers "F.Cu" "B.Cu")
		(net "TRAY_MBP_CTRL_EN_N")
	)
	(via
		(at 65.385188 -30.935168)
		(size 0.508)
		(drill 0.254)
		(layers "F.Cu" "B.Cu")
		(net "TRAY_MBP_CTRL_EN_N")
	)
	(via
		(at 16.5989 -175.350424)
		(size 0.508)
		(drill 0.254)
		(layers "F.Cu" "B.Cu")
		(net "TRAY_MBP_CTRL_EN_N")
	)
	(via
		(at 48.09871 -83.79587)
		(size 0.508)
		(drill 0.254)
		(layers "F.Cu" "B.Cu")
		(net "TRAY_MBP_CTRL_EN_N")
	)
	(segment
		(start 48.133 -81.93405)
		(end 48.09871 -81.96834)
		(width 0.12065)
		(layer "B.Cu")
		(net "TRAY_MBP_CTRL_EN_N")
	)
	(segment
		(start 58.063384 -34.00044)
		(end 57.19826 -34.00044)
		(width 0.12065)
		(layer "B.Cu")
		(net "TRAY_MBP_CTRL_EN_N")
	)
	(segment
		(start 50.722022 -50.35677)
		(end 50.722022 -52.58943)
		(width 0.12065)
		(layer "B.Cu")
		(net "TRAY_MBP_CTRL_EN_N")
	)
	(segment
		(start 64.175386 -32.14497)
		(end 59.918854 -32.14497)
		(width 0.12065)
		(layer "B.Cu")
		(net "TRAY_MBP_CTRL_EN_N")
	)
	(segment
		(start 50.722022 -52.58943)
		(end 50.2666 -53.044852)
		(width 0.12065)
		(layer "B.Cu")
		(net "TRAY_MBP_CTRL_EN_N")
	)
	(segment
		(start 48.133 -78.9686)
		(end 48.133 -81.93405)
		(width 0.12065)
		(layer "B.Cu")
		(net "TRAY_MBP_CTRL_EN_N")
	)
	(segment
		(start 50.149252 -39.843202)
		(end 50.149252 -49.784)
		(width 0.12065)
		(layer "B.Cu")
		(net "TRAY_MBP_CTRL_EN_N")
	)
	(segment
		(start 50.149252 -49.784)
		(end 50.722022 -50.35677)
		(width 0.12065)
		(layer "B.Cu")
		(net "TRAY_MBP_CTRL_EN_N")
	)
	(segment
		(start 55.479188 -34.513266)
		(end 50.149252 -39.843202)
		(width 0.12065)
		(layer "B.Cu")
		(net "TRAY_MBP_CTRL_EN_N")
	)
	(segment
		(start 57.19826 -34.00044)
		(end 56.685434 -34.513266)
		(width 0.12065)
		(layer "B.Cu")
		(net "TRAY_MBP_CTRL_EN_N")
	)
	(segment
		(start 50.2666 -53.044852)
		(end 50.2666 -76.835)
		(width 0.12065)
		(layer "B.Cu")
		(net "TRAY_MBP_CTRL_EN_N")
	)
	(segment
		(start 59.918854 -32.14497)
		(end 58.063384 -34.00044)
		(width 0.12065)
		(layer "B.Cu")
		(net "TRAY_MBP_CTRL_EN_N")
	)
	(segment
		(start 48.09871 -81.96834)
		(end 48.09871 -83.79587)
		(width 0.12065)
		(layer "B.Cu")
		(net "TRAY_MBP_CTRL_EN_N")
	)
	(segment
		(start 65.385188 -30.935168)
		(end 64.175386 -32.14497)
		(width 0.12065)
		(layer "B.Cu")
		(net "TRAY_MBP_CTRL_EN_N")
	)
	(segment
		(start 50.2666 -76.835)
		(end 48.133 -78.9686)
		(width 0.12065)
		(layer "B.Cu")
		(net "TRAY_MBP_CTRL_EN_N")
	)
	(segment
		(start 56.685434 -34.513266)
		(end 55.479188 -34.513266)
		(width 0.12065)
		(layer "B.Cu")
		(net "TRAY_MBP_CTRL_EN_N")
	)
	(segment
		(start 29.74467 -84.4931)
		(end 29.93517 -84.6836)
		(width 0.127)
		(layer "In2.Cu")
		(net "TRAY_MBP_CTRL_EN_N")
	)
	(segment
		(start 5.746242 -103.42753)
		(end 5.746242 -102.71506)
		(width 0.127)
		(layer "In2.Cu")
		(net "TRAY_MBP_CTRL_EN_N")
	)
	(segment
		(start 9.5123 -98.738182)
		(end 9.787382 -98.4631)
		(width 0.127)
		(layer "In2.Cu")
		(net "TRAY_MBP_CTRL_EN_N")
	)
	(segment
		(start 2.49936 -110.075472)
		(end 5.746242 -106.82859)
		(width 0.127)
		(layer "In2.Cu")
		(net "TRAY_MBP_CTRL_EN_N")
	)
	(segment
		(start 2.49936 -161.250884)
		(end 2.49936 -110.075472)
		(width 0.127)
		(layer "In2.Cu")
		(net "TRAY_MBP_CTRL_EN_N")
	)
	(segment
		(start 29.93517 -84.6836)
		(end 42.280078 -84.6836)
		(width 0.127)
		(layer "In2.Cu")
		(net "TRAY_MBP_CTRL_EN_N")
	)
	(segment
		(start 27.106372 -84.4931)
		(end 29.74467 -84.4931)
		(width 0.127)
		(layer "In2.Cu")
		(net "TRAY_MBP_CTRL_EN_N")
	)
	(segment
		(start 5.745988 -104.059228)
		(end 5.745988 -103.427784)
		(width 0.127)
		(layer "In2.Cu")
		(net "TRAY_MBP_CTRL_EN_N")
	)
	(segment
		(start 22.058122 -88.722454)
		(end 22.877018 -88.722454)
		(width 0.127)
		(layer "In2.Cu")
		(net "TRAY_MBP_CTRL_EN_N")
	)
	(segment
		(start 42.280078 -84.6836)
		(end 43.167808 -83.79587)
		(width 0.127)
		(layer "In2.Cu")
		(net "TRAY_MBP_CTRL_EN_N")
	)
	(segment
		(start 9.5123 -98.949002)
		(end 9.5123 -98.738182)
		(width 0.127)
		(layer "In2.Cu")
		(net "TRAY_MBP_CTRL_EN_N")
	)
	(segment
		(start 5.746242 -106.82859)
		(end 5.746242 -104.059482)
		(width 0.127)
		(layer "In2.Cu")
		(net "TRAY_MBP_CTRL_EN_N")
	)
	(segment
		(start 5.746242 -104.059482)
		(end 5.745988 -104.059228)
		(width 0.127)
		(layer "In2.Cu")
		(net "TRAY_MBP_CTRL_EN_N")
	)
	(segment
		(start 43.167808 -83.79587)
		(end 48.09871 -83.79587)
		(width 0.127)
		(layer "In2.Cu")
		(net "TRAY_MBP_CTRL_EN_N")
	)
	(segment
		(start 18.580354 -89.41054)
		(end 21.370036 -89.41054)
		(width 0.127)
		(layer "In2.Cu")
		(net "TRAY_MBP_CTRL_EN_N")
	)
	(segment
		(start 11.96467 -96.496632)
		(end 11.96467 -96.026224)
		(width 0.127)
		(layer "In2.Cu")
		(net "TRAY_MBP_CTRL_EN_N")
	)
	(segment
		(start 9.787382 -98.4631)
		(end 9.998202 -98.4631)
		(width 0.127)
		(layer "In2.Cu")
		(net "TRAY_MBP_CTRL_EN_N")
	)
	(segment
		(start 9.998202 -98.4631)
		(end 11.96467 -96.496632)
		(width 0.127)
		(layer "In2.Cu")
		(net "TRAY_MBP_CTRL_EN_N")
	)
	(segment
		(start 16.5989 -175.350424)
		(end 2.49936 -161.250884)
		(width 0.127)
		(layer "In2.Cu")
		(net "TRAY_MBP_CTRL_EN_N")
	)
	(segment
		(start 22.877018 -88.722454)
		(end 27.106372 -84.4931)
		(width 0.127)
		(layer "In2.Cu")
		(net "TRAY_MBP_CTRL_EN_N")
	)
	(segment
		(start 5.746242 -102.71506)
		(end 9.5123 -98.949002)
		(width 0.127)
		(layer "In2.Cu")
		(net "TRAY_MBP_CTRL_EN_N")
	)
	(segment
		(start 11.96467 -96.026224)
		(end 18.580354 -89.41054)
		(width 0.127)
		(layer "In2.Cu")
		(net "TRAY_MBP_CTRL_EN_N")
	)
	(segment
		(start 5.745988 -103.427784)
		(end 5.746242 -103.42753)
		(width 0.127)
		(layer "In2.Cu")
		(net "TRAY_MBP_CTRL_EN_N")
	)
	(segment
		(start 21.370036 -89.41054)
		(end 22.058122 -88.722454)
		(width 0.127)
		(layer "In2.Cu")
		(net "TRAY_MBP_CTRL_EN_N")
	)
	(segment
		(start 98.425 -83.1342)
		(end 99.8474 -81.7118)
		(width 0.136652)
		(layer "F.Cu")
		(net "USB2_BMC_DP")
	)
	(segment
		(start 74.419968 -93.3704)
		(end 92.9894 -93.3704)
		(width 0.136652)
		(layer "F.Cu")
		(net "USB2_BMC_DP")
	)
	(segment
		(start 26.8859 -142.9766)
		(end 26.52522 -142.9766)
		(width 0.136652)
		(layer "F.Cu")
		(net "USB2_BMC_DP")
	)
	(segment
		(start 132.7658 -38.83025)
		(end 132.766816 -38.83025)
		(width 0.136652)
		(layer "F.Cu")
		(net "USB2_BMC_DP")
	)
	(segment
		(start 131.459986 -37.134546)
		(end 128.901698 -37.134546)
		(width 0.136652)
		(layer "F.Cu")
		(net "USB2_BMC_DP")
	)
	(segment
		(start 132.501132 -37.634164)
		(end 132.384038 -37.51707)
		(width 0.136652)
		(layer "F.Cu")
		(net "USB2_BMC_DP")
	)
	(segment
		(start 132.7658 -41.801796)
		(end 132.7658 -38.83025)
		(width 0.136652)
		(layer "F.Cu")
		(net "USB2_BMC_DP")
	)
	(segment
		(start 73.747376 -94.042992)
		(end 74.419968 -93.3704)
		(width 0.136652)
		(layer "F.Cu")
		(net "USB2_BMC_DP")
	)
	(segment
		(start 59.944 -89.648792)
		(end 64.3382 -94.042992)
		(width 0.136652)
		(layer "F.Cu")
		(net "USB2_BMC_DP")
	)
	(segment
		(start 127.73787 -36.06673)
		(end 127.73787 -34.67481)
		(width 0.136652)
		(layer "F.Cu")
		(net "USB2_BMC_DP")
	)
	(segment
		(start 99.8474 -81.7118)
		(end 102.271576 -81.7118)
		(width 0.136652)
		(layer "F.Cu")
		(net "USB2_BMC_DP")
	)
	(segment
		(start 57.054242 -85.89645)
		(end 59.944 -88.786208)
		(width 0.136652)
		(layer "F.Cu")
		(net "USB2_BMC_DP")
	)
	(segment
		(start 59.944 -88.786208)
		(end 59.944 -89.648792)
		(width 0.136652)
		(layer "F.Cu")
		(net "USB2_BMC_DP")
	)
	(segment
		(start 132.139944 -42.291)
		(end 132.276596 -42.291)
		(width 0.136652)
		(layer "F.Cu")
		(net "USB2_BMC_DP")
	)
	(segment
		(start 132.766816 -38.83025)
		(end 132.766816 -38.275514)
		(width 0.136652)
		(layer "F.Cu")
		(net "USB2_BMC_DP")
	)
	(segment
		(start 27.2415 -142.621)
		(end 26.8859 -142.9766)
		(width 0.136652)
		(layer "F.Cu")
		(net "USB2_BMC_DP")
	)
	(segment
		(start 56.68264 -85.89645)
		(end 57.054242 -85.89645)
		(width 0.136652)
		(layer "F.Cu")
		(net "USB2_BMC_DP")
	)
	(segment
		(start 64.3382 -94.042992)
		(end 73.747376 -94.042992)
		(width 0.136652)
		(layer "F.Cu")
		(net "USB2_BMC_DP")
	)
	(segment
		(start 98.425 -87.9348)
		(end 98.425 -83.1342)
		(width 0.136652)
		(layer "F.Cu")
		(net "USB2_BMC_DP")
	)
	(segment
		(start 128.495044 -36.966144)
		(end 127.838454 -36.309554)
		(width 0.136652)
		(layer "F.Cu")
		(net "USB2_BMC_DP")
	)
	(segment
		(start 131.746244 -42.7228)
		(end 131.746244 -42.6847)
		(width 0.136652)
		(layer "F.Cu")
		(net "USB2_BMC_DP")
	)
	(segment
		(start 92.9894 -93.3704)
		(end 98.425 -87.9348)
		(width 0.136652)
		(layer "F.Cu")
		(net "USB2_BMC_DP")
	)
	(segment
		(start 26.52522 -142.9766)
		(end 26.12898 -142.58036)
		(width 0.136652)
		(layer "F.Cu")
		(net "USB2_BMC_DP")
	)
	(via
		(at 26.12898 -142.58036)
		(size 0.508)
		(drill 0.254)
		(layers "F.Cu" "B.Cu")
		(net "USB2_BMC_DP")
	)
	(via
		(at 56.25084 -86.32825)
		(size 0.508)
		(drill 0.254)
		(layers "F.Cu" "B.Cu")
		(net "USB2_BMC_DP")
	)
	(via
		(at 131.746244 -42.7228)
		(size 0.508)
		(drill 0.254)
		(layers "F.Cu" "B.Cu")
		(net "USB2_BMC_DP")
	)
	(via
		(at 102.62616 -82.1182)
		(size 0.508)
		(drill 0.254)
		(layers "F.Cu" "B.Cu")
		(net "USB2_BMC_DP")
	)
	(arc
		(start 132.622544 -42.147744)
		(mid 132.728545 -41.989007)
		(end 132.7658 -41.801796)
		(width 0.136652)
		(layer "F.Cu")
		(net "USB2_BMC_DP")
	)
	(arc
		(start 132.384038 -37.51707)
		(mid 131.96005 -37.233927)
		(end 131.459986 -37.134546)
		(width 0.136652)
		(layer "F.Cu")
		(net "USB2_BMC_DP")
	)
	(arc
		(start 131.746244 -42.6847)
		(mid 131.861556 -42.406312)
		(end 132.139944 -42.291)
		(width 0.136652)
		(layer "F.Cu")
		(net "USB2_BMC_DP")
	)
	(arc
		(start 132.276596 -42.291)
		(mid 132.46382 -42.253777)
		(end 132.622544 -42.147744)
		(width 0.136652)
		(layer "F.Cu")
		(net "USB2_BMC_DP")
	)
	(arc
		(start 128.901698 -37.134546)
		(mid 128.681634 -37.090772)
		(end 128.495044 -36.966144)
		(width 0.136652)
		(layer "F.Cu")
		(net "USB2_BMC_DP")
	)
	(arc
		(start 127.73787 -34.67481)
		(mid 127.8285 -34.312728)
		(end 128.078992 -34.036)
		(width 0.136652)
		(layer "F.Cu")
		(net "USB2_BMC_DP")
	)
	(arc
		(start 127.838454 -36.309554)
		(mid 127.764013 -36.198145)
		(end 127.73787 -36.06673)
		(width 0.136652)
		(layer "F.Cu")
		(net "USB2_BMC_DP")
	)
	(arc
		(start 132.766816 -38.275514)
		(mid 132.697704 -37.928447)
		(end 132.501132 -37.634164)
		(width 0.136652)
		(layer "F.Cu")
		(net "USB2_BMC_DP")
	)
	(arc
		(start 102.271576 -81.7118)
		(mid 102.541247 -81.834399)
		(end 102.62616 -82.1182)
		(width 0.136652)
		(layer "F.Cu")
		(net "USB2_BMC_DP")
	)
	(arc
		(start 56.25084 -86.32825)
		(mid 56.377311 -86.022921)
		(end 56.68264 -85.89645)
		(width 0.136652)
		(layer "F.Cu")
		(net "USB2_BMC_DP")
	)
	(segment
		(start 122.46991 -39.142416)
		(end 124.227844 -40.90035)
		(width 0.1397)
		(layer "In2.Cu")
		(net "USB2_BMC_DP")
	)
	(segment
		(start 29.477208 -86.78545)
		(end 28.140914 -86.78545)
		(width 0.1397)
		(layer "In2.Cu")
		(net "USB2_BMC_DP")
	)
	(segment
		(start 21.707094 -91.528646)
		(end 20.507706 -91.528646)
		(width 0.1397)
		(layer "In2.Cu")
		(net "USB2_BMC_DP")
	)
	(segment
		(start 128.717548 -40.90035)
		(end 130.133598 -42.3164)
		(width 0.1397)
		(layer "In2.Cu")
		(net "USB2_BMC_DP")
	)
	(segment
		(start 12.118594 -140.21435)
		(end 12.356592 -140.21435)
		(width 0.1397)
		(layer "In2.Cu")
		(net "USB2_BMC_DP")
	)
	(segment
		(start 25.70734 -143.002)
		(end 26.12898 -142.58036)
		(width 0.1397)
		(layer "In2.Cu")
		(net "USB2_BMC_DP")
	)
	(segment
		(start 55.799228 -85.93455)
		(end 44.215304 -85.93455)
		(width 0.1397)
		(layer "In2.Cu")
		(net "USB2_BMC_DP")
	)
	(segment
		(start 105.3338 -77.020674)
		(end 105.5116 -76.842874)
		(width 0.1397)
		(layer "In2.Cu")
		(net "USB2_BMC_DP")
	)
	(segment
		(start 105.3338 -78.214474)
		(end 105.5116 -78.036674)
		(width 0.1397)
		(layer "In2.Cu")
		(net "USB2_BMC_DP")
	)
	(segment
		(start 27.861514 -87.06485)
		(end 26.986992 -87.06485)
		(width 0.1397)
		(layer "In2.Cu")
		(net "USB2_BMC_DP")
	)
	(segment
		(start 23.595838 -90.456004)
		(end 22.779736 -90.456004)
		(width 0.1397)
		(layer "In2.Cu")
		(net "USB2_BMC_DP")
	)
	(segment
		(start 22.780752 -145.091404)
		(end 24.870156 -143.002)
		(width 0.1397)
		(layer "In2.Cu")
		(net "USB2_BMC_DP")
	)
	(segment
		(start 131.746244 -42.693844)
		(end 131.746244 -42.7228)
		(width 0.1397)
		(layer "In2.Cu")
		(net "USB2_BMC_DP")
	)
	(segment
		(start 24.870156 -143.002)
		(end 25.70734 -143.002)
		(width 0.1397)
		(layer "In2.Cu")
		(net "USB2_BMC_DP")
	)
	(segment
		(start 18.469864 -146.08175)
		(end 19.962114 -147.574)
		(width 0.1397)
		(layer "In2.Cu")
		(net "USB2_BMC_DP")
	)
	(segment
		(start 119.113808 -39.142416)
		(end 122.46991 -39.142416)
		(width 0.1397)
		(layer "In2.Cu")
		(net "USB2_BMC_DP")
	)
	(segment
		(start 22.779736 -90.456004)
		(end 21.707094 -91.528646)
		(width 0.1397)
		(layer "In2.Cu")
		(net "USB2_BMC_DP")
	)
	(segment
		(start 19.962114 -147.574)
		(end 21.481034 -147.574)
		(width 0.1397)
		(layer "In2.Cu")
		(net "USB2_BMC_DP")
	)
	(segment
		(start 105.5116 -75.649074)
		(end 105.5116 -75.229974)
		(width 0.1397)
		(layer "In2.Cu")
		(net "USB2_BMC_DP")
	)
	(segment
		(start 105.3338 -80.324706)
		(end 105.3338 -78.214474)
		(width 0.1397)
		(layer "In2.Cu")
		(net "USB2_BMC_DP")
	)
	(segment
		(start 13.943076 -97.34423)
		(end 13.943076 -97.682812)
		(width 0.1397)
		(layer "In2.Cu")
		(net "USB2_BMC_DP")
	)
	(segment
		(start 4.23291 -111.471456)
		(end 4.23291 -132.387086)
		(width 0.1397)
		(layer "In2.Cu")
		(net "USB2_BMC_DP")
	)
	(segment
		(start 105.3338 -75.052174)
		(end 105.3338 -44.6278)
		(width 0.1397)
		(layer "In2.Cu")
		(net "USB2_BMC_DP")
	)
	(segment
		(start 4.23291 -132.387086)
		(end 12.059412 -140.213588)
		(width 0.1397)
		(layer "In2.Cu")
		(net "USB2_BMC_DP")
	)
	(segment
		(start 44.215304 -85.93455)
		(end 43.051984 -87.09787)
		(width 0.1397)
		(layer "In2.Cu")
		(net "USB2_BMC_DP")
	)
	(segment
		(start 22.780752 -146.274282)
		(end 22.780752 -145.091404)
		(width 0.1397)
		(layer "In2.Cu")
		(net "USB2_BMC_DP")
	)
	(segment
		(start 105.3338 -77.439774)
		(end 105.3338 -77.020674)
		(width 0.1397)
		(layer "In2.Cu")
		(net "USB2_BMC_DP")
	)
	(segment
		(start 105.5116 -76.423774)
		(end 105.3338 -76.245974)
		(width 0.1397)
		(layer "In2.Cu")
		(net "USB2_BMC_DP")
	)
	(segment
		(start 43.051984 -87.09787)
		(end 37.74567 -87.09787)
		(width 0.1397)
		(layer "In2.Cu")
		(net "USB2_BMC_DP")
	)
	(segment
		(start 124.227844 -40.90035)
		(end 128.717548 -40.90035)
		(width 0.1397)
		(layer "In2.Cu")
		(net "USB2_BMC_DP")
	)
	(segment
		(start 103.07066 -81.6737)
		(end 103.984806 -81.6737)
		(width 0.1397)
		(layer "In2.Cu")
		(net "USB2_BMC_DP")
	)
	(segment
		(start 13.943076 -97.682812)
		(end 7.480046 -104.145842)
		(width 0.1397)
		(layer "In2.Cu")
		(net "USB2_BMC_DP")
	)
	(segment
		(start 18.223992 -146.08175)
		(end 18.469864 -146.08175)
		(width 0.1397)
		(layer "In2.Cu")
		(net "USB2_BMC_DP")
	)
	(segment
		(start 12.356592 -140.21435)
		(end 18.223992 -146.08175)
		(width 0.1397)
		(layer "In2.Cu")
		(net "USB2_BMC_DP")
	)
	(segment
		(start 105.5116 -76.842874)
		(end 105.5116 -76.423774)
		(width 0.1397)
		(layer "In2.Cu")
		(net "USB2_BMC_DP")
	)
	(segment
		(start 7.480046 -104.145842)
		(end 7.480046 -108.22432)
		(width 0.1397)
		(layer "In2.Cu")
		(net "USB2_BMC_DP")
	)
	(segment
		(start 37.26815 -86.62035)
		(end 29.642308 -86.62035)
		(width 0.1397)
		(layer "In2.Cu")
		(net "USB2_BMC_DP")
	)
	(segment
		(start 105.5116 -75.229974)
		(end 105.3338 -75.052174)
		(width 0.1397)
		(layer "In2.Cu")
		(net "USB2_BMC_DP")
	)
	(segment
		(start 28.140914 -86.78545)
		(end 27.861514 -87.06485)
		(width 0.1397)
		(layer "In2.Cu")
		(net "USB2_BMC_DP")
	)
	(segment
		(start 7.480046 -108.22432)
		(end 4.23291 -111.471456)
		(width 0.1397)
		(layer "In2.Cu")
		(net "USB2_BMC_DP")
	)
	(segment
		(start 103.984806 -81.6737)
		(end 105.3338 -80.324706)
		(width 0.1397)
		(layer "In2.Cu")
		(net "USB2_BMC_DP")
	)
	(segment
		(start 37.74567 -87.09787)
		(end 37.26815 -86.62035)
		(width 0.1397)
		(layer "In2.Cu")
		(net "USB2_BMC_DP")
	)
	(segment
		(start 21.481034 -147.574)
		(end 22.780752 -146.274282)
		(width 0.1397)
		(layer "In2.Cu")
		(net "USB2_BMC_DP")
	)
	(segment
		(start 105.5116 -78.036674)
		(end 105.5116 -77.617574)
		(width 0.1397)
		(layer "In2.Cu")
		(net "USB2_BMC_DP")
	)
	(segment
		(start 105.3338 -76.245974)
		(end 105.3338 -75.826874)
		(width 0.1397)
		(layer "In2.Cu")
		(net "USB2_BMC_DP")
	)
	(segment
		(start 29.642308 -86.62035)
		(end 29.477208 -86.78545)
		(width 0.1397)
		(layer "In2.Cu")
		(net "USB2_BMC_DP")
	)
	(segment
		(start 12.117832 -140.213588)
		(end 12.118594 -140.21435)
		(width 0.1397)
		(layer "In2.Cu")
		(net "USB2_BMC_DP")
	)
	(segment
		(start 105.5116 -77.617574)
		(end 105.3338 -77.439774)
		(width 0.1397)
		(layer "In2.Cu")
		(net "USB2_BMC_DP")
	)
	(segment
		(start 105.3338 -44.6278)
		(end 109.6772 -40.2844)
		(width 0.1397)
		(layer "In2.Cu")
		(net "USB2_BMC_DP")
	)
	(segment
		(start 20.507706 -91.528646)
		(end 19.376898 -92.659454)
		(width 0.1397)
		(layer "In2.Cu")
		(net "USB2_BMC_DP")
	)
	(segment
		(start 117.971824 -40.2844)
		(end 119.113808 -39.142416)
		(width 0.1397)
		(layer "In2.Cu")
		(net "USB2_BMC_DP")
	)
	(segment
		(start 105.3338 -75.826874)
		(end 105.5116 -75.649074)
		(width 0.1397)
		(layer "In2.Cu")
		(net "USB2_BMC_DP")
	)
	(segment
		(start 12.059412 -140.213588)
		(end 12.117832 -140.213588)
		(width 0.1397)
		(layer "In2.Cu")
		(net "USB2_BMC_DP")
	)
	(segment
		(start 109.6772 -40.2844)
		(end 117.971824 -40.2844)
		(width 0.1397)
		(layer "In2.Cu")
		(net "USB2_BMC_DP")
	)
	(segment
		(start 19.376898 -92.659454)
		(end 18.627852 -92.659454)
		(width 0.1397)
		(layer "In2.Cu")
		(net "USB2_BMC_DP")
	)
	(segment
		(start 18.627852 -92.659454)
		(end 13.943076 -97.34423)
		(width 0.1397)
		(layer "In2.Cu")
		(net "USB2_BMC_DP")
	)
	(segment
		(start 26.986992 -87.06485)
		(end 23.595838 -90.456004)
		(width 0.1397)
		(layer "In2.Cu")
		(net "USB2_BMC_DP")
	)
	(segment
		(start 130.133598 -42.3164)
		(end 131.3688 -42.3164)
		(width 0.1397)
		(layer "In2.Cu")
		(net "USB2_BMC_DP")
	)
	(arc
		(start 56.25084 -86.32825)
		(mid 56.098775 -86.046827)
		(end 55.799228 -85.93455)
		(width 0.1397)
		(layer "In2.Cu")
		(net "USB2_BMC_DP")
	)
	(arc
		(start 102.62616 -82.1182)
		(mid 102.756351 -81.803891)
		(end 103.07066 -81.6737)
		(width 0.1397)
		(layer "In2.Cu")
		(net "USB2_BMC_DP")
	)
	(arc
		(start 131.3688 -42.3164)
		(mid 131.635693 -42.426951)
		(end 131.746244 -42.693844)
		(width 0.1397)
		(layer "In2.Cu")
		(net "USB2_BMC_DP")
	)
	(segment
		(start 128.901952 -37.439346)
		(end 131.459986 -37.439346)
		(width 0.136652)
		(layer "F.Cu")
		(net "USB2_BMC_DN")
	)
	(segment
		(start 60.2488 -89.5223)
		(end 60.2488 -88.659716)
		(width 0.136652)
		(layer "F.Cu")
		(net "USB2_BMC_DN")
	)
	(segment
		(start 132.276596 -41.9862)
		(end 132.127244 -41.9862)
		(width 0.136652)
		(layer "F.Cu")
		(net "USB2_BMC_DN")
	)
	(segment
		(start 128.901698 -37.4396)
		(end 128.901952 -37.439346)
		(width 0.136652)
		(layer "F.Cu")
		(net "USB2_BMC_DN")
	)
	(segment
		(start 127.622808 -36.5252)
		(end 128.279398 -37.18179)
		(width 0.136652)
		(layer "F.Cu")
		(net "USB2_BMC_DN")
	)
	(segment
		(start 73.620884 -93.738192)
		(end 64.464692 -93.738192)
		(width 0.136652)
		(layer "F.Cu")
		(net "USB2_BMC_DN")
	)
	(segment
		(start 92.862908 -93.0656)
		(end 74.293476 -93.0656)
		(width 0.136652)
		(layer "F.Cu")
		(net "USB2_BMC_DN")
	)
	(segment
		(start 132.461 -38.52545)
		(end 132.461 -41.801796)
		(width 0.136652)
		(layer "F.Cu")
		(net "USB2_BMC_DN")
	)
	(segment
		(start 102.21976 -81.407)
		(end 99.720908 -81.407)
		(width 0.136652)
		(layer "F.Cu")
		(net "USB2_BMC_DN")
	)
	(segment
		(start 26.12898 -143.69796)
		(end 26.54554 -143.2814)
		(width 0.136652)
		(layer "F.Cu")
		(net "USB2_BMC_DN")
	)
	(segment
		(start 132.462016 -38.275768)
		(end 132.462016 -38.52545)
		(width 0.136652)
		(layer "F.Cu")
		(net "USB2_BMC_DN")
	)
	(segment
		(start 26.54554 -143.2814)
		(end 26.8859 -143.2814)
		(width 0.136652)
		(layer "F.Cu")
		(net "USB2_BMC_DN")
	)
	(segment
		(start 56.25084 -85.22081)
		(end 56.25084 -85.21065)
		(width 0.136652)
		(layer "F.Cu")
		(net "USB2_BMC_DN")
	)
	(segment
		(start 98.1202 -87.808308)
		(end 92.862908 -93.0656)
		(width 0.136652)
		(layer "F.Cu")
		(net "USB2_BMC_DN")
	)
	(segment
		(start 132.462016 -38.52545)
		(end 132.461 -38.52545)
		(width 0.136652)
		(layer "F.Cu")
		(net "USB2_BMC_DN")
	)
	(segment
		(start 127.43307 -34.672016)
		(end 127.43307 -36.06673)
		(width 0.136652)
		(layer "F.Cu")
		(net "USB2_BMC_DN")
	)
	(segment
		(start 98.1202 -83.007708)
		(end 98.1202 -87.808308)
		(width 0.136652)
		(layer "F.Cu")
		(net "USB2_BMC_DN")
	)
	(segment
		(start 26.8859 -143.2814)
		(end 27.2415 -143.637)
		(width 0.136652)
		(layer "F.Cu")
		(net "USB2_BMC_DN")
	)
	(segment
		(start 128.901698 -37.439346)
		(end 128.901698 -37.4396)
		(width 0.136652)
		(layer "F.Cu")
		(net "USB2_BMC_DN")
	)
	(segment
		(start 99.720908 -81.407)
		(end 98.1202 -83.007708)
		(width 0.136652)
		(layer "F.Cu")
		(net "USB2_BMC_DN")
	)
	(segment
		(start 132.168392 -37.732716)
		(end 132.285486 -37.84981)
		(width 0.136652)
		(layer "F.Cu")
		(net "USB2_BMC_DN")
	)
	(segment
		(start 60.2488 -88.659716)
		(end 57.180734 -85.59165)
		(width 0.136652)
		(layer "F.Cu")
		(net "USB2_BMC_DN")
	)
	(segment
		(start 74.293476 -93.0656)
		(end 73.620884 -93.738192)
		(width 0.136652)
		(layer "F.Cu")
		(net "USB2_BMC_DN")
	)
	(segment
		(start 64.464692 -93.738192)
		(end 60.2488 -89.5223)
		(width 0.136652)
		(layer "F.Cu")
		(net "USB2_BMC_DN")
	)
	(segment
		(start 57.180734 -85.59165)
		(end 56.62168 -85.59165)
		(width 0.136652)
		(layer "F.Cu")
		(net "USB2_BMC_DN")
	)
	(via
		(at 56.25084 -85.21065)
		(size 0.508)
		(drill 0.254)
		(layers "F.Cu" "B.Cu")
		(net "USB2_BMC_DN")
	)
	(via
		(at 131.746244 -41.6052)
		(size 0.508)
		(drill 0.254)
		(layers "F.Cu" "B.Cu")
		(net "USB2_BMC_DN")
	)
	(via
		(at 102.62616 -81.0006)
		(size 0.508)
		(drill 0.254)
		(layers "F.Cu" "B.Cu")
		(net "USB2_BMC_DN")
	)
	(via
		(at 26.12898 -143.69796)
		(size 0.508)
		(drill 0.254)
		(layers "F.Cu" "B.Cu")
		(net "USB2_BMC_DN")
	)
	(arc
		(start 132.461 -41.801796)
		(mid 132.44688 -41.872311)
		(end 132.406898 -41.932098)
		(width 0.136652)
		(layer "F.Cu")
		(net "USB2_BMC_DN")
	)
	(arc
		(start 132.406898 -41.932098)
		(mid 132.34713 -41.972127)
		(end 132.276596 -41.9862)
		(width 0.136652)
		(layer "F.Cu")
		(net "USB2_BMC_DN")
	)
	(arc
		(start 132.127244 -41.9862)
		(mid 131.857836 -41.874608)
		(end 131.746244 -41.6052)
		(width 0.136652)
		(layer "F.Cu")
		(net "USB2_BMC_DN")
	)
	(arc
		(start 56.62168 -85.59165)
		(mid 56.359457 -85.483033)
		(end 56.25084 -85.22081)
		(width 0.136652)
		(layer "F.Cu")
		(net "USB2_BMC_DN")
	)
	(arc
		(start 127.060452 -34.036)
		(mid 127.333012 -34.303467)
		(end 127.43307 -34.672016)
		(width 0.136652)
		(layer "F.Cu")
		(net "USB2_BMC_DN")
	)
	(arc
		(start 127.43307 -36.06673)
		(mid 127.482329 -36.314842)
		(end 127.622808 -36.5252)
		(width 0.136652)
		(layer "F.Cu")
		(net "USB2_BMC_DN")
	)
	(arc
		(start 102.62616 -81.0006)
		(mid 102.507128 -81.287968)
		(end 102.21976 -81.407)
		(width 0.136652)
		(layer "F.Cu")
		(net "USB2_BMC_DN")
	)
	(arc
		(start 132.285486 -37.84981)
		(mid 132.416152 -38.045226)
		(end 132.462016 -38.275768)
		(width 0.136652)
		(layer "F.Cu")
		(net "USB2_BMC_DN")
	)
	(arc
		(start 128.279398 -37.18179)
		(mid 128.564927 -37.372481)
		(end 128.901698 -37.439346)
		(width 0.136652)
		(layer "F.Cu")
		(net "USB2_BMC_DN")
	)
	(arc
		(start 131.459986 -37.439346)
		(mid 131.843363 -37.515587)
		(end 132.168392 -37.732716)
		(width 0.136652)
		(layer "F.Cu")
		(net "USB2_BMC_DN")
	)
	(segment
		(start 23.458932 -90.125804)
		(end 22.64283 -90.125804)
		(width 0.1397)
		(layer "In2.Cu")
		(net "USB2_BMC_DN")
	)
	(segment
		(start 118.976902 -38.812216)
		(end 117.834918 -39.9542)
		(width 0.1397)
		(layer "In2.Cu")
		(net "USB2_BMC_DN")
	)
	(segment
		(start 27.724608 -86.73465)
		(end 26.850086 -86.73465)
		(width 0.1397)
		(layer "In2.Cu")
		(net "USB2_BMC_DN")
	)
	(segment
		(start 37.882576 -86.76767)
		(end 37.405056 -86.29015)
		(width 0.1397)
		(layer "In2.Cu")
		(net "USB2_BMC_DN")
	)
	(segment
		(start 109.540294 -39.9542)
		(end 105.0036 -44.490894)
		(width 0.1397)
		(layer "In2.Cu")
		(net "USB2_BMC_DN")
	)
	(segment
		(start 21.61794 -147.9042)
		(end 23.110952 -146.411188)
		(width 0.1397)
		(layer "In2.Cu")
		(net "USB2_BMC_DN")
	)
	(segment
		(start 18.332958 -146.41195)
		(end 19.825208 -147.9042)
		(width 0.1397)
		(layer "In2.Cu")
		(net "USB2_BMC_DN")
	)
	(segment
		(start 42.915078 -86.76767)
		(end 37.882576 -86.76767)
		(width 0.1397)
		(layer "In2.Cu")
		(net "USB2_BMC_DN")
	)
	(segment
		(start 29.340302 -86.45525)
		(end 28.004008 -86.45525)
		(width 0.1397)
		(layer "In2.Cu")
		(net "USB2_BMC_DN")
	)
	(segment
		(start 28.004008 -86.45525)
		(end 27.724608 -86.73465)
		(width 0.1397)
		(layer "In2.Cu")
		(net "USB2_BMC_DN")
	)
	(segment
		(start 20.3708 -91.198446)
		(end 19.239992 -92.329254)
		(width 0.1397)
		(layer "In2.Cu")
		(net "USB2_BMC_DN")
	)
	(segment
		(start 3.90271 -111.33455)
		(end 3.90271 -132.523992)
		(width 0.1397)
		(layer "In2.Cu")
		(net "USB2_BMC_DN")
	)
	(segment
		(start 7.149846 -104.008936)
		(end 7.149846 -108.087414)
		(width 0.1397)
		(layer "In2.Cu")
		(net "USB2_BMC_DN")
	)
	(segment
		(start 44.078398 -85.60435)
		(end 42.915078 -86.76767)
		(width 0.1397)
		(layer "In2.Cu")
		(net "USB2_BMC_DN")
	)
	(segment
		(start 29.505402 -86.29015)
		(end 29.340302 -86.45525)
		(width 0.1397)
		(layer "In2.Cu")
		(net "USB2_BMC_DN")
	)
	(segment
		(start 105.0036 -80.1878)
		(end 103.8479 -81.3435)
		(width 0.1397)
		(layer "In2.Cu")
		(net "USB2_BMC_DN")
	)
	(segment
		(start 25.76322 -143.3322)
		(end 26.12898 -143.69796)
		(width 0.1397)
		(layer "In2.Cu")
		(net "USB2_BMC_DN")
	)
	(segment
		(start 11.922506 -140.543788)
		(end 11.980926 -140.543788)
		(width 0.1397)
		(layer "In2.Cu")
		(net "USB2_BMC_DN")
	)
	(segment
		(start 55.799228 -85.60435)
		(end 44.078398 -85.60435)
		(width 0.1397)
		(layer "In2.Cu")
		(net "USB2_BMC_DN")
	)
	(segment
		(start 128.854454 -40.57015)
		(end 124.36475 -40.57015)
		(width 0.1397)
		(layer "In2.Cu")
		(net "USB2_BMC_DN")
	)
	(segment
		(start 124.36475 -40.57015)
		(end 122.606816 -38.812216)
		(width 0.1397)
		(layer "In2.Cu")
		(net "USB2_BMC_DN")
	)
	(segment
		(start 11.980926 -140.543788)
		(end 11.981688 -140.54455)
		(width 0.1397)
		(layer "In2.Cu")
		(net "USB2_BMC_DN")
	)
	(segment
		(start 130.270504 -41.9862)
		(end 128.854454 -40.57015)
		(width 0.1397)
		(layer "In2.Cu")
		(net "USB2_BMC_DN")
	)
	(segment
		(start 19.239992 -92.329254)
		(end 18.490946 -92.329254)
		(width 0.1397)
		(layer "In2.Cu")
		(net "USB2_BMC_DN")
	)
	(segment
		(start 23.110952 -145.22831)
		(end 25.007062 -143.3322)
		(width 0.1397)
		(layer "In2.Cu")
		(net "USB2_BMC_DN")
	)
	(segment
		(start 21.570188 -91.198446)
		(end 20.3708 -91.198446)
		(width 0.1397)
		(layer "In2.Cu")
		(net "USB2_BMC_DN")
	)
	(segment
		(start 105.0036 -44.490894)
		(end 105.0036 -80.1878)
		(width 0.1397)
		(layer "In2.Cu")
		(net "USB2_BMC_DN")
	)
	(segment
		(start 25.007062 -143.3322)
		(end 25.76322 -143.3322)
		(width 0.1397)
		(layer "In2.Cu")
		(net "USB2_BMC_DN")
	)
	(segment
		(start 13.612876 -97.545906)
		(end 7.149846 -104.008936)
		(width 0.1397)
		(layer "In2.Cu")
		(net "USB2_BMC_DN")
	)
	(segment
		(start 131.746244 -41.6052)
		(end 131.746244 -41.6306)
		(width 0.1397)
		(layer "In2.Cu")
		(net "USB2_BMC_DN")
	)
	(segment
		(start 18.087086 -146.41195)
		(end 18.332958 -146.41195)
		(width 0.1397)
		(layer "In2.Cu")
		(net "USB2_BMC_DN")
	)
	(segment
		(start 19.825208 -147.9042)
		(end 21.61794 -147.9042)
		(width 0.1397)
		(layer "In2.Cu")
		(net "USB2_BMC_DN")
	)
	(segment
		(start 117.834918 -39.9542)
		(end 109.540294 -39.9542)
		(width 0.1397)
		(layer "In2.Cu")
		(net "USB2_BMC_DN")
	)
	(segment
		(start 26.850086 -86.73465)
		(end 23.458932 -90.125804)
		(width 0.1397)
		(layer "In2.Cu")
		(net "USB2_BMC_DN")
	)
	(segment
		(start 131.390644 -41.9862)
		(end 130.270504 -41.9862)
		(width 0.1397)
		(layer "In2.Cu")
		(net "USB2_BMC_DN")
	)
	(segment
		(start 102.62616 -81.005172)
		(end 102.62616 -81.0006)
		(width 0.1397)
		(layer "In2.Cu")
		(net "USB2_BMC_DN")
	)
	(segment
		(start 18.490946 -92.329254)
		(end 13.612876 -97.207324)
		(width 0.1397)
		(layer "In2.Cu")
		(net "USB2_BMC_DN")
	)
	(segment
		(start 37.405056 -86.29015)
		(end 29.505402 -86.29015)
		(width 0.1397)
		(layer "In2.Cu")
		(net "USB2_BMC_DN")
	)
	(segment
		(start 11.981688 -140.54455)
		(end 12.219686 -140.54455)
		(width 0.1397)
		(layer "In2.Cu")
		(net "USB2_BMC_DN")
	)
	(segment
		(start 22.64283 -90.125804)
		(end 21.570188 -91.198446)
		(width 0.1397)
		(layer "In2.Cu")
		(net "USB2_BMC_DN")
	)
	(segment
		(start 23.110952 -146.411188)
		(end 23.110952 -145.22831)
		(width 0.1397)
		(layer "In2.Cu")
		(net "USB2_BMC_DN")
	)
	(segment
		(start 103.8479 -81.3435)
		(end 102.964488 -81.3435)
		(width 0.1397)
		(layer "In2.Cu")
		(net "USB2_BMC_DN")
	)
	(segment
		(start 122.606816 -38.812216)
		(end 118.976902 -38.812216)
		(width 0.1397)
		(layer "In2.Cu")
		(net "USB2_BMC_DN")
	)
	(segment
		(start 7.149846 -108.087414)
		(end 3.90271 -111.33455)
		(width 0.1397)
		(layer "In2.Cu")
		(net "USB2_BMC_DN")
	)
	(segment
		(start 3.90271 -132.523992)
		(end 11.922506 -140.543788)
		(width 0.1397)
		(layer "In2.Cu")
		(net "USB2_BMC_DN")
	)
	(segment
		(start 13.612876 -97.207324)
		(end 13.612876 -97.545906)
		(width 0.1397)
		(layer "In2.Cu")
		(net "USB2_BMC_DN")
	)
	(segment
		(start 12.219686 -140.54455)
		(end 18.087086 -146.41195)
		(width 0.1397)
		(layer "In2.Cu")
		(net "USB2_BMC_DN")
	)
	(arc
		(start 102.964488 -81.3435)
		(mid 102.725254 -81.244406)
		(end 102.62616 -81.005172)
		(width 0.1397)
		(layer "In2.Cu")
		(net "USB2_BMC_DN")
	)
	(arc
		(start 56.25084 -85.21065)
		(mid 56.098775 -85.492073)
		(end 55.799228 -85.60435)
		(width 0.1397)
		(layer "In2.Cu")
		(net "USB2_BMC_DN")
	)
	(arc
		(start 131.746244 -41.6306)
		(mid 131.642091 -41.882047)
		(end 131.390644 -41.9862)
		(width 0.1397)
		(layer "In2.Cu")
		(net "USB2_BMC_DN")
	)
	(segment
		(start 40.53967 -122.519694)
		(end 40.904922 -122.884946)
		(width 0.12065)
		(layer "F.Cu")
		(net "TP_RGMIICK")
	)
	(segment
		(start 42.75328 -115.640612)
		(end 42.75328 -117.59946)
		(width 0.12065)
		(layer "F.Cu")
		(net "TP_RGMIICK")
	)
	(segment
		(start 40.53967 -120.42521)
		(end 40.53967 -122.519694)
		(width 0.12065)
		(layer "F.Cu")
		(net "TP_RGMIICK")
	)
	(segment
		(start 42.75328 -117.59946)
		(end 41.34866 -119.00408)
		(width 0.12065)
		(layer "F.Cu")
		(net "TP_RGMIICK")
	)
	(segment
		(start 41.34866 -119.61622)
		(end 40.53967 -120.42521)
		(width 0.12065)
		(layer "F.Cu")
		(net "TP_RGMIICK")
	)
	(segment
		(start 41.34866 -119.00408)
		(end 41.34866 -119.61622)
		(width 0.12065)
		(layer "F.Cu")
		(net "TP_RGMIICK")
	)
	(segment
		(start 49.35601 -127.684784)
		(end 46.50486 -127.684784)
		(width 0.12065)
		(layer "F.Cu")
		(net "TCA9554_INT_N_R")
	)
	(segment
		(start 50.495962 -127.404114)
		(end 49.63668 -127.404114)
		(width 0.12065)
		(layer "F.Cu")
		(net "TCA9554_INT_N_R")
	)
	(segment
		(start 49.63668 -127.404114)
		(end 49.35601 -127.684784)
		(width 0.12065)
		(layer "F.Cu")
		(net "TCA9554_INT_N_R")
	)
	(segment
		(start 55.106316 -126.818898)
		(end 56.419496 -125.505718)
		(width 0.12065)
		(layer "F.Cu")
		(net "TCA9554_INT_N_R")
	)
	(segment
		(start 56.419496 -125.215904)
		(end 56.8706 -124.7648)
		(width 0.12065)
		(layer "F.Cu")
		(net "TCA9554_INT_N_R")
	)
	(segment
		(start 50.495962 -127.404114)
		(end 52.254912 -127.404114)
		(width 0.12065)
		(layer "F.Cu")
		(net "TCA9554_INT_N_R")
	)
	(segment
		(start 56.419496 -125.505718)
		(end 56.419496 -125.215904)
		(width 0.12065)
		(layer "F.Cu")
		(net "TCA9554_INT_N_R")
	)
	(segment
		(start 52.254912 -127.404114)
		(end 52.840128 -126.818898)
		(width 0.12065)
		(layer "F.Cu")
		(net "TCA9554_INT_N_R")
	)
	(segment
		(start 52.840128 -126.818898)
		(end 55.106316 -126.818898)
		(width 0.12065)
		(layer "F.Cu")
		(net "TCA9554_INT_N_R")
	)
	(via
		(at 50.495962 -127.404114)
		(size 0.7112)
		(drill 0.3556)
		(layers "F.Cu" "B.Cu")
		(net "TCA9554_INT_N_R")
	)
	(segment
		(start 205.69555 -17.617186)
		(end 207.4164 -19.338036)
		(width 0.12065)
		(layer "F.Cu")
		(net "TCA9554_INT_N")
	)
	(segment
		(start 207.4164 -21.08835)
		(end 206.53375 -21.971)
		(width 0.12065)
		(layer "F.Cu")
		(net "TCA9554_INT_N")
	)
	(segment
		(start 57.3532 -122.7836)
		(end 57.3532 -124.003054)
		(width 0.12065)
		(layer "F.Cu")
		(net "TCA9554_INT_N")
	)
	(segment
		(start 57.5818 -114.046)
		(end 57.5818 -116.031264)
		(width 0.12065)
		(layer "F.Cu")
		(net "TCA9554_INT_N")
	)
	(segment
		(start 205.69555 -17.61363)
		(end 205.69555 -17.617186)
		(width 0.12065)
		(layer "F.Cu")
		(net "TCA9554_INT_N")
	)
	(segment
		(start 58.518298 -116.967762)
		(end 58.518298 -121.618502)
		(width 0.12065)
		(layer "F.Cu")
		(net "TCA9554_INT_N")
	)
	(segment
		(start 57.7596 -124.409454)
		(end 57.7596 -124.7648)
		(width 0.12065)
		(layer "F.Cu")
		(net "TCA9554_INT_N")
	)
	(segment
		(start 207.4164 -19.338036)
		(end 207.4164 -21.08835)
		(width 0.12065)
		(layer "F.Cu")
		(net "TCA9554_INT_N")
	)
	(segment
		(start 206.53375 -21.971)
		(end 205.8035 -21.971)
		(width 0.12065)
		(layer "F.Cu")
		(net "TCA9554_INT_N")
	)
	(segment
		(start 57.3532 -124.003054)
		(end 57.7596 -124.409454)
		(width 0.12065)
		(layer "F.Cu")
		(net "TCA9554_INT_N")
	)
	(segment
		(start 57.5818 -116.031264)
		(end 58.518298 -116.967762)
		(width 0.12065)
		(layer "F.Cu")
		(net "TCA9554_INT_N")
	)
	(segment
		(start 58.1406 -113.4872)
		(end 57.5818 -114.046)
		(width 0.12065)
		(layer "F.Cu")
		(net "TCA9554_INT_N")
	)
	(segment
		(start 58.518298 -121.618502)
		(end 57.3532 -122.7836)
		(width 0.12065)
		(layer "F.Cu")
		(net "TCA9554_INT_N")
	)
	(segment
		(start 205.260956 -17.179036)
		(end 205.69555 -17.61363)
		(width 0.12065)
		(layer "F.Cu")
		(net "TCA9554_INT_N")
	)
	(via
		(at 205.260956 -17.179036)
		(size 0.508)
		(drill 0.254)
		(layers "F.Cu" "B.Cu")
		(net "TCA9554_INT_N")
	)
	(via
		(at 207.4164 -21.08835)
		(size 0.7112)
		(drill 0.3556)
		(layers "F.Cu" "B.Cu")
		(net "TCA9554_INT_N")
	)
	(via
		(at 58.1406 -113.4872)
		(size 0.508)
		(drill 0.254)
		(layers "F.Cu" "B.Cu")
		(net "TCA9554_INT_N")
	)
	(segment
		(start 113.919 -28.360116)
		(end 113.919 -41.007284)
		(width 0.127)
		(layer "In5.Cu")
		(net "TCA9554_INT_N")
	)
	(segment
		(start 113.792 -41.134284)
		(end 113.792 -48.429164)
		(width 0.127)
		(layer "In5.Cu")
		(net "TCA9554_INT_N")
	)
	(segment
		(start 126.4539 -12.788138)
		(end 126.4539 -15.825216)
		(width 0.127)
		(layer "In5.Cu")
		(net "TCA9554_INT_N")
	)
	(segment
		(start 173.97857 -5.05841)
		(end 134.183628 -5.05841)
		(width 0.127)
		(layer "In5.Cu")
		(net "TCA9554_INT_N")
	)
	(segment
		(start 63.75654 -94.370906)
		(end 64.4017 -95.016066)
		(width 0.127)
		(layer "In5.Cu")
		(net "TCA9554_INT_N")
	)
	(segment
		(start 205.260956 -17.179036)
		(end 204.90942 -16.8275)
		(width 0.127)
		(layer "In5.Cu")
		(net "TCA9554_INT_N")
	)
	(segment
		(start 204.90942 -16.8275)
		(end 202.344782 -16.8275)
		(width 0.127)
		(layer "In5.Cu")
		(net "TCA9554_INT_N")
	)
	(segment
		(start 202.344782 -16.8275)
		(end 200.693782 -18.4785)
		(width 0.127)
		(layer "In5.Cu")
		(net "TCA9554_INT_N")
	)
	(segment
		(start 63.75654 -77.260196)
		(end 63.75654 -94.370906)
		(width 0.127)
		(layer "In5.Cu")
		(net "TCA9554_INT_N")
	)
	(segment
		(start 195.4657 -18.4785)
		(end 191.535304 -14.548104)
		(width 0.127)
		(layer "In5.Cu")
		(net "TCA9554_INT_N")
	)
	(segment
		(start 200.693782 -18.4785)
		(end 195.4657 -18.4785)
		(width 0.127)
		(layer "In5.Cu")
		(net "TCA9554_INT_N")
	)
	(segment
		(start 179.93741 -12.596622)
		(end 179.93741 -11.01725)
		(width 0.127)
		(layer "In5.Cu")
		(net "TCA9554_INT_N")
	)
	(segment
		(start 126.4539 -15.825216)
		(end 113.919 -28.360116)
		(width 0.127)
		(layer "In5.Cu")
		(net "TCA9554_INT_N")
	)
	(segment
		(start 179.93741 -11.01725)
		(end 173.97857 -5.05841)
		(width 0.127)
		(layer "In5.Cu")
		(net "TCA9554_INT_N")
	)
	(segment
		(start 64.4017 -108.195618)
		(end 59.110118 -113.4872)
		(width 0.127)
		(layer "In5.Cu")
		(net "TCA9554_INT_N")
	)
	(segment
		(start 113.792 -48.429164)
		(end 96.427544 -65.79362)
		(width 0.127)
		(layer "In5.Cu")
		(net "TCA9554_INT_N")
	)
	(segment
		(start 64.4017 -95.016066)
		(end 64.4017 -108.195618)
		(width 0.127)
		(layer "In5.Cu")
		(net "TCA9554_INT_N")
	)
	(segment
		(start 181.332124 -14.548104)
		(end 179.937156 -13.153136)
		(width 0.127)
		(layer "In5.Cu")
		(net "TCA9554_INT_N")
	)
	(segment
		(start 179.937156 -13.153136)
		(end 179.937156 -12.596876)
		(width 0.127)
		(layer "In5.Cu")
		(net "TCA9554_INT_N")
	)
	(segment
		(start 59.110118 -113.4872)
		(end 58.1406 -113.4872)
		(width 0.127)
		(layer "In5.Cu")
		(net "TCA9554_INT_N")
	)
	(segment
		(start 179.937156 -12.596876)
		(end 179.93741 -12.596622)
		(width 0.127)
		(layer "In5.Cu")
		(net "TCA9554_INT_N")
	)
	(segment
		(start 96.427544 -65.79362)
		(end 75.223116 -65.79362)
		(width 0.127)
		(layer "In5.Cu")
		(net "TCA9554_INT_N")
	)
	(segment
		(start 113.919 -41.007284)
		(end 113.792 -41.134284)
		(width 0.127)
		(layer "In5.Cu")
		(net "TCA9554_INT_N")
	)
	(segment
		(start 75.223116 -65.79362)
		(end 63.75654 -77.260196)
		(width 0.127)
		(layer "In5.Cu")
		(net "TCA9554_INT_N")
	)
	(segment
		(start 134.183628 -5.05841)
		(end 126.4539 -12.788138)
		(width 0.127)
		(layer "In5.Cu")
		(net "TCA9554_INT_N")
	)
	(segment
		(start 191.535304 -14.548104)
		(end 181.332124 -14.548104)
		(width 0.127)
		(layer "In5.Cu")
		(net "TCA9554_INT_N")
	)
	(segment
		(start 85.70214 -74.27214)
		(end 85.809836 -74.164444)
		(width 0.12065)
		(layer "F.Cu")
		(net "SEC_SPI_HOLD_N")
	)
	(segment
		(start 85.809836 -72.00646)
		(end 85.809836 -71.827644)
		(width 0.12065)
		(layer "F.Cu")
		(net "SEC_SPI_HOLD_N")
	)
	(segment
		(start 85.809836 -74.164444)
		(end 85.809836 -72.00646)
		(width 0.12065)
		(layer "F.Cu")
		(net "SEC_SPI_HOLD_N")
	)
	(segment
		(start 83.269836 -72.737472)
		(end 83.269836 -72.00646)
		(width 0.12065)
		(layer "F.Cu")
		(net "SEC_RST_N_R")
	)
	(segment
		(start 81.444338 -74.55535)
		(end 81.448148 -74.55916)
		(width 0.12065)
		(layer "F.Cu")
		(net "SEC_RST_N_R")
	)
	(segment
		(start 80.428084 -74.55535)
		(end 81.444338 -74.55535)
		(width 0.12065)
		(layer "F.Cu")
		(net "SEC_RST_N_R")
	)
	(segment
		(start 81.448148 -74.55916)
		(end 83.269836 -72.737472)
		(width 0.12065)
		(layer "F.Cu")
		(net "SEC_RST_N_R")
	)
	(segment
		(start 76.919836 -74.772012)
		(end 76.919836 -72.00646)
		(width 0.12065)
		(layer "F.Cu")
		(net "ROMD2_SEC")
	)
	(segment
		(start 76.8858 -74.806048)
		(end 76.919836 -74.772012)
		(width 0.12065)
		(layer "F.Cu")
		(net "ROMD2_SEC")
	)
	(segment
		(start 229.599998 -38.999922)
		(end 229.100126 -38.50005)
		(width 0.12065)
		(layer "F.Cu")
		(net "LBI_DATA_9")
	)
	(via
		(at 229.100126 -38.50005)
		(size 0.4572)
		(drill 0.2032)
		(layers "F.Cu" "B.Cu")
		(net "LBI_DATA_9")
	)
	(segment
		(start 229.60838 -39.008304)
		(end 229.100126 -38.50005)
		(width 0.12065)
		(layer "B.Cu")
		(net "LBI_DATA_9")
	)
	(segment
		(start 229.60838 -39.999412)
		(end 229.60838 -39.008304)
		(width 0.12065)
		(layer "B.Cu")
		(net "LBI_DATA_9")
	)
	(segment
		(start 218.77274 -31.142432)
		(end 218.77274 -29.92374)
		(width 0.12065)
		(layer "F.Cu")
		(net "LBI_DATA_8")
	)
	(segment
		(start 218.77274 -29.92374)
		(end 218.7702 -29.9212)
		(width 0.12065)
		(layer "F.Cu")
		(net "LBI_DATA_8")
	)
	(segment
		(start 229.599998 -39.99992)
		(end 229.100126 -39.500048)
		(width 0.12065)
		(layer "F.Cu")
		(net "LBI_DATA_8")
	)
	(via
		(at 218.7702 -29.9212)
		(size 0.508)
		(drill 0.254)
		(layers "F.Cu" "B.Cu")
		(net "LBI_DATA_8")
	)
	(via
		(at 229.100126 -39.500048)
		(size 0.4572)
		(drill 0.2032)
		(layers "F.Cu" "B.Cu")
		(net "LBI_DATA_8")
	)
	(segment
		(start 230.506524 -38.668452)
		(end 230.185976 -38.989)
		(width 0.127)
		(layer "In2.Cu")
		(net "LBI_DATA_8")
	)
	(segment
		(start 228.931724 -31.906464)
		(end 229.08133 -31.906464)
		(width 0.127)
		(layer "In2.Cu")
		(net "LBI_DATA_8")
	)
	(segment
		(start 229.693724 -32.668464)
		(end 229.931722 -32.906462)
		(width 0.127)
		(layer "In2.Cu")
		(net "LBI_DATA_8")
	)
	(segment
		(start 229.931722 -32.906462)
		(end 230.081328 -32.906462)
		(width 0.127)
		(layer "In2.Cu")
		(net "LBI_DATA_8")
	)
	(segment
		(start 230.081328 -32.906462)
		(end 230.506524 -33.331658)
		(width 0.127)
		(layer "In2.Cu")
		(net "LBI_DATA_8")
	)
	(segment
		(start 228.693726 -31.668466)
		(end 228.931724 -31.906464)
		(width 0.127)
		(layer "In2.Cu")
		(net "LBI_DATA_8")
	)
	(segment
		(start 218.7702 -29.9212)
		(end 228.096064 -29.9212)
		(width 0.127)
		(layer "In2.Cu")
		(net "LBI_DATA_8")
	)
	(segment
		(start 230.185976 -38.989)
		(end 229.611174 -38.989)
		(width 0.127)
		(layer "In2.Cu")
		(net "LBI_DATA_8")
	)
	(segment
		(start 229.611174 -38.989)
		(end 229.100126 -39.500048)
		(width 0.127)
		(layer "In2.Cu")
		(net "LBI_DATA_8")
	)
	(segment
		(start 228.096064 -29.9212)
		(end 228.693726 -30.518862)
		(width 0.127)
		(layer "In2.Cu")
		(net "LBI_DATA_8")
	)
	(segment
		(start 228.693726 -30.518862)
		(end 228.693726 -31.668466)
		(width 0.127)
		(layer "In2.Cu")
		(net "LBI_DATA_8")
	)
	(segment
		(start 229.08133 -31.906464)
		(end 229.693724 -32.518858)
		(width 0.127)
		(layer "In2.Cu")
		(net "LBI_DATA_8")
	)
	(segment
		(start 229.693724 -32.518858)
		(end 229.693724 -32.668464)
		(width 0.127)
		(layer "In2.Cu")
		(net "LBI_DATA_8")
	)
	(segment
		(start 230.506524 -33.331658)
		(end 230.506524 -38.668452)
		(width 0.127)
		(layer "In2.Cu")
		(net "LBI_DATA_8")
	)
	(segment
		(start 19.939 -156.337)
		(end 19.939 -155.5115)
		(width 0.12065)
		(layer "F.Cu")
		(net "HOST_I2C_RESET_N_D")
	)
	(segment
		(start 19.939 -155.5115)
		(end 19.304 -154.8765)
		(width 0.12065)
		(layer "F.Cu")
		(net "HOST_I2C_RESET_N_D")
	)
	(segment
		(start 21.336 -156.337)
		(end 19.939 -156.337)
		(width 0.12065)
		(layer "F.Cu")
		(net "HOST_I2C_RESET_N_D")
	)
	(via
		(at 21.336 -156.337)
		(size 0.7112)
		(drill 0.3556)
		(layers "F.Cu" "B.Cu")
		(net "HOST_I2C_RESET_N_D")
	)
	(segment
		(start 87.8332 -30.784546)
		(end 87.8332 -34.0614)
		(width 0.12065)
		(layer "F.Cu")
		(net "HOST_I2C_RESET_N")
	)
	(segment
		(start 115.7732 -26.1493)
		(end 110.8329 -26.1493)
		(width 0.12065)
		(layer "F.Cu")
		(net "HOST_I2C_RESET_N")
	)
	(segment
		(start 191.2366 -30.8991)
		(end 191.2366 -31.2166)
		(width 0.12065)
		(layer "F.Cu")
		(net "HOST_I2C_RESET_N")
	)
	(segment
		(start 110.8329 -26.1493)
		(end 107.2642 -29.718)
		(width 0.12065)
		(layer "F.Cu")
		(net "HOST_I2C_RESET_N")
	)
	(segment
		(start 176.1744 -46.101)
		(end 176.0982 -46.0248)
		(width 0.12065)
		(layer "F.Cu")
		(net "HOST_I2C_RESET_N")
	)
	(segment
		(start 18.724118 -160.659318)
		(end 18.144236 -161.2392)
		(width 0.12065)
		(layer "F.Cu")
		(net "HOST_I2C_RESET_N")
	)
	(segment
		(start 176.3522 -46.101)
		(end 176.1744 -46.101)
		(width 0.12065)
		(layer "F.Cu")
		(net "HOST_I2C_RESET_N")
	)
	(segment
		(start 191.2366 -31.2166)
		(end 176.3522 -46.101)
		(width 0.12065)
		(layer "F.Cu")
		(net "HOST_I2C_RESET_N")
	)
	(segment
		(start 88.899746 -29.718)
		(end 87.8332 -30.784546)
		(width 0.12065)
		(layer "F.Cu")
		(net "HOST_I2C_RESET_N")
	)
	(segment
		(start 19.939 -158.623)
		(end 19.939 -159.444436)
		(width 0.12065)
		(layer "F.Cu")
		(net "HOST_I2C_RESET_N")
	)
	(segment
		(start 87.8332 -34.0614)
		(end 95.070422 -41.298622)
		(width 0.12065)
		(layer "F.Cu")
		(net "HOST_I2C_RESET_N")
	)
	(segment
		(start 191.9605 -30.1752)
		(end 191.2366 -30.8991)
		(width 0.12065)
		(layer "F.Cu")
		(net "HOST_I2C_RESET_N")
	)
	(segment
		(start 19.939 -159.444436)
		(end 18.724118 -160.659318)
		(width 0.12065)
		(layer "F.Cu")
		(net "HOST_I2C_RESET_N")
	)
	(segment
		(start 115.7732 -26.1493)
		(end 115.7732 -25.1333)
		(width 0.12065)
		(layer "F.Cu")
		(net "HOST_I2C_RESET_N")
	)
	(segment
		(start 107.2642 -29.718)
		(end 88.899746 -29.718)
		(width 0.12065)
		(layer "F.Cu")
		(net "HOST_I2C_RESET_N")
	)
	(segment
		(start 95.070422 -49.248822)
		(end 97.4344 -51.6128)
		(width 0.12065)
		(layer "F.Cu")
		(net "HOST_I2C_RESET_N")
	)
	(segment
		(start 95.070422 -41.298622)
		(end 95.070422 -49.248822)
		(width 0.12065)
		(layer "F.Cu")
		(net "HOST_I2C_RESET_N")
	)
	(segment
		(start 18.144236 -161.2392)
		(end 16.0782 -161.2392)
		(width 0.12065)
		(layer "F.Cu")
		(net "HOST_I2C_RESET_N")
	)
	(via
		(at 138.981942 -42.668698)
		(size 0.508)
		(drill 0.254)
		(layers "F.Cu" "B.Cu")
		(net "HOST_I2C_RESET_N")
	)
	(via
		(at 16.0782 -161.2392)
		(size 0.508)
		(drill 0.254)
		(layers "F.Cu" "B.Cu")
		(net "HOST_I2C_RESET_N")
	)
	(via
		(at 18.724118 -160.659318)
		(size 0.7112)
		(drill 0.3556)
		(layers "F.Cu" "B.Cu")
		(net "HOST_I2C_RESET_N")
	)
	(via
		(at 176.0982 -46.0248)
		(size 0.508)
		(drill 0.254)
		(layers "F.Cu" "B.Cu")
		(net "HOST_I2C_RESET_N")
	)
	(via
		(at 97.4344 -51.6128)
		(size 0.508)
		(drill 0.254)
		(layers "F.Cu" "B.Cu")
		(net "HOST_I2C_RESET_N")
	)
	(segment
		(start 103.556816 -46.7614)
		(end 101.818948 -46.7614)
		(width 0.12065)
		(layer "B.Cu")
		(net "HOST_I2C_RESET_N")
	)
	(segment
		(start 138.981942 -42.665142)
		(end 138.357356 -42.040556)
		(width 0.12065)
		(layer "B.Cu")
		(net "HOST_I2C_RESET_N")
	)
	(segment
		(start 97.4344 -51.145948)
		(end 97.4344 -51.6128)
		(width 0.12065)
		(layer "B.Cu")
		(net "HOST_I2C_RESET_N")
	)
	(segment
		(start 132.334 -40.88765)
		(end 123.483624 -40.88765)
		(width 0.12065)
		(layer "B.Cu")
		(net "HOST_I2C_RESET_N")
	)
	(segment
		(start 138.357356 -42.040556)
		(end 133.486906 -42.040556)
		(width 0.12065)
		(layer "B.Cu")
		(net "HOST_I2C_RESET_N")
	)
	(segment
		(start 138.981942 -42.668698)
		(end 138.981942 -42.665142)
		(width 0.12065)
		(layer "B.Cu")
		(net "HOST_I2C_RESET_N")
	)
	(segment
		(start 101.818948 -46.7614)
		(end 97.4344 -51.145948)
		(width 0.12065)
		(layer "B.Cu")
		(net "HOST_I2C_RESET_N")
	)
	(segment
		(start 110.465616 -39.852854)
		(end 103.556816 -46.7614)
		(width 0.12065)
		(layer "B.Cu")
		(net "HOST_I2C_RESET_N")
	)
	(segment
		(start 116.633244 -39.852854)
		(end 110.465616 -39.852854)
		(width 0.12065)
		(layer "B.Cu")
		(net "HOST_I2C_RESET_N")
	)
	(segment
		(start 123.18365 -40.887904)
		(end 121.299986 -39.00424)
		(width 0.12065)
		(layer "B.Cu")
		(net "HOST_I2C_RESET_N")
	)
	(segment
		(start 117.672866 -39.00424)
		(end 116.824506 -39.8526)
		(width 0.12065)
		(layer "B.Cu")
		(net "HOST_I2C_RESET_N")
	)
	(segment
		(start 133.486906 -42.040556)
		(end 132.334 -40.88765)
		(width 0.12065)
		(layer "B.Cu")
		(net "HOST_I2C_RESET_N")
	)
	(segment
		(start 123.483624 -40.88765)
		(end 123.48337 -40.887904)
		(width 0.12065)
		(layer "B.Cu")
		(net "HOST_I2C_RESET_N")
	)
	(segment
		(start 116.633498 -39.8526)
		(end 116.633244 -39.852854)
		(width 0.12065)
		(layer "B.Cu")
		(net "HOST_I2C_RESET_N")
	)
	(segment
		(start 121.299986 -39.00424)
		(end 117.672866 -39.00424)
		(width 0.12065)
		(layer "B.Cu")
		(net "HOST_I2C_RESET_N")
	)
	(segment
		(start 123.48337 -40.887904)
		(end 123.18365 -40.887904)
		(width 0.12065)
		(layer "B.Cu")
		(net "HOST_I2C_RESET_N")
	)
	(segment
		(start 116.824506 -39.8526)
		(end 116.633498 -39.8526)
		(width 0.12065)
		(layer "B.Cu")
		(net "HOST_I2C_RESET_N")
	)
	(segment
		(start 18.84807 -91.011248)
		(end 18.84807 -90.520012)
		(width 0.127)
		(layer "In2.Cu")
		(net "HOST_I2C_RESET_N")
	)
	(segment
		(start 140.500354 -44.183554)
		(end 143.303498 -44.183554)
		(width 0.127)
		(layer "In2.Cu")
		(net "HOST_I2C_RESET_N")
	)
	(segment
		(start 3.26136 -145.04416)
		(end 3.26136 -110.391448)
		(width 0.127)
		(layer "In2.Cu")
		(net "HOST_I2C_RESET_N")
	)
	(segment
		(start 95.48495 -76.688188)
		(end 95.81388 -76.359004)
		(width 0.127)
		(layer "In2.Cu")
		(net "HOST_I2C_RESET_N")
	)
	(segment
		(start 176.022 -46.101)
		(end 176.0982 -46.0248)
		(width 0.127)
		(layer "In2.Cu")
		(net "HOST_I2C_RESET_N")
	)
	(segment
		(start 23.193248 -89.484454)
		(end 26.584402 -86.0933)
		(width 0.127)
		(layer "In2.Cu")
		(net "HOST_I2C_RESET_N")
	)
	(segment
		(start 97.4598 -74.713084)
		(end 97.4598 -51.6382)
		(width 0.127)
		(layer "In2.Cu")
		(net "HOST_I2C_RESET_N")
	)
	(segment
		(start 29.265118 -85.6234)
		(end 29.265118 -85.622892)
		(width 0.127)
		(layer "In2.Cu")
		(net "HOST_I2C_RESET_N")
	)
	(segment
		(start 145.754344 -46.6344)
		(end 156.634434 -46.6344)
		(width 0.127)
		(layer "In2.Cu")
		(net "HOST_I2C_RESET_N")
	)
	(segment
		(start 16.3195 -158.1023)
		(end 3.26136 -145.04416)
		(width 0.127)
		(layer "In2.Cu")
		(net "HOST_I2C_RESET_N")
	)
	(segment
		(start 64.938402 -84.534756)
		(end 65.790826 -85.38718)
		(width 0.127)
		(layer "In2.Cu")
		(net "HOST_I2C_RESET_N")
	)
	(segment
		(start 12.966192 -97.285556)
		(end 12.9667 -97.088452)
		(width 0.127)
		(layer "In2.Cu")
		(net "HOST_I2C_RESET_N")
	)
	(segment
		(start 158.549594 -48.54956)
		(end 172.88764 -48.54956)
		(width 0.127)
		(layer "In2.Cu")
		(net "HOST_I2C_RESET_N")
	)
	(segment
		(start 175.3362 -46.101)
		(end 176.022 -46.101)
		(width 0.127)
		(layer "In2.Cu")
		(net "HOST_I2C_RESET_N")
	)
	(segment
		(start 16.0782 -161.2392)
		(end 16.3195 -160.9979)
		(width 0.127)
		(layer "In2.Cu")
		(net "HOST_I2C_RESET_N")
	)
	(segment
		(start 95.262192 -76.911454)
		(end 95.33636 -76.837286)
		(width 0.127)
		(layer "In2.Cu")
		(net "HOST_I2C_RESET_N")
	)
	(segment
		(start 27.458924 -86.0933)
		(end 27.738324 -85.8139)
		(width 0.127)
		(layer "In2.Cu")
		(net "HOST_I2C_RESET_N")
	)
	(segment
		(start 12.9667 -97.088452)
		(end 12.9667 -96.892618)
		(width 0.127)
		(layer "In2.Cu")
		(net "HOST_I2C_RESET_N")
	)
	(segment
		(start 69.743574 -85.38718)
		(end 72.951594 -82.17916)
		(width 0.127)
		(layer "In2.Cu")
		(net "HOST_I2C_RESET_N")
	)
	(segment
		(start 95.81388 -76.359004)
		(end 95.920306 -76.252324)
		(width 0.127)
		(layer "In2.Cu")
		(net "HOST_I2C_RESET_N")
	)
	(segment
		(start 92.918026 -81.635092)
		(end 95.0214 -79.531718)
		(width 0.127)
		(layer "In2.Cu")
		(net "HOST_I2C_RESET_N")
	)
	(segment
		(start 81.435448 -83.03514)
		(end 82.835496 -81.635092)
		(width 0.127)
		(layer "In2.Cu")
		(net "HOST_I2C_RESET_N")
	)
	(segment
		(start 3.26136 -110.391448)
		(end 6.508242 -107.144566)
		(width 0.127)
		(layer "In2.Cu")
		(net "HOST_I2C_RESET_N")
	)
	(segment
		(start 72.951594 -82.17916)
		(end 75.671172 -82.17916)
		(width 0.127)
		(layer "In2.Cu")
		(net "HOST_I2C_RESET_N")
	)
	(segment
		(start 27.738324 -85.8139)
		(end 29.074618 -85.8139)
		(width 0.127)
		(layer "In2.Cu")
		(net "HOST_I2C_RESET_N")
	)
	(segment
		(start 21.688806 -90.172794)
		(end 22.377146 -89.484454)
		(width 0.127)
		(layer "In2.Cu")
		(net "HOST_I2C_RESET_N")
	)
	(segment
		(start 54.582568 -84.534756)
		(end 64.938402 -84.534756)
		(width 0.127)
		(layer "In2.Cu")
		(net "HOST_I2C_RESET_N")
	)
	(segment
		(start 95.0214 -77.155294)
		(end 95.262192 -76.913486)
		(width 0.127)
		(layer "In2.Cu")
		(net "HOST_I2C_RESET_N")
	)
	(segment
		(start 26.584402 -86.0933)
		(end 27.458924 -86.0933)
		(width 0.127)
		(layer "In2.Cu")
		(net "HOST_I2C_RESET_N")
	)
	(segment
		(start 76.527152 -83.03514)
		(end 81.435448 -83.03514)
		(width 0.127)
		(layer "In2.Cu")
		(net "HOST_I2C_RESET_N")
	)
	(segment
		(start 29.265118 -85.622892)
		(end 42.599102 -85.622892)
		(width 0.127)
		(layer "In2.Cu")
		(net "HOST_I2C_RESET_N")
	)
	(segment
		(start 18.84807 -90.520012)
		(end 19.195288 -90.172794)
		(width 0.127)
		(layer "In2.Cu")
		(net "HOST_I2C_RESET_N")
	)
	(segment
		(start 29.074618 -85.8139)
		(end 29.265118 -85.6234)
		(width 0.127)
		(layer "In2.Cu")
		(net "HOST_I2C_RESET_N")
	)
	(segment
		(start 6.508242 -103.743506)
		(end 12.966192 -97.285556)
		(width 0.127)
		(layer "In2.Cu")
		(net "HOST_I2C_RESET_N")
	)
	(segment
		(start 12.9667 -96.892618)
		(end 18.84807 -91.011248)
		(width 0.127)
		(layer "In2.Cu")
		(net "HOST_I2C_RESET_N")
	)
	(segment
		(start 82.835496 -81.635092)
		(end 92.918026 -81.635092)
		(width 0.127)
		(layer "In2.Cu")
		(net "HOST_I2C_RESET_N")
	)
	(segment
		(start 95.262192 -76.913486)
		(end 95.262192 -76.911454)
		(width 0.127)
		(layer "In2.Cu")
		(net "HOST_I2C_RESET_N")
	)
	(segment
		(start 16.3195 -160.9979)
		(end 16.3195 -158.1023)
		(width 0.127)
		(layer "In2.Cu")
		(net "HOST_I2C_RESET_N")
	)
	(segment
		(start 6.508242 -107.144566)
		(end 6.508242 -103.743506)
		(width 0.127)
		(layer "In2.Cu")
		(net "HOST_I2C_RESET_N")
	)
	(segment
		(start 95.33636 -76.837286)
		(end 95.48495 -76.688188)
		(width 0.127)
		(layer "In2.Cu")
		(net "HOST_I2C_RESET_N")
	)
	(segment
		(start 138.981942 -42.668698)
		(end 138.981942 -42.665142)
		(width 0.127)
		(layer "In2.Cu")
		(net "HOST_I2C_RESET_N")
	)
	(segment
		(start 65.790826 -85.38718)
		(end 69.743574 -85.38718)
		(width 0.127)
		(layer "In2.Cu")
		(net "HOST_I2C_RESET_N")
	)
	(segment
		(start 138.981942 -42.665142)
		(end 140.500354 -44.183554)
		(width 0.127)
		(layer "In2.Cu")
		(net "HOST_I2C_RESET_N")
	)
	(segment
		(start 95.920306 -76.252324)
		(end 97.4598 -74.713084)
		(width 0.127)
		(layer "In2.Cu")
		(net "HOST_I2C_RESET_N")
	)
	(segment
		(start 19.195288 -90.172794)
		(end 21.688806 -90.172794)
		(width 0.127)
		(layer "In2.Cu")
		(net "HOST_I2C_RESET_N")
	)
	(segment
		(start 172.88764 -48.54956)
		(end 175.3362 -46.101)
		(width 0.127)
		(layer "In2.Cu")
		(net "HOST_I2C_RESET_N")
	)
	(segment
		(start 75.671172 -82.17916)
		(end 76.527152 -83.03514)
		(width 0.127)
		(layer "In2.Cu")
		(net "HOST_I2C_RESET_N")
	)
	(segment
		(start 95.0214 -79.531718)
		(end 95.0214 -77.155294)
		(width 0.127)
		(layer "In2.Cu")
		(net "HOST_I2C_RESET_N")
	)
	(segment
		(start 22.377146 -89.484454)
		(end 23.193248 -89.484454)
		(width 0.127)
		(layer "In2.Cu")
		(net "HOST_I2C_RESET_N")
	)
	(segment
		(start 54.156864 -84.96046)
		(end 54.582568 -84.534756)
		(width 0.127)
		(layer "In2.Cu")
		(net "HOST_I2C_RESET_N")
	)
	(segment
		(start 42.599102 -85.622892)
		(end 43.261534 -84.96046)
		(width 0.127)
		(layer "In2.Cu")
		(net "HOST_I2C_RESET_N")
	)
	(segment
		(start 143.303498 -44.183554)
		(end 145.754344 -46.6344)
		(width 0.127)
		(layer "In2.Cu")
		(net "HOST_I2C_RESET_N")
	)
	(segment
		(start 156.634434 -46.6344)
		(end 158.549594 -48.54956)
		(width 0.127)
		(layer "In2.Cu")
		(net "HOST_I2C_RESET_N")
	)
	(segment
		(start 43.261534 -84.96046)
		(end 54.156864 -84.96046)
		(width 0.127)
		(layer "In2.Cu")
		(net "HOST_I2C_RESET_N")
	)
	(segment
		(start 97.4598 -51.6382)
		(end 97.4344 -51.6128)
		(width 0.127)
		(layer "In2.Cu")
		(net "HOST_I2C_RESET_N")
	)
	(segment
		(start 35.30473 -124.484892)
		(end 34.904934 -124.085096)
		(width 0.12065)
		(layer "F.Cu")
		(net "FLA1_WPN_R")
	)
	(via
		(at 34.904934 -124.085096)
		(size 0.4572)
		(drill 0.2032)
		(layers "F.Cu" "B.Cu")
		(net "FLA1_WPN_R")
	)
	(via
		(at 33.931606 -121.313702)
		(size 0.7112)
		(drill 0.3556)
		(layers "F.Cu" "B.Cu")
		(net "FLA1_WPN_R")
	)
	(segment
		(start 33.183068 -119.55272)
		(end 33.55594 -119.925592)
		(width 0.12065)
		(layer "B.Cu")
		(net "FLA1_WPN_R")
	)
	(segment
		(start 33.55594 -120.938036)
		(end 33.931606 -121.313702)
		(width 0.12065)
		(layer "B.Cu")
		(net "FLA1_WPN_R")
	)
	(segment
		(start 34.514282 -123.694444)
		(end 34.904934 -124.085096)
		(width 0.12065)
		(layer "B.Cu")
		(net "FLA1_WPN_R")
	)
	(segment
		(start 34.514282 -121.896378)
		(end 34.514282 -123.694444)
		(width 0.12065)
		(layer "B.Cu")
		(net "FLA1_WPN_R")
	)
	(segment
		(start 33.931606 -121.313702)
		(end 34.514282 -121.896378)
		(width 0.12065)
		(layer "B.Cu")
		(net "FLA1_WPN_R")
	)
	(segment
		(start 33.55594 -119.925592)
		(end 33.55594 -120.938036)
		(width 0.12065)
		(layer "B.Cu")
		(net "FLA1_WPN_R")
	)
	(segment
		(start 31.304738 -136.484868)
		(end 30.904942 -136.884664)
		(width 0.12065)
		(layer "F.Cu")
		(net "BMC0_SRST_N")
	)
	(via
		(at 30.904942 -136.884664)
		(size 0.4572)
		(drill 0.2032)
		(layers "F.Cu" "B.Cu")
		(net "BMC0_SRST_N")
	)
	(via
		(at 22.437852 -140.70457)
		(size 0.7112)
		(drill 0.3556)
		(layers "F.Cu" "B.Cu")
		(net "BMC0_SRST_N")
	)
	(segment
		(start 21.3995 -141.884908)
		(end 21.389848 -141.89456)
		(width 0.12065)
		(layer "B.Cu")
		(net "BMC0_SRST_N")
	)
	(segment
		(start 22.872446 -141.139164)
		(end 22.437852 -140.70457)
		(width 0.12065)
		(layer "B.Cu")
		(net "BMC0_SRST_N")
	)
	(segment
		(start 30.904942 -136.884664)
		(end 29.588206 -138.2014)
		(width 0.12065)
		(layer "B.Cu")
		(net "BMC0_SRST_N")
	)
	(segment
		(start 26.2001 -141.139164)
		(end 22.872446 -141.139164)
		(width 0.12065)
		(layer "B.Cu")
		(net "BMC0_SRST_N")
	)
	(segment
		(start 21.3995 -140.843)
		(end 21.517864 -140.724636)
		(width 0.12065)
		(layer "B.Cu")
		(net "BMC0_SRST_N")
	)
	(segment
		(start 21.517864 -140.724636)
		(end 22.433788 -140.724636)
		(width 0.12065)
		(layer "B.Cu")
		(net "BMC0_SRST_N")
	)
	(segment
		(start 22.433788 -140.724636)
		(end 22.433788 -140.70457)
		(width 0.12065)
		(layer "B.Cu")
		(net "BMC0_SRST_N")
	)
	(segment
		(start 29.588206 -138.2014)
		(end 29.137864 -138.2014)
		(width 0.12065)
		(layer "B.Cu")
		(net "BMC0_SRST_N")
	)
	(segment
		(start 29.137864 -138.2014)
		(end 26.2001 -141.139164)
		(width 0.12065)
		(layer "B.Cu")
		(net "BMC0_SRST_N")
	)
	(segment
		(start 22.433788 -140.70457)
		(end 22.437852 -140.70457)
		(width 0.12065)
		(layer "B.Cu")
		(net "BMC0_SRST_N")
	)
	(segment
		(start 21.3995 -140.843)
		(end 21.3995 -141.884908)
		(width 0.12065)
		(layer "B.Cu")
		(net "BMC0_SRST_N")
	)
	(segment
		(start 71.3994 -52.0827)
		(end 73.7489 -52.0827)
		(width 0.12065)
		(layer "F.Cu")
		(net "BMC_CPU_EN")
	)
	(segment
		(start 73.7489 -52.0827)
		(end 74.295 -52.6288)
		(width 0.12065)
		(layer "F.Cu")
		(net "BMC_CPU_EN")
	)
	(segment
		(start 79.9465 -56.3626)
		(end 79.9465 -53.2003)
		(width 0.12065)
		(layer "F.Cu")
		(net "BMC_CPU_DIS")
	)
	(segment
		(start 79.9465 -53.2003)
		(end 79.375 -52.6288)
		(width 0.12065)
		(layer "F.Cu")
		(net "BMC_CPU_DIS")
	)
	(segment
		(start 118.031768 -29.7307)
		(end 117.568472 -30.193996)
		(width 0.12065)
		(layer "F.Cu")
		(net "U54_SDA")
	)
	(segment
		(start 118.031768 -28.972002)
		(end 118.031768 -29.7307)
		(width 0.12065)
		(layer "F.Cu")
		(net "U54_SDA")
	)
	(segment
		(start 117.856 -27.1272)
		(end 117.856 -28.796234)
		(width 0.12065)
		(layer "F.Cu")
		(net "U54_SDA")
	)
	(segment
		(start 117.856 -28.796234)
		(end 118.031768 -28.972002)
		(width 0.12065)
		(layer "F.Cu")
		(net "U54_SDA")
	)
	(via
		(at 118.031768 -28.972002)
		(size 0.7112)
		(drill 0.3556)
		(layers "F.Cu" "B.Cu")
		(net "U54_SDA")
	)
	(segment
		(start 118.50624 -27.1272)
		(end 118.50624 -28.062428)
		(width 0.12065)
		(layer "F.Cu")
		(net "U54_SCL")
	)
	(segment
		(start 119.391938 -29.396944)
		(end 118.59387 -30.195012)
		(width 0.12065)
		(layer "F.Cu")
		(net "U54_SCL")
	)
	(segment
		(start 118.50624 -28.062428)
		(end 119.391938 -28.948126)
		(width 0.12065)
		(layer "F.Cu")
		(net "U54_SCL")
	)
	(segment
		(start 119.391938 -28.948126)
		(end 119.391938 -29.396944)
		(width 0.12065)
		(layer "F.Cu")
		(net "U54_SCL")
	)
	(via
		(at 119.391938 -28.948126)
		(size 0.7112)
		(drill 0.3556)
		(layers "F.Cu" "B.Cu")
		(net "U54_SCL")
	)
	(segment
		(start 115.7732 -23.1394)
		(end 115.6462 -23.0124)
		(width 0.12065)
		(layer "F.Cu")
		(net "U54_P0")
	)
	(segment
		(start 119.15648 -22.78507)
		(end 117.69725 -24.2443)
		(width 0.12065)
		(layer "F.Cu")
		(net "U54_P0")
	)
	(segment
		(start 117.69725 -24.2443)
		(end 115.7732 -24.2443)
		(width 0.12065)
		(layer "F.Cu")
		(net "U54_P0")
	)
	(segment
		(start 119.15648 -21.4884)
		(end 119.15648 -22.78507)
		(width 0.12065)
		(layer "F.Cu")
		(net "U54_P0")
	)
	(segment
		(start 115.7732 -24.2443)
		(end 115.7732 -23.1394)
		(width 0.12065)
		(layer "F.Cu")
		(net "U54_P0")
	)
	(via
		(at 115.6462 -23.0124)
		(size 0.7112)
		(drill 0.3556)
		(layers "F.Cu" "B.Cu")
		(net "U54_P0")
	)
	(segment
		(start 119.15648 -27.742134)
		(end 119.15648 -27.1272)
		(width 0.12065)
		(layer "F.Cu")
		(net "U54_INT_N")
	)
	(segment
		(start 120.672606 -29.121608)
		(end 120.535954 -29.121608)
		(width 0.12065)
		(layer "F.Cu")
		(net "U54_INT_N")
	)
	(segment
		(start 121.6152 -29.692346)
		(end 121.044462 -29.121608)
		(width 0.12065)
		(layer "F.Cu")
		(net "U54_INT_N")
	)
	(segment
		(start 121.044462 -29.121608)
		(end 120.672606 -29.121608)
		(width 0.12065)
		(layer "F.Cu")
		(net "U54_INT_N")
	)
	(segment
		(start 120.535954 -29.121608)
		(end 119.15648 -27.742134)
		(width 0.12065)
		(layer "F.Cu")
		(net "U54_INT_N")
	)
	(segment
		(start 121.6152 -30.2895)
		(end 121.6152 -29.692346)
		(width 0.12065)
		(layer "F.Cu")
		(net "U54_INT_N")
	)
	(via
		(at 120.672606 -29.121608)
		(size 0.7112)
		(drill 0.3556)
		(layers "F.Cu" "B.Cu")
		(net "U54_INT_N")
	)
	(segment
		(start 118.50624 -20.43176)
		(end 119.507 -19.431)
		(width 0.12065)
		(layer "F.Cu")
		(net "U54_A2")
	)
	(segment
		(start 121.5136 -17.5133)
		(end 120.4976 -17.5133)
		(width 0.12065)
		(layer "F.Cu")
		(net "U54_A2")
	)
	(segment
		(start 119.507 -19.431)
		(end 120.8278 -19.431)
		(width 0.12065)
		(layer "F.Cu")
		(net "U54_A2")
	)
	(segment
		(start 121.5136 -17.5133)
		(end 121.5136 -18.7452)
		(width 0.12065)
		(layer "F.Cu")
		(net "U54_A2")
	)
	(segment
		(start 120.8278 -19.431)
		(end 121.5136 -18.7452)
		(width 0.12065)
		(layer "F.Cu")
		(net "U54_A2")
	)
	(segment
		(start 118.50624 -21.4884)
		(end 118.50624 -20.43176)
		(width 0.12065)
		(layer "F.Cu")
		(net "U54_A2")
	)
	(via
		(at 121.5136 -18.7452)
		(size 0.7112)
		(drill 0.3556)
		(layers "F.Cu" "B.Cu")
		(net "U54_A2")
	)
	(segment
		(start 117.856 -20.32)
		(end 119.4308 -18.7452)
		(width 0.12065)
		(layer "F.Cu")
		(net "U54_A1")
	)
	(segment
		(start 119.4308 -17.5133)
		(end 119.4308 -18.7452)
		(width 0.12065)
		(layer "F.Cu")
		(net "U54_A1")
	)
	(segment
		(start 118.364 -17.5133)
		(end 119.4308 -17.5133)
		(width 0.12065)
		(layer "F.Cu")
		(net "U54_A1")
	)
	(segment
		(start 117.856 -21.4884)
		(end 117.856 -20.32)
		(width 0.12065)
		(layer "F.Cu")
		(net "U54_A1")
	)
	(via
		(at 119.4308 -18.7452)
		(size 0.7112)
		(drill 0.3556)
		(layers "F.Cu" "B.Cu")
		(net "U54_A1")
	)
	(segment
		(start 117.3226 -17.5133)
		(end 116.2558 -17.5133)
		(width 0.12065)
		(layer "F.Cu")
		(net "U54_A0")
	)
	(segment
		(start 117.20576 -18.86204)
		(end 117.3226 -18.7452)
		(width 0.12065)
		(layer "F.Cu")
		(net "U54_A0")
	)
	(segment
		(start 117.3226 -18.7452)
		(end 117.3226 -17.5133)
		(width 0.12065)
		(layer "F.Cu")
		(net "U54_A0")
	)
	(segment
		(start 117.20576 -21.4884)
		(end 117.20576 -18.86204)
		(width 0.12065)
		(layer "F.Cu")
		(net "U54_A0")
	)
	(via
		(at 117.3226 -18.7452)
		(size 0.7112)
		(drill 0.3556)
		(layers "F.Cu" "B.Cu")
		(net "U54_A0")
	)
	(segment
		(start 8.6487 -135.509)
		(end 9.746234 -135.509)
		(width 0.12065)
		(layer "F.Cu")
		(net "TRAY_RESET_N_R")
	)
	(segment
		(start 9.746234 -135.509)
		(end 10.062464 -135.19277)
		(width 0.12065)
		(layer "F.Cu")
		(net "TRAY_RESET_N_R")
	)
	(segment
		(start 10.062464 -135.19277)
		(end 10.062464 -134.17804)
		(width 0.12065)
		(layer "F.Cu")
		(net "TRAY_RESET_N_R")
	)
	(segment
		(start 10.062464 -134.17804)
		(end 9.758172 -133.873748)
		(width 0.12065)
		(layer "F.Cu")
		(net "TRAY_RESET_N_R")
	)
	(segment
		(start 9.758172 -133.873748)
		(end 8.636 -133.873748)
		(width 0.12065)
		(layer "F.Cu")
		(net "TRAY_RESET_N_R")
	)
	(via
		(at 10.062464 -135.19277)
		(size 0.7112)
		(drill 0.3556)
		(layers "F.Cu" "B.Cu")
		(net "TRAY_RESET_N_R")
	)
	(segment
		(start 6.35 -133.873748)
		(end 6.2992 -133.924548)
		(width 0.12065)
		(layer "F.Cu")
		(net "TRAY_RESET_N")
	)
	(segment
		(start 67.168522 -27.835098)
		(end 66.635884 -27.30246)
		(width 0.12065)
		(layer "F.Cu")
		(net "TRAY_RESET_N")
	)
	(segment
		(start 57.1246 -27.7749)
		(end 56.312308 -27.7749)
		(width 0.12065)
		(layer "F.Cu")
		(net "TRAY_RESET_N")
	)
	(segment
		(start 66.635884 -27.30246)
		(end 65.815972 -27.30246)
		(width 0.12065)
		(layer "F.Cu")
		(net "TRAY_RESET_N")
	)
	(segment
		(start 6.2992 -133.924548)
		(end 6.2992 -137.3886)
		(width 0.12065)
		(layer "F.Cu")
		(net "TRAY_RESET_N")
	)
	(segment
		(start 64.825118 -26.311606)
		(end 63.545974 -26.311606)
		(width 0.12065)
		(layer "F.Cu")
		(net "TRAY_RESET_N")
	)
	(segment
		(start 65.815972 -27.30246)
		(end 64.825118 -26.311606)
		(width 0.12065)
		(layer "F.Cu")
		(net "TRAY_RESET_N")
	)
	(segment
		(start 56.312308 -27.7749)
		(end 56.240172 -27.847036)
		(width 0.12065)
		(layer "F.Cu")
		(net "TRAY_RESET_N")
	)
	(via
		(at 6.2992 -137.3886)
		(size 0.508)
		(drill 0.254)
		(layers "F.Cu" "B.Cu")
		(net "TRAY_RESET_N")
	)
	(via
		(at 67.168522 -27.835098)
		(size 0.508)
		(drill 0.254)
		(layers "F.Cu" "B.Cu")
		(net "TRAY_RESET_N")
	)
	(via
		(at 13.945362 -113.538762)
		(size 0.7112)
		(drill 0.3556)
		(layers "F.Cu" "B.Cu")
		(net "TRAY_RESET_N")
	)
	(via
		(at 11.706098 -115.778026)
		(size 0.508)
		(drill 0.254)
		(layers "F.Cu" "B.Cu")
		(net "TRAY_RESET_N")
	)
	(via
		(at 56.240172 -27.847036)
		(size 0.508)
		(drill 0.254)
		(layers "F.Cu" "B.Cu")
		(net "TRAY_RESET_N")
	)
	(segment
		(start 56.200548 -27.975814)
		(end 56.200548 -27.88666)
		(width 0.12065)
		(layer "B.Cu")
		(net "TRAY_RESET_N")
	)
	(segment
		(start 54.22519 -29.957522)
		(end 55.056532 -29.12618)
		(width 0.12065)
		(layer "B.Cu")
		(net "TRAY_RESET_N")
	)
	(segment
		(start 13.945362 -113.538762)
		(end 17.259808 -110.224316)
		(width 0.12065)
		(layer "B.Cu")
		(net "TRAY_RESET_N")
	)
	(segment
		(start 26.697432 -75.203558)
		(end 28.143708 -76.649834)
		(width 0.12065)
		(layer "B.Cu")
		(net "TRAY_RESET_N")
	)
	(segment
		(start 11.706098 -115.778026)
		(end 13.945362 -113.538762)
		(width 0.12065)
		(layer "B.Cu")
		(net "TRAY_RESET_N")
	)
	(segment
		(start 55.056532 -29.12618)
		(end 55.056532 -29.11983)
		(width 0.12065)
		(layer "B.Cu")
		(net "TRAY_RESET_N")
	)
	(segment
		(start 32.971994 -83.194652)
		(end 34.511742 -84.7344)
		(width 0.12065)
		(layer "B.Cu")
		(net "TRAY_RESET_N")
	)
	(segment
		(start 41.2242 -77.75194)
		(end 41.2242 -65.531746)
		(width 0.12065)
		(layer "B.Cu")
		(net "TRAY_RESET_N")
	)
	(segment
		(start 23.114 -76.0476)
		(end 23.958042 -75.203558)
		(width 0.12065)
		(layer "B.Cu")
		(net "TRAY_RESET_N")
	)
	(segment
		(start 54.21884 -29.957522)
		(end 54.22519 -29.957522)
		(width 0.12065)
		(layer "B.Cu")
		(net "TRAY_RESET_N")
	)
	(segment
		(start 32.971994 -80.093058)
		(end 32.971994 -83.194652)
		(width 0.12065)
		(layer "B.Cu")
		(net "TRAY_RESET_N")
	)
	(segment
		(start 29.52877 -76.649834)
		(end 32.971994 -80.093058)
		(width 0.12065)
		(layer "B.Cu")
		(net "TRAY_RESET_N")
	)
	(segment
		(start 17.259808 -99.159314)
		(end 23.745698 -92.673424)
		(width 0.12065)
		(layer "B.Cu")
		(net "TRAY_RESET_N")
	)
	(segment
		(start 41.951148 -64.804798)
		(end 41.951148 -42.225214)
		(width 0.12065)
		(layer "B.Cu")
		(net "TRAY_RESET_N")
	)
	(segment
		(start 55.056532 -29.11983)
		(end 56.200548 -27.975814)
		(width 0.12065)
		(layer "B.Cu")
		(net "TRAY_RESET_N")
	)
	(segment
		(start 17.259808 -110.224316)
		(end 17.259808 -99.159314)
		(width 0.12065)
		(layer "B.Cu")
		(net "TRAY_RESET_N")
	)
	(segment
		(start 28.143708 -76.649834)
		(end 29.52877 -76.649834)
		(width 0.12065)
		(layer "B.Cu")
		(net "TRAY_RESET_N")
	)
	(segment
		(start 41.2242 -65.531746)
		(end 41.951148 -64.804798)
		(width 0.12065)
		(layer "B.Cu")
		(net "TRAY_RESET_N")
	)
	(segment
		(start 23.745698 -92.673424)
		(end 23.745698 -79.875634)
		(width 0.12065)
		(layer "B.Cu")
		(net "TRAY_RESET_N")
	)
	(segment
		(start 42.037 -78.56474)
		(end 41.2242 -77.75194)
		(width 0.12065)
		(layer "B.Cu")
		(net "TRAY_RESET_N")
	)
	(segment
		(start 23.958042 -75.203558)
		(end 26.697432 -75.203558)
		(width 0.12065)
		(layer "B.Cu")
		(net "TRAY_RESET_N")
	)
	(segment
		(start 56.200548 -27.88666)
		(end 56.240172 -27.847036)
		(width 0.12065)
		(layer "B.Cu")
		(net "TRAY_RESET_N")
	)
	(segment
		(start 34.511742 -84.7344)
		(end 40.809926 -84.7344)
		(width 0.12065)
		(layer "B.Cu")
		(net "TRAY_RESET_N")
	)
	(segment
		(start 40.809926 -84.7344)
		(end 42.037 -83.507326)
		(width 0.12065)
		(layer "B.Cu")
		(net "TRAY_RESET_N")
	)
	(segment
		(start 23.114 -79.243936)
		(end 23.114 -76.0476)
		(width 0.12065)
		(layer "B.Cu")
		(net "TRAY_RESET_N")
	)
	(segment
		(start 42.037 -83.507326)
		(end 42.037 -78.56474)
		(width 0.12065)
		(layer "B.Cu")
		(net "TRAY_RESET_N")
	)
	(segment
		(start 23.745698 -79.875634)
		(end 23.114 -79.243936)
		(width 0.12065)
		(layer "B.Cu")
		(net "TRAY_RESET_N")
	)
	(segment
		(start 41.951148 -42.225214)
		(end 54.21884 -29.957522)
		(width 0.12065)
		(layer "B.Cu")
		(net "TRAY_RESET_N")
	)
	(segment
		(start 6.2992 -130.2766)
		(end 6.2992 -137.3886)
		(width 0.127)
		(layer "In5.Cu")
		(net "TRAY_RESET_N")
	)
	(segment
		(start 67.168522 -27.835098)
		(end 66.548508 -27.215084)
		(width 0.127)
		(layer "In5.Cu")
		(net "TRAY_RESET_N")
	)
	(segment
		(start 57.887616 -27.215084)
		(end 57.727342 -27.05481)
		(width 0.127)
		(layer "In5.Cu")
		(net "TRAY_RESET_N")
	)
	(segment
		(start 12.770866 -122.446034)
		(end 12.770866 -123.804934)
		(width 0.127)
		(layer "In5.Cu")
		(net "TRAY_RESET_N")
	)
	(segment
		(start 13.091414 -121.075196)
		(end 13.091414 -121.674382)
		(width 0.127)
		(layer "In5.Cu")
		(net "TRAY_RESET_N")
	)
	(segment
		(start 11.706098 -115.778026)
		(end 11.3411 -116.143024)
		(width 0.127)
		(layer "In5.Cu")
		(net "TRAY_RESET_N")
	)
	(segment
		(start 13.122148 -121.705116)
		(end 13.122148 -122.094752)
		(width 0.127)
		(layer "In5.Cu")
		(net "TRAY_RESET_N")
	)
	(segment
		(start 66.548508 -27.215084)
		(end 57.887616 -27.215084)
		(width 0.127)
		(layer "In5.Cu")
		(net "TRAY_RESET_N")
	)
	(segment
		(start 57.727342 -27.05481)
		(end 57.032398 -27.05481)
		(width 0.127)
		(layer "In5.Cu")
		(net "TRAY_RESET_N")
	)
	(segment
		(start 11.3411 -116.143024)
		(end 11.3411 -117.111018)
		(width 0.127)
		(layer "In5.Cu")
		(net "TRAY_RESET_N")
	)
	(segment
		(start 13.122148 -122.094752)
		(end 12.770866 -122.446034)
		(width 0.127)
		(layer "In5.Cu")
		(net "TRAY_RESET_N")
	)
	(segment
		(start 12.035282 -117.8052)
		(end 12.283186 -117.8052)
		(width 0.127)
		(layer "In5.Cu")
		(net "TRAY_RESET_N")
	)
	(segment
		(start 12.770866 -120.754648)
		(end 13.091414 -121.075196)
		(width 0.127)
		(layer "In5.Cu")
		(net "TRAY_RESET_N")
	)
	(segment
		(start 12.770866 -123.804934)
		(end 6.2992 -130.2766)
		(width 0.127)
		(layer "In5.Cu")
		(net "TRAY_RESET_N")
	)
	(segment
		(start 13.091414 -121.674382)
		(end 13.122148 -121.705116)
		(width 0.127)
		(layer "In5.Cu")
		(net "TRAY_RESET_N")
	)
	(segment
		(start 12.770866 -118.29288)
		(end 12.770866 -120.754648)
		(width 0.127)
		(layer "In5.Cu")
		(net "TRAY_RESET_N")
	)
	(segment
		(start 57.032398 -27.05481)
		(end 56.240172 -27.847036)
		(width 0.127)
		(layer "In5.Cu")
		(net "TRAY_RESET_N")
	)
	(segment
		(start 12.283186 -117.8052)
		(end 12.770866 -118.29288)
		(width 0.127)
		(layer "In5.Cu")
		(net "TRAY_RESET_N")
	)
	(segment
		(start 11.3411 -117.111018)
		(end 12.035282 -117.8052)
		(width 0.127)
		(layer "In5.Cu")
		(net "TRAY_RESET_N")
	)
	(segment
		(start 19.9517 -137.287)
		(end 18.288 -137.287)
		(width 0.12065)
		(layer "F.Cu")
		(net "TRAY_POWER_CRIT_N")
	)
	(segment
		(start 65.83299 -30.121606)
		(end 63.545974 -30.121606)
		(width 0.12065)
		(layer "F.Cu")
		(net "TRAY_POWER_CRIT_N")
	)
	(segment
		(start 65.870074 -30.11932)
		(end 65.835276 -30.11932)
		(width 0.12065)
		(layer "F.Cu")
		(net "TRAY_POWER_CRIT_N")
	)
	(segment
		(start 65.835276 -30.11932)
		(end 65.83299 -30.121606)
		(width 0.12065)
		(layer "F.Cu")
		(net "TRAY_POWER_CRIT_N")
	)
	(segment
		(start 57.0484 -30.4927)
		(end 57.0484 -29.68752)
		(width 0.12065)
		(layer "F.Cu")
		(net "TRAY_POWER_CRIT_N")
	)
	(segment
		(start 57.0484 -29.68752)
		(end 57.042304 -29.636212)
		(width 0.12065)
		(layer "F.Cu")
		(net "TRAY_POWER_CRIT_N")
	)
	(segment
		(start 18.288 -137.287)
		(end 17.78 -137.795)
		(width 0.12065)
		(layer "F.Cu")
		(net "TRAY_POWER_CRIT_N")
	)
	(segment
		(start 20.5105 -136.7282)
		(end 19.9517 -137.287)
		(width 0.12065)
		(layer "F.Cu")
		(net "TRAY_POWER_CRIT_N")
	)
	(via
		(at 57.042304 -29.636212)
		(size 0.508)
		(drill 0.254)
		(layers "F.Cu" "B.Cu")
		(net "TRAY_POWER_CRIT_N")
	)
	(via
		(at 65.870074 -30.11932)
		(size 0.508)
		(drill 0.254)
		(layers "F.Cu" "B.Cu")
		(net "TRAY_POWER_CRIT_N")
	)
	(via
		(at 46.186852 -84.526882)
		(size 0.7112)
		(drill 0.3556)
		(layers "F.Cu" "B.Cu")
		(net "TRAY_POWER_CRIT_N")
	)
	(via
		(at 46.474126 -89.570814)
		(size 0.508)
		(drill 0.254)
		(layers "F.Cu" "B.Cu")
		(net "TRAY_POWER_CRIT_N")
	)
	(via
		(at 17.78 -137.795)
		(size 0.508)
		(drill 0.254)
		(layers "F.Cu" "B.Cu")
		(net "TRAY_POWER_CRIT_N")
	)
	(segment
		(start 44.90085 -72.889618)
		(end 46.366684 -74.355452)
		(width 0.12065)
		(layer "B.Cu")
		(net "TRAY_POWER_CRIT_N")
	)
	(segment
		(start 57.042304 -30.66923)
		(end 55.698136 -32.013398)
		(width 0.12065)
		(layer "B.Cu")
		(net "TRAY_POWER_CRIT_N")
	)
	(segment
		(start 45.63745 -49.84623)
		(end 45.63745 -66.77406)
		(width 0.12065)
		(layer "B.Cu")
		(net "TRAY_POWER_CRIT_N")
	)
	(segment
		(start 46.474126 -89.570814)
		(end 45.876718 -88.973406)
		(width 0.12065)
		(layer "B.Cu")
		(net "TRAY_POWER_CRIT_N")
	)
	(segment
		(start 44.90085 -67.51066)
		(end 44.90085 -72.889618)
		(width 0.12065)
		(layer "B.Cu")
		(net "TRAY_POWER_CRIT_N")
	)
	(segment
		(start 46.366684 -74.355452)
		(end 46.366684 -84.34705)
		(width 0.12065)
		(layer "B.Cu")
		(net "TRAY_POWER_CRIT_N")
	)
	(segment
		(start 45.876718 -88.973406)
		(end 45.876718 -84.837016)
		(width 0.12065)
		(layer "B.Cu")
		(net "TRAY_POWER_CRIT_N")
	)
	(segment
		(start 55.698136 -32.013398)
		(end 54.97703 -32.013398)
		(width 0.12065)
		(layer "B.Cu")
		(net "TRAY_POWER_CRIT_N")
	)
	(segment
		(start 45.63745 -66.77406)
		(end 44.90085 -67.51066)
		(width 0.12065)
		(layer "B.Cu")
		(net "TRAY_POWER_CRIT_N")
	)
	(segment
		(start 46.1518 -49.33188)
		(end 45.63745 -49.84623)
		(width 0.12065)
		(layer "B.Cu")
		(net "TRAY_POWER_CRIT_N")
	)
	(segment
		(start 46.1518 -40.838628)
		(end 46.1518 -49.33188)
		(width 0.12065)
		(layer "B.Cu")
		(net "TRAY_POWER_CRIT_N")
	)
	(segment
		(start 54.97703 -32.013398)
		(end 46.1518 -40.838628)
		(width 0.12065)
		(layer "B.Cu")
		(net "TRAY_POWER_CRIT_N")
	)
	(segment
		(start 46.366684 -84.34705)
		(end 46.186852 -84.526882)
		(width 0.12065)
		(layer "B.Cu")
		(net "TRAY_POWER_CRIT_N")
	)
	(segment
		(start 45.876718 -84.837016)
		(end 46.186852 -84.526882)
		(width 0.12065)
		(layer "B.Cu")
		(net "TRAY_POWER_CRIT_N")
	)
	(segment
		(start 57.042304 -29.636212)
		(end 57.042304 -30.66923)
		(width 0.12065)
		(layer "B.Cu")
		(net "TRAY_POWER_CRIT_N")
	)
	(segment
		(start 14.128496 -136.524746)
		(end 13.648182 -136.524746)
		(width 0.127)
		(layer "In2.Cu")
		(net "TRAY_POWER_CRIT_N")
	)
	(segment
		(start 9.4615 -118.510558)
		(end 8.8646 -117.913658)
		(width 0.127)
		(layer "In2.Cu")
		(net "TRAY_POWER_CRIT_N")
	)
	(segment
		(start 8.0772 -122.252994)
		(end 8.78078 -121.549414)
		(width 0.127)
		(layer "In2.Cu")
		(net "TRAY_POWER_CRIT_N")
	)
	(segment
		(start 13.648182 -136.524746)
		(end 13.64742 -136.523984)
		(width 0.127)
		(layer "In2.Cu")
		(net "TRAY_POWER_CRIT_N")
	)
	(segment
		(start 10.495788 -111.506)
		(end 12.882118 -109.11967)
		(width 0.127)
		(layer "In2.Cu")
		(net "TRAY_POWER_CRIT_N")
	)
	(segment
		(start 18.56486 -99.75469)
		(end 24.260556 -94.058994)
		(width 0.127)
		(layer "In2.Cu")
		(net "TRAY_POWER_CRIT_N")
	)
	(segment
		(start 15.710916 -102.967282)
		(end 16.404336 -102.273862)
		(width 0.127)
		(layer "In2.Cu")
		(net "TRAY_POWER_CRIT_N")
	)
	(segment
		(start 8.8646 -115.308634)
		(end 10.495788 -113.677446)
		(width 0.127)
		(layer "In2.Cu")
		(net "TRAY_POWER_CRIT_N")
	)
	(segment
		(start 8.8646 -117.913658)
		(end 8.8646 -115.308634)
		(width 0.127)
		(layer "In2.Cu")
		(net "TRAY_POWER_CRIT_N")
	)
	(segment
		(start 13.647166 -136.523984)
		(end 8.582406 -131.459224)
		(width 0.127)
		(layer "In2.Cu")
		(net "TRAY_POWER_CRIT_N")
	)
	(segment
		(start 13.023342 -105.655364)
		(end 13.380212 -105.298494)
		(width 0.127)
		(layer "In2.Cu")
		(net "TRAY_POWER_CRIT_N")
	)
	(segment
		(start 16.404336 -102.273862)
		(end 16.635476 -102.042468)
		(width 0.127)
		(layer "In2.Cu")
		(net "TRAY_POWER_CRIT_N")
	)
	(segment
		(start 16.895318 -137.414)
		(end 15.01775 -137.414)
		(width 0.127)
		(layer "In2.Cu")
		(net "TRAY_POWER_CRIT_N")
	)
	(segment
		(start 17.276318 -137.795)
		(end 16.895318 -137.414)
		(width 0.127)
		(layer "In2.Cu")
		(net "TRAY_POWER_CRIT_N")
	)
	(segment
		(start 29.84119 -90.17)
		(end 45.87494 -90.17)
		(width 0.127)
		(layer "In2.Cu")
		(net "TRAY_POWER_CRIT_N")
	)
	(segment
		(start 8.582406 -131.459224)
		(end 8.582406 -131.45897)
		(width 0.127)
		(layer "In2.Cu")
		(net "TRAY_POWER_CRIT_N")
	)
	(segment
		(start 45.87494 -90.17)
		(end 46.474126 -89.570814)
		(width 0.127)
		(layer "In2.Cu")
		(net "TRAY_POWER_CRIT_N")
	)
	(segment
		(start 18.56486 -100.113084)
		(end 18.56486 -99.75469)
		(width 0.127)
		(layer "In2.Cu")
		(net "TRAY_POWER_CRIT_N")
	)
	(segment
		(start 8.78078 -120.556274)
		(end 9.4615 -119.875554)
		(width 0.127)
		(layer "In2.Cu")
		(net "TRAY_POWER_CRIT_N")
	)
	(segment
		(start 12.6873 -107.684316)
		(end 12.6873 -105.992168)
		(width 0.127)
		(layer "In2.Cu")
		(net "TRAY_POWER_CRIT_N")
	)
	(segment
		(start 12.881864 -105.797604)
		(end 12.881864 -105.797096)
		(width 0.127)
		(layer "In2.Cu")
		(net "TRAY_POWER_CRIT_N")
	)
	(segment
		(start 15.01775 -137.414)
		(end 14.128496 -136.524746)
		(width 0.127)
		(layer "In2.Cu")
		(net "TRAY_POWER_CRIT_N")
	)
	(segment
		(start 16.635476 -102.042468)
		(end 18.56486 -100.113084)
		(width 0.127)
		(layer "In2.Cu")
		(net "TRAY_POWER_CRIT_N")
	)
	(segment
		(start 12.881864 -105.797096)
		(end 13.023342 -105.655364)
		(width 0.127)
		(layer "In2.Cu")
		(net "TRAY_POWER_CRIT_N")
	)
	(segment
		(start 24.260556 -94.058994)
		(end 25.895808 -94.058994)
		(width 0.127)
		(layer "In2.Cu")
		(net "TRAY_POWER_CRIT_N")
	)
	(segment
		(start 10.495788 -113.677446)
		(end 10.495788 -111.506)
		(width 0.127)
		(layer "In2.Cu")
		(net "TRAY_POWER_CRIT_N")
	)
	(segment
		(start 17.78 -137.795)
		(end 17.276318 -137.795)
		(width 0.127)
		(layer "In2.Cu")
		(net "TRAY_POWER_CRIT_N")
	)
	(segment
		(start 25.898602 -94.0562)
		(end 25.95499 -94.0562)
		(width 0.127)
		(layer "In2.Cu")
		(net "TRAY_POWER_CRIT_N")
	)
	(segment
		(start 12.6873 -105.992168)
		(end 12.881864 -105.797604)
		(width 0.127)
		(layer "In2.Cu")
		(net "TRAY_POWER_CRIT_N")
	)
	(segment
		(start 8.78078 -121.549414)
		(end 8.78078 -120.556274)
		(width 0.127)
		(layer "In2.Cu")
		(net "TRAY_POWER_CRIT_N")
	)
	(segment
		(start 8.0772 -130.953764)
		(end 8.0772 -122.252994)
		(width 0.127)
		(layer "In2.Cu")
		(net "TRAY_POWER_CRIT_N")
	)
	(segment
		(start 9.4615 -119.875554)
		(end 9.4615 -118.510558)
		(width 0.127)
		(layer "In2.Cu")
		(net "TRAY_POWER_CRIT_N")
	)
	(segment
		(start 12.882118 -109.11967)
		(end 12.882118 -107.879388)
		(width 0.127)
		(layer "In2.Cu")
		(net "TRAY_POWER_CRIT_N")
	)
	(segment
		(start 8.582406 -131.45897)
		(end 8.0772 -130.953764)
		(width 0.127)
		(layer "In2.Cu")
		(net "TRAY_POWER_CRIT_N")
	)
	(segment
		(start 13.64742 -136.523984)
		(end 13.647166 -136.523984)
		(width 0.127)
		(layer "In2.Cu")
		(net "TRAY_POWER_CRIT_N")
	)
	(segment
		(start 13.380212 -105.298494)
		(end 15.710916 -102.967282)
		(width 0.127)
		(layer "In2.Cu")
		(net "TRAY_POWER_CRIT_N")
	)
	(segment
		(start 12.882118 -107.879388)
		(end 12.6873 -107.684316)
		(width 0.127)
		(layer "In2.Cu")
		(net "TRAY_POWER_CRIT_N")
	)
	(segment
		(start 25.895808 -94.058994)
		(end 25.898602 -94.0562)
		(width 0.127)
		(layer "In2.Cu")
		(net "TRAY_POWER_CRIT_N")
	)
	(segment
		(start 25.95499 -94.0562)
		(end 29.84119 -90.17)
		(width 0.127)
		(layer "In2.Cu")
		(net "TRAY_POWER_CRIT_N")
	)
	(segment
		(start 57.042304 -29.636212)
		(end 57.525412 -30.11932)
		(width 0.127)
		(layer "In5.Cu")
		(net "TRAY_POWER_CRIT_N")
	)
	(segment
		(start 57.525412 -30.11932)
		(end 65.870074 -30.11932)
		(width 0.127)
		(layer "In5.Cu")
		(net "TRAY_POWER_CRIT_N")
	)
	(segment
		(start 19.1008 -139.5222)
		(end 19.8628 -138.7602)
		(width 0.12065)
		(layer "F.Cu")
		(net "TRAY_ID2")
	)
	(segment
		(start 59.871102 -22.501606)
		(end 57.953402 -22.501606)
		(width 0.12065)
		(layer "F.Cu")
		(net "TRAY_ID2")
	)
	(segment
		(start 18.7198 -139.5222)
		(end 19.1008 -139.5222)
		(width 0.12065)
		(layer "F.Cu")
		(net "TRAY_ID2")
	)
	(segment
		(start 19.8628 -138.7602)
		(end 20.5105 -138.7602)
		(width 0.12065)
		(layer "F.Cu")
		(net "TRAY_ID2")
	)
	(via
		(at 18.7198 -139.5222)
		(size 0.508)
		(drill 0.254)
		(layers "F.Cu" "B.Cu")
		(net "TRAY_ID2")
	)
	(via
		(at 49.76876 -88.598756)
		(size 0.508)
		(drill 0.254)
		(layers "F.Cu" "B.Cu")
		(net "TRAY_ID2")
	)
	(via
		(at 57.953402 -22.501606)
		(size 0.508)
		(drill 0.254)
		(layers "F.Cu" "B.Cu")
		(net "TRAY_ID2")
	)
	(via
		(at 47.589694 -86.914482)
		(size 0.7112)
		(drill 0.3556)
		(layers "F.Cu" "B.Cu")
		(net "TRAY_ID2")
	)
	(segment
		(start 48.084486 -86.914482)
		(end 49.76876 -88.598756)
		(width 0.12065)
		(layer "B.Cu")
		(net "TRAY_ID2")
	)
	(segment
		(start 66.678302 -28.61945)
		(end 66.678302 -23.720298)
		(width 0.12065)
		(layer "B.Cu")
		(net "TRAY_ID2")
	)
	(segment
		(start 63.514732 -31.78302)
		(end 66.678302 -28.61945)
		(width 0.12065)
		(layer "B.Cu")
		(net "TRAY_ID2")
	)
	(segment
		(start 65.45961 -22.501606)
		(end 57.953402 -22.501606)
		(width 0.12065)
		(layer "B.Cu")
		(net "TRAY_ID2")
	)
	(segment
		(start 58.232548 -33.319212)
		(end 59.76874 -31.78302)
		(width 0.12065)
		(layer "B.Cu")
		(net "TRAY_ID2")
	)
	(segment
		(start 47.589694 -86.914482)
		(end 47.23384 -86.558628)
		(width 0.12065)
		(layer "B.Cu")
		(net "TRAY_ID2")
	)
	(segment
		(start 47.589694 -86.914482)
		(end 48.084486 -86.914482)
		(width 0.12065)
		(layer "B.Cu")
		(net "TRAY_ID2")
	)
	(segment
		(start 54.695344 -33.319212)
		(end 58.232548 -33.319212)
		(width 0.12065)
		(layer "B.Cu")
		(net "TRAY_ID2")
	)
	(segment
		(start 47.609252 -68.904866)
		(end 47.211996 -68.50761)
		(width 0.12065)
		(layer "B.Cu")
		(net "TRAY_ID2")
	)
	(segment
		(start 66.678302 -23.720298)
		(end 65.45961 -22.501606)
		(width 0.12065)
		(layer "B.Cu")
		(net "TRAY_ID2")
	)
	(segment
		(start 59.76874 -31.78302)
		(end 63.514732 -31.78302)
		(width 0.12065)
		(layer "B.Cu")
		(net "TRAY_ID2")
	)
	(segment
		(start 47.23384 -74.114152)
		(end 47.609252 -73.73874)
		(width 0.12065)
		(layer "B.Cu")
		(net "TRAY_ID2")
	)
	(segment
		(start 47.23384 -86.558628)
		(end 47.23384 -74.114152)
		(width 0.12065)
		(layer "B.Cu")
		(net "TRAY_ID2")
	)
	(segment
		(start 47.211996 -40.80256)
		(end 54.695344 -33.319212)
		(width 0.12065)
		(layer "B.Cu")
		(net "TRAY_ID2")
	)
	(segment
		(start 47.609252 -73.73874)
		(end 47.609252 -68.904866)
		(width 0.12065)
		(layer "B.Cu")
		(net "TRAY_ID2")
	)
	(segment
		(start 47.211996 -68.50761)
		(end 47.211996 -40.80256)
		(width 0.12065)
		(layer "B.Cu")
		(net "TRAY_ID2")
	)
	(segment
		(start 45.190664 -89.352882)
		(end 46.064424 -88.479122)
		(width 0.127)
		(layer "In2.Cu")
		(net "TRAY_ID2")
	)
	(segment
		(start 46.064424 -88.479122)
		(end 49.649126 -88.479122)
		(width 0.127)
		(layer "In2.Cu")
		(net "TRAY_ID2")
	)
	(segment
		(start 9.5504 -110.410752)
		(end 11.176 -108.785152)
		(width 0.127)
		(layer "In2.Cu")
		(net "TRAY_ID2")
	)
	(segment
		(start 13.244576 -104.3559)
		(end 15.171928 -102.428294)
		(width 0.127)
		(layer "In2.Cu")
		(net "TRAY_ID2")
	)
	(segment
		(start 23.945342 -93.296486)
		(end 24.150828 -93.091)
		(width 0.127)
		(layer "In2.Cu")
		(net "TRAY_ID2")
	)
	(segment
		(start 18.0213 -138.8237)
		(end 15.66545 -138.8237)
		(width 0.127)
		(layer "In2.Cu")
		(net "TRAY_ID2")
	)
	(segment
		(start 17.80286 -99.438714)
		(end 23.945088 -93.296486)
		(width 0.127)
		(layer "In2.Cu")
		(net "TRAY_ID2")
	)
	(segment
		(start 12.120372 -105.480612)
		(end 12.337796 -105.26268)
		(width 0.127)
		(layer "In2.Cu")
		(net "TRAY_ID2")
	)
	(segment
		(start 8.01878 -121.233438)
		(end 8.01878 -115.076478)
		(width 0.127)
		(layer "In2.Cu")
		(net "TRAY_ID2")
	)
	(segment
		(start 8.01878 -115.076478)
		(end 9.5504 -113.544858)
		(width 0.127)
		(layer "In2.Cu")
		(net "TRAY_ID2")
	)
	(segment
		(start 15.171928 -102.428294)
		(end 15.865094 -101.734874)
		(width 0.127)
		(layer "In2.Cu")
		(net "TRAY_ID2")
	)
	(segment
		(start 12.11961 -105.481374)
		(end 12.120372 -105.480612)
		(width 0.127)
		(layer "In2.Cu")
		(net "TRAY_ID2")
	)
	(segment
		(start 13.33246 -137.287254)
		(end 7.2644 -131.219194)
		(width 0.127)
		(layer "In2.Cu")
		(net "TRAY_ID2")
	)
	(segment
		(start 15.865094 -101.734874)
		(end 17.80286 -99.797108)
		(width 0.127)
		(layer "In2.Cu")
		(net "TRAY_ID2")
	)
	(segment
		(start 15.66545 -138.8237)
		(end 15.665196 -138.823954)
		(width 0.127)
		(layer "In2.Cu")
		(net "TRAY_ID2")
	)
	(segment
		(start 11.9253 -105.676192)
		(end 12.11961 -105.481882)
		(width 0.127)
		(layer "In2.Cu")
		(net "TRAY_ID2")
	)
	(segment
		(start 13.648182 -137.287)
		(end 13.647928 -137.287254)
		(width 0.127)
		(layer "In2.Cu")
		(net "TRAY_ID2")
	)
	(segment
		(start 15.349728 -138.823954)
		(end 13.812774 -137.287)
		(width 0.127)
		(layer "In2.Cu")
		(net "TRAY_ID2")
	)
	(segment
		(start 9.5504 -113.544858)
		(end 9.5504 -110.410752)
		(width 0.127)
		(layer "In2.Cu")
		(net "TRAY_ID2")
	)
	(segment
		(start 49.649126 -88.479122)
		(end 49.76876 -88.598756)
		(width 0.127)
		(layer "In2.Cu")
		(net "TRAY_ID2")
	)
	(segment
		(start 17.80286 -99.797108)
		(end 17.80286 -99.438714)
		(width 0.127)
		(layer "In2.Cu")
		(net "TRAY_ID2")
	)
	(segment
		(start 27.145488 -90.5764)
		(end 28.286964 -90.5764)
		(width 0.127)
		(layer "In2.Cu")
		(net "TRAY_ID2")
	)
	(segment
		(start 12.11961 -105.481882)
		(end 12.11961 -105.481374)
		(width 0.127)
		(layer "In2.Cu")
		(net "TRAY_ID2")
	)
	(segment
		(start 18.7198 -139.5222)
		(end 18.0213 -138.8237)
		(width 0.127)
		(layer "In2.Cu")
		(net "TRAY_ID2")
	)
	(segment
		(start 7.2644 -121.987818)
		(end 8.01878 -121.233438)
		(width 0.127)
		(layer "In2.Cu")
		(net "TRAY_ID2")
	)
	(segment
		(start 13.647928 -137.287254)
		(end 13.33246 -137.287254)
		(width 0.127)
		(layer "In2.Cu")
		(net "TRAY_ID2")
	)
	(segment
		(start 23.945088 -93.296486)
		(end 23.945342 -93.296486)
		(width 0.127)
		(layer "In2.Cu")
		(net "TRAY_ID2")
	)
	(segment
		(start 11.176 -106.913426)
		(end 11.9253 -106.164126)
		(width 0.127)
		(layer "In2.Cu")
		(net "TRAY_ID2")
	)
	(segment
		(start 24.630888 -93.091)
		(end 27.145488 -90.5764)
		(width 0.127)
		(layer "In2.Cu")
		(net "TRAY_ID2")
	)
	(segment
		(start 7.2644 -131.219194)
		(end 7.2644 -121.987818)
		(width 0.127)
		(layer "In2.Cu")
		(net "TRAY_ID2")
	)
	(segment
		(start 11.176 -108.785152)
		(end 11.176 -106.913426)
		(width 0.127)
		(layer "In2.Cu")
		(net "TRAY_ID2")
	)
	(segment
		(start 15.665196 -138.823954)
		(end 15.349728 -138.823954)
		(width 0.127)
		(layer "In2.Cu")
		(net "TRAY_ID2")
	)
	(segment
		(start 11.9253 -106.164126)
		(end 11.9253 -105.676192)
		(width 0.127)
		(layer "In2.Cu")
		(net "TRAY_ID2")
	)
	(segment
		(start 24.150828 -93.091)
		(end 24.630888 -93.091)
		(width 0.127)
		(layer "In2.Cu")
		(net "TRAY_ID2")
	)
	(segment
		(start 12.337796 -105.26268)
		(end 13.244576 -104.3559)
		(width 0.127)
		(layer "In2.Cu")
		(net "TRAY_ID2")
	)
	(segment
		(start 13.812774 -137.287)
		(end 13.648182 -137.287)
		(width 0.127)
		(layer "In2.Cu")
		(net "TRAY_ID2")
	)
	(segment
		(start 29.510482 -89.352882)
		(end 45.190664 -89.352882)
		(width 0.127)
		(layer "In2.Cu")
		(net "TRAY_ID2")
	)
	(segment
		(start 28.286964 -90.5764)
		(end 29.510482 -89.352882)
		(width 0.127)
		(layer "In2.Cu")
		(net "TRAY_ID2")
	)
	(segment
		(start 17.5514 -139.4968)
		(end 18.1102 -138.938)
		(width 0.12065)
		(layer "F.Cu")
		(net "TRAY_ID1")
	)
	(segment
		(start 63.545974 -22.501606)
		(end 65.522094 -22.501606)
		(width 0.12065)
		(layer "F.Cu")
		(net "TRAY_ID1")
	)
	(segment
		(start 20.1168 -137.7442)
		(end 20.5105 -137.7442)
		(width 0.12065)
		(layer "F.Cu")
		(net "TRAY_ID1")
	)
	(segment
		(start 18.923 -138.938)
		(end 20.1168 -137.7442)
		(width 0.12065)
		(layer "F.Cu")
		(net "TRAY_ID1")
	)
	(segment
		(start 18.1102 -138.938)
		(end 18.923 -138.938)
		(width 0.12065)
		(layer "F.Cu")
		(net "TRAY_ID1")
	)
	(segment
		(start 65.522094 -22.501606)
		(end 66.182748 -21.840952)
		(width 0.12065)
		(layer "F.Cu")
		(net "TRAY_ID1")
	)
	(via
		(at 44.875196 -87.613236)
		(size 0.508)
		(drill 0.254)
		(layers "F.Cu" "B.Cu")
		(net "TRAY_ID1")
	)
	(via
		(at 66.182748 -21.840952)
		(size 0.508)
		(drill 0.254)
		(layers "F.Cu" "B.Cu")
		(net "TRAY_ID1")
	)
	(via
		(at 44.920916 -84.416138)
		(size 0.7112)
		(drill 0.3556)
		(layers "F.Cu" "B.Cu")
		(net "TRAY_ID1")
	)
	(via
		(at 17.5514 -139.4968)
		(size 0.508)
		(drill 0.254)
		(layers "F.Cu" "B.Cu")
		(net "TRAY_ID1")
	)
	(segment
		(start 55.497476 -26.648918)
		(end 56.228742 -27.380184)
		(width 0.12065)
		(layer "B.Cu")
		(net "TRAY_ID1")
	)
	(segment
		(start 56.707024 -28.093416)
		(end 44.2722 -40.52824)
		(width 0.12065)
		(layer "B.Cu")
		(net "TRAY_ID1")
	)
	(segment
		(start 44.2722 -63.917576)
		(end 42.338498 -65.851278)
		(width 0.12065)
		(layer "B.Cu")
		(net "TRAY_ID1")
	)
	(segment
		(start 56.228742 -27.380184)
		(end 56.433466 -27.380184)
		(width 0.12065)
		(layer "B.Cu")
		(net "TRAY_ID1")
	)
	(segment
		(start 55.497476 -23.799292)
		(end 55.497476 -26.648918)
		(width 0.12065)
		(layer "B.Cu")
		(net "TRAY_ID1")
	)
	(segment
		(start 56.433466 -27.380184)
		(end 56.707024 -27.653742)
		(width 0.12065)
		(layer "B.Cu")
		(net "TRAY_ID1")
	)
	(segment
		(start 44.2722 -40.52824)
		(end 44.2722 -63.917576)
		(width 0.12065)
		(layer "B.Cu")
		(net "TRAY_ID1")
	)
	(segment
		(start 57.45353 -21.843238)
		(end 55.497476 -23.799292)
		(width 0.12065)
		(layer "B.Cu")
		(net "TRAY_ID1")
	)
	(segment
		(start 56.707024 -27.653742)
		(end 56.707024 -28.093416)
		(width 0.12065)
		(layer "B.Cu")
		(net "TRAY_ID1")
	)
	(segment
		(start 66.180462 -21.843238)
		(end 57.45353 -21.843238)
		(width 0.12065)
		(layer "B.Cu")
		(net "TRAY_ID1")
	)
	(segment
		(start 44.875196 -87.613236)
		(end 44.875196 -87.649812)
		(width 0.12065)
		(layer "B.Cu")
		(net "TRAY_ID1")
	)
	(segment
		(start 42.338498 -65.851278)
		(end 42.338498 -72.299322)
		(width 0.12065)
		(layer "B.Cu")
		(net "TRAY_ID1")
	)
	(segment
		(start 44.875196 -87.649812)
		(end 44.920916 -87.604092)
		(width 0.12065)
		(layer "B.Cu")
		(net "TRAY_ID1")
	)
	(segment
		(start 44.920916 -74.88174)
		(end 44.920916 -84.416138)
		(width 0.12065)
		(layer "B.Cu")
		(net "TRAY_ID1")
	)
	(segment
		(start 44.920916 -87.604092)
		(end 44.920916 -84.416138)
		(width 0.12065)
		(layer "B.Cu")
		(net "TRAY_ID1")
	)
	(segment
		(start 66.182748 -21.840952)
		(end 66.180462 -21.843238)
		(width 0.12065)
		(layer "B.Cu")
		(net "TRAY_ID1")
	)
	(segment
		(start 42.338498 -72.299322)
		(end 44.920916 -74.88174)
		(width 0.12065)
		(layer "B.Cu")
		(net "TRAY_ID1")
	)
	(segment
		(start 24.201374 -92.277946)
		(end 24.201628 -92.2782)
		(width 0.127)
		(layer "In2.Cu")
		(net "TRAY_ID1")
	)
	(segment
		(start 11.94435 -104.577388)
		(end 12.284202 -104.23779)
		(width 0.127)
		(layer "In2.Cu")
		(net "TRAY_ID1")
	)
	(segment
		(start 20.498054 -95.636588)
		(end 23.856442 -92.2782)
		(width 0.127)
		(layer "In2.Cu")
		(net "TRAY_ID1")
	)
	(segment
		(start 23.856442 -92.2782)
		(end 23.885652 -92.2782)
		(width 0.127)
		(layer "In2.Cu")
		(net "TRAY_ID1")
	)
	(segment
		(start 11.358118 -104.741726)
		(end 11.780266 -104.741726)
		(width 0.127)
		(layer "In2.Cu")
		(net "TRAY_ID1")
	)
	(segment
		(start 17.823434 -97.02165)
		(end 19.208496 -95.636588)
		(width 0.127)
		(layer "In2.Cu")
		(net "TRAY_ID1")
	)
	(segment
		(start 27.970988 -89.8144)
		(end 29.284422 -88.500966)
		(width 0.127)
		(layer "In2.Cu")
		(net "TRAY_ID1")
	)
	(segment
		(start 43.987212 -88.50122)
		(end 44.875196 -87.613236)
		(width 0.127)
		(layer "In2.Cu")
		(net "TRAY_ID1")
	)
	(segment
		(start 13.496798 -138.049254)
		(end 13.016484 -138.049254)
		(width 0.127)
		(layer "In2.Cu")
		(net "TRAY_ID1")
	)
	(segment
		(start 6.5024 -131.53517)
		(end 6.5024 -121.671842)
		(width 0.127)
		(layer "In2.Cu")
		(net "TRAY_ID1")
	)
	(segment
		(start 9.920986 -108.96219)
		(end 9.920986 -106.178858)
		(width 0.127)
		(layer "In2.Cu")
		(net "TRAY_ID1")
	)
	(segment
		(start 11.797792 -104.7242)
		(end 11.94435 -104.577388)
		(width 0.127)
		(layer "In2.Cu")
		(net "TRAY_ID1")
	)
	(segment
		(start 26.829512 -89.8144)
		(end 27.970988 -89.8144)
		(width 0.127)
		(layer "In2.Cu")
		(net "TRAY_ID1")
	)
	(segment
		(start 17.04086 -99.481132)
		(end 17.04086 -99.122738)
		(width 0.127)
		(layer "In2.Cu")
		(net "TRAY_ID1")
	)
	(segment
		(start 23.885652 -92.2782)
		(end 23.885906 -92.277946)
		(width 0.127)
		(layer "In2.Cu")
		(net "TRAY_ID1")
	)
	(segment
		(start 29.284422 -88.500966)
		(end 29.59989 -88.500966)
		(width 0.127)
		(layer "In2.Cu")
		(net "TRAY_ID1")
	)
	(segment
		(start 29.59989 -88.500966)
		(end 29.600144 -88.50122)
		(width 0.127)
		(layer "In2.Cu")
		(net "TRAY_ID1")
	)
	(segment
		(start 7.25678 -120.917462)
		(end 7.25678 -111.626396)
		(width 0.127)
		(layer "In2.Cu")
		(net "TRAY_ID1")
	)
	(segment
		(start 19.208496 -95.636588)
		(end 20.498054 -95.636588)
		(width 0.127)
		(layer "In2.Cu")
		(net "TRAY_ID1")
	)
	(segment
		(start 29.600144 -88.50122)
		(end 43.987212 -88.50122)
		(width 0.127)
		(layer "In2.Cu")
		(net "TRAY_ID1")
	)
	(segment
		(start 7.25678 -111.626396)
		(end 9.920986 -108.96219)
		(width 0.127)
		(layer "In2.Cu")
		(net "TRAY_ID1")
	)
	(segment
		(start 9.920986 -106.178858)
		(end 11.358118 -104.741726)
		(width 0.127)
		(layer "In2.Cu")
		(net "TRAY_ID1")
	)
	(segment
		(start 11.780266 -104.741726)
		(end 11.797792 -104.7242)
		(width 0.127)
		(layer "In2.Cu")
		(net "TRAY_ID1")
	)
	(segment
		(start 24.365712 -92.2782)
		(end 26.829512 -89.8144)
		(width 0.127)
		(layer "In2.Cu")
		(net "TRAY_ID1")
	)
	(segment
		(start 12.284202 -104.23779)
		(end 17.04086 -99.481132)
		(width 0.127)
		(layer "In2.Cu")
		(net "TRAY_ID1")
	)
	(segment
		(start 17.04086 -99.122738)
		(end 17.823434 -98.340164)
		(width 0.127)
		(layer "In2.Cu")
		(net "TRAY_ID1")
	)
	(segment
		(start 6.5024 -121.671842)
		(end 7.25678 -120.917462)
		(width 0.127)
		(layer "In2.Cu")
		(net "TRAY_ID1")
	)
	(segment
		(start 24.201628 -92.2782)
		(end 24.365712 -92.2782)
		(width 0.127)
		(layer "In2.Cu")
		(net "TRAY_ID1")
	)
	(segment
		(start 23.885906 -92.277946)
		(end 24.201374 -92.277946)
		(width 0.127)
		(layer "In2.Cu")
		(net "TRAY_ID1")
	)
	(segment
		(start 17.5514 -139.4968)
		(end 17.203674 -139.844526)
		(width 0.127)
		(layer "In2.Cu")
		(net "TRAY_ID1")
	)
	(segment
		(start 17.823434 -98.340164)
		(end 17.823434 -97.02165)
		(width 0.127)
		(layer "In2.Cu")
		(net "TRAY_ID1")
	)
	(segment
		(start 15.29207 -139.844526)
		(end 13.496798 -138.049254)
		(width 0.127)
		(layer "In2.Cu")
		(net "TRAY_ID1")
	)
	(segment
		(start 17.203674 -139.844526)
		(end 15.29207 -139.844526)
		(width 0.127)
		(layer "In2.Cu")
		(net "TRAY_ID1")
	)
	(segment
		(start 13.016484 -138.049254)
		(end 6.5024 -131.53517)
		(width 0.127)
		(layer "In2.Cu")
		(net "TRAY_ID1")
	)
	(segment
		(start 59.871102 -23.771606)
		(end 57.953402 -23.771606)
		(width 0.12065)
		(layer "F.Cu")
		(net "TRAY_ID0")
	)
	(segment
		(start 15.7988 -136.2964)
		(end 15.7988 -135.11784)
		(width 0.12065)
		(layer "F.Cu")
		(net "TRAY_ID0")
	)
	(segment
		(start 15.6972 -136.398)
		(end 15.7988 -136.2964)
		(width 0.12065)
		(layer "F.Cu")
		(net "TRAY_ID0")
	)
	(segment
		(start 15.7988 -135.11784)
		(end 16.99006 -133.92658)
		(width 0.12065)
		(layer "F.Cu")
		(net "TRAY_ID0")
	)
	(via
		(at 46.44517 -85.8393)
		(size 0.7112)
		(drill 0.3556)
		(layers "F.Cu" "B.Cu")
		(net "TRAY_ID0")
	)
	(via
		(at 57.953402 -23.771606)
		(size 0.508)
		(drill 0.254)
		(layers "F.Cu" "B.Cu")
		(net "TRAY_ID0")
	)
	(via
		(at 47.23638 -91.176348)
		(size 0.508)
		(drill 0.254)
		(layers "F.Cu" "B.Cu")
		(net "TRAY_ID0")
	)
	(via
		(at 15.6972 -136.398)
		(size 0.508)
		(drill 0.254)
		(layers "F.Cu" "B.Cu")
		(net "TRAY_ID0")
	)
	(segment
		(start 45.9994 -49.996344)
		(end 46.51375 -49.481994)
		(width 0.12065)
		(layer "B.Cu")
		(net "TRAY_ID0")
	)
	(segment
		(start 45.811948 -67.111626)
		(end 45.9994 -66.924174)
		(width 0.12065)
		(layer "B.Cu")
		(net "TRAY_ID0")
	)
	(segment
		(start 66.222626 -23.776686)
		(end 65.750694 -23.304754)
		(width 0.12065)
		(layer "B.Cu")
		(net "TRAY_ID0")
	)
	(segment
		(start 55.127144 -32.375348)
		(end 57.519824 -32.375348)
		(width 0.12065)
		(layer "B.Cu")
		(net "TRAY_ID0")
	)
	(segment
		(start 66.222626 -28.32227)
		(end 66.222626 -23.776686)
		(width 0.12065)
		(layer "B.Cu")
		(net "TRAY_ID0")
	)
	(segment
		(start 59.618626 -31.42107)
		(end 63.123826 -31.42107)
		(width 0.12065)
		(layer "B.Cu")
		(net "TRAY_ID0")
	)
	(segment
		(start 46.755304 -85.529166)
		(end 46.755304 -72.384158)
		(width 0.12065)
		(layer "B.Cu")
		(net "TRAY_ID0")
	)
	(segment
		(start 57.519824 -32.375348)
		(end 57.898538 -32.754062)
		(width 0.12065)
		(layer "B.Cu")
		(net "TRAY_ID0")
	)
	(segment
		(start 47.0662 -91.006168)
		(end 47.0662 -89.383108)
		(width 0.12065)
		(layer "B.Cu")
		(net "TRAY_ID0")
	)
	(segment
		(start 65.750694 -23.304754)
		(end 58.420254 -23.304754)
		(width 0.12065)
		(layer "B.Cu")
		(net "TRAY_ID0")
	)
	(segment
		(start 46.755304 -72.384158)
		(end 45.811948 -71.440802)
		(width 0.12065)
		(layer "B.Cu")
		(net "TRAY_ID0")
	)
	(segment
		(start 46.44517 -85.8393)
		(end 46.755304 -85.529166)
		(width 0.12065)
		(layer "B.Cu")
		(net "TRAY_ID0")
	)
	(segment
		(start 45.811948 -71.440802)
		(end 45.811948 -67.111626)
		(width 0.12065)
		(layer "B.Cu")
		(net "TRAY_ID0")
	)
	(segment
		(start 57.898538 -32.754062)
		(end 58.285634 -32.754062)
		(width 0.12065)
		(layer "B.Cu")
		(net "TRAY_ID0")
	)
	(segment
		(start 58.285634 -32.754062)
		(end 59.618626 -31.42107)
		(width 0.12065)
		(layer "B.Cu")
		(net "TRAY_ID0")
	)
	(segment
		(start 46.51375 -49.481994)
		(end 46.51375 -40.988742)
		(width 0.12065)
		(layer "B.Cu")
		(net "TRAY_ID0")
	)
	(segment
		(start 58.420254 -23.304754)
		(end 57.953402 -23.771606)
		(width 0.12065)
		(layer "B.Cu")
		(net "TRAY_ID0")
	)
	(segment
		(start 46.51375 -40.988742)
		(end 55.127144 -32.375348)
		(width 0.12065)
		(layer "B.Cu")
		(net "TRAY_ID0")
	)
	(segment
		(start 45.9994 -66.924174)
		(end 45.9994 -49.996344)
		(width 0.12065)
		(layer "B.Cu")
		(net "TRAY_ID0")
	)
	(segment
		(start 47.0662 -89.383108)
		(end 46.44517 -88.762078)
		(width 0.12065)
		(layer "B.Cu")
		(net "TRAY_ID0")
	)
	(segment
		(start 47.23638 -91.176348)
		(end 47.0662 -91.006168)
		(width 0.12065)
		(layer "B.Cu")
		(net "TRAY_ID0")
	)
	(segment
		(start 63.123826 -31.42107)
		(end 66.222626 -28.32227)
		(width 0.12065)
		(layer "B.Cu")
		(net "TRAY_ID0")
	)
	(segment
		(start 46.44517 -88.762078)
		(end 46.44517 -85.8393)
		(width 0.12065)
		(layer "B.Cu")
		(net "TRAY_ID0")
	)
	(segment
		(start 47.226728 -91.186)
		(end 47.23638 -91.176348)
		(width 0.127)
		(layer "In2.Cu")
		(net "TRAY_ID0")
	)
	(segment
		(start 19.58086 -100.534724)
		(end 19.58086 -100.175822)
		(width 0.127)
		(layer "In2.Cu")
		(net "TRAY_ID0")
	)
	(segment
		(start 16.76019 -103.355394)
		(end 19.58086 -100.534724)
		(width 0.127)
		(layer "In2.Cu")
		(net "TRAY_ID0")
	)
	(segment
		(start 10.55878 -120.789192)
		(end 10.55878 -115.096544)
		(width 0.127)
		(layer "In2.Cu")
		(net "TRAY_ID0")
	)
	(segment
		(start 13.1572 -112.49787)
		(end 13.898372 -111.756698)
		(width 0.127)
		(layer "In2.Cu")
		(net "TRAY_ID0")
	)
	(segment
		(start 15.6972 -136.398)
		(end 15.438882 -136.398)
		(width 0.127)
		(layer "In2.Cu")
		(net "TRAY_ID0")
	)
	(segment
		(start 13.7033 -107.263184)
		(end 13.7033 -106.4133)
		(width 0.127)
		(layer "In2.Cu")
		(net "TRAY_ID0")
	)
	(segment
		(start 29.043122 -92.4052)
		(end 29.939488 -92.4052)
		(width 0.127)
		(layer "In2.Cu")
		(net "TRAY_ID0")
	)
	(segment
		(start 10.55878 -115.096544)
		(end 13.1572 -112.498124)
		(width 0.127)
		(layer "In2.Cu")
		(net "TRAY_ID0")
	)
	(segment
		(start 14.099032 -106.017314)
		(end 16.429736 -103.686102)
		(width 0.127)
		(layer "In2.Cu")
		(net "TRAY_ID0")
	)
	(segment
		(start 31.158688 -91.186)
		(end 47.226728 -91.186)
		(width 0.127)
		(layer "In2.Cu")
		(net "TRAY_ID0")
	)
	(segment
		(start 20.722082 -99.0346)
		(end 21.696426 -99.0346)
		(width 0.127)
		(layer "In2.Cu")
		(net "TRAY_ID0")
	)
	(segment
		(start 14.068552 -135.507984)
		(end 14.068298 -135.507984)
		(width 0.127)
		(layer "In2.Cu")
		(net "TRAY_ID0")
	)
	(segment
		(start 14.06906 -135.508492)
		(end 14.068552 -135.507984)
		(width 0.127)
		(layer "In2.Cu")
		(net "TRAY_ID0")
	)
	(segment
		(start 9.598406 -127.208534)
		(end 9.598406 -123.515628)
		(width 0.127)
		(layer "In2.Cu")
		(net "TRAY_ID0")
	)
	(segment
		(start 9.59866 -123.51512)
		(end 10.180066 -122.933714)
		(width 0.127)
		(layer "In2.Cu")
		(net "TRAY_ID0")
	)
	(segment
		(start 19.58086 -100.175822)
		(end 20.722082 -99.0346)
		(width 0.127)
		(layer "In2.Cu")
		(net "TRAY_ID0")
	)
	(segment
		(start 21.696426 -99.0346)
		(end 25.633426 -95.0976)
		(width 0.127)
		(layer "In2.Cu")
		(net "TRAY_ID0")
	)
	(segment
		(start 16.429736 -103.686102)
		(end 16.76019 -103.355394)
		(width 0.127)
		(layer "In2.Cu")
		(net "TRAY_ID0")
	)
	(segment
		(start 15.438882 -136.398)
		(end 14.549374 -135.508492)
		(width 0.127)
		(layer "In2.Cu")
		(net "TRAY_ID0")
	)
	(segment
		(start 25.633426 -95.0976)
		(end 26.350722 -95.0976)
		(width 0.127)
		(layer "In2.Cu")
		(net "TRAY_ID0")
	)
	(segment
		(start 13.7033 -106.4133)
		(end 13.898372 -106.218228)
		(width 0.127)
		(layer "In2.Cu")
		(net "TRAY_ID0")
	)
	(segment
		(start 13.898372 -106.218228)
		(end 13.898372 -106.217974)
		(width 0.127)
		(layer "In2.Cu")
		(net "TRAY_ID0")
	)
	(segment
		(start 9.59866 -123.515374)
		(end 9.59866 -123.51512)
		(width 0.127)
		(layer "In2.Cu")
		(net "TRAY_ID0")
	)
	(segment
		(start 26.350722 -95.0976)
		(end 29.043122 -92.4052)
		(width 0.127)
		(layer "In2.Cu")
		(net "TRAY_ID0")
	)
	(segment
		(start 14.068298 -135.507984)
		(end 9.598406 -131.038092)
		(width 0.127)
		(layer "In2.Cu")
		(net "TRAY_ID0")
	)
	(segment
		(start 13.898118 -109.481366)
		(end 13.898118 -107.58678)
		(width 0.127)
		(layer "In2.Cu")
		(net "TRAY_ID0")
	)
	(segment
		(start 14.549374 -135.508492)
		(end 14.06906 -135.508492)
		(width 0.127)
		(layer "In2.Cu")
		(net "TRAY_ID0")
	)
	(segment
		(start 13.1572 -112.498124)
		(end 13.1572 -112.49787)
		(width 0.127)
		(layer "In2.Cu")
		(net "TRAY_ID0")
	)
	(segment
		(start 10.180066 -122.933714)
		(end 10.180066 -121.167906)
		(width 0.127)
		(layer "In2.Cu")
		(net "TRAY_ID0")
	)
	(segment
		(start 13.898118 -107.58678)
		(end 13.7033 -107.263184)
		(width 0.127)
		(layer "In2.Cu")
		(net "TRAY_ID0")
	)
	(segment
		(start 13.898372 -109.48162)
		(end 13.898118 -109.481366)
		(width 0.127)
		(layer "In2.Cu")
		(net "TRAY_ID0")
	)
	(segment
		(start 9.598406 -131.037838)
		(end 9.598152 -131.037584)
		(width 0.127)
		(layer "In2.Cu")
		(net "TRAY_ID0")
	)
	(segment
		(start 13.898372 -111.756698)
		(end 13.898372 -109.48162)
		(width 0.127)
		(layer "In2.Cu")
		(net "TRAY_ID0")
	)
	(segment
		(start 9.598152 -131.037584)
		(end 9.598152 -127.208788)
		(width 0.127)
		(layer "In2.Cu")
		(net "TRAY_ID0")
	)
	(segment
		(start 9.598152 -127.208788)
		(end 9.598406 -127.208534)
		(width 0.127)
		(layer "In2.Cu")
		(net "TRAY_ID0")
	)
	(segment
		(start 13.898372 -106.217974)
		(end 14.099032 -106.017314)
		(width 0.127)
		(layer "In2.Cu")
		(net "TRAY_ID0")
	)
	(segment
		(start 9.598406 -131.038092)
		(end 9.598406 -131.037838)
		(width 0.127)
		(layer "In2.Cu")
		(net "TRAY_ID0")
	)
	(segment
		(start 29.939488 -92.4052)
		(end 31.158688 -91.186)
		(width 0.127)
		(layer "In2.Cu")
		(net "TRAY_ID0")
	)
	(segment
		(start 9.598406 -123.515628)
		(end 9.59866 -123.515374)
		(width 0.127)
		(layer "In2.Cu")
		(net "TRAY_ID0")
	)
	(segment
		(start 10.180066 -121.167906)
		(end 10.55878 -120.789192)
		(width 0.127)
		(layer "In2.Cu")
		(net "TRAY_ID0")
	)
	(segment
		(start 32.904938 -133.284976)
		(end 32.505142 -132.88518)
		(width 0.12065)
		(layer "F.Cu")
		(net "TP_GPIOS4")
	)
	(via
		(at 32.505142 -132.88518)
		(size 0.4572)
		(drill 0.2032)
		(layers "F.Cu" "B.Cu")
		(net "TP_GPIOS4")
	)
	(segment
		(start 32.11449 -133.275832)
		(end 27.89809 -133.275832)
		(width 0.12065)
		(layer "B.Cu")
		(net "TP_GPIOS4")
	)
	(segment
		(start 25.266904 -133.514592)
		(end 24.829262 -133.07695)
		(width 0.12065)
		(layer "B.Cu")
		(net "TP_GPIOS4")
	)
	(segment
		(start 32.505142 -132.88518)
		(end 32.11449 -133.275832)
		(width 0.12065)
		(layer "B.Cu")
		(net "TP_GPIOS4")
	)
	(segment
		(start 24.829262 -133.07695)
		(end 22.77745 -133.07695)
		(width 0.12065)
		(layer "B.Cu")
		(net "TP_GPIOS4")
	)
	(segment
		(start 22.77745 -133.07695)
		(end 22.5298 -133.3246)
		(width 0.12065)
		(layer "B.Cu")
		(net "TP_GPIOS4")
	)
	(segment
		(start 27.89809 -133.275832)
		(end 27.65933 -133.514592)
		(width 0.12065)
		(layer "B.Cu")
		(net "TP_GPIOS4")
	)
	(segment
		(start 27.65933 -133.514592)
		(end 25.266904 -133.514592)
		(width 0.12065)
		(layer "B.Cu")
		(net "TP_GPIOS4")
	)
	(segment
		(start 9.5758 -174.353474)
		(end 9.5758 -174.625)
		(width 0.12065)
		(layer "F.Cu")
		(net "Q95_G")
	)
	(segment
		(start 8.254492 -173.351698)
		(end 8.574024 -173.351698)
		(width 0.12065)
		(layer "F.Cu")
		(net "Q95_G")
	)
	(segment
		(start 9.5758 -174.625)
		(end 10.4521 -174.625)
		(width 0.12065)
		(layer "F.Cu")
		(net "Q95_G")
	)
	(segment
		(start 8.0137 -174.63135)
		(end 8.0137 -173.59249)
		(width 0.12065)
		(layer "F.Cu")
		(net "Q95_G")
	)
	(segment
		(start 8.0137 -173.59249)
		(end 8.254492 -173.351698)
		(width 0.12065)
		(layer "F.Cu")
		(net "Q95_G")
	)
	(segment
		(start 8.574024 -173.351698)
		(end 9.5758 -174.353474)
		(width 0.12065)
		(layer "F.Cu")
		(net "Q95_G")
	)
	(segment
		(start 10.4521 -174.625)
		(end 11.1633 -175.3362)
		(width 0.12065)
		(layer "F.Cu")
		(net "Q95_G")
	)
	(via
		(at 8.254492 -173.351698)
		(size 0.7112)
		(drill 0.3556)
		(layers "F.Cu" "B.Cu")
		(net "Q95_G")
	)
	(segment
		(start 4.7752 -187.160154)
		(end 4.7752 -180.7972)
		(width 0.12065)
		(layer "F.Cu")
		(net "Q95_D")
	)
	(segment
		(start 5.359146 -187.7441)
		(end 4.7752 -187.160154)
		(width 0.12065)
		(layer "F.Cu")
		(net "Q95_D")
	)
	(segment
		(start 4.7752 -180.7972)
		(end 6.1087 -179.4637)
		(width 0.12065)
		(layer "F.Cu")
		(net "Q95_D")
	)
	(segment
		(start 6.4262 -187.7441)
		(end 5.359146 -187.7441)
		(width 0.12065)
		(layer "F.Cu")
		(net "Q95_D")
	)
	(segment
		(start 7.4676 -187.579)
		(end 7.3025 -187.7441)
		(width 0.12065)
		(layer "F.Cu")
		(net "Q95_D")
	)
	(segment
		(start 6.1087 -179.4637)
		(end 6.1087 -175.6156)
		(width 0.12065)
		(layer "F.Cu")
		(net "Q95_D")
	)
	(segment
		(start 7.3025 -187.7441)
		(end 6.4262 -187.7441)
		(width 0.12065)
		(layer "F.Cu")
		(net "Q95_D")
	)
	(via
		(at 7.4676 -187.579)
		(size 0.7112)
		(drill 0.3556)
		(layers "F.Cu" "B.Cu")
		(net "Q95_D")
	)
	(segment
		(start 71.47814 -126.04496)
		(end 71.7423 -125.7808)
		(width 0.12065)
		(layer "F.Cu")
		(net "MBP_UART_TX")
	)
	(segment
		(start 70.2056 -126.04496)
		(end 71.47814 -126.04496)
		(width 0.12065)
		(layer "F.Cu")
		(net "MBP_UART_TX")
	)
	(segment
		(start 71.7296 -124.11329)
		(end 71.1962 -124.64669)
		(width 0.12065)
		(layer "F.Cu")
		(net "MBP_UART_TX")
	)
	(segment
		(start 65.145158 -27.581606)
		(end 63.545974 -27.581606)
		(width 0.12065)
		(layer "F.Cu")
		(net "MBP_UART_TX")
	)
	(segment
		(start 71.7296 -123.7742)
		(end 71.7296 -124.11329)
		(width 0.12065)
		(layer "F.Cu")
		(net "MBP_UART_TX")
	)
	(segment
		(start 71.1962 -124.64669)
		(end 71.1962 -125.2347)
		(width 0.12065)
		(layer "F.Cu")
		(net "MBP_UART_TX")
	)
	(segment
		(start 71.1962 -125.2347)
		(end 71.7423 -125.7808)
		(width 0.12065)
		(layer "F.Cu")
		(net "MBP_UART_TX")
	)
	(segment
		(start 71.7423 -125.7808)
		(end 71.755 -125.7935)
		(width 0.12065)
		(layer "F.Cu")
		(net "MBP_UART_TX")
	)
	(segment
		(start 65.549272 -27.98572)
		(end 65.145158 -27.581606)
		(width 0.12065)
		(layer "F.Cu")
		(net "MBP_UART_TX")
	)
	(via
		(at 55.447946 -31.323026)
		(size 0.508)
		(drill 0.254)
		(layers "F.Cu" "B.Cu")
		(net "MBP_UART_TX")
	)
	(via
		(at 44.55922 -66.307716)
		(size 0.7112)
		(drill 0.3556)
		(layers "F.Cu" "B.Cu")
		(net "MBP_UART_TX")
	)
	(via
		(at 71.7296 -123.7742)
		(size 0.508)
		(drill 0.254)
		(layers "F.Cu" "B.Cu")
		(net "MBP_UART_TX")
	)
	(via
		(at 65.549272 -27.98572)
		(size 0.508)
		(drill 0.254)
		(layers "F.Cu" "B.Cu")
		(net "MBP_UART_TX")
	)
	(via
		(at 72.0598 -81.8134)
		(size 0.508)
		(drill 0.254)
		(layers "F.Cu" "B.Cu")
		(net "MBP_UART_TX")
	)
	(via
		(at 45.865034 -83.063842)
		(size 0.508)
		(drill 0.254)
		(layers "F.Cu" "B.Cu")
		(net "MBP_UART_TX")
	)
	(segment
		(start 54.769004 -31.511748)
		(end 45.65015 -40.630602)
		(width 0.12065)
		(layer "B.Cu")
		(net "MBP_UART_TX")
	)
	(segment
		(start 45.1358 -65.731136)
		(end 44.55922 -66.307716)
		(width 0.12065)
		(layer "B.Cu")
		(net "MBP_UART_TX")
	)
	(segment
		(start 44.398946 -67.302888)
		(end 44.398946 -68.01866)
		(width 0.12065)
		(layer "B.Cu")
		(net "MBP_UART_TX")
	)
	(segment
		(start 55.447946 -31.323026)
		(end 55.012082 -31.323026)
		(width 0.12065)
		(layer "B.Cu")
		(net "MBP_UART_TX")
	)
	(segment
		(start 44.3992 -68.018914)
		(end 44.3992 -73.122536)
		(width 0.12065)
		(layer "B.Cu")
		(net "MBP_UART_TX")
	)
	(segment
		(start 44.55922 -66.307716)
		(end 44.3992 -66.467736)
		(width 0.12065)
		(layer "B.Cu")
		(net "MBP_UART_TX")
	)
	(segment
		(start 45.65015 -40.630602)
		(end 45.65015 -49.123854)
		(width 0.12065)
		(layer "B.Cu")
		(net "MBP_UART_TX")
	)
	(segment
		(start 44.398946 -68.01866)
		(end 44.3992 -68.018914)
		(width 0.12065)
		(layer "B.Cu")
		(net "MBP_UART_TX")
	)
	(segment
		(start 45.784516 -74.507852)
		(end 45.784516 -81.60512)
		(width 0.12065)
		(layer "B.Cu")
		(net "MBP_UART_TX")
	)
	(segment
		(start 44.3992 -66.467736)
		(end 44.3992 -67.302634)
		(width 0.12065)
		(layer "B.Cu")
		(net "MBP_UART_TX")
	)
	(segment
		(start 45.65015 -49.123854)
		(end 45.1358 -49.638204)
		(width 0.12065)
		(layer "B.Cu")
		(net "MBP_UART_TX")
	)
	(segment
		(start 44.3992 -67.302634)
		(end 44.398946 -67.302888)
		(width 0.12065)
		(layer "B.Cu")
		(net "MBP_UART_TX")
	)
	(segment
		(start 54.82336 -31.511748)
		(end 54.769004 -31.511748)
		(width 0.12065)
		(layer "B.Cu")
		(net "MBP_UART_TX")
	)
	(segment
		(start 45.1358 -49.638204)
		(end 45.1358 -65.731136)
		(width 0.12065)
		(layer "B.Cu")
		(net "MBP_UART_TX")
	)
	(segment
		(start 45.865034 -81.685638)
		(end 45.865034 -83.063842)
		(width 0.12065)
		(layer "B.Cu")
		(net "MBP_UART_TX")
	)
	(segment
		(start 44.3992 -73.122536)
		(end 45.784516 -74.507852)
		(width 0.12065)
		(layer "B.Cu")
		(net "MBP_UART_TX")
	)
	(segment
		(start 55.012082 -31.323026)
		(end 54.82336 -31.511748)
		(width 0.12065)
		(layer "B.Cu")
		(net "MBP_UART_TX")
	)
	(segment
		(start 45.784516 -81.60512)
		(end 45.865034 -81.685638)
		(width 0.12065)
		(layer "B.Cu")
		(net "MBP_UART_TX")
	)
	(segment
		(start 46.00956 -82.919316)
		(end 50.611278 -82.919316)
		(width 0.127)
		(layer "In2.Cu")
		(net "MBP_UART_TX")
	)
	(segment
		(start 50.611278 -82.919316)
		(end 51.316636 -83.624674)
		(width 0.127)
		(layer "In2.Cu")
		(net "MBP_UART_TX")
	)
	(segment
		(start 45.865034 -83.063842)
		(end 46.00956 -82.919316)
		(width 0.127)
		(layer "In2.Cu")
		(net "MBP_UART_TX")
	)
	(segment
		(start 69.37502 -84.49818)
		(end 72.0598 -81.8134)
		(width 0.127)
		(layer "In2.Cu")
		(net "MBP_UART_TX")
	)
	(segment
		(start 66.15938 -84.49818)
		(end 69.37502 -84.49818)
		(width 0.127)
		(layer "In2.Cu")
		(net "MBP_UART_TX")
	)
	(segment
		(start 54.928516 -82.780886)
		(end 64.442086 -82.780886)
		(width 0.127)
		(layer "In2.Cu")
		(net "MBP_UART_TX")
	)
	(segment
		(start 54.084728 -83.624674)
		(end 54.928516 -82.780886)
		(width 0.127)
		(layer "In2.Cu")
		(net "MBP_UART_TX")
	)
	(segment
		(start 64.442086 -82.780886)
		(end 66.15938 -84.49818)
		(width 0.127)
		(layer "In2.Cu")
		(net "MBP_UART_TX")
	)
	(segment
		(start 51.316636 -83.624674)
		(end 54.084728 -83.624674)
		(width 0.127)
		(layer "In2.Cu")
		(net "MBP_UART_TX")
	)
	(segment
		(start 56.53405 -29.801058)
		(end 55.447946 -30.887162)
		(width 0.127)
		(layer "In5.Cu")
		(net "MBP_UART_TX")
	)
	(segment
		(start 55.447946 -30.887162)
		(end 55.447946 -31.323026)
		(width 0.127)
		(layer "In5.Cu")
		(net "MBP_UART_TX")
	)
	(segment
		(start 58.118756 -27.841194)
		(end 56.53405 -29.4259)
		(width 0.127)
		(layer "In5.Cu")
		(net "MBP_UART_TX")
	)
	(segment
		(start 65.549272 -27.98572)
		(end 65.404746 -27.841194)
		(width 0.127)
		(layer "In5.Cu")
		(net "MBP_UART_TX")
	)
	(segment
		(start 65.404746 -27.841194)
		(end 58.118756 -27.841194)
		(width 0.127)
		(layer "In5.Cu")
		(net "MBP_UART_TX")
	)
	(segment
		(start 71.7296 -123.2662)
		(end 71.7296 -123.7742)
		(width 0.127)
		(layer "In5.Cu")
		(net "MBP_UART_TX")
	)
	(segment
		(start 73.1774 -121.8184)
		(end 71.7296 -123.2662)
		(width 0.127)
		(layer "In5.Cu")
		(net "MBP_UART_TX")
	)
	(segment
		(start 72.1614 -81.915)
		(end 72.1614 -92.785946)
		(width 0.127)
		(layer "In5.Cu")
		(net "MBP_UART_TX")
	)
	(segment
		(start 72.0598 -81.8134)
		(end 72.1614 -81.915)
		(width 0.127)
		(layer "In5.Cu")
		(net "MBP_UART_TX")
	)
	(segment
		(start 56.53405 -29.4259)
		(end 56.53405 -29.801058)
		(width 0.127)
		(layer "In5.Cu")
		(net "MBP_UART_TX")
	)
	(segment
		(start 72.1614 -92.785946)
		(end 73.1774 -93.801946)
		(width 0.127)
		(layer "In5.Cu")
		(net "MBP_UART_TX")
	)
	(segment
		(start 73.1774 -93.801946)
		(end 73.1774 -121.8184)
		(width 0.127)
		(layer "In5.Cu")
		(net "MBP_UART_TX")
	)
	(segment
		(start 58.549032 -31.83001)
		(end 58.091832 -32.28721)
		(width 0.12065)
		(layer "F.Cu")
		(net "MBP_UART_RX")
	)
	(segment
		(start 76.52258 -119.31777)
		(end 76.52258 -119.9134)
		(width 0.12065)
		(layer "F.Cu")
		(net "MBP_UART_RX")
	)
	(segment
		(start 76.255118 -119.050308)
		(end 76.52258 -119.31777)
		(width 0.12065)
		(layer "F.Cu")
		(net "MBP_UART_RX")
	)
	(segment
		(start 57.83453 -30.115256)
		(end 58.549032 -30.829758)
		(width 0.12065)
		(layer "F.Cu")
		(net "MBP_UART_RX")
	)
	(segment
		(start 76.220828 -119.050308)
		(end 76.255118 -119.050308)
		(width 0.12065)
		(layer "F.Cu")
		(net "MBP_UART_RX")
	)
	(segment
		(start 76.74356 -112.81664)
		(end 76.74356 -114.92484)
		(width 0.12065)
		(layer "F.Cu")
		(net "MBP_UART_RX")
	)
	(segment
		(start 75.42276 -116.24564)
		(end 75.42276 -116.42598)
		(width 0.12065)
		(layer "F.Cu")
		(net "MBP_UART_RX")
	)
	(segment
		(start 76.74356 -114.92484)
		(end 75.42276 -116.24564)
		(width 0.12065)
		(layer "F.Cu")
		(net "MBP_UART_RX")
	)
	(segment
		(start 75.42276 -116.42598)
		(end 75.42276 -118.25224)
		(width 0.12065)
		(layer "F.Cu")
		(net "MBP_UART_RX")
	)
	(segment
		(start 75.42276 -118.25224)
		(end 76.220828 -119.050308)
		(width 0.12065)
		(layer "F.Cu")
		(net "MBP_UART_RX")
	)
	(segment
		(start 57.83453 -27.866848)
		(end 57.83453 -30.115256)
		(width 0.12065)
		(layer "F.Cu")
		(net "MBP_UART_RX")
	)
	(segment
		(start 59.871102 -27.581606)
		(end 58.119772 -27.581606)
		(width 0.12065)
		(layer "F.Cu")
		(net "MBP_UART_RX")
	)
	(segment
		(start 76.52258 -119.9134)
		(end 76.34478 -120.0912)
		(width 0.12065)
		(layer "F.Cu")
		(net "MBP_UART_RX")
	)
	(segment
		(start 58.119772 -27.581606)
		(end 57.83453 -27.866848)
		(width 0.12065)
		(layer "F.Cu")
		(net "MBP_UART_RX")
	)
	(segment
		(start 58.549032 -30.829758)
		(end 58.549032 -31.83001)
		(width 0.12065)
		(layer "F.Cu")
		(net "MBP_UART_RX")
	)
	(segment
		(start 76.34478 -120.0912)
		(end 75.568048 -120.0912)
		(width 0.12065)
		(layer "F.Cu")
		(net "MBP_UART_RX")
	)
	(via
		(at 48.871378 -81.346548)
		(size 0.508)
		(drill 0.254)
		(layers "F.Cu" "B.Cu")
		(net "MBP_UART_RX")
	)
	(via
		(at 54.644544 -36.267644)
		(size 0.508)
		(drill 0.254)
		(layers "F.Cu" "B.Cu")
		(net "MBP_UART_RX")
	)
	(via
		(at 80.2386 -81.5086)
		(size 0.508)
		(drill 0.254)
		(layers "F.Cu" "B.Cu")
		(net "MBP_UART_RX")
	)
	(via
		(at 75.42276 -116.42598)
		(size 0.7112)
		(drill 0.3556)
		(layers "F.Cu" "B.Cu")
		(net "MBP_UART_RX")
	)
	(via
		(at 58.091832 -32.28721)
		(size 0.508)
		(drill 0.254)
		(layers "F.Cu" "B.Cu")
		(net "MBP_UART_RX")
	)
	(via
		(at 76.74356 -112.81664)
		(size 0.508)
		(drill 0.254)
		(layers "F.Cu" "B.Cu")
		(net "MBP_UART_RX")
	)
	(segment
		(start 50.8254 -49.7332)
		(end 51.223672 -50.131472)
		(width 0.12065)
		(layer "B.Cu")
		(net "MBP_UART_RX")
	)
	(segment
		(start 50.8254 -77.088746)
		(end 48.871378 -79.042768)
		(width 0.12065)
		(layer "B.Cu")
		(net "MBP_UART_RX")
	)
	(segment
		(start 51.223672 -50.131472)
		(end 51.223672 -52.967128)
		(width 0.12065)
		(layer "B.Cu")
		(net "MBP_UART_RX")
	)
	(segment
		(start 54.644544 -36.267644)
		(end 54.644544 -36.562284)
		(width 0.12065)
		(layer "B.Cu")
		(net "MBP_UART_RX")
	)
	(segment
		(start 50.8254 -53.3654)
		(end 50.8254 -77.088746)
		(width 0.12065)
		(layer "B.Cu")
		(net "MBP_UART_RX")
	)
	(segment
		(start 48.871378 -79.042768)
		(end 48.871378 -81.346548)
		(width 0.12065)
		(layer "B.Cu")
		(net "MBP_UART_RX")
	)
	(segment
		(start 50.8254 -40.381428)
		(end 50.8254 -49.7332)
		(width 0.12065)
		(layer "B.Cu")
		(net "MBP_UART_RX")
	)
	(segment
		(start 51.223672 -52.967128)
		(end 50.8254 -53.3654)
		(width 0.12065)
		(layer "B.Cu")
		(net "MBP_UART_RX")
	)
	(segment
		(start 54.644544 -36.562284)
		(end 50.8254 -40.381428)
		(width 0.12065)
		(layer "B.Cu")
		(net "MBP_UART_RX")
	)
	(segment
		(start 51.527202 -83.116674)
		(end 49.743106 -81.332578)
		(width 0.127)
		(layer "In2.Cu")
		(net "MBP_UART_RX")
	)
	(segment
		(start 71.864474 -81.29016)
		(end 70.881748 -82.272886)
		(width 0.127)
		(layer "In2.Cu")
		(net "MBP_UART_RX")
	)
	(segment
		(start 76.895706 -82.14614)
		(end 76.039726 -81.29016)
		(width 0.127)
		(layer "In2.Cu")
		(net "MBP_UART_RX")
	)
	(segment
		(start 54.71795 -82.272886)
		(end 53.874162 -83.116674)
		(width 0.127)
		(layer "In2.Cu")
		(net "MBP_UART_RX")
	)
	(segment
		(start 80.2386 -81.5086)
		(end 79.60106 -82.14614)
		(width 0.127)
		(layer "In2.Cu")
		(net "MBP_UART_RX")
	)
	(segment
		(start 53.874162 -83.116674)
		(end 51.527202 -83.116674)
		(width 0.127)
		(layer "In2.Cu")
		(net "MBP_UART_RX")
	)
	(segment
		(start 79.60106 -82.14614)
		(end 76.895706 -82.14614)
		(width 0.127)
		(layer "In2.Cu")
		(net "MBP_UART_RX")
	)
	(segment
		(start 49.743106 -81.332578)
		(end 48.885348 -81.332578)
		(width 0.127)
		(layer "In2.Cu")
		(net "MBP_UART_RX")
	)
	(segment
		(start 76.039726 -81.29016)
		(end 71.864474 -81.29016)
		(width 0.127)
		(layer "In2.Cu")
		(net "MBP_UART_RX")
	)
	(segment
		(start 70.881748 -82.272886)
		(end 54.71795 -82.272886)
		(width 0.127)
		(layer "In2.Cu")
		(net "MBP_UART_RX")
	)
	(segment
		(start 48.885348 -81.332578)
		(end 48.871378 -81.346548)
		(width 0.127)
		(layer "In2.Cu")
		(net "MBP_UART_RX")
	)
	(segment
		(start 78.37678 -83.37042)
		(end 80.2386 -81.5086)
		(width 0.127)
		(layer "In5.Cu")
		(net "MBP_UART_RX")
	)
	(segment
		(start 78.37678 -93.664532)
		(end 78.37678 -83.37042)
		(width 0.127)
		(layer "In5.Cu")
		(net "MBP_UART_RX")
	)
	(segment
		(start 76.74356 -95.297752)
		(end 78.37678 -93.664532)
		(width 0.127)
		(layer "In5.Cu")
		(net "MBP_UART_RX")
	)
	(segment
		(start 55.846472 -32.28721)
		(end 54.644544 -33.489138)
		(width 0.127)
		(layer "In5.Cu")
		(net "MBP_UART_RX")
	)
	(segment
		(start 76.74356 -112.81664)
		(end 76.74356 -95.297752)
		(width 0.127)
		(layer "In5.Cu")
		(net "MBP_UART_RX")
	)
	(segment
		(start 58.091832 -32.28721)
		(end 55.846472 -32.28721)
		(width 0.127)
		(layer "In5.Cu")
		(net "MBP_UART_RX")
	)
	(segment
		(start 54.644544 -33.489138)
		(end 54.644544 -36.267644)
		(width 0.127)
		(layer "In5.Cu")
		(net "MBP_UART_RX")
	)
	(segment
		(start 57.3786 -25.796494)
		(end 56.804814 -25.222708)
		(width 0.12065)
		(layer "F.Cu")
		(net "IPMB_DAT")
	)
	(segment
		(start 63.545974 -25.041606)
		(end 65.225422 -25.041606)
		(width 0.12065)
		(layer "F.Cu")
		(net "IPMB_DAT")
	)
	(segment
		(start 57.3786 -25.8699)
		(end 57.3786 -25.796494)
		(width 0.12065)
		(layer "F.Cu")
		(net "IPMB_DAT")
	)
	(segment
		(start 65.225422 -25.041606)
		(end 65.539366 -24.727662)
		(width 0.12065)
		(layer "F.Cu")
		(net "IPMB_DAT")
	)
	(via
		(at 65.539366 -24.727662)
		(size 0.508)
		(drill 0.254)
		(layers "F.Cu" "B.Cu")
		(net "IPMB_DAT")
	)
	(via
		(at 56.804814 -25.222708)
		(size 0.508)
		(drill 0.254)
		(layers "F.Cu" "B.Cu")
		(net "IPMB_DAT")
	)
	(segment
		(start 58.5724 -25.5397)
		(end 57.121806 -25.5397)
		(width 0.12065)
		(layer "B.Cu")
		(net "IPMB_DAT")
	)
	(segment
		(start 57.121806 -25.5397)
		(end 56.804814 -25.222708)
		(width 0.12065)
		(layer "B.Cu")
		(net "IPMB_DAT")
	)
	(segment
		(start 59.0804 -25.0317)
		(end 58.5724 -25.5397)
		(width 0.12065)
		(layer "B.Cu")
		(net "IPMB_DAT")
	)
	(segment
		(start 65.539366 -24.727662)
		(end 65.397634 -24.727662)
		(width 0.127)
		(layer "In2.Cu")
		(net "IPMB_DAT")
	)
	(segment
		(start 56.804814 -24.965152)
		(end 56.804814 -25.222708)
		(width 0.127)
		(layer "In2.Cu")
		(net "IPMB_DAT")
	)
	(segment
		(start 63.739522 -24.902668)
		(end 63.316866 -24.480012)
		(width 0.127)
		(layer "In2.Cu")
		(net "IPMB_DAT")
	)
	(segment
		(start 65.397634 -24.727662)
		(end 65.222628 -24.902668)
		(width 0.127)
		(layer "In2.Cu")
		(net "IPMB_DAT")
	)
	(segment
		(start 57.289954 -24.480012)
		(end 56.804814 -24.965152)
		(width 0.127)
		(layer "In2.Cu")
		(net "IPMB_DAT")
	)
	(segment
		(start 63.316866 -24.480012)
		(end 57.289954 -24.480012)
		(width 0.127)
		(layer "In2.Cu")
		(net "IPMB_DAT")
	)
	(segment
		(start 65.222628 -24.902668)
		(end 63.739522 -24.902668)
		(width 0.127)
		(layer "In2.Cu")
		(net "IPMB_DAT")
	)
	(segment
		(start 66.3448 -25.8699)
		(end 65.621916 -25.8699)
		(width 0.12065)
		(layer "F.Cu")
		(net "IPMB_CLK")
	)
	(segment
		(start 65.621916 -25.8699)
		(end 65.509648 -25.757632)
		(width 0.12065)
		(layer "F.Cu")
		(net "IPMB_CLK")
	)
	(segment
		(start 59.871102 -25.041606)
		(end 57.825386 -25.041606)
		(width 0.12065)
		(layer "F.Cu")
		(net "IPMB_CLK")
	)
	(segment
		(start 57.825386 -25.041606)
		(end 57.811924 -25.055068)
		(width 0.12065)
		(layer "F.Cu")
		(net "IPMB_CLK")
	)
	(via
		(at 65.509648 -25.757632)
		(size 0.508)
		(drill 0.254)
		(layers "F.Cu" "B.Cu")
		(net "IPMB_CLK")
	)
	(via
		(at 57.811924 -25.055068)
		(size 0.508)
		(drill 0.254)
		(layers "F.Cu" "B.Cu")
		(net "IPMB_CLK")
	)
	(segment
		(start 64.1604 -25.071832)
		(end 64.8462 -25.757632)
		(width 0.12065)
		(layer "B.Cu")
		(net "IPMB_CLK")
	)
	(segment
		(start 64.8462 -25.757632)
		(end 65.509648 -25.757632)
		(width 0.12065)
		(layer "B.Cu")
		(net "IPMB_CLK")
	)
	(segment
		(start 63.49873 -25.071832)
		(end 64.1604 -25.071832)
		(width 0.12065)
		(layer "B.Cu")
		(net "IPMB_CLK")
	)
	(segment
		(start 63.528956 -25.410668)
		(end 63.1063 -24.988012)
		(width 0.127)
		(layer "In2.Cu")
		(net "IPMB_CLK")
	)
	(segment
		(start 65.509648 -25.757632)
		(end 65.162684 -25.410668)
		(width 0.127)
		(layer "In2.Cu")
		(net "IPMB_CLK")
	)
	(segment
		(start 65.162684 -25.410668)
		(end 63.528956 -25.410668)
		(width 0.127)
		(layer "In2.Cu")
		(net "IPMB_CLK")
	)
	(segment
		(start 63.1063 -24.988012)
		(end 57.87898 -24.988012)
		(width 0.127)
		(layer "In2.Cu")
		(net "IPMB_CLK")
	)
	(segment
		(start 57.87898 -24.988012)
		(end 57.811924 -25.055068)
		(width 0.127)
		(layer "In2.Cu")
		(net "IPMB_CLK")
	)
	(segment
		(start 59.871102 -30.788102)
		(end 60.783216 -31.700216)
		(width 0.12065)
		(layer "F.Cu")
		(net "CN2_P23")
	)
	(segment
		(start 60.783216 -31.700216)
		(end 63.621412 -31.700216)
		(width 0.12065)
		(layer "F.Cu")
		(net "CN2_P23")
	)
	(segment
		(start 63.621412 -32.862774)
		(end 63.243968 -33.240218)
		(width 0.12065)
		(layer "F.Cu")
		(net "CN2_P23")
	)
	(segment
		(start 63.621412 -31.700216)
		(end 63.621412 -32.862774)
		(width 0.12065)
		(layer "F.Cu")
		(net "CN2_P23")
	)
	(segment
		(start 59.871102 -30.121606)
		(end 59.871102 -30.788102)
		(width 0.12065)
		(layer "F.Cu")
		(net "CN2_P23")
	)
	(via
		(at 63.243968 -33.240218)
		(size 0.7112)
		(drill 0.3556)
		(layers "F.Cu" "B.Cu")
		(net "CN2_P23")
	)
	(segment
		(start 56.478424 -33.893252)
		(end 56.478424 -32.704278)
		(width 0.12065)
		(layer "F.Cu")
		(net "BP_PRSNT_N")
	)
	(segment
		(start 54.981094 -31.51632)
		(end 54.981094 -28.445968)
		(width 0.12065)
		(layer "F.Cu")
		(net "BP_PRSNT_N")
	)
	(segment
		(start 58.16219 -26.311606)
		(end 59.871102 -26.311606)
		(width 0.12065)
		(layer "F.Cu")
		(net "BP_PRSNT_N")
	)
	(segment
		(start 57.67578 -27.272742)
		(end 57.845452 -27.10307)
		(width 0.12065)
		(layer "F.Cu")
		(net "BP_PRSNT_N")
	)
	(segment
		(start 56.15432 -27.272742)
		(end 57.67578 -27.272742)
		(width 0.12065)
		(layer "F.Cu")
		(net "BP_PRSNT_N")
	)
	(segment
		(start 57.845452 -26.628344)
		(end 58.16219 -26.311606)
		(width 0.12065)
		(layer "F.Cu")
		(net "BP_PRSNT_N")
	)
	(segment
		(start 57.845452 -27.10307)
		(end 57.845452 -26.628344)
		(width 0.12065)
		(layer "F.Cu")
		(net "BP_PRSNT_N")
	)
	(segment
		(start 55.564024 -31.789878)
		(end 55.254652 -31.789878)
		(width 0.12065)
		(layer "F.Cu")
		(net "BP_PRSNT_N")
	)
	(segment
		(start 54.981094 -28.445968)
		(end 56.15432 -27.272742)
		(width 0.12065)
		(layer "F.Cu")
		(net "BP_PRSNT_N")
	)
	(segment
		(start 55.254652 -31.789878)
		(end 54.981094 -31.51632)
		(width 0.12065)
		(layer "F.Cu")
		(net "BP_PRSNT_N")
	)
	(segment
		(start 56.478424 -32.704278)
		(end 55.564024 -31.789878)
		(width 0.12065)
		(layer "F.Cu")
		(net "BP_PRSNT_N")
	)
	(via
		(at 49.918366 -89.480136)
		(size 0.508)
		(drill 0.254)
		(layers "F.Cu" "B.Cu")
		(net "BP_PRSNT_N")
	)
	(via
		(at 56.478424 -33.893252)
		(size 0.508)
		(drill 0.254)
		(layers "F.Cu" "B.Cu")
		(net "BP_PRSNT_N")
	)
	(via
		(at 47.80661 -84.826348)
		(size 0.7112)
		(drill 0.3556)
		(layers "F.Cu" "B.Cu")
		(net "BP_PRSNT_N")
	)
	(via
		(at 18.7198 -137.8204)
		(size 0.508)
		(drill 0.254)
		(layers "F.Cu" "B.Cu")
		(net "BP_PRSNT_N")
	)
	(segment
		(start 18.8087 -138.6078)
		(end 19.0119 -138.811)
		(width 0.12065)
		(layer "B.Cu")
		(net "BP_PRSNT_N")
	)
	(segment
		(start 54.633368 -33.893252)
		(end 47.573946 -40.952674)
		(width 0.12065)
		(layer "B.Cu")
		(net "BP_PRSNT_N")
	)
	(segment
		(start 48.23968 -85.597746)
		(end 48.23968 -85.259418)
		(width 0.12065)
		(layer "B.Cu")
		(net "BP_PRSNT_N")
	)
	(segment
		(start 48.23968 -85.259418)
		(end 47.80661 -84.826348)
		(width 0.12065)
		(layer "B.Cu")
		(net "BP_PRSNT_N")
	)
	(segment
		(start 47.573946 -40.952674)
		(end 47.573946 -49.176686)
		(width 0.12065)
		(layer "B.Cu")
		(net "BP_PRSNT_N")
	)
	(segment
		(start 47.59579 -74.264266)
		(end 47.59579 -84.615528)
		(width 0.12065)
		(layer "B.Cu")
		(net "BP_PRSNT_N")
	)
	(segment
		(start 50.262028 -87.620094)
		(end 48.23968 -85.597746)
		(width 0.12065)
		(layer "B.Cu")
		(net "BP_PRSNT_N")
	)
	(segment
		(start 48.133 -68.60921)
		(end 48.133 -73.727056)
		(width 0.12065)
		(layer "B.Cu")
		(net "BP_PRSNT_N")
	)
	(segment
		(start 50.262028 -89.136474)
		(end 50.262028 -87.620094)
		(width 0.12065)
		(layer "B.Cu")
		(net "BP_PRSNT_N")
	)
	(segment
		(start 18.8087 -138.6078)
		(end 18.7198 -138.5189)
		(width 0.12065)
		(layer "B.Cu")
		(net "BP_PRSNT_N")
	)
	(segment
		(start 48.133 -73.727056)
		(end 47.59579 -74.264266)
		(width 0.12065)
		(layer "B.Cu")
		(net "BP_PRSNT_N")
	)
	(segment
		(start 47.573946 -49.176686)
		(end 47.59579 -49.19853)
		(width 0.12065)
		(layer "B.Cu")
		(net "BP_PRSNT_N")
	)
	(segment
		(start 56.478424 -33.893252)
		(end 54.633368 -33.893252)
		(width 0.12065)
		(layer "B.Cu")
		(net "BP_PRSNT_N")
	)
	(segment
		(start 18.7198 -138.5189)
		(end 18.7198 -137.8204)
		(width 0.12065)
		(layer "B.Cu")
		(net "BP_PRSNT_N")
	)
	(segment
		(start 47.59579 -84.615528)
		(end 47.80661 -84.826348)
		(width 0.12065)
		(layer "B.Cu")
		(net "BP_PRSNT_N")
	)
	(segment
		(start 49.918366 -89.480136)
		(end 50.262028 -89.136474)
		(width 0.12065)
		(layer "B.Cu")
		(net "BP_PRSNT_N")
	)
	(segment
		(start 47.59579 -68.072)
		(end 48.133 -68.60921)
		(width 0.12065)
		(layer "B.Cu")
		(net "BP_PRSNT_N")
	)
	(segment
		(start 19.0119 -138.811)
		(end 20.5105 -138.811)
		(width 0.12065)
		(layer "B.Cu")
		(net "BP_PRSNT_N")
	)
	(segment
		(start 47.59579 -49.19853)
		(end 47.59579 -68.072)
		(width 0.12065)
		(layer "B.Cu")
		(net "BP_PRSNT_N")
	)
	(segment
		(start 46.344078 -88.860122)
		(end 49.298352 -88.860122)
		(width 0.127)
		(layer "In2.Cu")
		(net "BP_PRSNT_N")
	)
	(segment
		(start 8.39978 -120.30202)
		(end 9.0805 -119.6213)
		(width 0.127)
		(layer "In2.Cu")
		(net "BP_PRSNT_N")
	)
	(segment
		(start 49.298352 -88.860122)
		(end 49.918366 -89.480136)
		(width 0.127)
		(layer "In2.Cu")
		(net "BP_PRSNT_N")
	)
	(segment
		(start 7.6454 -131.061206)
		(end 7.6454 -122.145806)
		(width 0.127)
		(layer "In2.Cu")
		(net "BP_PRSNT_N")
	)
	(segment
		(start 7.6454 -122.145806)
		(end 8.39978 -121.391426)
		(width 0.127)
		(layer "In2.Cu")
		(net "BP_PRSNT_N")
	)
	(segment
		(start 13.970508 -136.905746)
		(end 13.805916 -136.905746)
		(width 0.127)
		(layer "In2.Cu")
		(net "BP_PRSNT_N")
	)
	(segment
		(start 8.4836 -115.150646)
		(end 10.048494 -113.585752)
		(width 0.127)
		(layer "In2.Cu")
		(net "BP_PRSNT_N")
	)
	(segment
		(start 25.740614 -93.6752)
		(end 29.648404 -89.789)
		(width 0.127)
		(layer "In2.Cu")
		(net "BP_PRSNT_N")
	)
	(segment
		(start 12.3063 -106.37012)
		(end 12.3063 -105.83418)
		(width 0.127)
		(layer "In2.Cu")
		(net "BP_PRSNT_N")
	)
	(segment
		(start 18.7198 -137.8204)
		(end 18.0975 -138.4427)
		(width 0.127)
		(layer "In2.Cu")
		(net "BP_PRSNT_N")
	)
	(segment
		(start 16.134588 -102.004368)
		(end 18.18386 -99.955096)
		(width 0.127)
		(layer "In2.Cu")
		(net "BP_PRSNT_N")
	)
	(segment
		(start 45.4152 -89.789)
		(end 46.344078 -88.860122)
		(width 0.127)
		(layer "In2.Cu")
		(net "BP_PRSNT_N")
	)
	(segment
		(start 12.500864 -105.639616)
		(end 12.500864 -105.639108)
		(width 0.127)
		(layer "In2.Cu")
		(net "BP_PRSNT_N")
	)
	(segment
		(start 15.507462 -138.4427)
		(end 13.970508 -136.905746)
		(width 0.127)
		(layer "In2.Cu")
		(net "BP_PRSNT_N")
	)
	(segment
		(start 18.0975 -138.4427)
		(end 15.507462 -138.4427)
		(width 0.127)
		(layer "In2.Cu")
		(net "BP_PRSNT_N")
	)
	(segment
		(start 12.628118 -105.5116)
		(end 13.110718 -105.029)
		(width 0.127)
		(layer "In2.Cu")
		(net "BP_PRSNT_N")
	)
	(segment
		(start 13.490194 -136.906)
		(end 7.6454 -131.061206)
		(width 0.127)
		(layer "In2.Cu")
		(net "BP_PRSNT_N")
	)
	(segment
		(start 12.500864 -105.639108)
		(end 12.628118 -105.5116)
		(width 0.127)
		(layer "In2.Cu")
		(net "BP_PRSNT_N")
	)
	(segment
		(start 18.18386 -99.596702)
		(end 24.102822 -93.67774)
		(width 0.127)
		(layer "In2.Cu")
		(net "BP_PRSNT_N")
	)
	(segment
		(start 12.3063 -105.83418)
		(end 12.500864 -105.639616)
		(width 0.127)
		(layer "In2.Cu")
		(net "BP_PRSNT_N")
	)
	(segment
		(start 29.683456 -89.788746)
		(end 29.998924 -89.788746)
		(width 0.127)
		(layer "In2.Cu")
		(net "BP_PRSNT_N")
	)
	(segment
		(start 11.66622 -107.0102)
		(end 12.3063 -106.37012)
		(width 0.127)
		(layer "In2.Cu")
		(net "BP_PRSNT_N")
	)
	(segment
		(start 24.102822 -93.67774)
		(end 24.41829 -93.67774)
		(width 0.127)
		(layer "In2.Cu")
		(net "BP_PRSNT_N")
	)
	(segment
		(start 24.41829 -93.67774)
		(end 24.418544 -93.677994)
		(width 0.127)
		(layer "In2.Cu")
		(net "BP_PRSNT_N")
	)
	(segment
		(start 18.18386 -99.955096)
		(end 18.18386 -99.596702)
		(width 0.127)
		(layer "In2.Cu")
		(net "BP_PRSNT_N")
	)
	(segment
		(start 11.66622 -108.83392)
		(end 11.66622 -107.0102)
		(width 0.127)
		(layer "In2.Cu")
		(net "BP_PRSNT_N")
	)
	(segment
		(start 13.805662 -136.906)
		(end 13.490194 -136.906)
		(width 0.127)
		(layer "In2.Cu")
		(net "BP_PRSNT_N")
	)
	(segment
		(start 29.648404 -89.789)
		(end 29.683456 -89.788746)
		(width 0.127)
		(layer "In2.Cu")
		(net "BP_PRSNT_N")
	)
	(segment
		(start 13.805916 -136.905746)
		(end 13.805662 -136.906)
		(width 0.127)
		(layer "In2.Cu")
		(net "BP_PRSNT_N")
	)
	(segment
		(start 29.998924 -89.788746)
		(end 29.999178 -89.789)
		(width 0.127)
		(layer "In2.Cu")
		(net "BP_PRSNT_N")
	)
	(segment
		(start 8.39978 -121.391426)
		(end 8.39978 -120.30202)
		(width 0.127)
		(layer "In2.Cu")
		(net "BP_PRSNT_N")
	)
	(segment
		(start 9.0805 -118.668546)
		(end 8.4836 -118.071646)
		(width 0.127)
		(layer "In2.Cu")
		(net "BP_PRSNT_N")
	)
	(segment
		(start 29.999178 -89.789)
		(end 45.4152 -89.789)
		(width 0.127)
		(layer "In2.Cu")
		(net "BP_PRSNT_N")
	)
	(segment
		(start 9.0805 -119.6213)
		(end 9.0805 -118.668546)
		(width 0.127)
		(layer "In2.Cu")
		(net "BP_PRSNT_N")
	)
	(segment
		(start 8.4836 -118.071646)
		(end 8.4836 -115.150646)
		(width 0.127)
		(layer "In2.Cu")
		(net "BP_PRSNT_N")
	)
	(segment
		(start 10.048494 -110.451646)
		(end 11.66622 -108.83392)
		(width 0.127)
		(layer "In2.Cu")
		(net "BP_PRSNT_N")
	)
	(segment
		(start 10.048494 -113.585752)
		(end 10.048494 -110.451646)
		(width 0.127)
		(layer "In2.Cu")
		(net "BP_PRSNT_N")
	)
	(segment
		(start 15.441422 -102.697788)
		(end 16.134588 -102.004368)
		(width 0.127)
		(layer "In2.Cu")
		(net "BP_PRSNT_N")
	)
	(segment
		(start 13.110718 -105.029)
		(end 15.441422 -102.697788)
		(width 0.127)
		(layer "In2.Cu")
		(net "BP_PRSNT_N")
	)
	(segment
		(start 24.418544 -93.677994)
		(end 25.73782 -93.677994)
		(width 0.127)
		(layer "In2.Cu")
		(net "BP_PRSNT_N")
	)
	(segment
		(start 25.73782 -93.677994)
		(end 25.740614 -93.6752)
		(width 0.127)
		(layer "In2.Cu")
		(net "BP_PRSNT_N")
	)
	(segment
		(start 63.545974 -23.771606)
		(end 65.5574 -23.771606)
		(width 0.12065)
		(layer "F.Cu")
		(net "BMC_INT_N")
	)
	(segment
		(start 20.107148 -134.79907)
		(end 20.5105 -135.202422)
		(width 0.12065)
		(layer "F.Cu")
		(net "BMC_INT_N")
	)
	(segment
		(start 19.652488 -134.079488)
		(end 20.107148 -134.534148)
		(width 0.12065)
		(layer "F.Cu")
		(net "BMC_INT_N")
	)
	(segment
		(start 20.107148 -134.534148)
		(end 20.107148 -134.79907)
		(width 0.12065)
		(layer "F.Cu")
		(net "BMC_INT_N")
	)
	(segment
		(start 19.652488 -133.82879)
		(end 19.652488 -134.079488)
		(width 0.12065)
		(layer "F.Cu")
		(net "BMC_INT_N")
	)
	(segment
		(start 20.5105 -135.202422)
		(end 20.5105 -135.7122)
		(width 0.12065)
		(layer "F.Cu")
		(net "BMC_INT_N")
	)
	(via
		(at 45.562774 -93.955362)
		(size 0.508)
		(drill 0.254)
		(layers "F.Cu" "B.Cu")
		(net "BMC_INT_N")
	)
	(via
		(at 19.652488 -133.82879)
		(size 0.508)
		(drill 0.254)
		(layers "F.Cu" "B.Cu")
		(net "BMC_INT_N")
	)
	(via
		(at 45.387768 -89.505282)
		(size 0.7112)
		(drill 0.3556)
		(layers "F.Cu" "B.Cu")
		(net "BMC_INT_N")
	)
	(via
		(at 65.5574 -23.771606)
		(size 0.508)
		(drill 0.254)
		(layers "F.Cu" "B.Cu")
		(net "BMC_INT_N")
	)
	(segment
		(start 43.897296 -65.34785)
		(end 44.63415 -64.610996)
		(width 0.12065)
		(layer "B.Cu")
		(net "BMC_INT_N")
	)
	(segment
		(start 56.452008 -24.238458)
		(end 59.379358 -24.238458)
		(width 0.12065)
		(layer "B.Cu")
		(net "BMC_INT_N")
	)
	(segment
		(start 56.011064 -26.356818)
		(end 56.011064 -26.353262)
		(width 0.12065)
		(layer "B.Cu")
		(net "BMC_INT_N")
	)
	(segment
		(start 45.489368 -89.403682)
		(end 45.489368 -83.861148)
		(width 0.12065)
		(layer "B.Cu")
		(net "BMC_INT_N")
	)
	(segment
		(start 45.562774 -92.527374)
		(end 45.387768 -92.352368)
		(width 0.12065)
		(layer "B.Cu")
		(net "BMC_INT_N")
	)
	(segment
		(start 45.489368 -83.861148)
		(end 45.282866 -83.654646)
		(width 0.12065)
		(layer "B.Cu")
		(net "BMC_INT_N")
	)
	(segment
		(start 56.011064 -26.353262)
		(end 55.859426 -26.201624)
		(width 0.12065)
		(layer "B.Cu")
		(net "BMC_INT_N")
	)
	(segment
		(start 63.167768 -23.771606)
		(end 61.933074 -25.0063)
		(width 0.12065)
		(layer "B.Cu")
		(net "BMC_INT_N")
	)
	(segment
		(start 43.897296 -73.346056)
		(end 43.897296 -65.34785)
		(width 0.12065)
		(layer "B.Cu")
		(net "BMC_INT_N")
	)
	(segment
		(start 56.288178 -26.630376)
		(end 56.284622 -26.630376)
		(width 0.12065)
		(layer "B.Cu")
		(net "BMC_INT_N")
	)
	(segment
		(start 44.63415 -64.610996)
		(end 44.63415 -40.71112)
		(width 0.12065)
		(layer "B.Cu")
		(net "BMC_INT_N")
	)
	(segment
		(start 57.107328 -27.449526)
		(end 56.288178 -26.630376)
		(width 0.12065)
		(layer "B.Cu")
		(net "BMC_INT_N")
	)
	(segment
		(start 45.282866 -83.654646)
		(end 45.282866 -74.731626)
		(width 0.12065)
		(layer "B.Cu")
		(net "BMC_INT_N")
	)
	(segment
		(start 55.859426 -24.83104)
		(end 56.452008 -24.238458)
		(width 0.12065)
		(layer "B.Cu")
		(net "BMC_INT_N")
	)
	(segment
		(start 57.107328 -28.237942)
		(end 57.107328 -27.449526)
		(width 0.12065)
		(layer "B.Cu")
		(net "BMC_INT_N")
	)
	(segment
		(start 45.387768 -89.505282)
		(end 45.489368 -89.403682)
		(width 0.12065)
		(layer "B.Cu")
		(net "BMC_INT_N")
	)
	(segment
		(start 59.379358 -24.238458)
		(end 60.1472 -25.0063)
		(width 0.12065)
		(layer "B.Cu")
		(net "BMC_INT_N")
	)
	(segment
		(start 55.859426 -26.201624)
		(end 55.859426 -24.83104)
		(width 0.12065)
		(layer "B.Cu")
		(net "BMC_INT_N")
	)
	(segment
		(start 45.387768 -92.352368)
		(end 45.387768 -89.505282)
		(width 0.12065)
		(layer "B.Cu")
		(net "BMC_INT_N")
	)
	(segment
		(start 65.5574 -23.771606)
		(end 63.167768 -23.771606)
		(width 0.12065)
		(layer "B.Cu")
		(net "BMC_INT_N")
	)
	(segment
		(start 44.63415 -40.71112)
		(end 57.107328 -28.237942)
		(width 0.12065)
		(layer "B.Cu")
		(net "BMC_INT_N")
	)
	(segment
		(start 61.933074 -25.0063)
		(end 60.1472 -25.0063)
		(width 0.12065)
		(layer "B.Cu")
		(net "BMC_INT_N")
	)
	(segment
		(start 45.282866 -74.731626)
		(end 43.897296 -73.346056)
		(width 0.12065)
		(layer "B.Cu")
		(net "BMC_INT_N")
	)
	(segment
		(start 45.562774 -93.955362)
		(end 45.562774 -92.527374)
		(width 0.12065)
		(layer "B.Cu")
		(net "BMC_INT_N")
	)
	(segment
		(start 56.284622 -26.630376)
		(end 56.011064 -26.356818)
		(width 0.12065)
		(layer "B.Cu")
		(net "BMC_INT_N")
	)
	(segment
		(start 38.616636 -93.491812)
		(end 41.617392 -93.491812)
		(width 0.127)
		(layer "In2.Cu")
		(net "BMC_INT_N")
	)
	(segment
		(start 14.971522 -119.814086)
		(end 15.5321 -119.253508)
		(width 0.127)
		(layer "In2.Cu")
		(net "BMC_INT_N")
	)
	(segment
		(start 16.184372 -108.5342)
		(end 16.184626 -108.533946)
		(width 0.127)
		(layer "In2.Cu")
		(net "BMC_INT_N")
	)
	(segment
		(start 19.652488 -133.82879)
		(end 19.135598 -133.3119)
		(width 0.127)
		(layer "In2.Cu")
		(net "BMC_INT_N")
	)
	(segment
		(start 42.080942 -93.955362)
		(end 45.562774 -93.955362)
		(width 0.127)
		(layer "In2.Cu")
		(net "BMC_INT_N")
	)
	(segment
		(start 24.268938 -100.35159)
		(end 26.467054 -98.153474)
		(width 0.127)
		(layer "In2.Cu")
		(net "BMC_INT_N")
	)
	(segment
		(start 13.417804 -122.92965)
		(end 13.417804 -122.404886)
		(width 0.127)
		(layer "In2.Cu")
		(net "BMC_INT_N")
	)
	(segment
		(start 27.863038 -97.361248)
		(end 30.367478 -94.856808)
		(width 0.127)
		(layer "In2.Cu")
		(net "BMC_INT_N")
	)
	(segment
		(start 19.939 -103.71709)
		(end 20.359116 -103.71709)
		(width 0.127)
		(layer "In2.Cu")
		(net "BMC_INT_N")
	)
	(segment
		(start 15.49654 -133.222238)
		(end 15.496286 -133.221984)
		(width 0.127)
		(layer "In2.Cu")
		(net "BMC_INT_N")
	)
	(segment
		(start 23.72487 -100.35159)
		(end 23.989792 -100.35159)
		(width 0.127)
		(layer "In2.Cu")
		(net "BMC_INT_N")
	)
	(segment
		(start 27.255216 -97.361248)
		(end 27.863038 -97.361248)
		(width 0.127)
		(layer "In2.Cu")
		(net "BMC_INT_N")
	)
	(segment
		(start 19.135598 -133.3119)
		(end 15.586456 -133.3119)
		(width 0.127)
		(layer "In2.Cu")
		(net "BMC_INT_N")
	)
	(segment
		(start 35.217354 -94.856808)
		(end 36.067238 -94.006924)
		(width 0.127)
		(layer "In2.Cu")
		(net "BMC_INT_N")
	)
	(segment
		(start 14.294612 -132.500878)
		(end 14.294612 -132.500624)
		(width 0.127)
		(layer "In2.Cu")
		(net "BMC_INT_N")
	)
	(segment
		(start 21.570442 -102.506018)
		(end 23.72487 -100.35159)
		(width 0.127)
		(layer "In2.Cu")
		(net "BMC_INT_N")
	)
	(segment
		(start 41.617392 -93.491812)
		(end 42.080942 -93.955362)
		(width 0.127)
		(layer "In2.Cu")
		(net "BMC_INT_N")
	)
	(segment
		(start 13.417804 -122.404886)
		(end 14.971522 -120.850914)
		(width 0.127)
		(layer "In2.Cu")
		(net "BMC_INT_N")
	)
	(segment
		(start 16.184626 -108.523532)
		(end 17.028922 -107.679236)
		(width 0.127)
		(layer "In2.Cu")
		(net "BMC_INT_N")
	)
	(segment
		(start 36.067238 -94.006924)
		(end 38.101524 -94.006924)
		(width 0.127)
		(layer "In2.Cu")
		(net "BMC_INT_N")
	)
	(segment
		(start 15.5321 -113.519712)
		(end 16.184372 -112.86744)
		(width 0.127)
		(layer "In2.Cu")
		(net "BMC_INT_N")
	)
	(segment
		(start 38.101524 -94.006924)
		(end 38.616636 -93.491812)
		(width 0.127)
		(layer "In2.Cu")
		(net "BMC_INT_N")
	)
	(segment
		(start 15.586456 -133.3119)
		(end 15.496794 -133.222238)
		(width 0.127)
		(layer "In2.Cu")
		(net "BMC_INT_N")
	)
	(segment
		(start 14.294612 -132.500624)
		(end 11.88466 -130.090672)
		(width 0.127)
		(layer "In2.Cu")
		(net "BMC_INT_N")
	)
	(segment
		(start 11.88466 -130.090672)
		(end 11.88466 -124.462794)
		(width 0.127)
		(layer "In2.Cu")
		(net "BMC_INT_N")
	)
	(segment
		(start 24.167084 -100.351844)
		(end 24.26462 -100.351844)
		(width 0.127)
		(layer "In2.Cu")
		(net "BMC_INT_N")
	)
	(segment
		(start 15.496794 -133.222238)
		(end 15.49654 -133.222238)
		(width 0.127)
		(layer "In2.Cu")
		(net "BMC_INT_N")
	)
	(segment
		(start 20.359116 -103.71709)
		(end 21.570188 -102.506018)
		(width 0.127)
		(layer "In2.Cu")
		(net "BMC_INT_N")
	)
	(segment
		(start 26.467054 -98.153474)
		(end 26.467054 -98.14941)
		(width 0.127)
		(layer "In2.Cu")
		(net "BMC_INT_N")
	)
	(segment
		(start 17.028922 -107.679236)
		(end 17.028922 -106.627168)
		(width 0.127)
		(layer "In2.Cu")
		(net "BMC_INT_N")
	)
	(segment
		(start 24.26462 -100.351844)
		(end 24.264874 -100.35159)
		(width 0.127)
		(layer "In2.Cu")
		(net "BMC_INT_N")
	)
	(segment
		(start 23.989792 -100.35159)
		(end 24.167084 -100.351844)
		(width 0.127)
		(layer "In2.Cu")
		(net "BMC_INT_N")
	)
	(segment
		(start 30.367478 -94.856808)
		(end 35.217354 -94.856808)
		(width 0.127)
		(layer "In2.Cu")
		(net "BMC_INT_N")
	)
	(segment
		(start 26.467054 -98.14941)
		(end 27.255216 -97.361248)
		(width 0.127)
		(layer "In2.Cu")
		(net "BMC_INT_N")
	)
	(segment
		(start 15.496286 -133.221984)
		(end 15.015718 -133.221984)
		(width 0.127)
		(layer "In2.Cu")
		(net "BMC_INT_N")
	)
	(segment
		(start 21.570188 -102.506018)
		(end 21.570442 -102.506018)
		(width 0.127)
		(layer "In2.Cu")
		(net "BMC_INT_N")
	)
	(segment
		(start 24.264874 -100.35159)
		(end 24.268938 -100.35159)
		(width 0.127)
		(layer "In2.Cu")
		(net "BMC_INT_N")
	)
	(segment
		(start 16.184626 -108.533946)
		(end 16.184626 -108.523532)
		(width 0.127)
		(layer "In2.Cu")
		(net "BMC_INT_N")
	)
	(segment
		(start 16.184372 -112.86744)
		(end 16.184372 -108.5342)
		(width 0.127)
		(layer "In2.Cu")
		(net "BMC_INT_N")
	)
	(segment
		(start 14.971522 -120.850914)
		(end 14.971522 -119.814086)
		(width 0.127)
		(layer "In2.Cu")
		(net "BMC_INT_N")
	)
	(segment
		(start 15.015718 -133.221984)
		(end 14.294612 -132.500878)
		(width 0.127)
		(layer "In2.Cu")
		(net "BMC_INT_N")
	)
	(segment
		(start 17.028922 -106.627168)
		(end 19.939 -103.71709)
		(width 0.127)
		(layer "In2.Cu")
		(net "BMC_INT_N")
	)
	(segment
		(start 11.88466 -124.462794)
		(end 13.417804 -122.92965)
		(width 0.127)
		(layer "In2.Cu")
		(net "BMC_INT_N")
	)
	(segment
		(start 15.5321 -119.253508)
		(end 15.5321 -113.519712)
		(width 0.127)
		(layer "In2.Cu")
		(net "BMC_INT_N")
	)
	(segment
		(start 24.9936 -84.4296)
		(end 24.457152 -83.893152)
		(width 0.12065)
		(layer "F.Cu")
		(net "PHY_WAKE_N")
	)
	(segment
		(start 23.7998 -82.0928)
		(end 22.711918 -81.004918)
		(width 0.12065)
		(layer "F.Cu")
		(net "PHY_WAKE_N")
	)
	(segment
		(start 23.7998 -82.821526)
		(end 23.7998 -82.0928)
		(width 0.12065)
		(layer "F.Cu")
		(net "PHY_WAKE_N")
	)
	(segment
		(start 24.457152 -83.478878)
		(end 23.7998 -82.821526)
		(width 0.12065)
		(layer "F.Cu")
		(net "PHY_WAKE_N")
	)
	(segment
		(start 24.457152 -83.893152)
		(end 24.457152 -83.478878)
		(width 0.12065)
		(layer "F.Cu")
		(net "PHY_WAKE_N")
	)
	(segment
		(start 25.08631 -84.52231)
		(end 24.9936 -84.4296)
		(width 0.12065)
		(layer "F.Cu")
		(net "PHY_WAKE_N")
	)
	(segment
		(start 22.711918 -79.543656)
		(end 22.584918 -79.416656)
		(width 0.12065)
		(layer "F.Cu")
		(net "PHY_WAKE_N")
	)
	(segment
		(start 26.318718 -84.52231)
		(end 25.08631 -84.52231)
		(width 0.12065)
		(layer "F.Cu")
		(net "PHY_WAKE_N")
	)
	(segment
		(start 22.711918 -81.004918)
		(end 22.711918 -79.543656)
		(width 0.12065)
		(layer "F.Cu")
		(net "PHY_WAKE_N")
	)
	(via
		(at 24.9936 -84.4296)
		(size 0.7112)
		(drill 0.3556)
		(layers "F.Cu" "B.Cu")
		(net "PHY_WAKE_N")
	)
	(segment
		(start 24.059896 -72.41667)
		(end 22.584918 -72.41667)
		(width 0.12065)
		(layer "F.Cu")
		(net "CLK_50M_RMII_PHY_IN")
	)
	(segment
		(start 24.107902 -72.464676)
		(end 24.059896 -72.41667)
		(width 0.12065)
		(layer "F.Cu")
		(net "CLK_50M_RMII_PHY_IN")
	)
	(segment
		(start 24.555958 -72.464676)
		(end 24.107902 -72.464676)
		(width 0.12065)
		(layer "F.Cu")
		(net "CLK_50M_RMII_PHY_IN")
	)
	(segment
		(start 24.555958 -72.464676)
		(end 24.555958 -71.806308)
		(width 0.12065)
		(layer "F.Cu")
		(net "CLK_50M_RMII_PHY_IN")
	)
	(segment
		(start 24.555958 -71.806308)
		(end 24.271478 -71.521828)
		(width 0.12065)
		(layer "F.Cu")
		(net "CLK_50M_RMII_PHY_IN")
	)
	(via
		(at 24.555958 -72.464676)
		(size 0.7112)
		(drill 0.3556)
		(layers "F.Cu" "B.Cu")
		(net "CLK_50M_RMII_PHY_IN")
	)
	(segment
		(start 32.814006 -85.200744)
		(end 32.814006 -85.976206)
		(width 0.508)
		(layer "F.Cu")
		(net "Q46_D")
	)
	(segment
		(start 34.0614 -86.5632)
		(end 33.401 -86.5632)
		(width 0.508)
		(layer "F.Cu")
		(net "Q46_D")
	)
	(segment
		(start 32.814006 -85.976206)
		(end 33.401 -86.5632)
		(width 0.508)
		(layer "F.Cu")
		(net "Q46_D")
	)
	(segment
		(start 34.840418 -84.64931)
		(end 34.840418 -85.784182)
		(width 0.508)
		(layer "F.Cu")
		(net "Q46_D")
	)
	(segment
		(start 34.840418 -85.784182)
		(end 34.0614 -86.5632)
		(width 0.508)
		(layer "F.Cu")
		(net "Q46_D")
	)
	(via
		(at 33.401 -86.5632)
		(size 0.7112)
		(drill 0.3556)
		(layers "F.Cu" "B.Cu")
		(net "Q46_D")
	)
	(segment
		(start 54.983126 -42.80535)
		(end 55.3212 -42.467276)
		(width 0.508)
		(layer "F.Cu")
		(net "Q43_C")
	)
	(segment
		(start 54.4322 -40.7924)
		(end 53.848 -40.2082)
		(width 0.508)
		(layer "F.Cu")
		(net "Q43_C")
	)
	(segment
		(start 55.3212 -40.7924)
		(end 54.4322 -40.7924)
		(width 0.508)
		(layer "F.Cu")
		(net "Q43_C")
	)
	(segment
		(start 56.604916 -38.737794)
		(end 55.318406 -38.737794)
		(width 0.508)
		(layer "F.Cu")
		(net "Q43_C")
	)
	(segment
		(start 55.318406 -38.737794)
		(end 53.848 -40.2082)
		(width 0.508)
		(layer "F.Cu")
		(net "Q43_C")
	)
	(segment
		(start 55.3212 -42.467276)
		(end 55.3212 -40.7924)
		(width 0.508)
		(layer "F.Cu")
		(net "Q43_C")
	)
	(via
		(at 53.848 -40.2082)
		(size 0.7112)
		(drill 0.3556)
		(layers "F.Cu" "B.Cu")
		(net "Q43_C")
	)
	(segment
		(start 347.133672 -43.363388)
		(end 346.543122 -43.953938)
		(width 0.12065)
		(layer "F.Cu")
		(net "Q37_G")
	)
	(segment
		(start 347.133672 -42.697908)
		(end 347.133672 -43.363388)
		(width 0.12065)
		(layer "F.Cu")
		(net "Q37_G")
	)
	(segment
		(start 347.133672 -42.697908)
		(end 347.910404 -42.697908)
		(width 0.12065)
		(layer "F.Cu")
		(net "Q37_G")
	)
	(segment
		(start 346.543122 -43.953938)
		(end 346.543122 -44.158408)
		(width 0.12065)
		(layer "F.Cu")
		(net "Q37_G")
	)
	(segment
		(start 347.910404 -42.697908)
		(end 348.371414 -42.236898)
		(width 0.12065)
		(layer "F.Cu")
		(net "Q37_G")
	)
	(via
		(at 348.371414 -42.236898)
		(size 0.7112)
		(drill 0.3556)
		(layers "F.Cu" "B.Cu")
		(net "Q37_G")
	)
	(segment
		(start 20.651978 -96.186498)
		(end 21.251418 -96.186498)
		(width 0.12065)
		(layer "F.Cu")
		(net "Q20_G")
	)
	(segment
		(start 17.946116 -95.07474)
		(end 17.872456 -95.1484)
		(width 0.12065)
		(layer "F.Cu")
		(net "Q20_G")
	)
	(segment
		(start 16.551656 -94.642178)
		(end 16.75511 -94.845632)
		(width 0.12065)
		(layer "F.Cu")
		(net "Q20_G")
	)
	(segment
		(start 17.872456 -95.471488)
		(end 17.458944 -95.885)
		(width 0.12065)
		(layer "F.Cu")
		(net "Q20_G")
	)
	(segment
		(start 17.872456 -95.1484)
		(end 17.872456 -95.471488)
		(width 0.12065)
		(layer "F.Cu")
		(net "Q20_G")
	)
	(segment
		(start 17.018 -95.108522)
		(end 16.75511 -94.845632)
		(width 0.12065)
		(layer "F.Cu")
		(net "Q20_G")
	)
	(segment
		(start 17.018 -95.885)
		(end 17.018 -95.108522)
		(width 0.12065)
		(layer "F.Cu")
		(net "Q20_G")
	)
	(segment
		(start 19.54022 -95.07474)
		(end 20.651978 -96.186498)
		(width 0.12065)
		(layer "F.Cu")
		(net "Q20_G")
	)
	(segment
		(start 15.696946 -94.642178)
		(end 16.551656 -94.642178)
		(width 0.12065)
		(layer "F.Cu")
		(net "Q20_G")
	)
	(segment
		(start 17.946116 -95.07474)
		(end 19.54022 -95.07474)
		(width 0.12065)
		(layer "F.Cu")
		(net "Q20_G")
	)
	(segment
		(start 17.458944 -95.885)
		(end 17.018 -95.885)
		(width 0.12065)
		(layer "F.Cu")
		(net "Q20_G")
	)
	(via
		(at 17.018 -95.885)
		(size 0.7112)
		(drill 0.3556)
		(layers "F.Cu" "B.Cu")
		(net "Q20_G")
	)
	(segment
		(start 44.904914 -135.684768)
		(end 45.30471 -135.284972)
		(width 0.12065)
		(layer "F.Cu")
		(net "GPIOM0_I210_PERST_N")
	)
	(segment
		(start 56.545988 -143.254476)
		(end 55.15356 -143.254476)
		(width 0.12065)
		(layer "F.Cu")
		(net "GPIOM0_I210_PERST_N")
	)
	(segment
		(start 55.15356 -143.254476)
		(end 54.925214 -143.02613)
		(width 0.12065)
		(layer "F.Cu")
		(net "GPIOM0_I210_PERST_N")
	)
	(via
		(at 53.46954 -142.9512)
		(size 0.7112)
		(drill 0.3556)
		(layers "F.Cu" "B.Cu")
		(net "GPIOM0_I210_PERST_N")
	)
	(via
		(at 54.925214 -143.02613)
		(size 0.508)
		(drill 0.254)
		(layers "F.Cu" "B.Cu")
		(net "GPIOM0_I210_PERST_N")
	)
	(via
		(at 45.30471 -135.284972)
		(size 0.4572)
		(drill 0.2032)
		(layers "F.Cu" "B.Cu")
		(net "GPIOM0_I210_PERST_N")
	)
	(segment
		(start 46.796452 -135.284972)
		(end 45.30471 -135.284972)
		(width 0.12065)
		(layer "B.Cu")
		(net "GPIOM0_I210_PERST_N")
	)
	(segment
		(start 50.510948 -138.999468)
		(end 46.796452 -135.284972)
		(width 0.12065)
		(layer "B.Cu")
		(net "GPIOM0_I210_PERST_N")
	)
	(segment
		(start 54.925214 -143.02613)
		(end 54.850284 -142.9512)
		(width 0.12065)
		(layer "B.Cu")
		(net "GPIOM0_I210_PERST_N")
	)
	(segment
		(start 54.850284 -142.9512)
		(end 53.46954 -142.9512)
		(width 0.12065)
		(layer "B.Cu")
		(net "GPIOM0_I210_PERST_N")
	)
	(segment
		(start 53.46954 -142.9512)
		(end 51.001422 -142.9512)
		(width 0.12065)
		(layer "B.Cu")
		(net "GPIOM0_I210_PERST_N")
	)
	(segment
		(start 51.001422 -142.9512)
		(end 50.510948 -142.460726)
		(width 0.12065)
		(layer "B.Cu")
		(net "GPIOM0_I210_PERST_N")
	)
	(segment
		(start 50.510948 -142.460726)
		(end 50.510948 -138.999468)
		(width 0.12065)
		(layer "B.Cu")
		(net "GPIOM0_I210_PERST_N")
	)
	(segment
		(start 188.214 -10.4394)
		(end 187.8965 -10.7569)
		(width 0.12065)
		(layer "F.Cu")
		(net "ENCLO_LED_RED")
	)
	(segment
		(start 196.96684 -0.78613)
		(end 196.01561 -1.73736)
		(width 0.12065)
		(layer "F.Cu")
		(net "ENCLO_LED_RED")
	)
	(segment
		(start 187.8965 -10.7569)
		(end 187.8965 -11.303)
		(width 0.12065)
		(layer "F.Cu")
		(net "ENCLO_LED_RED")
	)
	(segment
		(start 196.96684 0)
		(end 196.96684 -0.78613)
		(width 0.12065)
		(layer "F.Cu")
		(net "ENCLO_LED_RED")
	)
	(segment
		(start 188.3664 -10.414)
		(end 188.341 -10.4394)
		(width 0.12065)
		(layer "F.Cu")
		(net "ENCLO_LED_RED")
	)
	(segment
		(start 188.341 -10.4394)
		(end 188.214 -10.4394)
		(width 0.12065)
		(layer "F.Cu")
		(net "ENCLO_LED_RED")
	)
	(via
		(at 188.3664 -10.414)
		(size 0.508)
		(drill 0.254)
		(layers "F.Cu" "B.Cu")
		(net "ENCLO_LED_RED")
	)
	(via
		(at 196.01561 -1.73736)
		(size 0.508)
		(drill 0.254)
		(layers "F.Cu" "B.Cu")
		(net "ENCLO_LED_RED")
	)
	(via
		(at 188.3664 -8.747506)
		(size 0.7112)
		(drill 0.3556)
		(layers "F.Cu" "B.Cu")
		(net "ENCLO_LED_RED")
	)
	(segment
		(start 195.00977 -2.7432)
		(end 196.01561 -1.73736)
		(width 0.12065)
		(layer "B.Cu")
		(net "ENCLO_LED_RED")
	)
	(segment
		(start 188.3664 -10.414)
		(end 188.3664 -8.747506)
		(width 0.12065)
		(layer "B.Cu")
		(net "ENCLO_LED_RED")
	)
	(segment
		(start 188.3664 -8.747506)
		(end 188.3664 -5.561838)
		(width 0.12065)
		(layer "B.Cu")
		(net "ENCLO_LED_RED")
	)
	(segment
		(start 188.3664 -5.561838)
		(end 191.185038 -2.7432)
		(width 0.12065)
		(layer "B.Cu")
		(net "ENCLO_LED_RED")
	)
	(segment
		(start 191.185038 -2.7432)
		(end 195.00977 -2.7432)
		(width 0.12065)
		(layer "B.Cu")
		(net "ENCLO_LED_RED")
	)
	(segment
		(start 66.7512 -74.5617)
		(end 65.7606 -74.5617)
		(width 0.12065)
		(layer "F.Cu")
		(net "U19_PERST_N")
	)
	(segment
		(start 66.352674 -72.023986)
		(end 66.352674 -73.236074)
		(width 0.12065)
		(layer "F.Cu")
		(net "U19_PERST_N")
	)
	(segment
		(start 66.352674 -73.236074)
		(end 66.802 -73.6854)
		(width 0.12065)
		(layer "F.Cu")
		(net "U19_PERST_N")
	)
	(segment
		(start 66.802 -74.5109)
		(end 66.7512 -74.5617)
		(width 0.12065)
		(layer "F.Cu")
		(net "U19_PERST_N")
	)
	(segment
		(start 66.802 -73.6854)
		(end 66.802 -74.5109)
		(width 0.12065)
		(layer "F.Cu")
		(net "U19_PERST_N")
	)
	(segment
		(start 132.852668 -74.657712)
		(end 132.94741 -74.657712)
		(width 0.12065)
		(layer "F.Cu")
		(net "SPI_DATA0_3_R")
	)
	(segment
		(start 133.229604 -72.455532)
		(end 132.445506 -73.23963)
		(width 0.12065)
		(layer "F.Cu")
		(net "SPI_DATA0_3_R")
	)
	(segment
		(start 132.445506 -73.23963)
		(end 132.445506 -74.25055)
		(width 0.12065)
		(layer "F.Cu")
		(net "SPI_DATA0_3_R")
	)
	(segment
		(start 133.140958 -74.85126)
		(end 134.230364 -74.85126)
		(width 0.12065)
		(layer "F.Cu")
		(net "SPI_DATA0_3_R")
	)
	(segment
		(start 132.94741 -74.657712)
		(end 133.140958 -74.85126)
		(width 0.12065)
		(layer "F.Cu")
		(net "SPI_DATA0_3_R")
	)
	(segment
		(start 134.230364 -74.85126)
		(end 134.292086 -74.912982)
		(width 0.12065)
		(layer "F.Cu")
		(net "SPI_DATA0_3_R")
	)
	(segment
		(start 132.445506 -74.25055)
		(end 132.852668 -74.657712)
		(width 0.12065)
		(layer "F.Cu")
		(net "SPI_DATA0_3_R")
	)
	(segment
		(start 133.229604 -71.223886)
		(end 133.229604 -72.455532)
		(width 0.12065)
		(layer "F.Cu")
		(net "SPI_DATA0_3_R")
	)
	(segment
		(start 134.499604 -63.223902)
		(end 134.499604 -60.62472)
		(width 0.12065)
		(layer "F.Cu")
		(net "SPI_DATA0_2_R")
	)
	(segment
		(start 135.96493 -60.200032)
		(end 134.941564 -60.200032)
		(width 0.12065)
		(layer "F.Cu")
		(net "SPI_DATA0_2_R")
	)
	(segment
		(start 134.499604 -60.62472)
		(end 134.932928 -60.191396)
		(width 0.12065)
		(layer "F.Cu")
		(net "SPI_DATA0_2_R")
	)
	(segment
		(start 134.941564 -60.200032)
		(end 134.932928 -60.191396)
		(width 0.12065)
		(layer "F.Cu")
		(net "SPI_DATA0_2_R")
	)
	(segment
		(start 132.816346 -61.54293)
		(end 132.816346 -60.194698)
		(width 0.12065)
		(layer "F.Cu")
		(net "SPI_DATA0_1_R")
	)
	(segment
		(start 132.816346 -60.194698)
		(end 133.876796 -60.194698)
		(width 0.12065)
		(layer "F.Cu")
		(net "SPI_DATA0_1_R")
	)
	(segment
		(start 133.876796 -60.194698)
		(end 133.891274 -60.18022)
		(width 0.12065)
		(layer "F.Cu")
		(net "SPI_DATA0_1_R")
	)
	(segment
		(start 133.229604 -61.956188)
		(end 132.816346 -61.54293)
		(width 0.12065)
		(layer "F.Cu")
		(net "SPI_DATA0_1_R")
	)
	(segment
		(start 133.229604 -63.223902)
		(end 133.229604 -61.956188)
		(width 0.12065)
		(layer "F.Cu")
		(net "SPI_DATA0_1_R")
	)
	(segment
		(start 139.636754 -75.07859)
		(end 140.189204 -75.07859)
		(width 0.12065)
		(layer "F.Cu")
		(net "SPI_DATA0_0_R")
	)
	(segment
		(start 136.298178 -72.16267)
		(end 137.19048 -72.16267)
		(width 0.12065)
		(layer "F.Cu")
		(net "SPI_DATA0_0_R")
	)
	(segment
		(start 135.769604 -71.223886)
		(end 135.769604 -71.634096)
		(width 0.12065)
		(layer "F.Cu")
		(net "SPI_DATA0_0_R")
	)
	(segment
		(start 138.671046 -74.112882)
		(end 139.636754 -75.07859)
		(width 0.12065)
		(layer "F.Cu")
		(net "SPI_DATA0_0_R")
	)
	(segment
		(start 137.19048 -72.16267)
		(end 137.586974 -72.559164)
		(width 0.12065)
		(layer "F.Cu")
		(net "SPI_DATA0_0_R")
	)
	(segment
		(start 137.586974 -73.920604)
		(end 138.660124 -73.920604)
		(width 0.12065)
		(layer "F.Cu")
		(net "SPI_DATA0_0_R")
	)
	(segment
		(start 138.671046 -73.931526)
		(end 138.671046 -74.112882)
		(width 0.12065)
		(layer "F.Cu")
		(net "SPI_DATA0_0_R")
	)
	(segment
		(start 138.660124 -73.920604)
		(end 138.671046 -73.931526)
		(width 0.12065)
		(layer "F.Cu")
		(net "SPI_DATA0_0_R")
	)
	(segment
		(start 137.586974 -72.559164)
		(end 137.586974 -73.920604)
		(width 0.12065)
		(layer "F.Cu")
		(net "SPI_DATA0_0_R")
	)
	(segment
		(start 135.769604 -71.223886)
		(end 135.769604 -70.741794)
		(width 0.12065)
		(layer "F.Cu")
		(net "SPI_DATA0_0_R")
	)
	(segment
		(start 135.769604 -71.634096)
		(end 136.298178 -72.16267)
		(width 0.12065)
		(layer "F.Cu")
		(net "SPI_DATA0_0_R")
	)
	(via
		(at 140.189204 -75.07859)
		(size 0.7112)
		(drill 0.3556)
		(layers "F.Cu" "B.Cu")
		(net "SPI_DATA0_0_R")
	)
	(segment
		(start 135.275574 -72.561704)
		(end 135.275574 -73.844658)
		(width 0.12065)
		(layer "F.Cu")
		(net "SPI_CLK0_R")
	)
	(segment
		(start 135.275574 -73.844658)
		(end 135.361934 -73.931018)
		(width 0.12065)
		(layer "F.Cu")
		(net "SPI_CLK0_R")
	)
	(segment
		(start 134.499604 -71.785734)
		(end 135.275574 -72.561704)
		(width 0.12065)
		(layer "F.Cu")
		(net "SPI_CLK0_R")
	)
	(segment
		(start 136.386062 -73.99274)
		(end 135.423656 -73.99274)
		(width 0.12065)
		(layer "F.Cu")
		(net "SPI_CLK0_R")
	)
	(segment
		(start 135.423656 -73.99274)
		(end 135.361934 -73.931018)
		(width 0.12065)
		(layer "F.Cu")
		(net "SPI_CLK0_R")
	)
	(segment
		(start 134.499604 -71.223886)
		(end 134.499604 -71.785734)
		(width 0.12065)
		(layer "F.Cu")
		(net "SPI_CLK0_R")
	)
	(segment
		(start 38.504876 -124.484892)
		(end 38.10508 -124.085096)
		(width 0.12065)
		(layer "F.Cu")
		(net "RMII0_PHY_BMC_RXCTL0")
	)
	(segment
		(start 36.28898 -106.853736)
		(end 36.28898 -107.85602)
		(width 0.12065)
		(layer "F.Cu")
		(net "RMII0_PHY_BMC_RXCTL0")
	)
	(segment
		(start 36.384992 -106.757724)
		(end 36.28898 -106.853736)
		(width 0.12065)
		(layer "F.Cu")
		(net "RMII0_PHY_BMC_RXCTL0")
	)
	(segment
		(start 36.28898 -107.85602)
		(end 36.340542 -107.907582)
		(width 0.12065)
		(layer "F.Cu")
		(net "RMII0_PHY_BMC_RXCTL0")
	)
	(segment
		(start 38.856412 -110.423452)
		(end 36.340542 -107.907582)
		(width 0.12065)
		(layer "F.Cu")
		(net "RMII0_PHY_BMC_RXCTL0")
	)
	(segment
		(start 38.856412 -110.642908)
		(end 38.856412 -110.423452)
		(width 0.12065)
		(layer "F.Cu")
		(net "RMII0_PHY_BMC_RXCTL0")
	)
	(via
		(at 36.340542 -107.907582)
		(size 0.7112)
		(drill 0.3556)
		(layers "F.Cu" "B.Cu")
		(net "RMII0_PHY_BMC_RXCTL0")
	)
	(via
		(at 38.10508 -124.085096)
		(size 0.4572)
		(drill 0.2032)
		(layers "F.Cu" "B.Cu")
		(net "RMII0_PHY_BMC_RXCTL0")
	)
	(via
		(at 38.856412 -110.642908)
		(size 0.508)
		(drill 0.254)
		(layers "F.Cu" "B.Cu")
		(net "RMII0_PHY_BMC_RXCTL0")
	)
	(segment
		(start 36.985448 -113.697512)
		(end 36.546282 -113.258346)
		(width 0.127)
		(layer "In2.Cu")
		(net "RMII0_PHY_BMC_RXCTL0")
	)
	(segment
		(start 38.10508 -124.085096)
		(end 38.10508 -123.913392)
		(width 0.127)
		(layer "In2.Cu")
		(net "RMII0_PHY_BMC_RXCTL0")
	)
	(segment
		(start 37.700204 -123.508516)
		(end 37.700204 -116.474748)
		(width 0.127)
		(layer "In2.Cu")
		(net "RMII0_PHY_BMC_RXCTL0")
	)
	(segment
		(start 36.985448 -115.759992)
		(end 36.985448 -113.697512)
		(width 0.127)
		(layer "In2.Cu")
		(net "RMII0_PHY_BMC_RXCTL0")
	)
	(segment
		(start 38.10508 -123.913392)
		(end 37.700204 -123.508516)
		(width 0.127)
		(layer "In2.Cu")
		(net "RMII0_PHY_BMC_RXCTL0")
	)
	(segment
		(start 36.546282 -111.840518)
		(end 36.7792 -111.6076)
		(width 0.127)
		(layer "In2.Cu")
		(net "RMII0_PHY_BMC_RXCTL0")
	)
	(segment
		(start 37.700204 -116.474748)
		(end 36.985448 -115.759992)
		(width 0.127)
		(layer "In2.Cu")
		(net "RMII0_PHY_BMC_RXCTL0")
	)
	(segment
		(start 37.89172 -111.6076)
		(end 38.856412 -110.642908)
		(width 0.127)
		(layer "In2.Cu")
		(net "RMII0_PHY_BMC_RXCTL0")
	)
	(segment
		(start 36.546282 -113.258346)
		(end 36.546282 -111.840518)
		(width 0.127)
		(layer "In2.Cu")
		(net "RMII0_PHY_BMC_RXCTL0")
	)
	(segment
		(start 36.7792 -111.6076)
		(end 37.89172 -111.6076)
		(width 0.127)
		(layer "In2.Cu")
		(net "RMII0_PHY_BMC_RXCTL0")
	)
	(segment
		(start 36.084002 -81.8769)
		(end 35.066986 -81.8769)
		(width 0.12065)
		(layer "F.Cu")
		(net "Q46_G")
	)
	(segment
		(start 34.993072 -82.774536)
		(end 34.993072 -81.950814)
		(width 0.12065)
		(layer "F.Cu")
		(net "Q46_G")
	)
	(segment
		(start 35.066986 -81.8769)
		(end 34.993072 -81.950814)
		(width 0.12065)
		(layer "F.Cu")
		(net "Q46_G")
	)
	(segment
		(start 36.745418 -83.66506)
		(end 36.087558 -83.0072)
		(width 0.12065)
		(layer "F.Cu")
		(net "Q46_G")
	)
	(segment
		(start 35.225736 -83.0072)
		(end 34.993072 -82.774536)
		(width 0.12065)
		(layer "F.Cu")
		(net "Q46_G")
	)
	(segment
		(start 36.087558 -83.0072)
		(end 35.225736 -83.0072)
		(width 0.12065)
		(layer "F.Cu")
		(net "Q46_G")
	)
	(via
		(at 34.993072 -81.950814)
		(size 0.7112)
		(drill 0.3556)
		(layers "F.Cu" "B.Cu")
		(net "Q46_G")
	)
	(segment
		(start 41.6179 -82.883248)
		(end 41.6179 -83.585558)
		(width 0.12065)
		(layer "F.Cu")
		(net "Q45_D")
	)
	(segment
		(start 37.024818 -80.708246)
		(end 37.989256 -81.672684)
		(width 0.12065)
		(layer "F.Cu")
		(net "Q45_D")
	)
	(segment
		(start 37.989256 -81.858358)
		(end 38.49116 -82.360262)
		(width 0.12065)
		(layer "F.Cu")
		(net "Q45_D")
	)
	(segment
		(start 41.094914 -82.360262)
		(end 41.6179 -82.883248)
		(width 0.12065)
		(layer "F.Cu")
		(net "Q45_D")
	)
	(segment
		(start 36.872672 -80.708246)
		(end 37.024818 -80.708246)
		(width 0.12065)
		(layer "F.Cu")
		(net "Q45_D")
	)
	(segment
		(start 40.923464 -84.279994)
		(end 38.71849 -84.279994)
		(width 0.12065)
		(layer "F.Cu")
		(net "Q45_D")
	)
	(segment
		(start 36.839906 -81.743804)
		(end 36.973002 -81.8769)
		(width 0.12065)
		(layer "F.Cu")
		(net "Q45_D")
	)
	(segment
		(start 36.872672 -80.708246)
		(end 36.839906 -80.741012)
		(width 0.12065)
		(layer "F.Cu")
		(net "Q45_D")
	)
	(segment
		(start 37.989256 -81.672684)
		(end 37.989256 -81.858358)
		(width 0.12065)
		(layer "F.Cu")
		(net "Q45_D")
	)
	(segment
		(start 41.6179 -83.585558)
		(end 40.923464 -84.279994)
		(width 0.12065)
		(layer "F.Cu")
		(net "Q45_D")
	)
	(segment
		(start 36.839906 -80.741012)
		(end 36.839906 -81.743804)
		(width 0.12065)
		(layer "F.Cu")
		(net "Q45_D")
	)
	(segment
		(start 38.49116 -82.360262)
		(end 41.094914 -82.360262)
		(width 0.12065)
		(layer "F.Cu")
		(net "Q45_D")
	)
	(via
		(at 36.872672 -80.708246)
		(size 0.7112)
		(drill 0.3556)
		(layers "F.Cu" "B.Cu")
		(net "Q45_D")
	)
	(segment
		(start 55.620666 -36.832794)
		(end 54.98973 -37.551614)
		(width 0.12065)
		(layer "F.Cu")
		(net "Q43_B")
	)
	(segment
		(start 53.644546 -37.368734)
		(end 53.827426 -37.551614)
		(width 0.12065)
		(layer "F.Cu")
		(net "Q43_B")
	)
	(segment
		(start 53.644546 -36.471098)
		(end 53.644546 -37.368734)
		(width 0.12065)
		(layer "F.Cu")
		(net "Q43_B")
	)
	(segment
		(start 54.98973 -37.551614)
		(end 54.39283 -37.551614)
		(width 0.12065)
		(layer "F.Cu")
		(net "Q43_B")
	)
	(segment
		(start 53.827426 -37.551614)
		(end 54.39283 -37.551614)
		(width 0.12065)
		(layer "F.Cu")
		(net "Q43_B")
	)
	(via
		(at 54.39283 -37.551614)
		(size 0.7112)
		(drill 0.3556)
		(layers "F.Cu" "B.Cu")
		(net "Q43_B")
	)
	(segment
		(start 51.74996 -37.01542)
		(end 51.74996 -36.660836)
		(width 0.12065)
		(layer "F.Cu")
		(net "Q42_D")
	)
	(segment
		(start 52.755546 -36.471098)
		(end 52.755546 -37.440616)
		(width 0.12065)
		(layer "F.Cu")
		(net "Q42_D")
	)
	(segment
		(start 52.351178 -34.1122)
		(end 51.74996 -34.713418)
		(width 0.12065)
		(layer "F.Cu")
		(net "Q42_D")
	)
	(segment
		(start 52.671726 -37.524436)
		(end 52.258976 -37.524436)
		(width 0.12065)
		(layer "F.Cu")
		(net "Q42_D")
	)
	(segment
		(start 52.755546 -37.440616)
		(end 52.671726 -37.524436)
		(width 0.12065)
		(layer "F.Cu")
		(net "Q42_D")
	)
	(segment
		(start 52.258976 -37.524436)
		(end 51.74996 -37.01542)
		(width 0.12065)
		(layer "F.Cu")
		(net "Q42_D")
	)
	(segment
		(start 51.74996 -34.713418)
		(end 51.74996 -36.660836)
		(width 0.12065)
		(layer "F.Cu")
		(net "Q42_D")
	)
	(via
		(at 51.74996 -36.660836)
		(size 0.7112)
		(drill 0.3556)
		(layers "F.Cu" "B.Cu")
		(net "Q42_D")
	)
	(segment
		(start 24.697436 -85.895688)
		(end 24.697436 -85.11794)
		(width 0.12065)
		(layer "F.Cu")
		(net "PHY_RESET_N")
	)
	(segment
		(start 25.470358 -85.363558)
		(end 26.415492 -86.308692)
		(width 0.12065)
		(layer "F.Cu")
		(net "PHY_RESET_N")
	)
	(segment
		(start 25.371298 -86.56955)
		(end 24.697436 -85.895688)
		(width 0.12065)
		(layer "F.Cu")
		(net "PHY_RESET_N")
	)
	(segment
		(start 24.095202 -84.515706)
		(end 24.095202 -83.851242)
		(width 0.12065)
		(layer "F.Cu")
		(net "PHY_RESET_N")
	)
	(segment
		(start 23.43785 -82.306922)
		(end 21.911056 -80.780128)
		(width 0.12065)
		(layer "F.Cu")
		(net "PHY_RESET_N")
	)
	(segment
		(start 25.377648 -86.5632)
		(end 25.371298 -86.56955)
		(width 0.12065)
		(layer "F.Cu")
		(net "PHY_RESET_N")
	)
	(segment
		(start 23.43785 -83.19389)
		(end 23.43785 -82.306922)
		(width 0.12065)
		(layer "F.Cu")
		(net "PHY_RESET_N")
	)
	(segment
		(start 24.697436 -85.11794)
		(end 24.095202 -84.515706)
		(width 0.12065)
		(layer "F.Cu")
		(net "PHY_RESET_N")
	)
	(segment
		(start 21.911056 -80.780128)
		(end 21.911056 -80.090518)
		(width 0.12065)
		(layer "F.Cu")
		(net "PHY_RESET_N")
	)
	(segment
		(start 26.415492 -86.5632)
		(end 25.377648 -86.5632)
		(width 0.12065)
		(layer "F.Cu")
		(net "PHY_RESET_N")
	)
	(segment
		(start 24.095202 -83.851242)
		(end 23.43785 -83.19389)
		(width 0.12065)
		(layer "F.Cu")
		(net "PHY_RESET_N")
	)
	(segment
		(start 26.415492 -86.308692)
		(end 26.415492 -86.5632)
		(width 0.12065)
		(layer "F.Cu")
		(net "PHY_RESET_N")
	)
	(via
		(at 25.771602 -68.277994)
		(size 0.508)
		(drill 0.254)
		(layers "F.Cu" "B.Cu")
		(net "PHY_RESET_N")
	)
	(via
		(at 25.470358 -85.363558)
		(size 0.508)
		(drill 0.254)
		(layers "F.Cu" "B.Cu")
		(net "PHY_RESET_N")
	)
	(via
		(at 23.598378 -71.31431)
		(size 0.7112)
		(drill 0.3556)
		(layers "F.Cu" "B.Cu")
		(net "PHY_RESET_N")
	)
	(segment
		(start 23.4315 -69.58076)
		(end 23.885652 -69.58076)
		(width 0.12065)
		(layer "B.Cu")
		(net "PHY_RESET_N")
	)
	(segment
		(start 23.578566 -71.31431)
		(end 23.4315 -71.167244)
		(width 0.12065)
		(layer "B.Cu")
		(net "PHY_RESET_N")
	)
	(segment
		(start 23.885652 -69.58076)
		(end 25.188418 -68.277994)
		(width 0.12065)
		(layer "B.Cu")
		(net "PHY_RESET_N")
	)
	(segment
		(start 25.188418 -68.277994)
		(end 25.771602 -68.277994)
		(width 0.12065)
		(layer "B.Cu")
		(net "PHY_RESET_N")
	)
	(segment
		(start 23.598378 -71.31431)
		(end 23.578566 -71.31431)
		(width 0.12065)
		(layer "B.Cu")
		(net "PHY_RESET_N")
	)
	(segment
		(start 23.4315 -71.167244)
		(end 23.4315 -69.58076)
		(width 0.12065)
		(layer "B.Cu")
		(net "PHY_RESET_N")
	)
	(segment
		(start 25.146 -85.0392)
		(end 25.146 -72.749918)
		(width 0.127)
		(layer "In5.Cu")
		(net "PHY_RESET_N")
	)
	(segment
		(start 25.146 -72.749918)
		(end 24.8412 -72.445118)
		(width 0.127)
		(layer "In5.Cu")
		(net "PHY_RESET_N")
	)
	(segment
		(start 24.8412 -72.445118)
		(end 24.8412 -69.208396)
		(width 0.127)
		(layer "In5.Cu")
		(net "PHY_RESET_N")
	)
	(segment
		(start 25.470358 -85.363558)
		(end 25.146 -85.0392)
		(width 0.127)
		(layer "In5.Cu")
		(net "PHY_RESET_N")
	)
	(segment
		(start 24.8412 -69.208396)
		(end 25.771602 -68.277994)
		(width 0.127)
		(layer "In5.Cu")
		(net "PHY_RESET_N")
	)
	(segment
		(start 203.755498 -40.710358)
		(end 203.700126 -40.722296)
		(width 0.136652)
		(layer "F.Cu")
		(net "PCIE_TX_P78")
	)
	(segment
		(start 18.410936 -80.800194)
		(end 19.078194 -81.467452)
		(width 0.136652)
		(layer "F.Cu")
		(net "PCIE_TX_P78")
	)
	(segment
		(start 19.078194 -81.68132)
		(end 18.852134 -81.90738)
		(width 0.136652)
		(layer "F.Cu")
		(net "PCIE_TX_P78")
	)
	(segment
		(start 199.572626 -45.268896)
		(end 198.849742 -45.992288)
		(width 0.136652)
		(layer "F.Cu")
		(net "PCIE_TX_P78")
	)
	(segment
		(start 198.849742 -45.992288)
		(end 198.17969 -45.992288)
		(width 0.136652)
		(layer "F.Cu")
		(net "PCIE_TX_P78")
	)
	(segment
		(start 197.816978 -45.629576)
		(end 197.816978 -45.59046)
		(width 0.136652)
		(layer "F.Cu")
		(net "PCIE_TX_P78")
	)
	(segment
		(start 18.410936 -80.090518)
		(end 18.410936 -80.800194)
		(width 0.136652)
		(layer "F.Cu")
		(net "PCIE_TX_P78")
	)
	(segment
		(start 211.864194 -40.47871)
		(end 206.50835 -40.47871)
		(width 0.136652)
		(layer "F.Cu")
		(net "PCIE_TX_P78")
	)
	(segment
		(start 212.149944 -40.19296)
		(end 211.864194 -40.47871)
		(width 0.136652)
		(layer "F.Cu")
		(net "PCIE_TX_P78")
	)
	(segment
		(start 19.078194 -81.467452)
		(end 19.078194 -81.68132)
		(width 0.136652)
		(layer "F.Cu")
		(net "PCIE_TX_P78")
	)
	(segment
		(start 199.748902 -44.440602)
		(end 199.572626 -45.268896)
		(width 0.136652)
		(layer "F.Cu")
		(net "PCIE_TX_P78")
	)
	(segment
		(start 200.895966 -42.675302)
		(end 199.748902 -44.440602)
		(width 0.136652)
		(layer "F.Cu")
		(net "PCIE_TX_P78")
	)
	(segment
		(start 206.50835 -40.47871)
		(end 205.776322 -40.28059)
		(width 0.136652)
		(layer "F.Cu")
		(net "PCIE_TX_P78")
	)
	(segment
		(start 205.776322 -40.28059)
		(end 203.755498 -40.710612)
		(width 0.136652)
		(layer "F.Cu")
		(net "PCIE_TX_P78")
	)
	(segment
		(start 203.755498 -40.710612)
		(end 203.755498 -40.710358)
		(width 0.136652)
		(layer "F.Cu")
		(net "PCIE_TX_P78")
	)
	(segment
		(start 203.700126 -40.722296)
		(end 201.275188 -42.296334)
		(width 0.136652)
		(layer "F.Cu")
		(net "PCIE_TX_P78")
	)
	(via
		(at 18.852134 -81.90738)
		(size 0.508)
		(drill 0.254)
		(layers "F.Cu" "B.Cu")
		(net "PCIE_TX_P78")
	)
	(via
		(at 197.816978 -45.59046)
		(size 0.508)
		(drill 0.254)
		(layers "F.Cu" "B.Cu")
		(net "PCIE_TX_P78")
	)
	(via
		(at 101.9302 -38.91661)
		(size 0.508)
		(drill 0.254)
		(layers "F.Cu" "B.Cu")
		(net "PCIE_TX_P78")
	)
	(arc
		(start 198.17969 -45.992288)
		(mid 197.923214 -45.886052)
		(end 197.816978 -45.629576)
		(width 0.136652)
		(layer "F.Cu")
		(net "PCIE_TX_P78")
	)
	(arc
		(start 201.275188 -42.296334)
		(mid 201.06564 -42.465868)
		(end 200.895966 -42.675302)
		(width 0.136652)
		(layer "F.Cu")
		(net "PCIE_TX_P78")
	)
	(segment
		(start 105.406952 -39.19601)
		(end 102.2096 -39.19601)
		(width 0.1397)
		(layer "In2.Cu")
		(net "PCIE_TX_P78")
	)
	(segment
		(start 145.880074 -43.1673)
		(end 141.996668 -40.645842)
		(width 0.1397)
		(layer "In2.Cu")
		(net "PCIE_TX_P78")
	)
	(segment
		(start 197.423278 -45.98416)
		(end 194.022218 -45.98416)
		(width 0.1397)
		(layer "In2.Cu")
		(net "PCIE_TX_P78")
	)
	(segment
		(start 181.485032 -43.318684)
		(end 164.079936 -47.018956)
		(width 0.1397)
		(layer "In2.Cu")
		(net "PCIE_TX_P78")
	)
	(segment
		(start 132.01777 -39.452042)
		(end 119.842534 -36.127182)
		(width 0.1397)
		(layer "In2.Cu")
		(net "PCIE_TX_P78")
	)
	(segment
		(start 141.996668 -40.645842)
		(end 134.197852 -38.988492)
		(width 0.1397)
		(layer "In2.Cu")
		(net "PCIE_TX_P78")
	)
	(segment
		(start 102.2096 -39.19601)
		(end 101.9302 -38.91661)
		(width 0.1397)
		(layer "In2.Cu")
		(net "PCIE_TX_P78")
	)
	(segment
		(start 119.842534 -36.127182)
		(end 105.406952 -39.19601)
		(width 0.1397)
		(layer "In2.Cu")
		(net "PCIE_TX_P78")
	)
	(segment
		(start 134.197852 -38.988492)
		(end 132.01777 -39.452042)
		(width 0.1397)
		(layer "In2.Cu")
		(net "PCIE_TX_P78")
	)
	(segment
		(start 164.079936 -47.018956)
		(end 145.880074 -43.1673)
		(width 0.1397)
		(layer "In2.Cu")
		(net "PCIE_TX_P78")
	)
	(segment
		(start 194.022218 -45.98416)
		(end 181.485032 -43.318684)
		(width 0.1397)
		(layer "In2.Cu")
		(net "PCIE_TX_P78")
	)
	(arc
		(start 197.816978 -45.59046)
		(mid 197.701666 -45.868848)
		(end 197.423278 -45.98416)
		(width 0.1397)
		(layer "In2.Cu")
		(net "PCIE_TX_P78")
	)
	(segment
		(start 20.552664 -78.362048)
		(end 19.309334 -80.276192)
		(width 0.1397)
		(layer "In5.Cu")
		(net "PCIE_TX_P78")
	)
	(segment
		(start 98.00971 -47.566072)
		(end 94.769432 -52.555648)
		(width 0.1397)
		(layer "In5.Cu")
		(net "PCIE_TX_P78")
	)
	(segment
		(start 60.346336 -54.90718)
		(end 55.96255 -55.838852)
		(width 0.1397)
		(layer "In5.Cu")
		(net "PCIE_TX_P78")
	)
	(segment
		(start 99.854258 -39.316914)
		(end 99.16414 -39.764716)
		(width 0.1397)
		(layer "In5.Cu")
		(net "PCIE_TX_P78")
	)
	(segment
		(start 19.309334 -80.276192)
		(end 19.093942 -81.289144)
		(width 0.1397)
		(layer "In5.Cu")
		(net "PCIE_TX_P78")
	)
	(segment
		(start 98.359722 -42.551604)
		(end 98.717608 -44.235116)
		(width 0.1397)
		(layer "In5.Cu")
		(net "PCIE_TX_P78")
	)
	(segment
		(start 91.584018 -54.62397)
		(end 78.452726 -57.41543)
		(width 0.1397)
		(layer "In5.Cu")
		(net "PCIE_TX_P78")
	)
	(segment
		(start 22.872446 -76.221844)
		(end 22.16023 -77.318362)
		(width 0.1397)
		(layer "In5.Cu")
		(net "PCIE_TX_P78")
	)
	(segment
		(start 100.423218 -39.19601)
		(end 99.854258 -39.316914)
		(width 0.1397)
		(layer "In5.Cu")
		(net "PCIE_TX_P78")
	)
	(segment
		(start 101.9302 -38.91661)
		(end 101.6508 -39.19601)
		(width 0.1397)
		(layer "In5.Cu")
		(net "PCIE_TX_P78")
	)
	(segment
		(start 78.452726 -57.41543)
		(end 71.976488 -56.03875)
		(width 0.1397)
		(layer "In5.Cu")
		(net "PCIE_TX_P78")
	)
	(segment
		(start 27.527504 -60.185808)
		(end 23.111714 -66.985388)
		(width 0.1397)
		(layer "In5.Cu")
		(net "PCIE_TX_P78")
	)
	(segment
		(start 48.164242 -54.183026)
		(end 31.225998 -57.78373)
		(width 0.1397)
		(layer "In5.Cu")
		(net "PCIE_TX_P78")
	)
	(segment
		(start 23.621238 -72.698864)
		(end 22.872446 -76.221844)
		(width 0.1397)
		(layer "In5.Cu")
		(net "PCIE_TX_P78")
	)
	(segment
		(start 22.758908 -68.642738)
		(end 23.621238 -72.698864)
		(width 0.1397)
		(layer "In5.Cu")
		(net "PCIE_TX_P78")
	)
	(segment
		(start 23.111714 -66.985388)
		(end 22.758908 -68.642738)
		(width 0.1397)
		(layer "In5.Cu")
		(net "PCIE_TX_P78")
	)
	(segment
		(start 55.96255 -55.838852)
		(end 48.164242 -54.183026)
		(width 0.1397)
		(layer "In5.Cu")
		(net "PCIE_TX_P78")
	)
	(segment
		(start 31.225998 -57.78373)
		(end 27.527504 -60.185808)
		(width 0.1397)
		(layer "In5.Cu")
		(net "PCIE_TX_P78")
	)
	(segment
		(start 98.84918 -40.249856)
		(end 98.359722 -42.551604)
		(width 0.1397)
		(layer "In5.Cu")
		(net "PCIE_TX_P78")
	)
	(segment
		(start 19.093942 -81.665572)
		(end 18.852134 -81.90738)
		(width 0.1397)
		(layer "In5.Cu")
		(net "PCIE_TX_P78")
	)
	(segment
		(start 22.16023 -77.318362)
		(end 20.552664 -78.362048)
		(width 0.1397)
		(layer "In5.Cu")
		(net "PCIE_TX_P78")
	)
	(segment
		(start 94.769432 -52.555648)
		(end 91.584018 -54.62397)
		(width 0.1397)
		(layer "In5.Cu")
		(net "PCIE_TX_P78")
	)
	(segment
		(start 98.717608 -44.235116)
		(end 98.00971 -47.566072)
		(width 0.1397)
		(layer "In5.Cu")
		(net "PCIE_TX_P78")
	)
	(segment
		(start 19.093942 -81.289144)
		(end 19.093942 -81.665572)
		(width 0.1397)
		(layer "In5.Cu")
		(net "PCIE_TX_P78")
	)
	(segment
		(start 71.976488 -56.03875)
		(end 68.822316 -56.708802)
		(width 0.1397)
		(layer "In5.Cu")
		(net "PCIE_TX_P78")
	)
	(segment
		(start 68.822316 -56.708802)
		(end 60.346336 -54.90718)
		(width 0.1397)
		(layer "In5.Cu")
		(net "PCIE_TX_P78")
	)
	(segment
		(start 99.16414 -39.764716)
		(end 98.84918 -40.249856)
		(width 0.1397)
		(layer "In5.Cu")
		(net "PCIE_TX_P78")
	)
	(segment
		(start 101.6508 -39.19601)
		(end 100.423218 -39.19601)
		(width 0.1397)
		(layer "In5.Cu")
		(net "PCIE_TX_P78")
	)
	(segment
		(start 198.976234 -46.297088)
		(end 199.852026 -45.420534)
		(width 0.136652)
		(layer "F.Cu")
		(net "PCIE_TX_N78")
	)
	(segment
		(start 200.035414 -44.559474)
		(end 201.151744 -42.841418)
		(width 0.136652)
		(layer "F.Cu")
		(net "PCIE_TX_N78")
	)
	(segment
		(start 211.86394 -40.78351)
		(end 212.149944 -41.069514)
		(width 0.136652)
		(layer "F.Cu")
		(net "PCIE_TX_N78")
	)
	(segment
		(start 199.852026 -45.420534)
		(end 200.035414 -44.559474)
		(width 0.136652)
		(layer "F.Cu")
		(net "PCIE_TX_N78")
	)
	(segment
		(start 203.818744 -41.008808)
		(end 205.767686 -40.59428)
		(width 0.136652)
		(layer "F.Cu")
		(net "PCIE_TX_N78")
	)
	(segment
		(start 18.911062 -80.869028)
		(end 19.382994 -81.34096)
		(width 0.136652)
		(layer "F.Cu")
		(net "PCIE_TX_N78")
	)
	(segment
		(start 18.911062 -80.090518)
		(end 18.911062 -80.869028)
		(width 0.136652)
		(layer "F.Cu")
		(net "PCIE_TX_N78")
	)
	(segment
		(start 201.44105 -42.552112)
		(end 203.818744 -41.008808)
		(width 0.136652)
		(layer "F.Cu")
		(net "PCIE_TX_N78")
	)
	(segment
		(start 19.382994 -81.62544)
		(end 19.664934 -81.90738)
		(width 0.136652)
		(layer "F.Cu")
		(net "PCIE_TX_N78")
	)
	(segment
		(start 198.275956 -46.297088)
		(end 198.976234 -46.297088)
		(width 0.136652)
		(layer "F.Cu")
		(net "PCIE_TX_N78")
	)
	(segment
		(start 206.46771 -40.78351)
		(end 211.86394 -40.78351)
		(width 0.136652)
		(layer "F.Cu")
		(net "PCIE_TX_N78")
	)
	(segment
		(start 19.382994 -81.34096)
		(end 19.382994 -81.62544)
		(width 0.136652)
		(layer "F.Cu")
		(net "PCIE_TX_N78")
	)
	(segment
		(start 205.767686 -40.59428)
		(end 206.46771 -40.78351)
		(width 0.136652)
		(layer "F.Cu")
		(net "PCIE_TX_N78")
	)
	(via
		(at 197.816978 -46.70806)
		(size 0.508)
		(drill 0.254)
		(layers "F.Cu" "B.Cu")
		(net "PCIE_TX_N78")
	)
	(via
		(at 101.9302 -39.80561)
		(size 0.508)
		(drill 0.254)
		(layers "F.Cu" "B.Cu")
		(net "PCIE_TX_N78")
	)
	(via
		(at 19.664934 -81.90738)
		(size 0.508)
		(drill 0.254)
		(layers "F.Cu" "B.Cu")
		(net "PCIE_TX_N78")
	)
	(arc
		(start 201.151744 -42.841418)
		(mid 201.281183 -42.681551)
		(end 201.44105 -42.552112)
		(width 0.136652)
		(layer "F.Cu")
		(net "PCIE_TX_N78")
	)
	(arc
		(start 197.816978 -46.70806)
		(mid 197.967911 -46.41484)
		(end 198.275956 -46.297088)
		(width 0.136652)
		(layer "F.Cu")
		(net "PCIE_TX_N78")
	)
	(segment
		(start 187.836556 -45.006768)
		(end 187.973462 -45.217588)
		(width 0.1397)
		(layer "In2.Cu")
		(net "PCIE_TX_N78")
	)
	(segment
		(start 190.172086 -45.503338)
		(end 190.308992 -45.714158)
		(width 0.1397)
		(layer "In2.Cu")
		(net "PCIE_TX_N78")
	)
	(segment
		(start 181.485032 -43.656504)
		(end 186.668918 -44.75861)
		(width 0.1397)
		(layer "In2.Cu")
		(net "PCIE_TX_N78")
	)
	(segment
		(start 190.929768 -45.664374)
		(end 193.98742 -46.31436)
		(width 0.1397)
		(layer "In2.Cu")
		(net "PCIE_TX_N78")
	)
	(segment
		(start 188.594238 -45.167804)
		(end 189.004194 -45.254926)
		(width 0.1397)
		(layer "In2.Cu")
		(net "PCIE_TX_N78")
	)
	(segment
		(start 189.76213 -45.416216)
		(end 190.172086 -45.503338)
		(width 0.1397)
		(layer "In2.Cu")
		(net "PCIE_TX_N78")
	)
	(segment
		(start 186.805824 -44.96943)
		(end 187.21578 -45.056552)
		(width 0.1397)
		(layer "In2.Cu")
		(net "PCIE_TX_N78")
	)
	(segment
		(start 132.008118 -39.791894)
		(end 134.197852 -39.326312)
		(width 0.1397)
		(layer "In2.Cu")
		(net "PCIE_TX_N78")
	)
	(segment
		(start 190.718948 -45.80128)
		(end 190.929768 -45.664374)
		(width 0.1397)
		(layer "In2.Cu")
		(net "PCIE_TX_N78")
	)
	(segment
		(start 105.44175 -39.52621)
		(end 119.832882 -36.467034)
		(width 0.1397)
		(layer "In2.Cu")
		(net "PCIE_TX_N78")
	)
	(segment
		(start 145.75155 -43.477942)
		(end 164.08019 -47.356776)
		(width 0.1397)
		(layer "In2.Cu")
		(net "PCIE_TX_N78")
	)
	(segment
		(start 102.2096 -39.52621)
		(end 105.44175 -39.52621)
		(width 0.1397)
		(layer "In2.Cu")
		(net "PCIE_TX_N78")
	)
	(segment
		(start 164.08019 -47.356776)
		(end 181.485032 -43.656504)
		(width 0.1397)
		(layer "In2.Cu")
		(net "PCIE_TX_N78")
	)
	(segment
		(start 189.551056 -45.553122)
		(end 189.76213 -45.416216)
		(width 0.1397)
		(layer "In2.Cu")
		(net "PCIE_TX_N78")
	)
	(segment
		(start 187.973462 -45.217588)
		(end 188.383418 -45.30471)
		(width 0.1397)
		(layer "In2.Cu")
		(net "PCIE_TX_N78")
	)
	(segment
		(start 119.832882 -36.467034)
		(end 132.008118 -39.791894)
		(width 0.1397)
		(layer "In2.Cu")
		(net "PCIE_TX_N78")
	)
	(segment
		(start 188.383418 -45.30471)
		(end 188.594238 -45.167804)
		(width 0.1397)
		(layer "In2.Cu")
		(net "PCIE_TX_N78")
	)
	(segment
		(start 186.668918 -44.75861)
		(end 186.805824 -44.96943)
		(width 0.1397)
		(layer "In2.Cu")
		(net "PCIE_TX_N78")
	)
	(segment
		(start 187.21578 -45.056552)
		(end 187.4266 -44.919646)
		(width 0.1397)
		(layer "In2.Cu")
		(net "PCIE_TX_N78")
	)
	(segment
		(start 189.1411 -45.466)
		(end 189.551056 -45.553122)
		(width 0.1397)
		(layer "In2.Cu")
		(net "PCIE_TX_N78")
	)
	(segment
		(start 187.4266 -44.919646)
		(end 187.836556 -45.006768)
		(width 0.1397)
		(layer "In2.Cu")
		(net "PCIE_TX_N78")
	)
	(segment
		(start 134.197852 -39.326312)
		(end 141.868144 -40.95623)
		(width 0.1397)
		(layer "In2.Cu")
		(net "PCIE_TX_N78")
	)
	(segment
		(start 190.308992 -45.714158)
		(end 190.718948 -45.80128)
		(width 0.1397)
		(layer "In2.Cu")
		(net "PCIE_TX_N78")
	)
	(segment
		(start 141.868144 -40.95623)
		(end 145.75155 -43.477942)
		(width 0.1397)
		(layer "In2.Cu")
		(net "PCIE_TX_N78")
	)
	(segment
		(start 101.9302 -39.80561)
		(end 102.2096 -39.52621)
		(width 0.1397)
		(layer "In2.Cu")
		(net "PCIE_TX_N78")
	)
	(segment
		(start 193.98742 -46.31436)
		(end 197.423278 -46.31436)
		(width 0.1397)
		(layer "In2.Cu")
		(net "PCIE_TX_N78")
	)
	(segment
		(start 189.004194 -45.254926)
		(end 189.1411 -45.466)
		(width 0.1397)
		(layer "In2.Cu")
		(net "PCIE_TX_N78")
	)
	(arc
		(start 197.423278 -46.31436)
		(mid 197.701666 -46.429672)
		(end 197.816978 -46.70806)
		(width 0.1397)
		(layer "In2.Cu")
		(net "PCIE_TX_N78")
	)
	(segment
		(start 78.452726 -57.75325)
		(end 71.976488 -56.37657)
		(width 0.1397)
		(layer "In5.Cu")
		(net "PCIE_TX_N78")
	)
	(segment
		(start 23.182834 -76.350368)
		(end 22.39899 -77.557122)
		(width 0.1397)
		(layer "In5.Cu")
		(net "PCIE_TX_N78")
	)
	(segment
		(start 27.766264 -60.424568)
		(end 23.422102 -67.114166)
		(width 0.1397)
		(layer "In5.Cu")
		(net "PCIE_TX_N78")
	)
	(segment
		(start 98.697542 -42.551604)
		(end 99.055428 -44.235116)
		(width 0.1397)
		(layer "In5.Cu")
		(net "PCIE_TX_N78")
	)
	(segment
		(start 60.346336 -55.245)
		(end 55.96255 -56.176672)
		(width 0.1397)
		(layer "In5.Cu")
		(net "PCIE_TX_N78")
	)
	(segment
		(start 23.959058 -72.698864)
		(end 23.182834 -76.350368)
		(width 0.1397)
		(layer "In5.Cu")
		(net "PCIE_TX_N78")
	)
	(segment
		(start 19.424142 -81.666588)
		(end 19.664934 -81.90738)
		(width 0.1397)
		(layer "In5.Cu")
		(net "PCIE_TX_N78")
	)
	(segment
		(start 71.976488 -56.37657)
		(end 68.822316 -57.046622)
		(width 0.1397)
		(layer "In5.Cu")
		(net "PCIE_TX_N78")
	)
	(segment
		(start 23.096728 -68.642738)
		(end 23.959058 -72.698864)
		(width 0.1397)
		(layer "In5.Cu")
		(net "PCIE_TX_N78")
	)
	(segment
		(start 99.159568 -40.37838)
		(end 98.697542 -42.551604)
		(width 0.1397)
		(layer "In5.Cu")
		(net "PCIE_TX_N78")
	)
	(segment
		(start 20.791424 -78.600808)
		(end 19.619722 -80.40497)
		(width 0.1397)
		(layer "In5.Cu")
		(net "PCIE_TX_N78")
	)
	(segment
		(start 31.354522 -58.094118)
		(end 27.766264 -60.424568)
		(width 0.1397)
		(layer "In5.Cu")
		(net "PCIE_TX_N78")
	)
	(segment
		(start 55.894224 -56.162194)
		(end 55.894224 -56.16194)
		(width 0.1397)
		(layer "In5.Cu")
		(net "PCIE_TX_N78")
	)
	(segment
		(start 100.458016 -39.52621)
		(end 99.982782 -39.627302)
		(width 0.1397)
		(layer "In5.Cu")
		(net "PCIE_TX_N78")
	)
	(segment
		(start 55.96255 -56.176672)
		(end 55.894224 -56.162194)
		(width 0.1397)
		(layer "In5.Cu")
		(net "PCIE_TX_N78")
	)
	(segment
		(start 23.422102 -67.114166)
		(end 23.096728 -68.642738)
		(width 0.1397)
		(layer "In5.Cu")
		(net "PCIE_TX_N78")
	)
	(segment
		(start 99.982782 -39.627302)
		(end 99.4029 -40.00373)
		(width 0.1397)
		(layer "In5.Cu")
		(net "PCIE_TX_N78")
	)
	(segment
		(start 22.39899 -77.557122)
		(end 20.791424 -78.600808)
		(width 0.1397)
		(layer "In5.Cu")
		(net "PCIE_TX_N78")
	)
	(segment
		(start 101.9302 -39.80561)
		(end 101.6508 -39.52621)
		(width 0.1397)
		(layer "In5.Cu")
		(net "PCIE_TX_N78")
	)
	(segment
		(start 99.055428 -44.235116)
		(end 98.320098 -47.694596)
		(width 0.1397)
		(layer "In5.Cu")
		(net "PCIE_TX_N78")
	)
	(segment
		(start 68.822316 -57.046622)
		(end 60.346336 -55.245)
		(width 0.1397)
		(layer "In5.Cu")
		(net "PCIE_TX_N78")
	)
	(segment
		(start 19.424142 -81.323942)
		(end 19.424142 -81.666588)
		(width 0.1397)
		(layer "In5.Cu")
		(net "PCIE_TX_N78")
	)
	(segment
		(start 101.6508 -39.52621)
		(end 100.458016 -39.52621)
		(width 0.1397)
		(layer "In5.Cu")
		(net "PCIE_TX_N78")
	)
	(segment
		(start 91.712542 -54.934358)
		(end 78.452726 -57.75325)
		(width 0.1397)
		(layer "In5.Cu")
		(net "PCIE_TX_N78")
	)
	(segment
		(start 55.894224 -56.16194)
		(end 48.164242 -54.520846)
		(width 0.1397)
		(layer "In5.Cu")
		(net "PCIE_TX_N78")
	)
	(segment
		(start 19.619722 -80.40497)
		(end 19.424142 -81.323942)
		(width 0.1397)
		(layer "In5.Cu")
		(net "PCIE_TX_N78")
	)
	(segment
		(start 99.4029 -40.00373)
		(end 99.159568 -40.37838)
		(width 0.1397)
		(layer "In5.Cu")
		(net "PCIE_TX_N78")
	)
	(segment
		(start 48.164242 -54.520846)
		(end 31.354522 -58.094118)
		(width 0.1397)
		(layer "In5.Cu")
		(net "PCIE_TX_N78")
	)
	(segment
		(start 95.008192 -52.794408)
		(end 91.712542 -54.934358)
		(width 0.1397)
		(layer "In5.Cu")
		(net "PCIE_TX_N78")
	)
	(segment
		(start 98.320098 -47.694596)
		(end 95.008192 -52.794408)
		(width 0.1397)
		(layer "In5.Cu")
		(net "PCIE_TX_N78")
	)
	(segment
		(start 224.381568 -43.999912)
		(end 224.600008 -43.999912)
		(width 0.1016)
		(layer "F.Cu")
		(net "PCIE_TX_CAP_P78")
	)
	(segment
		(start 219.495116 -40.891968)
		(end 221.461838 -42.85869)
		(width 0.136652)
		(layer "F.Cu")
		(net "PCIE_TX_CAP_P78")
	)
	(segment
		(start 213.038944 -40.19296)
		(end 213.324694 -40.47871)
		(width 0.136652)
		(layer "F.Cu")
		(net "PCIE_TX_CAP_P78")
	)
	(segment
		(start 213.324694 -40.47871)
		(end 218.49715 -40.47871)
		(width 0.136652)
		(layer "F.Cu")
		(net "PCIE_TX_CAP_P78")
	)
	(segment
		(start 221.479618 -42.87647)
		(end 221.479618 -42.948606)
		(width 0.1016)
		(layer "F.Cu")
		(net "PCIE_TX_CAP_P78")
	)
	(segment
		(start 224.201482 -43.819572)
		(end 224.201482 -43.819826)
		(width 0.1016)
		(layer "F.Cu")
		(net "PCIE_TX_CAP_P78")
	)
	(segment
		(start 221.914212 -43.3832)
		(end 223.76511 -43.3832)
		(width 0.1016)
		(layer "F.Cu")
		(net "PCIE_TX_CAP_P78")
	)
	(segment
		(start 221.479618 -42.948606)
		(end 221.914212 -43.3832)
		(width 0.1016)
		(layer "F.Cu")
		(net "PCIE_TX_CAP_P78")
	)
	(segment
		(start 221.461838 -42.85869)
		(end 221.479618 -42.87647)
		(width 0.1016)
		(layer "F.Cu")
		(net "PCIE_TX_CAP_P78")
	)
	(arc
		(start 224.201482 -43.819826)
		(mid 224.254228 -43.947166)
		(end 224.381568 -43.999912)
		(width 0.1016)
		(layer "F.Cu")
		(net "PCIE_TX_CAP_P78")
	)
	(arc
		(start 218.49715 -40.47871)
		(mid 219.037256 -40.58605)
		(end 219.495116 -40.891968)
		(width 0.136652)
		(layer "F.Cu")
		(net "PCIE_TX_CAP_P78")
	)
	(arc
		(start 223.76511 -43.3832)
		(mid 224.073672 -43.51101)
		(end 224.201482 -43.819572)
		(width 0.1016)
		(layer "F.Cu")
		(net "PCIE_TX_CAP_P78")
	)
	(segment
		(start 221.246192 -43.074336)
		(end 221.263972 -43.092116)
		(width 0.1016)
		(layer "F.Cu")
		(net "PCIE_TX_CAP_N78")
	)
	(segment
		(start 215.562942 -40.78351)
		(end 215.71839 -40.938958)
		(width 0.136652)
		(layer "F.Cu")
		(net "PCIE_TX_CAP_N78")
	)
	(segment
		(start 213.324948 -40.78351)
		(end 214.432134 -40.78351)
		(width 0.136652)
		(layer "F.Cu")
		(net "PCIE_TX_CAP_N78")
	)
	(segment
		(start 221.263972 -43.092116)
		(end 221.3356 -43.092116)
		(width 0.1016)
		(layer "F.Cu")
		(net "PCIE_TX_CAP_N78")
	)
	(segment
		(start 215.71839 -40.938958)
		(end 216.128346 -40.938958)
		(width 0.136652)
		(layer "F.Cu")
		(net "PCIE_TX_CAP_N78")
	)
	(segment
		(start 223.998282 -43.819572)
		(end 223.998282 -43.819826)
		(width 0.1016)
		(layer "F.Cu")
		(net "PCIE_TX_CAP_N78")
	)
	(segment
		(start 221.829884 -43.5864)
		(end 223.76511 -43.5864)
		(width 0.1016)
		(layer "F.Cu")
		(net "PCIE_TX_CAP_N78")
	)
	(segment
		(start 221.3356 -43.092116)
		(end 221.829884 -43.5864)
		(width 0.1016)
		(layer "F.Cu")
		(net "PCIE_TX_CAP_N78")
	)
	(segment
		(start 214.587582 -40.938958)
		(end 214.997538 -40.938958)
		(width 0.136652)
		(layer "F.Cu")
		(net "PCIE_TX_CAP_N78")
	)
	(segment
		(start 216.128346 -40.938958)
		(end 216.283794 -40.78351)
		(width 0.136652)
		(layer "F.Cu")
		(net "PCIE_TX_CAP_N78")
	)
	(segment
		(start 214.997538 -40.938958)
		(end 215.152986 -40.78351)
		(width 0.136652)
		(layer "F.Cu")
		(net "PCIE_TX_CAP_N78")
	)
	(segment
		(start 216.849198 -40.938958)
		(end 217.259154 -40.938958)
		(width 0.136652)
		(layer "F.Cu")
		(net "PCIE_TX_CAP_N78")
	)
	(segment
		(start 217.414602 -40.78351)
		(end 218.49715 -40.78351)
		(width 0.136652)
		(layer "F.Cu")
		(net "PCIE_TX_CAP_N78")
	)
	(segment
		(start 214.432134 -40.78351)
		(end 214.587582 -40.938958)
		(width 0.136652)
		(layer "F.Cu")
		(net "PCIE_TX_CAP_N78")
	)
	(segment
		(start 219.27947 -41.107614)
		(end 221.246192 -43.074336)
		(width 0.136652)
		(layer "F.Cu")
		(net "PCIE_TX_CAP_N78")
	)
	(segment
		(start 215.152986 -40.78351)
		(end 215.562942 -40.78351)
		(width 0.136652)
		(layer "F.Cu")
		(net "PCIE_TX_CAP_N78")
	)
	(segment
		(start 223.818196 -43.999912)
		(end 223.60001 -43.999912)
		(width 0.1016)
		(layer "F.Cu")
		(net "PCIE_TX_CAP_N78")
	)
	(segment
		(start 216.283794 -40.78351)
		(end 216.69375 -40.78351)
		(width 0.136652)
		(layer "F.Cu")
		(net "PCIE_TX_CAP_N78")
	)
	(segment
		(start 213.038944 -41.069514)
		(end 213.324948 -40.78351)
		(width 0.136652)
		(layer "F.Cu")
		(net "PCIE_TX_CAP_N78")
	)
	(segment
		(start 216.69375 -40.78351)
		(end 216.849198 -40.938958)
		(width 0.136652)
		(layer "F.Cu")
		(net "PCIE_TX_CAP_N78")
	)
	(segment
		(start 217.259154 -40.938958)
		(end 217.414602 -40.78351)
		(width 0.136652)
		(layer "F.Cu")
		(net "PCIE_TX_CAP_N78")
	)
	(arc
		(start 218.49715 -40.78351)
		(mid 218.920546 -40.867747)
		(end 219.27947 -41.107614)
		(width 0.136652)
		(layer "F.Cu")
		(net "PCIE_TX_CAP_N78")
	)
	(arc
		(start 223.998282 -43.819826)
		(mid 223.945536 -43.947166)
		(end 223.818196 -43.999912)
		(width 0.1016)
		(layer "F.Cu")
		(net "PCIE_TX_CAP_N78")
	)
	(arc
		(start 223.76511 -43.5864)
		(mid 223.929988 -43.654694)
		(end 223.998282 -43.819572)
		(width 0.1016)
		(layer "F.Cu")
		(net "PCIE_TX_CAP_N78")
	)
	(segment
		(start 226.0092 -44.213272)
		(end 226.0092 -43.677586)
		(width 0.1016)
		(layer "F.Cu")
		(net "PCIE_RX_P78")
	)
	(segment
		(start 206.84109 -42.102532)
		(end 217.240358 -44.346368)
		(width 0.136652)
		(layer "F.Cu")
		(net "PCIE_RX_P78")
	)
	(segment
		(start 201.76744 -45.146722)
		(end 202.434444 -45.146722)
		(width 0.136652)
		(layer "F.Cu")
		(net "PCIE_RX_P78")
	)
	(segment
		(start 227.277676 -43.898058)
		(end 227.37953 -43.999912)
		(width 0.1016)
		(layer "F.Cu")
		(net "PCIE_RX_P78")
	)
	(segment
		(start 20.644358 -86.995)
		(end 20.644358 -86.08695)
		(width 0.136652)
		(layer "F.Cu")
		(net "PCIE_RX_P78")
	)
	(segment
		(start 20.9296 -85.801708)
		(end 20.9296 -84.5439)
		(width 0.136652)
		(layer "F.Cu")
		(net "PCIE_RX_P78")
	)
	(segment
		(start 226.280472 -43.406314)
		(end 227.057204 -43.406314)
		(width 0.1016)
		(layer "F.Cu")
		(net "PCIE_RX_P78")
	)
	(segment
		(start 226.0092 -43.677586)
		(end 226.280472 -43.406314)
		(width 0.1016)
		(layer "F.Cu")
		(net "PCIE_RX_P78")
	)
	(segment
		(start 227.37953 -43.999912)
		(end 227.600002 -43.999912)
		(width 0.1016)
		(layer "F.Cu")
		(net "PCIE_RX_P78")
	)
	(segment
		(start 227.277676 -43.626786)
		(end 227.277676 -43.898058)
		(width 0.1016)
		(layer "F.Cu")
		(net "PCIE_RX_P78")
	)
	(segment
		(start 203.647548 -42.937176)
		(end 204.004418 -42.705782)
		(width 0.136652)
		(layer "F.Cu")
		(net "PCIE_RX_P78")
	)
	(segment
		(start 204.004418 -42.705782)
		(end 206.84109 -42.102532)
		(width 0.136652)
		(layer "F.Cu")
		(net "PCIE_RX_P78")
	)
	(segment
		(start 20.9296 -84.5439)
		(end 20.6502 -84.2645)
		(width 0.136652)
		(layer "F.Cu")
		(net "PCIE_RX_P78")
	)
	(segment
		(start 203.230734 -43.579288)
		(end 203.647548 -42.937176)
		(width 0.136652)
		(layer "F.Cu")
		(net "PCIE_RX_P78")
	)
	(segment
		(start 227.057204 -43.406314)
		(end 227.277676 -43.626786)
		(width 0.1016)
		(layer "F.Cu")
		(net "PCIE_RX_P78")
	)
	(segment
		(start 202.434444 -45.146722)
		(end 202.767692 -44.930568)
		(width 0.136652)
		(layer "F.Cu")
		(net "PCIE_RX_P78")
	)
	(segment
		(start 217.240358 -44.346368)
		(end 221.3102 -44.346368)
		(width 0.136652)
		(layer "F.Cu")
		(net "PCIE_RX_P78")
	)
	(segment
		(start 221.361 -44.397168)
		(end 225.825304 -44.397168)
		(width 0.1016)
		(layer "F.Cu")
		(net "PCIE_RX_P78")
	)
	(segment
		(start 221.3102 -44.346368)
		(end 221.361 -44.397168)
		(width 0.1016)
		(layer "F.Cu")
		(net "PCIE_RX_P78")
	)
	(segment
		(start 202.964542 -44.6278)
		(end 203.230734 -43.579288)
		(width 0.136652)
		(layer "F.Cu")
		(net "PCIE_RX_P78")
	)
	(segment
		(start 225.825304 -44.397168)
		(end 226.0092 -44.213272)
		(width 0.1016)
		(layer "F.Cu")
		(net "PCIE_RX_P78")
	)
	(segment
		(start 20.644358 -86.08695)
		(end 20.9296 -85.801708)
		(width 0.136652)
		(layer "F.Cu")
		(net "PCIE_RX_P78")
	)
	(segment
		(start 202.767692 -44.930568)
		(end 202.964542 -44.6278)
		(width 0.136652)
		(layer "F.Cu")
		(net "PCIE_RX_P78")
	)
	(via
		(at 102.5144 -36.205668)
		(size 0.508)
		(drill 0.254)
		(layers "F.Cu" "B.Cu")
		(net "PCIE_RX_P78")
	)
	(via
		(at 201.36104 -44.714922)
		(size 0.508)
		(drill 0.254)
		(layers "F.Cu" "B.Cu")
		(net "PCIE_RX_P78")
	)
	(via
		(at 20.3962 -87.4268)
		(size 0.508)
		(drill 0.254)
		(layers "F.Cu" "B.Cu")
		(net "PCIE_RX_P78")
	)
	(arc
		(start 20.3962 -87.4268)
		(mid 20.577857 -87.244)
		(end 20.644358 -86.995)
		(width 0.136652)
		(layer "F.Cu")
		(net "PCIE_RX_P78")
	)
	(arc
		(start 201.36104 -44.714922)
		(mid 201.470961 -45.018609)
		(end 201.76744 -45.146722)
		(width 0.136652)
		(layer "F.Cu")
		(net "PCIE_RX_P78")
	)
	(segment
		(start 133.854444 -36.963858)
		(end 131.187444 -37.530532)
		(width 0.1397)
		(layer "In2.Cu")
		(net "PCIE_RX_P78")
	)
	(segment
		(start 200.306686 -45.108622)
		(end 198.94423 -44.224194)
		(width 0.1397)
		(layer "In2.Cu")
		(net "PCIE_RX_P78")
	)
	(segment
		(start 164.585142 -45.339508)
		(end 146.633692 -41.54043)
		(width 0.1397)
		(layer "In2.Cu")
		(net "PCIE_RX_P78")
	)
	(segment
		(start 146.633692 -41.54043)
		(end 139.58697 -36.963858)
		(width 0.1397)
		(layer "In2.Cu")
		(net "PCIE_RX_P78")
	)
	(segment
		(start 195.62318 -44.317158)
		(end 182.344314 -41.566338)
		(width 0.1397)
		(layer "In2.Cu")
		(net "PCIE_RX_P78")
	)
	(segment
		(start 131.187444 -37.530532)
		(end 118.405402 -33.980882)
		(width 0.1397)
		(layer "In2.Cu")
		(net "PCIE_RX_P78")
	)
	(segment
		(start 139.58697 -36.963858)
		(end 133.854444 -36.963858)
		(width 0.1397)
		(layer "In2.Cu")
		(net "PCIE_RX_P78")
	)
	(segment
		(start 198.94423 -44.224194)
		(end 197.501764 -43.917616)
		(width 0.1397)
		(layer "In2.Cu")
		(net "PCIE_RX_P78")
	)
	(segment
		(start 118.405402 -33.980882)
		(end 106.633264 -36.485068)
		(width 0.1397)
		(layer "In2.Cu")
		(net "PCIE_RX_P78")
	)
	(segment
		(start 200.96734 -45.108622)
		(end 200.306686 -45.108622)
		(width 0.1397)
		(layer "In2.Cu")
		(net "PCIE_RX_P78")
	)
	(segment
		(start 106.633264 -36.485068)
		(end 102.7938 -36.485068)
		(width 0.1397)
		(layer "In2.Cu")
		(net "PCIE_RX_P78")
	)
	(segment
		(start 182.344314 -41.566338)
		(end 164.585142 -45.339508)
		(width 0.1397)
		(layer "In2.Cu")
		(net "PCIE_RX_P78")
	)
	(segment
		(start 102.7938 -36.485068)
		(end 102.5144 -36.205668)
		(width 0.1397)
		(layer "In2.Cu")
		(net "PCIE_RX_P78")
	)
	(segment
		(start 197.501764 -43.917616)
		(end 195.62318 -44.317158)
		(width 0.1397)
		(layer "In2.Cu")
		(net "PCIE_RX_P78")
	)
	(arc
		(start 201.36104 -44.714922)
		(mid 201.245728 -44.99331)
		(end 200.96734 -45.108622)
		(width 0.1397)
		(layer "In2.Cu")
		(net "PCIE_RX_P78")
	)
	(segment
		(start 21.756878 -72.063102)
		(end 20.9169 -68.110354)
		(width 0.1397)
		(layer "In5.Cu")
		(net "PCIE_RX_P78")
	)
	(segment
		(start 79.463138 -55.467504)
		(end 85.378798 -54.20995)
		(width 0.1397)
		(layer "In5.Cu")
		(net "PCIE_RX_P78")
	)
	(segment
		(start 17.672812 -83.237578)
		(end 17.50314 -82.97672)
		(width 0.1397)
		(layer "In5.Cu")
		(net "PCIE_RX_P78")
	)
	(segment
		(start 102.235 -36.485068)
		(end 102.5144 -36.205668)
		(width 0.1397)
		(layer "In5.Cu")
		(net "PCIE_RX_P78")
	)
	(segment
		(start 71.921624 -54.43601)
		(end 75.377802 -55.170578)
		(width 0.1397)
		(layer "In5.Cu")
		(net "PCIE_RX_P78")
	)
	(segment
		(start 20.3962 -87.4268)
		(end 20.565618 -87.257382)
		(width 0.1397)
		(layer "In5.Cu")
		(net "PCIE_RX_P78")
	)
	(segment
		(start 17.361154 -82.158332)
		(end 18.35912 -77.42428)
		(width 0.1397)
		(layer "In5.Cu")
		(net "PCIE_RX_P78")
	)
	(segment
		(start 96.463104 -47.172372)
		(end 97.06229 -44.351956)
		(width 0.1397)
		(layer "In5.Cu")
		(net "PCIE_RX_P78")
	)
	(segment
		(start 20.631404 -87.098632)
		(end 20.631404 -85.958934)
		(width 0.1397)
		(layer "In5.Cu")
		(net "PCIE_RX_P78")
	)
	(segment
		(start 56.477662 -50.300382)
		(end 61.479684 -53.549042)
		(width 0.1397)
		(layer "In5.Cu")
		(net "PCIE_RX_P78")
	)
	(segment
		(start 93.74124 -51.363118)
		(end 96.463104 -47.172372)
		(width 0.1397)
		(layer "In5.Cu")
		(net "PCIE_RX_P78")
	)
	(segment
		(start 75.377802 -55.170578)
		(end 76.722478 -54.885082)
		(width 0.1397)
		(layer "In5.Cu")
		(net "PCIE_RX_P78")
	)
	(segment
		(start 28.005786 -57.734708)
		(end 37.06495 -51.85156)
		(width 0.1397)
		(layer "In5.Cu")
		(net "PCIE_RX_P78")
	)
	(segment
		(start 21.10486 -75.132692)
		(end 21.756878 -72.063102)
		(width 0.1397)
		(layer "In5.Cu")
		(net "PCIE_RX_P78")
	)
	(segment
		(start 61.479684 -53.549042)
		(end 68.786502 -55.101998)
		(width 0.1397)
		(layer "In5.Cu")
		(net "PCIE_RX_P78")
	)
	(segment
		(start 85.378798 -54.20995)
		(end 85.378798 -54.209696)
		(width 0.1397)
		(layer "In5.Cu")
		(net "PCIE_RX_P78")
	)
	(segment
		(start 96.683068 -42.568622)
		(end 97.376996 -39.304976)
		(width 0.1397)
		(layer "In5.Cu")
		(net "PCIE_RX_P78")
	)
	(segment
		(start 100.867718 -36.485068)
		(end 102.235 -36.485068)
		(width 0.1397)
		(layer "In5.Cu")
		(net "PCIE_RX_P78")
	)
	(segment
		(start 20.631404 -85.958934)
		(end 20.502626 -85.353144)
		(width 0.1397)
		(layer "In5.Cu")
		(net "PCIE_RX_P78")
	)
	(segment
		(start 68.786502 -55.101998)
		(end 71.921624 -54.43601)
		(width 0.1397)
		(layer "In5.Cu")
		(net "PCIE_RX_P78")
	)
	(segment
		(start 97.376996 -39.304976)
		(end 97.999042 -38.346888)
		(width 0.1397)
		(layer "In5.Cu")
		(net "PCIE_RX_P78")
	)
	(segment
		(start 97.06229 -44.351956)
		(end 96.683068 -42.568622)
		(width 0.1397)
		(layer "In5.Cu")
		(net "PCIE_RX_P78")
	)
	(segment
		(start 76.722478 -54.885082)
		(end 79.463138 -55.467504)
		(width 0.1397)
		(layer "In5.Cu")
		(net "PCIE_RX_P78")
	)
	(segment
		(start 46.96206 -49.747932)
		(end 49.351184 -50.255932)
		(width 0.1397)
		(layer "In5.Cu")
		(net "PCIE_RX_P78")
	)
	(segment
		(start 20.189952 -84.87156)
		(end 17.672812 -83.237578)
		(width 0.1397)
		(layer "In5.Cu")
		(net "PCIE_RX_P78")
	)
	(segment
		(start 18.35912 -77.42428)
		(end 18.736056 -76.84389)
		(width 0.1397)
		(layer "In5.Cu")
		(net "PCIE_RX_P78")
	)
	(segment
		(start 52.810156 -49.520602)
		(end 56.477662 -50.300382)
		(width 0.1397)
		(layer "In5.Cu")
		(net "PCIE_RX_P78")
	)
	(segment
		(start 85.378798 -54.209696)
		(end 91.293696 -52.95265)
		(width 0.1397)
		(layer "In5.Cu")
		(net "PCIE_RX_P78")
	)
	(segment
		(start 19.227546 -76.3524)
		(end 21.10486 -75.132692)
		(width 0.1397)
		(layer "In5.Cu")
		(net "PCIE_RX_P78")
	)
	(segment
		(start 20.502626 -85.353144)
		(end 20.189952 -84.87156)
		(width 0.1397)
		(layer "In5.Cu")
		(net "PCIE_RX_P78")
	)
	(segment
		(start 20.9169 -68.110354)
		(end 21.805392 -63.934848)
		(width 0.1397)
		(layer "In5.Cu")
		(net "PCIE_RX_P78")
	)
	(segment
		(start 97.999042 -38.346888)
		(end 100.867718 -36.485068)
		(width 0.1397)
		(layer "In5.Cu")
		(net "PCIE_RX_P78")
	)
	(segment
		(start 18.736056 -76.84389)
		(end 19.227546 -76.3524)
		(width 0.1397)
		(layer "In5.Cu")
		(net "PCIE_RX_P78")
	)
	(segment
		(start 49.351184 -50.255932)
		(end 52.810156 -49.520602)
		(width 0.1397)
		(layer "In5.Cu")
		(net "PCIE_RX_P78")
	)
	(segment
		(start 91.293696 -52.95265)
		(end 93.74124 -51.363118)
		(width 0.1397)
		(layer "In5.Cu")
		(net "PCIE_RX_P78")
	)
	(segment
		(start 17.50314 -82.97672)
		(end 17.361154 -82.158332)
		(width 0.1397)
		(layer "In5.Cu")
		(net "PCIE_RX_P78")
	)
	(segment
		(start 37.06495 -51.85156)
		(end 46.96206 -49.747932)
		(width 0.1397)
		(layer "In5.Cu")
		(net "PCIE_RX_P78")
	)
	(segment
		(start 21.805392 -63.934848)
		(end 28.005786 -57.734708)
		(width 0.1397)
		(layer "In5.Cu")
		(net "PCIE_RX_P78")
	)
	(arc
		(start 20.565618 -87.257382)
		(mid 20.614285 -87.184547)
		(end 20.631404 -87.098632)
		(width 0.1397)
		(layer "In5.Cu")
		(net "PCIE_RX_P78")
	)
	(segment
		(start 221.3102 -44.651168)
		(end 221.361 -44.600368)
		(width 0.1016)
		(layer "F.Cu")
		(net "PCIE_RX_N78")
	)
	(segment
		(start 221.361 -44.600368)
		(end 225.909632 -44.600368)
		(width 0.1016)
		(layer "F.Cu")
		(net "PCIE_RX_N78")
	)
	(segment
		(start 226.3648 -43.609514)
		(end 226.972876 -43.609514)
		(width 0.1016)
		(layer "F.Cu")
		(net "PCIE_RX_N78")
	)
	(segment
		(start 206.840582 -42.414444)
		(end 217.207846 -44.651168)
		(width 0.136652)
		(layer "F.Cu")
		(net "PCIE_RX_N78")
	)
	(segment
		(start 227.074476 -43.711114)
		(end 227.074476 -43.899582)
		(width 0.1016)
		(layer "F.Cu")
		(net "PCIE_RX_N78")
	)
	(segment
		(start 226.2124 -43.761914)
		(end 226.3648 -43.609514)
		(width 0.1016)
		(layer "F.Cu")
		(net "PCIE_RX_N78")
	)
	(segment
		(start 205.918816 -42.769282)
		(end 206.319882 -42.684192)
		(width 0.136652)
		(layer "F.Cu")
		(net "PCIE_RX_N78")
	)
	(segment
		(start 226.972876 -43.609514)
		(end 227.074476 -43.711114)
		(width 0.1016)
		(layer "F.Cu")
		(net "PCIE_RX_N78")
	)
	(segment
		(start 203.513944 -43.70324)
		(end 203.86802 -43.157648)
		(width 0.136652)
		(layer "F.Cu")
		(net "PCIE_RX_N78")
	)
	(segment
		(start 206.319882 -42.684192)
		(end 206.439516 -42.499788)
		(width 0.136652)
		(layer "F.Cu")
		(net "PCIE_RX_N78")
	)
	(segment
		(start 227.074476 -43.899582)
		(end 226.974146 -43.999912)
		(width 0.1016)
		(layer "F.Cu")
		(net "PCIE_RX_N78")
	)
	(segment
		(start 226.2124 -44.2976)
		(end 226.2124 -43.761914)
		(width 0.1016)
		(layer "F.Cu")
		(net "PCIE_RX_N78")
	)
	(segment
		(start 20.949158 -86.995)
		(end 20.949158 -86.213442)
		(width 0.136652)
		(layer "F.Cu")
		(net "PCIE_RX_N78")
	)
	(segment
		(start 206.439516 -42.499788)
		(end 206.840582 -42.414444)
		(width 0.136652)
		(layer "F.Cu")
		(net "PCIE_RX_N78")
	)
	(segment
		(start 201.76744 -45.451522)
		(end 202.524868 -45.451522)
		(width 0.136652)
		(layer "F.Cu")
		(net "PCIE_RX_N78")
	)
	(segment
		(start 202.524868 -45.451522)
		(end 202.98791 -45.15104)
		(width 0.136652)
		(layer "F.Cu")
		(net "PCIE_RX_N78")
	)
	(segment
		(start 203.247752 -44.751752)
		(end 203.513944 -43.70324)
		(width 0.136652)
		(layer "F.Cu")
		(net "PCIE_RX_N78")
	)
	(segment
		(start 226.974146 -43.999912)
		(end 226.600004 -43.999912)
		(width 0.1016)
		(layer "F.Cu")
		(net "PCIE_RX_N78")
	)
	(segment
		(start 21.2344 -84.5439)
		(end 21.5138 -84.2645)
		(width 0.136652)
		(layer "F.Cu")
		(net "PCIE_RX_N78")
	)
	(segment
		(start 205.734412 -42.649648)
		(end 205.918816 -42.769282)
		(width 0.136652)
		(layer "F.Cu")
		(net "PCIE_RX_N78")
	)
	(segment
		(start 217.207846 -44.651168)
		(end 221.3102 -44.651168)
		(width 0.136652)
		(layer "F.Cu")
		(net "PCIE_RX_N78")
	)
	(segment
		(start 20.949158 -86.213442)
		(end 21.2344 -85.9282)
		(width 0.136652)
		(layer "F.Cu")
		(net "PCIE_RX_N78")
	)
	(segment
		(start 203.86802 -43.157648)
		(end 204.122782 -42.992294)
		(width 0.136652)
		(layer "F.Cu")
		(net "PCIE_RX_N78")
	)
	(segment
		(start 225.909632 -44.600368)
		(end 226.2124 -44.2976)
		(width 0.1016)
		(layer "F.Cu")
		(net "PCIE_RX_N78")
	)
	(segment
		(start 21.2344 -85.9282)
		(end 21.2344 -84.5439)
		(width 0.136652)
		(layer "F.Cu")
		(net "PCIE_RX_N78")
	)
	(segment
		(start 204.122782 -42.992294)
		(end 205.734412 -42.649648)
		(width 0.136652)
		(layer "F.Cu")
		(net "PCIE_RX_N78")
	)
	(segment
		(start 202.98791 -45.15104)
		(end 203.247752 -44.751752)
		(width 0.136652)
		(layer "F.Cu")
		(net "PCIE_RX_N78")
	)
	(via
		(at 102.5144 -37.094668)
		(size 0.508)
		(drill 0.254)
		(layers "F.Cu" "B.Cu")
		(net "PCIE_RX_N78")
	)
	(via
		(at 201.36104 -45.832522)
		(size 0.508)
		(drill 0.254)
		(layers "F.Cu" "B.Cu")
		(net "PCIE_RX_N78")
	)
	(via
		(at 21.209 -87.4268)
		(size 0.508)
		(drill 0.254)
		(layers "F.Cu" "B.Cu")
		(net "PCIE_RX_N78")
	)
	(arc
		(start 21.209 -87.4268)
		(mid 21.019126 -87.246977)
		(end 20.949158 -86.995)
		(width 0.136652)
		(layer "F.Cu")
		(net "PCIE_RX_N78")
	)
	(arc
		(start 201.36104 -45.832522)
		(mid 201.48888 -45.561615)
		(end 201.76744 -45.451522)
		(width 0.136652)
		(layer "F.Cu")
		(net "PCIE_RX_N78")
	)
	(segment
		(start 192.875916 -44.085256)
		(end 193.286126 -44.170346)
		(width 0.1397)
		(layer "In2.Cu")
		(net "PCIE_RX_N78")
	)
	(segment
		(start 195.624196 -44.654724)
		(end 197.501764 -44.255436)
		(width 0.1397)
		(layer "In2.Cu")
		(net "PCIE_RX_N78")
	)
	(segment
		(start 198.815706 -44.534582)
		(end 200.208896 -45.438822)
		(width 0.1397)
		(layer "In2.Cu")
		(net "PCIE_RX_N78")
	)
	(segment
		(start 192.117218 -43.928284)
		(end 192.255394 -44.138342)
		(width 0.1397)
		(layer "In2.Cu")
		(net "PCIE_RX_N78")
	)
	(segment
		(start 192.255394 -44.138342)
		(end 192.665604 -44.223432)
		(width 0.1397)
		(layer "In2.Cu")
		(net "PCIE_RX_N78")
	)
	(segment
		(start 139.488926 -37.294058)
		(end 146.505168 -41.851072)
		(width 0.1397)
		(layer "In2.Cu")
		(net "PCIE_RX_N78")
	)
	(segment
		(start 191.706754 -43.843194)
		(end 192.117218 -43.928284)
		(width 0.1397)
		(layer "In2.Cu")
		(net "PCIE_RX_N78")
	)
	(segment
		(start 191.086232 -43.89628)
		(end 191.496696 -43.981116)
		(width 0.1397)
		(layer "In2.Cu")
		(net "PCIE_RX_N78")
	)
	(segment
		(start 102.5144 -37.094668)
		(end 102.7938 -36.815268)
		(width 0.1397)
		(layer "In2.Cu")
		(net "PCIE_RX_N78")
	)
	(segment
		(start 131.17703 -37.870384)
		(end 133.889242 -37.294058)
		(width 0.1397)
		(layer "In2.Cu")
		(net "PCIE_RX_N78")
	)
	(segment
		(start 195.213732 -44.569634)
		(end 195.624196 -44.654724)
		(width 0.1397)
		(layer "In2.Cu")
		(net "PCIE_RX_N78")
	)
	(segment
		(start 118.394988 -34.320734)
		(end 131.17703 -37.870384)
		(width 0.1397)
		(layer "In2.Cu")
		(net "PCIE_RX_N78")
	)
	(segment
		(start 194.59321 -44.62272)
		(end 195.003674 -44.70781)
		(width 0.1397)
		(layer "In2.Cu")
		(net "PCIE_RX_N78")
	)
	(segment
		(start 164.585396 -45.677328)
		(end 182.345076 -41.903904)
		(width 0.1397)
		(layer "In2.Cu")
		(net "PCIE_RX_N78")
	)
	(segment
		(start 193.834766 -44.465494)
		(end 194.044824 -44.327572)
		(width 0.1397)
		(layer "In2.Cu")
		(net "PCIE_RX_N78")
	)
	(segment
		(start 146.505168 -41.851072)
		(end 164.585396 -45.677328)
		(width 0.1397)
		(layer "In2.Cu")
		(net "PCIE_RX_N78")
	)
	(segment
		(start 193.424302 -44.380658)
		(end 193.834766 -44.465494)
		(width 0.1397)
		(layer "In2.Cu")
		(net "PCIE_RX_N78")
	)
	(segment
		(start 133.889242 -37.294058)
		(end 139.488926 -37.294058)
		(width 0.1397)
		(layer "In2.Cu")
		(net "PCIE_RX_N78")
	)
	(segment
		(start 197.501764 -44.255436)
		(end 198.815706 -44.534582)
		(width 0.1397)
		(layer "In2.Cu")
		(net "PCIE_RX_N78")
	)
	(segment
		(start 194.455288 -44.412662)
		(end 194.59321 -44.62272)
		(width 0.1397)
		(layer "In2.Cu")
		(net "PCIE_RX_N78")
	)
	(segment
		(start 182.345076 -41.903904)
		(end 190.94831 -43.685968)
		(width 0.1397)
		(layer "In2.Cu")
		(net "PCIE_RX_N78")
	)
	(segment
		(start 192.665604 -44.223432)
		(end 192.875916 -44.085256)
		(width 0.1397)
		(layer "In2.Cu")
		(net "PCIE_RX_N78")
	)
	(segment
		(start 195.003674 -44.70781)
		(end 195.213732 -44.569634)
		(width 0.1397)
		(layer "In2.Cu")
		(net "PCIE_RX_N78")
	)
	(segment
		(start 194.044824 -44.327572)
		(end 194.455288 -44.412662)
		(width 0.1397)
		(layer "In2.Cu")
		(net "PCIE_RX_N78")
	)
	(segment
		(start 106.668062 -36.815268)
		(end 118.394988 -34.320734)
		(width 0.1397)
		(layer "In2.Cu")
		(net "PCIE_RX_N78")
	)
	(segment
		(start 102.7938 -36.815268)
		(end 106.668062 -36.815268)
		(width 0.1397)
		(layer "In2.Cu")
		(net "PCIE_RX_N78")
	)
	(segment
		(start 193.286126 -44.170346)
		(end 193.424302 -44.380658)
		(width 0.1397)
		(layer "In2.Cu")
		(net "PCIE_RX_N78")
	)
	(segment
		(start 191.496696 -43.981116)
		(end 191.706754 -43.843194)
		(width 0.1397)
		(layer "In2.Cu")
		(net "PCIE_RX_N78")
	)
	(segment
		(start 190.94831 -43.685968)
		(end 191.086232 -43.89628)
		(width 0.1397)
		(layer "In2.Cu")
		(net "PCIE_RX_N78")
	)
	(segment
		(start 200.208896 -45.438822)
		(end 200.96734 -45.438822)
		(width 0.1397)
		(layer "In2.Cu")
		(net "PCIE_RX_N78")
	)
	(arc
		(start 200.96734 -45.438822)
		(mid 201.245728 -45.554134)
		(end 201.36104 -45.832522)
		(width 0.1397)
		(layer "In2.Cu")
		(net "PCIE_RX_N78")
	)
	(segment
		(start 61.35116 -53.85943)
		(end 68.786502 -55.439818)
		(width 0.1397)
		(layer "In5.Cu")
		(net "PCIE_RX_N78")
	)
	(segment
		(start 56.349138 -50.61077)
		(end 61.35116 -53.85943)
		(width 0.1397)
		(layer "In5.Cu")
		(net "PCIE_RX_N78")
	)
	(segment
		(start 97.020888 -42.568622)
		(end 97.687384 -39.4335)
		(width 0.1397)
		(layer "In5.Cu")
		(net "PCIE_RX_N78")
	)
	(segment
		(start 71.921624 -54.77383)
		(end 75.377802 -55.508398)
		(width 0.1397)
		(layer "In5.Cu")
		(net "PCIE_RX_N78")
	)
	(segment
		(start 98.237802 -38.585648)
		(end 100.965508 -36.815268)
		(width 0.1397)
		(layer "In5.Cu")
		(net "PCIE_RX_N78")
	)
	(segment
		(start 22.094698 -72.063102)
		(end 21.25472 -68.110354)
		(width 0.1397)
		(layer "In5.Cu")
		(net "PCIE_RX_N78")
	)
	(segment
		(start 21.209 -87.4268)
		(end 21.018754 -87.236554)
		(width 0.1397)
		(layer "In5.Cu")
		(net "PCIE_RX_N78")
	)
	(segment
		(start 17.817084 -82.853276)
		(end 17.69745 -82.164428)
		(width 0.1397)
		(layer "In5.Cu")
		(net "PCIE_RX_N78")
	)
	(segment
		(start 76.722478 -55.222902)
		(end 79.463138 -55.805324)
		(width 0.1397)
		(layer "In5.Cu")
		(net "PCIE_RX_N78")
	)
	(segment
		(start 18.99412 -77.052932)
		(end 19.436588 -76.610464)
		(width 0.1397)
		(layer "In5.Cu")
		(net "PCIE_RX_N78")
	)
	(segment
		(start 18.669762 -77.55255)
		(end 18.99412 -77.052932)
		(width 0.1397)
		(layer "In5.Cu")
		(net "PCIE_RX_N78")
	)
	(segment
		(start 20.961604 -85.924136)
		(end 20.813014 -85.22462)
		(width 0.1397)
		(layer "In5.Cu")
		(net "PCIE_RX_N78")
	)
	(segment
		(start 17.911572 -82.998564)
		(end 17.817084 -82.853276)
		(width 0.1397)
		(layer "In5.Cu")
		(net "PCIE_RX_N78")
	)
	(segment
		(start 100.965508 -36.815268)
		(end 102.235 -36.815268)
		(width 0.1397)
		(layer "In5.Cu")
		(net "PCIE_RX_N78")
	)
	(segment
		(start 93.98 -51.601878)
		(end 96.773492 -47.300896)
		(width 0.1397)
		(layer "In5.Cu")
		(net "PCIE_RX_N78")
	)
	(segment
		(start 49.351184 -50.593752)
		(end 52.810156 -49.858422)
		(width 0.1397)
		(layer "In5.Cu")
		(net "PCIE_RX_N78")
	)
	(segment
		(start 97.40011 -44.351956)
		(end 97.020888 -42.568622)
		(width 0.1397)
		(layer "In5.Cu")
		(net "PCIE_RX_N78")
	)
	(segment
		(start 37.193474 -52.161948)
		(end 46.96206 -50.085752)
		(width 0.1397)
		(layer "In5.Cu")
		(net "PCIE_RX_N78")
	)
	(segment
		(start 52.810156 -49.858422)
		(end 56.349138 -50.61077)
		(width 0.1397)
		(layer "In5.Cu")
		(net "PCIE_RX_N78")
	)
	(segment
		(start 79.463138 -55.805324)
		(end 91.42222 -53.263038)
		(width 0.1397)
		(layer "In5.Cu")
		(net "PCIE_RX_N78")
	)
	(segment
		(start 28.214828 -57.992772)
		(end 37.193474 -52.161948)
		(width 0.1397)
		(layer "In5.Cu")
		(net "PCIE_RX_N78")
	)
	(segment
		(start 97.687384 -39.4335)
		(end 98.237802 -38.585648)
		(width 0.1397)
		(layer "In5.Cu")
		(net "PCIE_RX_N78")
	)
	(segment
		(start 75.377802 -55.508398)
		(end 76.722478 -55.222902)
		(width 0.1397)
		(layer "In5.Cu")
		(net "PCIE_RX_N78")
	)
	(segment
		(start 20.961604 -87.098632)
		(end 20.961604 -85.924136)
		(width 0.1397)
		(layer "In5.Cu")
		(net "PCIE_RX_N78")
	)
	(segment
		(start 20.428712 -84.6328)
		(end 17.911572 -82.998564)
		(width 0.1397)
		(layer "In5.Cu")
		(net "PCIE_RX_N78")
	)
	(segment
		(start 91.42222 -53.263038)
		(end 93.98 -51.601878)
		(width 0.1397)
		(layer "In5.Cu")
		(net "PCIE_RX_N78")
	)
	(segment
		(start 22.10816 -64.09944)
		(end 28.214828 -57.992772)
		(width 0.1397)
		(layer "In5.Cu")
		(net "PCIE_RX_N78")
	)
	(segment
		(start 19.436588 -76.610464)
		(end 21.3995 -75.33513)
		(width 0.1397)
		(layer "In5.Cu")
		(net "PCIE_RX_N78")
	)
	(segment
		(start 21.25472 -68.110354)
		(end 22.10816 -64.09944)
		(width 0.1397)
		(layer "In5.Cu")
		(net "PCIE_RX_N78")
	)
	(segment
		(start 46.96206 -50.085752)
		(end 49.351184 -50.593752)
		(width 0.1397)
		(layer "In5.Cu")
		(net "PCIE_RX_N78")
	)
	(segment
		(start 20.813014 -85.22462)
		(end 20.428712 -84.6328)
		(width 0.1397)
		(layer "In5.Cu")
		(net "PCIE_RX_N78")
	)
	(segment
		(start 96.773492 -47.300896)
		(end 97.40011 -44.351956)
		(width 0.1397)
		(layer "In5.Cu")
		(net "PCIE_RX_N78")
	)
	(segment
		(start 102.235 -36.815268)
		(end 102.5144 -37.094668)
		(width 0.1397)
		(layer "In5.Cu")
		(net "PCIE_RX_N78")
	)
	(segment
		(start 68.786502 -55.439818)
		(end 71.921624 -54.77383)
		(width 0.1397)
		(layer "In5.Cu")
		(net "PCIE_RX_N78")
	)
	(segment
		(start 21.3995 -75.33513)
		(end 22.094698 -72.063102)
		(width 0.1397)
		(layer "In5.Cu")
		(net "PCIE_RX_N78")
	)
	(segment
		(start 17.69745 -82.164428)
		(end 18.669762 -77.55255)
		(width 0.1397)
		(layer "In5.Cu")
		(net "PCIE_RX_N78")
	)
	(arc
		(start 21.018754 -87.236554)
		(mid 20.976472 -87.173275)
		(end 20.961604 -87.098632)
		(width 0.1397)
		(layer "In5.Cu")
		(net "PCIE_RX_N78")
	)
	(segment
		(start 274.545806 -5.440426)
		(end 304.21072 -5.440426)
		(width 0.136652)
		(layer "B.Cu")
		(net "PCIE_REFCLK_H1_P_R")
	)
	(segment
		(start 271.8054 -5.8801)
		(end 273.484594 -5.8801)
		(width 0.136652)
		(layer "B.Cu")
		(net "PCIE_REFCLK_H1_P_R")
	)
	(segment
		(start 304.659792 -5.626354)
		(end 306.97805 -7.944612)
		(width 0.136652)
		(layer "B.Cu")
		(net "PCIE_REFCLK_H1_P_R")
	)
	(segment
		(start 271.4625 -6.223)
		(end 271.8054 -5.8801)
		(width 0.136652)
		(layer "B.Cu")
		(net "PCIE_REFCLK_H1_P_R")
	)
	(segment
		(start 307.163978 -8.393684)
		(end 307.163978 -11.80973)
		(width 0.136652)
		(layer "B.Cu")
		(net "PCIE_REFCLK_H1_P_R")
	)
	(segment
		(start 307.472842 -12.555728)
		(end 308.184804 -13.26769)
		(width 0.136652)
		(layer "B.Cu")
		(net "PCIE_REFCLK_H1_P_R")
	)
	(arc
		(start 306.97805 -7.944612)
		(mid 307.115719 -8.150648)
		(end 307.163978 -8.393684)
		(width 0.136652)
		(layer "B.Cu")
		(net "PCIE_REFCLK_H1_P_R")
	)
	(arc
		(start 307.163978 -11.80973)
		(mid 307.244192 -12.213462)
		(end 307.472842 -12.555728)
		(width 0.136652)
		(layer "B.Cu")
		(net "PCIE_REFCLK_H1_P_R")
	)
	(arc
		(start 273.484594 -5.8801)
		(mid 273.771908 -5.822932)
		(end 274.015454 -5.660136)
		(width 0.136652)
		(layer "B.Cu")
		(net "PCIE_REFCLK_H1_P_R")
	)
	(arc
		(start 274.015454 -5.660136)
		(mid 274.258782 -5.49755)
		(end 274.545806 -5.440426)
		(width 0.136652)
		(layer "B.Cu")
		(net "PCIE_REFCLK_H1_P_R")
	)
	(arc
		(start 304.21072 -5.440426)
		(mid 304.453724 -5.488762)
		(end 304.659792 -5.626354)
		(width 0.136652)
		(layer "B.Cu")
		(net "PCIE_REFCLK_H1_P_R")
	)
	(arc
		(start 308.184804 -13.26769)
		(mid 308.311799 -13.610459)
		(end 308.134512 -13.930122)
		(width 0.136652)
		(layer "B.Cu")
		(net "PCIE_REFCLK_H1_P_R")
	)
	(segment
		(start 307.193442 -7.728712)
		(end 304.875692 -5.410962)
		(width 0.136652)
		(layer "B.Cu")
		(net "PCIE_REFCLK_H1_N_R")
	)
	(segment
		(start 271.8308 -5.5753)
		(end 271.4625 -5.207)
		(width 0.136652)
		(layer "B.Cu")
		(net "PCIE_REFCLK_H1_N_R")
	)
	(segment
		(start 307.468778 -11.80973)
		(end 307.468778 -8.39343)
		(width 0.136652)
		(layer "B.Cu")
		(net "PCIE_REFCLK_H1_N_R")
	)
	(segment
		(start 304.210974 -5.135626)
		(end 274.545806 -5.135626)
		(width 0.136652)
		(layer "B.Cu")
		(net "PCIE_REFCLK_H1_N_R")
	)
	(segment
		(start 308.015894 -12.667488)
		(end 307.688488 -12.340082)
		(width 0.136652)
		(layer "B.Cu")
		(net "PCIE_REFCLK_H1_N_R")
	)
	(segment
		(start 273.484594 -5.5753)
		(end 271.8308 -5.5753)
		(width 0.136652)
		(layer "B.Cu")
		(net "PCIE_REFCLK_H1_N_R")
	)
	(arc
		(start 304.875692 -5.410962)
		(mid 304.570731 -5.20713)
		(end 304.210974 -5.135626)
		(width 0.136652)
		(layer "B.Cu")
		(net "PCIE_REFCLK_H1_N_R")
	)
	(arc
		(start 307.468778 -8.39343)
		(mid 307.397206 -8.033701)
		(end 307.193442 -7.728712)
		(width 0.136652)
		(layer "B.Cu")
		(net "PCIE_REFCLK_H1_N_R")
	)
	(arc
		(start 307.688488 -12.340082)
		(mid 307.525902 -12.096754)
		(end 307.468778 -11.80973)
		(width 0.136652)
		(layer "B.Cu")
		(net "PCIE_REFCLK_H1_N_R")
	)
	(arc
		(start 273.799808 -5.44449)
		(mid 273.655216 -5.54126)
		(end 273.484594 -5.5753)
		(width 0.136652)
		(layer "B.Cu")
		(net "PCIE_REFCLK_H1_N_R")
	)
	(arc
		(start 274.545806 -5.135626)
		(mid 274.142074 -5.21584)
		(end 273.799808 -5.44449)
		(width 0.136652)
		(layer "B.Cu")
		(net "PCIE_REFCLK_H1_N_R")
	)
	(arc
		(start 308.88432 -12.530074)
		(mid 308.485115 -12.819953)
		(end 308.015894 -12.667488)
		(width 0.136652)
		(layer "B.Cu")
		(net "PCIE_REFCLK_H1_N_R")
	)
	(segment
		(start 276.11324 -8.806688)
		(end 276.113494 -8.806942)
		(width 0.136652)
		(layer "B.Cu")
		(net "PCIE_REFCLK_H0_P_R")
	)
	(segment
		(start 272.6055 -9.271)
		(end 272.959576 -8.916924)
		(width 0.136652)
		(layer "B.Cu")
		(net "PCIE_REFCLK_H0_P_R")
	)
	(segment
		(start 272.959576 -8.916924)
		(end 274.097496 -8.916924)
		(width 0.136652)
		(layer "B.Cu")
		(net "PCIE_REFCLK_H0_P_R")
	)
	(segment
		(start 276.540722 -8.983726)
		(end 281.68219 -8.983726)
		(width 0.136652)
		(layer "B.Cu")
		(net "PCIE_REFCLK_H0_P_R")
	)
	(segment
		(start 282.131262 -9.169654)
		(end 285.8516 -12.889992)
		(width 0.136652)
		(layer "B.Cu")
		(net "PCIE_REFCLK_H0_P_R")
	)
	(segment
		(start 274.791424 -8.629396)
		(end 275.685758 -8.629396)
		(width 0.136652)
		(layer "B.Cu")
		(net "PCIE_REFCLK_H0_P_R")
	)
	(arc
		(start 281.68219 -8.983726)
		(mid 281.925194 -9.032062)
		(end 282.131262 -9.169654)
		(width 0.136652)
		(layer "B.Cu")
		(net "PCIE_REFCLK_H0_P_R")
	)
	(arc
		(start 274.097496 -8.916924)
		(mid 274.285275 -8.879555)
		(end 274.44446 -8.77316)
		(width 0.136652)
		(layer "B.Cu")
		(net "PCIE_REFCLK_H0_P_R")
	)
	(arc
		(start 276.113494 -8.806942)
		(mid 276.309536 -8.937807)
		(end 276.540722 -8.983726)
		(width 0.136652)
		(layer "B.Cu")
		(net "PCIE_REFCLK_H0_P_R")
	)
	(arc
		(start 274.44446 -8.77316)
		(mid 274.603634 -8.66674)
		(end 274.791424 -8.629396)
		(width 0.136652)
		(layer "B.Cu")
		(net "PCIE_REFCLK_H0_P_R")
	)
	(arc
		(start 275.685758 -8.629396)
		(mid 275.917141 -8.675515)
		(end 276.11324 -8.806688)
		(width 0.136652)
		(layer "B.Cu")
		(net "PCIE_REFCLK_H0_P_R")
	)
	(arc
		(start 285.8516 -12.889992)
		(mid 286.131282 -13.372449)
		(end 286.134302 -13.930122)
		(width 0.136652)
		(layer "B.Cu")
		(net "PCIE_REFCLK_H0_P_R")
	)
	(segment
		(start 275.686012 -8.324596)
		(end 274.791424 -8.324596)
		(width 0.136652)
		(layer "B.Cu")
		(net "PCIE_REFCLK_H0_N_R")
	)
	(segment
		(start 274.097496 -8.612124)
		(end 272.962624 -8.612124)
		(width 0.136652)
		(layer "B.Cu")
		(net "PCIE_REFCLK_H0_N_R")
	)
	(segment
		(start 281.682444 -8.678926)
		(end 276.540722 -8.678926)
		(width 0.136652)
		(layer "B.Cu")
		(net "PCIE_REFCLK_H0_N_R")
	)
	(segment
		(start 272.962624 -8.612124)
		(end 272.6055 -8.255)
		(width 0.136652)
		(layer "B.Cu")
		(net "PCIE_REFCLK_H0_N_R")
	)
	(segment
		(start 285.948374 -12.555474)
		(end 282.347162 -8.954262)
		(width 0.136652)
		(layer "B.Cu")
		(net "PCIE_REFCLK_H0_N_R")
	)
	(segment
		(start 276.32914 -8.591042)
		(end 276.328886 -8.591042)
		(width 0.136652)
		(layer "B.Cu")
		(net "PCIE_REFCLK_H0_N_R")
	)
	(arc
		(start 282.347162 -8.954262)
		(mid 282.042201 -8.75043)
		(end 281.682444 -8.678926)
		(width 0.136652)
		(layer "B.Cu")
		(net "PCIE_REFCLK_H0_N_R")
	)
	(arc
		(start 276.540722 -8.678926)
		(mid 276.426214 -8.65598)
		(end 276.32914 -8.591042)
		(width 0.136652)
		(layer "B.Cu")
		(net "PCIE_REFCLK_H0_N_R")
	)
	(arc
		(start 274.228814 -8.557514)
		(mid 274.168594 -8.597908)
		(end 274.097496 -8.612124)
		(width 0.136652)
		(layer "B.Cu")
		(net "PCIE_REFCLK_H0_N_R")
	)
	(arc
		(start 276.328886 -8.591042)
		(mid 276.033934 -8.393931)
		(end 275.686012 -8.324596)
		(width 0.136652)
		(layer "B.Cu")
		(net "PCIE_REFCLK_H0_N_R")
	)
	(arc
		(start 286.884364 -12.530074)
		(mid 286.421822 -12.744142)
		(end 285.948374 -12.555474)
		(width 0.136652)
		(layer "B.Cu")
		(net "PCIE_REFCLK_H0_N_R")
	)
	(arc
		(start 274.791424 -8.324596)
		(mid 274.486935 -8.385069)
		(end 274.228814 -8.557514)
		(width 0.136652)
		(layer "B.Cu")
		(net "PCIE_REFCLK_H0_N_R")
	)
	(segment
		(start 203.29652 -22.30628)
		(end 202.142852 -22.30628)
		(width 0.12065)
		(layer "F.Cu")
		(net "MINISAS_CN16_D_I2C_INT#")
	)
	(segment
		(start 200.39838 -17.6784)
		(end 203.4032 -17.6784)
		(width 0.12065)
		(layer "F.Cu")
		(net "MINISAS_CN16_D_I2C_INT#")
	)
	(segment
		(start 318.758824 -35.629596)
		(end 318.758824 -36.090352)
		(width 0.12065)
		(layer "F.Cu")
		(net "MINISAS_CN16_D_I2C_INT#")
	)
	(segment
		(start 203.4032 -17.6784)
		(end 204.9145 -19.1897)
		(width 0.12065)
		(layer "F.Cu")
		(net "MINISAS_CN16_D_I2C_INT#")
	)
	(segment
		(start 204.9145 -19.1897)
		(end 204.9145 -20.9296)
		(width 0.12065)
		(layer "F.Cu")
		(net "MINISAS_CN16_D_I2C_INT#")
	)
	(segment
		(start 318.444626 -33.86963)
		(end 318.444626 -35.315398)
		(width 0.12065)
		(layer "F.Cu")
		(net "MINISAS_CN16_D_I2C_INT#")
	)
	(segment
		(start 204.6732 -20.9296)
		(end 203.29652 -22.30628)
		(width 0.12065)
		(layer "F.Cu")
		(net "MINISAS_CN16_D_I2C_INT#")
	)
	(segment
		(start 318.758824 -36.090352)
		(end 318.051942 -36.797234)
		(width 0.12065)
		(layer "F.Cu")
		(net "MINISAS_CN16_D_I2C_INT#")
	)
	(segment
		(start 318.444626 -35.315398)
		(end 318.758824 -35.629596)
		(width 0.12065)
		(layer "F.Cu")
		(net "MINISAS_CN16_D_I2C_INT#")
	)
	(segment
		(start 318.051942 -36.797234)
		(end 317.957454 -36.797234)
		(width 0.12065)
		(layer "F.Cu")
		(net "MINISAS_CN16_D_I2C_INT#")
	)
	(segment
		(start 199.728582 -17.008602)
		(end 200.39838 -17.6784)
		(width 0.12065)
		(layer "F.Cu")
		(net "MINISAS_CN16_D_I2C_INT#")
	)
	(segment
		(start 204.9145 -20.9296)
		(end 204.6732 -20.9296)
		(width 0.12065)
		(layer "F.Cu")
		(net "MINISAS_CN16_D_I2C_INT#")
	)
	(via
		(at 231.088438 -13.979398)
		(size 0.508)
		(drill 0.254)
		(layers "F.Cu" "B.Cu")
		(net "MINISAS_CN16_D_I2C_INT#")
	)
	(via
		(at 199.728582 -17.008602)
		(size 0.508)
		(drill 0.254)
		(layers "F.Cu" "B.Cu")
		(net "MINISAS_CN16_D_I2C_INT#")
	)
	(via
		(at 317.957454 -36.797234)
		(size 0.508)
		(drill 0.254)
		(layers "F.Cu" "B.Cu")
		(net "MINISAS_CN16_D_I2C_INT#")
	)
	(via
		(at 263.360916 -11.96594)
		(size 0.508)
		(drill 0.254)
		(layers "F.Cu" "B.Cu")
		(net "MINISAS_CN16_D_I2C_INT#")
	)
	(via
		(at 231.38003 -12.505436)
		(size 0.7112)
		(drill 0.3556)
		(layers "F.Cu" "B.Cu")
		(net "MINISAS_CN16_D_I2C_INT#")
	)
	(segment
		(start 258.051554 -12.590018)
		(end 259.004054 -11.637518)
		(width 0.12065)
		(layer "B.Cu")
		(net "MINISAS_CN16_D_I2C_INT#")
	)
	(segment
		(start 250.91898 -9.172702)
		(end 251.444252 -9.697974)
		(width 0.12065)
		(layer "B.Cu")
		(net "MINISAS_CN16_D_I2C_INT#")
	)
	(segment
		(start 231.088438 -9.238488)
		(end 233.324654 -7.002272)
		(width 0.12065)
		(layer "B.Cu")
		(net "MINISAS_CN16_D_I2C_INT#")
	)
	(segment
		(start 243.555012 -9.172702)
		(end 250.91898 -9.172702)
		(width 0.12065)
		(layer "B.Cu")
		(net "MINISAS_CN16_D_I2C_INT#")
	)
	(segment
		(start 263.044432 -11.649456)
		(end 263.360916 -11.96594)
		(width 0.12065)
		(layer "B.Cu")
		(net "MINISAS_CN16_D_I2C_INT#")
	)
	(segment
		(start 251.444252 -9.697974)
		(end 251.444252 -10.857484)
		(width 0.12065)
		(layer "B.Cu")
		(net "MINISAS_CN16_D_I2C_INT#")
	)
	(segment
		(start 259.994146 -10.589768)
		(end 260.62305 -10.589768)
		(width 0.12065)
		(layer "B.Cu")
		(net "MINISAS_CN16_D_I2C_INT#")
	)
	(segment
		(start 259.004054 -11.57986)
		(end 259.994146 -10.589768)
		(width 0.12065)
		(layer "B.Cu")
		(net "MINISAS_CN16_D_I2C_INT#")
	)
	(segment
		(start 233.324654 -7.002272)
		(end 241.384582 -7.002272)
		(width 0.12065)
		(layer "B.Cu")
		(net "MINISAS_CN16_D_I2C_INT#")
	)
	(segment
		(start 251.444252 -10.857484)
		(end 251.539248 -10.95248)
		(width 0.12065)
		(layer "B.Cu")
		(net "MINISAS_CN16_D_I2C_INT#")
	)
	(segment
		(start 231.38003 -13.687806)
		(end 231.088438 -13.979398)
		(width 0.12065)
		(layer "B.Cu")
		(net "MINISAS_CN16_D_I2C_INT#")
	)
	(segment
		(start 231.38003 -12.505436)
		(end 231.088438 -12.213844)
		(width 0.12065)
		(layer "B.Cu")
		(net "MINISAS_CN16_D_I2C_INT#")
	)
	(segment
		(start 241.384582 -7.002272)
		(end 243.555012 -9.172702)
		(width 0.12065)
		(layer "B.Cu")
		(net "MINISAS_CN16_D_I2C_INT#")
	)
	(segment
		(start 261.682738 -11.649456)
		(end 263.044432 -11.649456)
		(width 0.12065)
		(layer "B.Cu")
		(net "MINISAS_CN16_D_I2C_INT#")
	)
	(segment
		(start 255.090168 -12.590018)
		(end 258.051554 -12.590018)
		(width 0.12065)
		(layer "B.Cu")
		(net "MINISAS_CN16_D_I2C_INT#")
	)
	(segment
		(start 231.088438 -12.213844)
		(end 231.088438 -9.238488)
		(width 0.12065)
		(layer "B.Cu")
		(net "MINISAS_CN16_D_I2C_INT#")
	)
	(segment
		(start 231.38003 -12.505436)
		(end 231.38003 -13.687806)
		(width 0.12065)
		(layer "B.Cu")
		(net "MINISAS_CN16_D_I2C_INT#")
	)
	(segment
		(start 251.539248 -10.95248)
		(end 253.45263 -10.95248)
		(width 0.12065)
		(layer "B.Cu")
		(net "MINISAS_CN16_D_I2C_INT#")
	)
	(segment
		(start 259.004054 -11.637518)
		(end 259.004054 -11.57986)
		(width 0.12065)
		(layer "B.Cu")
		(net "MINISAS_CN16_D_I2C_INT#")
	)
	(segment
		(start 260.62305 -10.589768)
		(end 261.682738 -11.649456)
		(width 0.12065)
		(layer "B.Cu")
		(net "MINISAS_CN16_D_I2C_INT#")
	)
	(segment
		(start 253.45263 -10.95248)
		(end 255.090168 -12.590018)
		(width 0.12065)
		(layer "B.Cu")
		(net "MINISAS_CN16_D_I2C_INT#")
	)
	(segment
		(start 317.957454 -36.797234)
		(end 317.957454 -36.77031)
		(width 0.127)
		(layer "In5.Cu")
		(net "MINISAS_CN16_D_I2C_INT#")
	)
	(segment
		(start 317.016638 -33.476184)
		(end 314.383928 -30.843474)
		(width 0.127)
		(layer "In5.Cu")
		(net "MINISAS_CN16_D_I2C_INT#")
	)
	(segment
		(start 269.529306 -12.841224)
		(end 268.140942 -12.841224)
		(width 0.127)
		(layer "In5.Cu")
		(net "MINISAS_CN16_D_I2C_INT#")
	)
	(segment
		(start 272.49501 -13.719556)
		(end 270.407638 -13.719556)
		(width 0.127)
		(layer "In5.Cu")
		(net "MINISAS_CN16_D_I2C_INT#")
	)
	(segment
		(start 314.383928 -30.843474)
		(end 289.618928 -30.843474)
		(width 0.127)
		(layer "In5.Cu")
		(net "MINISAS_CN16_D_I2C_INT#")
	)
	(segment
		(start 231.088438 -13.979398)
		(end 229.573836 -15.494)
		(width 0.127)
		(layer "In5.Cu")
		(net "MINISAS_CN16_D_I2C_INT#")
	)
	(segment
		(start 270.407638 -13.719556)
		(end 269.529306 -12.841224)
		(width 0.127)
		(layer "In5.Cu")
		(net "MINISAS_CN16_D_I2C_INT#")
	)
	(segment
		(start 229.573836 -15.494)
		(end 201.243184 -15.494)
		(width 0.127)
		(layer "In5.Cu")
		(net "MINISAS_CN16_D_I2C_INT#")
	)
	(segment
		(start 289.618928 -30.843474)
		(end 272.49501 -13.719556)
		(width 0.127)
		(layer "In5.Cu")
		(net "MINISAS_CN16_D_I2C_INT#")
	)
	(segment
		(start 268.140942 -12.841224)
		(end 267.908278 -12.60856)
		(width 0.127)
		(layer "In5.Cu")
		(net "MINISAS_CN16_D_I2C_INT#")
	)
	(segment
		(start 264.003536 -12.60856)
		(end 263.360916 -11.96594)
		(width 0.127)
		(layer "In5.Cu")
		(net "MINISAS_CN16_D_I2C_INT#")
	)
	(segment
		(start 317.016638 -35.829494)
		(end 317.016638 -33.476184)
		(width 0.127)
		(layer "In5.Cu")
		(net "MINISAS_CN16_D_I2C_INT#")
	)
	(segment
		(start 317.957454 -36.77031)
		(end 317.016638 -35.829494)
		(width 0.127)
		(layer "In5.Cu")
		(net "MINISAS_CN16_D_I2C_INT#")
	)
	(segment
		(start 267.908278 -12.60856)
		(end 264.003536 -12.60856)
		(width 0.127)
		(layer "In5.Cu")
		(net "MINISAS_CN16_D_I2C_INT#")
	)
	(segment
		(start 201.243184 -15.494)
		(end 199.728582 -17.008602)
		(width 0.127)
		(layer "In5.Cu")
		(net "MINISAS_CN16_D_I2C_INT#")
	)
	(segment
		(start 202.0697 -18.1356)
		(end 199.848978 -18.1356)
		(width 0.12065)
		(layer "F.Cu")
		(net "MINISAS_CN16_C_I2C_INT#")
	)
	(segment
		(start 202.7809 -18.8468)
		(end 202.823064 -18.8468)
		(width 0.12065)
		(layer "F.Cu")
		(net "MINISAS_CN16_C_I2C_INT#")
	)
	(segment
		(start 202.7809 -18.8468)
		(end 202.0697 -18.1356)
		(width 0.12065)
		(layer "F.Cu")
		(net "MINISAS_CN16_C_I2C_INT#")
	)
	(segment
		(start 203.7588 -19.782536)
		(end 203.7588 -21.0312)
		(width 0.12065)
		(layer "F.Cu")
		(net "MINISAS_CN16_C_I2C_INT#")
	)
	(segment
		(start 203.7588 -21.0312)
		(end 203.13396 -21.65604)
		(width 0.12065)
		(layer "F.Cu")
		(net "MINISAS_CN16_C_I2C_INT#")
	)
	(segment
		(start 203.13396 -21.65604)
		(end 202.142852 -21.65604)
		(width 0.12065)
		(layer "F.Cu")
		(net "MINISAS_CN16_C_I2C_INT#")
	)
	(segment
		(start 199.848978 -18.1356)
		(end 198.767954 -17.054576)
		(width 0.12065)
		(layer "F.Cu")
		(net "MINISAS_CN16_C_I2C_INT#")
	)
	(segment
		(start 202.823064 -18.8468)
		(end 203.7588 -19.782536)
		(width 0.12065)
		(layer "F.Cu")
		(net "MINISAS_CN16_C_I2C_INT#")
	)
	(via
		(at 198.767954 -17.054576)
		(size 0.508)
		(drill 0.254)
		(layers "F.Cu" "B.Cu")
		(net "MINISAS_CN16_C_I2C_INT#")
	)
	(via
		(at 267.3604 -3.6576)
		(size 0.508)
		(drill 0.254)
		(layers "F.Cu" "B.Cu")
		(net "MINISAS_CN16_C_I2C_INT#")
	)
	(via
		(at 229.993952 -13.837666)
		(size 0.508)
		(drill 0.254)
		(layers "F.Cu" "B.Cu")
		(net "MINISAS_CN16_C_I2C_INT#")
	)
	(via
		(at 243.808758 -6.852412)
		(size 0.508)
		(drill 0.254)
		(layers "F.Cu" "B.Cu")
		(net "MINISAS_CN16_C_I2C_INT#")
	)
	(via
		(at 229.993952 -12.337542)
		(size 0.7112)
		(drill 0.3556)
		(layers "F.Cu" "B.Cu")
		(net "MINISAS_CN16_C_I2C_INT#")
	)
	(segment
		(start 229.993952 -12.337542)
		(end 229.993952 -9.82091)
		(width 0.12065)
		(layer "B.Cu")
		(net "MINISAS_CN16_C_I2C_INT#")
	)
	(segment
		(start 269.254732 -3.9878)
		(end 269.40129 -3.841242)
		(width 0.12065)
		(layer "B.Cu")
		(net "MINISAS_CN16_C_I2C_INT#")
	)
	(segment
		(start 229.993952 -13.837666)
		(end 229.993952 -12.337542)
		(width 0.12065)
		(layer "B.Cu")
		(net "MINISAS_CN16_C_I2C_INT#")
	)
	(segment
		(start 233.244136 -6.570726)
		(end 243.527072 -6.570726)
		(width 0.12065)
		(layer "B.Cu")
		(net "MINISAS_CN16_C_I2C_INT#")
	)
	(segment
		(start 269.787878 -3.841242)
		(end 269.788132 -3.841496)
		(width 0.12065)
		(layer "B.Cu")
		(net "MINISAS_CN16_C_I2C_INT#")
	)
	(segment
		(start 270.236696 -3.841496)
		(end 270.7132 -4.318)
		(width 0.12065)
		(layer "B.Cu")
		(net "MINISAS_CN16_C_I2C_INT#")
	)
	(segment
		(start 267.6906 -3.9878)
		(end 269.254732 -3.9878)
		(width 0.12065)
		(layer "B.Cu")
		(net "MINISAS_CN16_C_I2C_INT#")
	)
	(segment
		(start 267.3604 -3.6576)
		(end 267.6906 -3.9878)
		(width 0.12065)
		(layer "B.Cu")
		(net "MINISAS_CN16_C_I2C_INT#")
	)
	(segment
		(start 243.527072 -6.570726)
		(end 243.808758 -6.852412)
		(width 0.12065)
		(layer "B.Cu")
		(net "MINISAS_CN16_C_I2C_INT#")
	)
	(segment
		(start 269.40129 -3.841242)
		(end 269.787878 -3.841242)
		(width 0.12065)
		(layer "B.Cu")
		(net "MINISAS_CN16_C_I2C_INT#")
	)
	(segment
		(start 270.7132 -4.318)
		(end 271.4625 -4.318)
		(width 0.12065)
		(layer "B.Cu")
		(net "MINISAS_CN16_C_I2C_INT#")
	)
	(segment
		(start 269.788132 -3.841496)
		(end 270.236696 -3.841496)
		(width 0.12065)
		(layer "B.Cu")
		(net "MINISAS_CN16_C_I2C_INT#")
	)
	(segment
		(start 229.993952 -9.82091)
		(end 233.244136 -6.570726)
		(width 0.12065)
		(layer "B.Cu")
		(net "MINISAS_CN16_C_I2C_INT#")
	)
	(segment
		(start 262.859266 -6.01345)
		(end 257.90652 -6.01345)
		(width 0.127)
		(layer "In2.Cu")
		(net "MINISAS_CN16_C_I2C_INT#")
	)
	(segment
		(start 250.611132 -7.825994)
		(end 244.78234 -7.825994)
		(width 0.127)
		(layer "In2.Cu")
		(net "MINISAS_CN16_C_I2C_INT#")
	)
	(segment
		(start 267.3604 -3.6576)
		(end 266.158726 -4.859274)
		(width 0.127)
		(layer "In2.Cu")
		(net "MINISAS_CN16_C_I2C_INT#")
	)
	(segment
		(start 257.419856 -5.526786)
		(end 252.91034 -5.526786)
		(width 0.127)
		(layer "In2.Cu")
		(net "MINISAS_CN16_C_I2C_INT#")
	)
	(segment
		(start 264.008616 -4.8641)
		(end 262.859266 -6.01345)
		(width 0.127)
		(layer "In2.Cu")
		(net "MINISAS_CN16_C_I2C_INT#")
	)
	(segment
		(start 257.90652 -6.01345)
		(end 257.419856 -5.526786)
		(width 0.127)
		(layer "In2.Cu")
		(net "MINISAS_CN16_C_I2C_INT#")
	)
	(segment
		(start 264.390124 -4.8641)
		(end 264.008616 -4.8641)
		(width 0.127)
		(layer "In2.Cu")
		(net "MINISAS_CN16_C_I2C_INT#")
	)
	(segment
		(start 264.390124 -4.859274)
		(end 264.390124 -4.8641)
		(width 0.127)
		(layer "In2.Cu")
		(net "MINISAS_CN16_C_I2C_INT#")
	)
	(segment
		(start 266.158726 -4.859274)
		(end 264.390124 -4.859274)
		(width 0.127)
		(layer "In2.Cu")
		(net "MINISAS_CN16_C_I2C_INT#")
	)
	(segment
		(start 244.78234 -7.825994)
		(end 243.808758 -6.852412)
		(width 0.127)
		(layer "In2.Cu")
		(net "MINISAS_CN16_C_I2C_INT#")
	)
	(segment
		(start 252.91034 -5.526786)
		(end 250.611132 -7.825994)
		(width 0.127)
		(layer "In2.Cu")
		(net "MINISAS_CN16_C_I2C_INT#")
	)
	(segment
		(start 228.846888 -14.9098)
		(end 229.919022 -13.837666)
		(width 0.127)
		(layer "In5.Cu")
		(net "MINISAS_CN16_C_I2C_INT#")
	)
	(segment
		(start 200.91273 -14.9098)
		(end 228.846888 -14.9098)
		(width 0.127)
		(layer "In5.Cu")
		(net "MINISAS_CN16_C_I2C_INT#")
	)
	(segment
		(start 198.767954 -17.054576)
		(end 200.91273 -14.9098)
		(width 0.127)
		(layer "In5.Cu")
		(net "MINISAS_CN16_C_I2C_INT#")
	)
	(segment
		(start 229.919022 -13.837666)
		(end 229.993952 -13.837666)
		(width 0.127)
		(layer "In5.Cu")
		(net "MINISAS_CN16_C_I2C_INT#")
	)
	(segment
		(start 199.1741 -18.8214)
		(end 199.8599 -19.5072)
		(width 0.12065)
		(layer "F.Cu")
		(net "MINISAS_CN16_B_I2C_INT#")
	)
	(segment
		(start 203.39685 -19.93265)
		(end 203.39685 -20.548854)
		(width 0.12065)
		(layer "F.Cu")
		(net "MINISAS_CN16_B_I2C_INT#")
	)
	(segment
		(start 202.939904 -21.0058)
		(end 202.142852 -21.0058)
		(width 0.12065)
		(layer "F.Cu")
		(net "MINISAS_CN16_B_I2C_INT#")
	)
	(segment
		(start 197.8152 -16.862552)
		(end 197.8152 -17.55521)
		(width 0.12065)
		(layer "F.Cu")
		(net "MINISAS_CN16_B_I2C_INT#")
	)
	(segment
		(start 203.39685 -20.548854)
		(end 202.939904 -21.0058)
		(width 0.12065)
		(layer "F.Cu")
		(net "MINISAS_CN16_B_I2C_INT#")
	)
	(segment
		(start 198.057008 -17.797018)
		(end 198.414132 -18.154142)
		(width 0.12065)
		(layer "F.Cu")
		(net "MINISAS_CN16_B_I2C_INT#")
	)
	(segment
		(start 202.9714 -19.5072)
		(end 203.39685 -19.93265)
		(width 0.12065)
		(layer "F.Cu")
		(net "MINISAS_CN16_B_I2C_INT#")
	)
	(segment
		(start 275.96465 -3.600958)
		(end 275.149056 -3.600958)
		(width 0.12065)
		(layer "F.Cu")
		(net "MINISAS_CN16_B_I2C_INT#")
	)
	(segment
		(start 198.506842 -18.154142)
		(end 199.1741 -18.8214)
		(width 0.12065)
		(layer "F.Cu")
		(net "MINISAS_CN16_B_I2C_INT#")
	)
	(segment
		(start 197.8152 -17.55521)
		(end 198.057008 -17.797018)
		(width 0.12065)
		(layer "F.Cu")
		(net "MINISAS_CN16_B_I2C_INT#")
	)
	(segment
		(start 199.8599 -19.5072)
		(end 202.9714 -19.5072)
		(width 0.12065)
		(layer "F.Cu")
		(net "MINISAS_CN16_B_I2C_INT#")
	)
	(segment
		(start 198.414132 -18.154142)
		(end 198.506842 -18.154142)
		(width 0.12065)
		(layer "F.Cu")
		(net "MINISAS_CN16_B_I2C_INT#")
	)
	(segment
		(start 275.149056 -3.600958)
		(end 275.075396 -3.674618)
		(width 0.12065)
		(layer "F.Cu")
		(net "MINISAS_CN16_B_I2C_INT#")
	)
	(via
		(at 243.80317 -15.521178)
		(size 0.508)
		(drill 0.254)
		(layers "F.Cu" "B.Cu")
		(net "MINISAS_CN16_B_I2C_INT#")
	)
	(via
		(at 275.075396 -3.674618)
		(size 0.508)
		(drill 0.254)
		(layers "F.Cu" "B.Cu")
		(net "MINISAS_CN16_B_I2C_INT#")
	)
	(via
		(at 198.057008 -17.797018)
		(size 0.7112)
		(drill 0.3556)
		(layers "F.Cu" "B.Cu")
		(net "MINISAS_CN16_B_I2C_INT#")
	)
	(via
		(at 197.8152 -16.862552)
		(size 0.508)
		(drill 0.254)
		(layers "F.Cu" "B.Cu")
		(net "MINISAS_CN16_B_I2C_INT#")
	)
	(segment
		(start 245.617492 -14.426692)
		(end 244.63756 -15.406624)
		(width 0.127)
		(layer "In2.Cu")
		(net "MINISAS_CN16_B_I2C_INT#")
	)
	(segment
		(start 257.748532 -6.39445)
		(end 257.461766 -6.107684)
		(width 0.127)
		(layer "In2.Cu")
		(net "MINISAS_CN16_B_I2C_INT#")
	)
	(segment
		(start 252.86843 -6.107684)
		(end 250.768866 -8.207248)
		(width 0.127)
		(layer "In2.Cu")
		(net "MINISAS_CN16_B_I2C_INT#")
	)
	(segment
		(start 247.019826 -11.708638)
		(end 247.019826 -13.429488)
		(width 0.127)
		(layer "In2.Cu")
		(net "MINISAS_CN16_B_I2C_INT#")
	)
	(segment
		(start 246.5705 -13.878814)
		(end 246.5705 -13.98143)
		(width 0.127)
		(layer "In2.Cu")
		(net "MINISAS_CN16_B_I2C_INT#")
	)
	(segment
		(start 246.5705 -13.98143)
		(end 246.125238 -14.426692)
		(width 0.127)
		(layer "In2.Cu")
		(net "MINISAS_CN16_B_I2C_INT#")
	)
	(segment
		(start 266.45997 -5.2451)
		(end 264.166604 -5.2451)
		(width 0.127)
		(layer "In2.Cu")
		(net "MINISAS_CN16_B_I2C_INT#")
	)
	(segment
		(start 273.040094 -5.70992)
		(end 271.932146 -5.70992)
		(width 0.127)
		(layer "In2.Cu")
		(net "MINISAS_CN16_B_I2C_INT#")
	)
	(segment
		(start 250.521216 -8.207248)
		(end 247.019826 -11.708638)
		(width 0.127)
		(layer "In2.Cu")
		(net "MINISAS_CN16_B_I2C_INT#")
	)
	(segment
		(start 271.932146 -5.70992)
		(end 270.734536 -4.51231)
		(width 0.127)
		(layer "In2.Cu")
		(net "MINISAS_CN16_B_I2C_INT#")
	)
	(segment
		(start 270.734536 -4.51231)
		(end 270.734536 -3.789934)
		(width 0.127)
		(layer "In2.Cu")
		(net "MINISAS_CN16_B_I2C_INT#")
	)
	(segment
		(start 268.309598 -3.395472)
		(end 266.45997 -5.2451)
		(width 0.127)
		(layer "In2.Cu")
		(net "MINISAS_CN16_B_I2C_INT#")
	)
	(segment
		(start 244.63756 -15.406624)
		(end 243.917724 -15.406624)
		(width 0.127)
		(layer "In2.Cu")
		(net "MINISAS_CN16_B_I2C_INT#")
	)
	(segment
		(start 246.125238 -14.426692)
		(end 245.617492 -14.426692)
		(width 0.127)
		(layer "In2.Cu")
		(net "MINISAS_CN16_B_I2C_INT#")
	)
	(segment
		(start 275.075396 -3.674618)
		(end 273.040094 -5.70992)
		(width 0.127)
		(layer "In2.Cu")
		(net "MINISAS_CN16_B_I2C_INT#")
	)
	(segment
		(start 250.768866 -8.207248)
		(end 250.521216 -8.207248)
		(width 0.127)
		(layer "In2.Cu")
		(net "MINISAS_CN16_B_I2C_INT#")
	)
	(segment
		(start 243.917724 -15.406624)
		(end 243.80317 -15.521178)
		(width 0.127)
		(layer "In2.Cu")
		(net "MINISAS_CN16_B_I2C_INT#")
	)
	(segment
		(start 270.340074 -3.395472)
		(end 268.309598 -3.395472)
		(width 0.127)
		(layer "In2.Cu")
		(net "MINISAS_CN16_B_I2C_INT#")
	)
	(segment
		(start 264.166604 -5.2451)
		(end 263.017254 -6.39445)
		(width 0.127)
		(layer "In2.Cu")
		(net "MINISAS_CN16_B_I2C_INT#")
	)
	(segment
		(start 270.734536 -3.789934)
		(end 270.340074 -3.395472)
		(width 0.127)
		(layer "In2.Cu")
		(net "MINISAS_CN16_B_I2C_INT#")
	)
	(segment
		(start 247.019826 -13.429488)
		(end 246.5705 -13.878814)
		(width 0.127)
		(layer "In2.Cu")
		(net "MINISAS_CN16_B_I2C_INT#")
	)
	(segment
		(start 263.017254 -6.39445)
		(end 257.748532 -6.39445)
		(width 0.127)
		(layer "In2.Cu")
		(net "MINISAS_CN16_B_I2C_INT#")
	)
	(segment
		(start 257.461766 -6.107684)
		(end 252.86843 -6.107684)
		(width 0.127)
		(layer "In2.Cu")
		(net "MINISAS_CN16_B_I2C_INT#")
	)
	(segment
		(start 197.8152 -16.862552)
		(end 200.402952 -14.2748)
		(width 0.127)
		(layer "In5.Cu")
		(net "MINISAS_CN16_B_I2C_INT#")
	)
	(segment
		(start 243.49837 -15.8369)
		(end 243.80317 -15.5321)
		(width 0.127)
		(layer "In5.Cu")
		(net "MINISAS_CN16_B_I2C_INT#")
	)
	(segment
		(start 234.003088 -10.164318)
		(end 234.003088 -14.948916)
		(width 0.127)
		(layer "In5.Cu")
		(net "MINISAS_CN16_B_I2C_INT#")
	)
	(segment
		(start 228.797104 -11.43)
		(end 231.360726 -8.866378)
		(width 0.127)
		(layer "In5.Cu")
		(net "MINISAS_CN16_B_I2C_INT#")
	)
	(segment
		(start 219.944442 -14.2748)
		(end 222.789242 -11.43)
		(width 0.127)
		(layer "In5.Cu")
		(net "MINISAS_CN16_B_I2C_INT#")
	)
	(segment
		(start 234.003088 -14.948916)
		(end 234.891072 -15.8369)
		(width 0.127)
		(layer "In5.Cu")
		(net "MINISAS_CN16_B_I2C_INT#")
	)
	(segment
		(start 231.360726 -8.866378)
		(end 232.705148 -8.866378)
		(width 0.127)
		(layer "In5.Cu")
		(net "MINISAS_CN16_B_I2C_INT#")
	)
	(segment
		(start 222.789242 -11.43)
		(end 228.797104 -11.43)
		(width 0.127)
		(layer "In5.Cu")
		(net "MINISAS_CN16_B_I2C_INT#")
	)
	(segment
		(start 243.80317 -15.5321)
		(end 243.80317 -15.521178)
		(width 0.127)
		(layer "In5.Cu")
		(net "MINISAS_CN16_B_I2C_INT#")
	)
	(segment
		(start 234.891072 -15.8369)
		(end 243.49837 -15.8369)
		(width 0.127)
		(layer "In5.Cu")
		(net "MINISAS_CN16_B_I2C_INT#")
	)
	(segment
		(start 200.402952 -14.2748)
		(end 219.944442 -14.2748)
		(width 0.127)
		(layer "In5.Cu")
		(net "MINISAS_CN16_B_I2C_INT#")
	)
	(segment
		(start 232.705148 -8.866378)
		(end 234.003088 -10.164318)
		(width 0.127)
		(layer "In5.Cu")
		(net "MINISAS_CN16_B_I2C_INT#")
	)
	(segment
		(start 197.159118 -18.18894)
		(end 196.695568 -17.72539)
		(width 0.12065)
		(layer "F.Cu")
		(net "MINISAS_CN16_A_I2C_INT#")
	)
	(segment
		(start 199.26046 -20.35556)
		(end 202.142852 -20.35556)
		(width 0.12065)
		(layer "F.Cu")
		(net "MINISAS_CN16_A_I2C_INT#")
	)
	(segment
		(start 197.159118 -18.254218)
		(end 197.159118 -18.18894)
		(width 0.12065)
		(layer "F.Cu")
		(net "MINISAS_CN16_A_I2C_INT#")
	)
	(segment
		(start 197.7009 -18.796)
		(end 199.26046 -20.35556)
		(width 0.12065)
		(layer "F.Cu")
		(net "MINISAS_CN16_A_I2C_INT#")
	)
	(segment
		(start 197.7009 -18.796)
		(end 197.159118 -18.254218)
		(width 0.12065)
		(layer "F.Cu")
		(net "MINISAS_CN16_A_I2C_INT#")
	)
	(segment
		(start 196.695568 -17.044416)
		(end 196.946774 -16.79321)
		(width 0.12065)
		(layer "F.Cu")
		(net "MINISAS_CN16_A_I2C_INT#")
	)
	(segment
		(start 196.695568 -17.72539)
		(end 196.695568 -17.044416)
		(width 0.12065)
		(layer "F.Cu")
		(net "MINISAS_CN16_A_I2C_INT#")
	)
	(via
		(at 244.88267 -15.826232)
		(size 0.508)
		(drill 0.254)
		(layers "F.Cu" "B.Cu")
		(net "MINISAS_CN16_A_I2C_INT#")
	)
	(via
		(at 273.55038 -7.724394)
		(size 0.508)
		(drill 0.254)
		(layers "F.Cu" "B.Cu")
		(net "MINISAS_CN16_A_I2C_INT#")
	)
	(via
		(at 196.946774 -16.79321)
		(size 0.508)
		(drill 0.254)
		(layers "F.Cu" "B.Cu")
		(net "MINISAS_CN16_A_I2C_INT#")
	)
	(via
		(at 196.695568 -17.72539)
		(size 0.7112)
		(drill 0.3556)
		(layers "F.Cu" "B.Cu")
		(net "MINISAS_CN16_A_I2C_INT#")
	)
	(segment
		(start 273.55038 -7.724394)
		(end 273.191986 -7.366)
		(width 0.12065)
		(layer "B.Cu")
		(net "MINISAS_CN16_A_I2C_INT#")
	)
	(segment
		(start 273.191986 -7.366)
		(end 272.6055 -7.366)
		(width 0.12065)
		(layer "B.Cu")
		(net "MINISAS_CN16_A_I2C_INT#")
	)
	(segment
		(start 247.691148 -13.610336)
		(end 246.493792 -14.807692)
		(width 0.127)
		(layer "In2.Cu")
		(net "MINISAS_CN16_A_I2C_INT#")
	)
	(segment
		(start 266.617704 -5.626354)
		(end 264.362692 -5.626354)
		(width 0.127)
		(layer "In2.Cu")
		(net "MINISAS_CN16_A_I2C_INT#")
	)
	(segment
		(start 257.590544 -6.77545)
		(end 257.384042 -6.568948)
		(width 0.127)
		(layer "In2.Cu")
		(net "MINISAS_CN16_A_I2C_INT#")
	)
	(segment
		(start 273.55038 -7.724394)
		(end 273.217894 -7.391908)
		(width 0.127)
		(layer "In2.Cu")
		(net "MINISAS_CN16_A_I2C_INT#")
	)
	(segment
		(start 250.7107 -8.588248)
		(end 247.691148 -11.6078)
		(width 0.127)
		(layer "In2.Cu")
		(net "MINISAS_CN16_A_I2C_INT#")
	)
	(segment
		(start 263.068054 -6.775704)
		(end 263.0678 -6.77545)
		(width 0.127)
		(layer "In2.Cu")
		(net "MINISAS_CN16_A_I2C_INT#")
	)
	(segment
		(start 252.946154 -6.568948)
		(end 250.926854 -8.588248)
		(width 0.127)
		(layer "In2.Cu")
		(net "MINISAS_CN16_A_I2C_INT#")
	)
	(segment
		(start 245.90121 -14.807692)
		(end 244.88267 -15.826232)
		(width 0.127)
		(layer "In2.Cu")
		(net "MINISAS_CN16_A_I2C_INT#")
	)
	(segment
		(start 270.353536 -4.466082)
		(end 269.663926 -3.776472)
		(width 0.127)
		(layer "In2.Cu")
		(net "MINISAS_CN16_A_I2C_INT#")
	)
	(segment
		(start 257.384042 -6.568948)
		(end 252.946154 -6.568948)
		(width 0.127)
		(layer "In2.Cu")
		(net "MINISAS_CN16_A_I2C_INT#")
	)
	(segment
		(start 246.493792 -14.807692)
		(end 245.90121 -14.807692)
		(width 0.127)
		(layer "In2.Cu")
		(net "MINISAS_CN16_A_I2C_INT#")
	)
	(segment
		(start 264.362692 -5.626354)
		(end 263.213342 -6.775704)
		(width 0.127)
		(layer "In2.Cu")
		(net "MINISAS_CN16_A_I2C_INT#")
	)
	(segment
		(start 263.213342 -6.775704)
		(end 263.068054 -6.775704)
		(width 0.127)
		(layer "In2.Cu")
		(net "MINISAS_CN16_A_I2C_INT#")
	)
	(segment
		(start 247.691148 -11.6078)
		(end 247.691148 -13.610336)
		(width 0.127)
		(layer "In2.Cu")
		(net "MINISAS_CN16_A_I2C_INT#")
	)
	(segment
		(start 273.075146 -7.391908)
		(end 270.353536 -4.670298)
		(width 0.127)
		(layer "In2.Cu")
		(net "MINISAS_CN16_A_I2C_INT#")
	)
	(segment
		(start 250.926854 -8.588248)
		(end 250.7107 -8.588248)
		(width 0.127)
		(layer "In2.Cu")
		(net "MINISAS_CN16_A_I2C_INT#")
	)
	(segment
		(start 273.217894 -7.391908)
		(end 273.075146 -7.391908)
		(width 0.127)
		(layer "In2.Cu")
		(net "MINISAS_CN16_A_I2C_INT#")
	)
	(segment
		(start 268.467586 -3.776472)
		(end 266.617704 -5.626354)
		(width 0.127)
		(layer "In2.Cu")
		(net "MINISAS_CN16_A_I2C_INT#")
	)
	(segment
		(start 270.353536 -4.670298)
		(end 270.353536 -4.466082)
		(width 0.127)
		(layer "In2.Cu")
		(net "MINISAS_CN16_A_I2C_INT#")
	)
	(segment
		(start 263.0678 -6.77545)
		(end 257.590544 -6.77545)
		(width 0.127)
		(layer "In2.Cu")
		(net "MINISAS_CN16_A_I2C_INT#")
	)
	(segment
		(start 269.663926 -3.776472)
		(end 268.467586 -3.776472)
		(width 0.127)
		(layer "In2.Cu")
		(net "MINISAS_CN16_A_I2C_INT#")
	)
	(segment
		(start 236.189012 -15.30223)
		(end 234.384088 -13.497306)
		(width 0.127)
		(layer "In5.Cu")
		(net "MINISAS_CN16_A_I2C_INT#")
	)
	(segment
		(start 231.090216 -8.5979)
		(end 216.465912 -8.5979)
		(width 0.127)
		(layer "In5.Cu")
		(net "MINISAS_CN16_A_I2C_INT#")
	)
	(segment
		(start 243.70538 -14.961362)
		(end 243.615464 -15.051278)
		(width 0.127)
		(layer "In5.Cu")
		(net "MINISAS_CN16_A_I2C_INT#")
	)
	(segment
		(start 244.0178 -14.961362)
		(end 243.70538 -14.961362)
		(width 0.127)
		(layer "In5.Cu")
		(net "MINISAS_CN16_A_I2C_INT#")
	)
	(segment
		(start 216.465912 -8.5979)
		(end 211.170012 -13.8938)
		(width 0.127)
		(layer "In5.Cu")
		(net "MINISAS_CN16_A_I2C_INT#")
	)
	(segment
		(start 231.202738 -8.485378)
		(end 231.090216 -8.5979)
		(width 0.127)
		(layer "In5.Cu")
		(net "MINISAS_CN16_A_I2C_INT#")
	)
	(segment
		(start 234.384088 -10.00633)
		(end 232.863136 -8.485378)
		(width 0.127)
		(layer "In5.Cu")
		(net "MINISAS_CN16_A_I2C_INT#")
	)
	(segment
		(start 232.863136 -8.485378)
		(end 231.202738 -8.485378)
		(width 0.127)
		(layer "In5.Cu")
		(net "MINISAS_CN16_A_I2C_INT#")
	)
	(segment
		(start 234.384088 -13.497306)
		(end 234.384088 -10.00633)
		(width 0.127)
		(layer "In5.Cu")
		(net "MINISAS_CN16_A_I2C_INT#")
	)
	(segment
		(start 211.170012 -13.8938)
		(end 199.846184 -13.8938)
		(width 0.127)
		(layer "In5.Cu")
		(net "MINISAS_CN16_A_I2C_INT#")
	)
	(segment
		(start 243.615464 -15.051278)
		(end 243.608352 -15.051278)
		(width 0.127)
		(layer "In5.Cu")
		(net "MINISAS_CN16_A_I2C_INT#")
	)
	(segment
		(start 243.608352 -15.051278)
		(end 243.3574 -15.30223)
		(width 0.127)
		(layer "In5.Cu")
		(net "MINISAS_CN16_A_I2C_INT#")
	)
	(segment
		(start 199.846184 -13.8938)
		(end 196.946774 -16.79321)
		(width 0.127)
		(layer "In5.Cu")
		(net "MINISAS_CN16_A_I2C_INT#")
	)
	(segment
		(start 244.88267 -15.826232)
		(end 244.0178 -14.961362)
		(width 0.127)
		(layer "In5.Cu")
		(net "MINISAS_CN16_A_I2C_INT#")
	)
	(segment
		(start 243.3574 -15.30223)
		(end 236.189012 -15.30223)
		(width 0.127)
		(layer "In5.Cu")
		(net "MINISAS_CN16_A_I2C_INT#")
	)
	(segment
		(start 166.5605 -88.5444)
		(end 166.92372 -88.90762)
		(width 0.136652)
		(layer "F.Cu")
		(net "I210_REFCLK_D_P")
	)
	(segment
		(start 167.440356 -88.90762)
		(end 167.701976 -88.646)
		(width 0.136652)
		(layer "F.Cu")
		(net "I210_REFCLK_D_P")
	)
	(segment
		(start 17.7292 -82.414872)
		(end 17.52092 -82.206592)
		(width 0.136652)
		(layer "F.Cu")
		(net "I210_REFCLK_D_P")
	)
	(segment
		(start 17.3101 -85.7758)
		(end 17.7292 -85.3567)
		(width 0.136652)
		(layer "F.Cu")
		(net "I210_REFCLK_D_P")
	)
	(segment
		(start 166.92372 -88.90762)
		(end 167.440356 -88.90762)
		(width 0.136652)
		(layer "F.Cu")
		(net "I210_REFCLK_D_P")
	)
	(segment
		(start 17.52092 -80.858868)
		(end 17.410938 -80.748886)
		(width 0.136652)
		(layer "F.Cu")
		(net "I210_REFCLK_D_P")
	)
	(segment
		(start 17.52092 -82.206592)
		(end 17.52092 -80.858868)
		(width 0.136652)
		(layer "F.Cu")
		(net "I210_REFCLK_D_P")
	)
	(segment
		(start 16.2814 -86.614)
		(end 16.2814 -86.214204)
		(width 0.136652)
		(layer "F.Cu")
		(net "I210_REFCLK_D_P")
	)
	(segment
		(start 17.410938 -80.748886)
		(end 17.410938 -80.090518)
		(width 0.136652)
		(layer "F.Cu")
		(net "I210_REFCLK_D_P")
	)
	(segment
		(start 16.719804 -85.7758)
		(end 17.3101 -85.7758)
		(width 0.136652)
		(layer "F.Cu")
		(net "I210_REFCLK_D_P")
	)
	(segment
		(start 15.8496 -87.0458)
		(end 16.2814 -86.614)
		(width 0.136652)
		(layer "F.Cu")
		(net "I210_REFCLK_D_P")
	)
	(segment
		(start 16.2814 -86.214204)
		(end 16.719804 -85.7758)
		(width 0.136652)
		(layer "F.Cu")
		(net "I210_REFCLK_D_P")
	)
	(segment
		(start 17.7292 -85.3567)
		(end 17.7292 -82.414872)
		(width 0.136652)
		(layer "F.Cu")
		(net "I210_REFCLK_D_P")
	)
	(via
		(at 167.701976 -88.646)
		(size 0.508)
		(drill 0.254)
		(layers "F.Cu" "B.Cu")
		(net "I210_REFCLK_D_P")
	)
	(via
		(at 86.779608 -76.589636)
		(size 0.508)
		(drill 0.254)
		(layers "F.Cu" "B.Cu")
		(net "I210_REFCLK_D_P")
	)
	(via
		(at 15.8496 -87.0458)
		(size 0.508)
		(drill 0.254)
		(layers "F.Cu" "B.Cu")
		(net "I210_REFCLK_D_P")
	)
	(segment
		(start 21.357336 -85.202268)
		(end 21.704046 -85.128354)
		(width 0.1397)
		(layer "In2.Cu")
		(net "I210_REFCLK_D_P")
	)
	(segment
		(start 49.17567 -78.751176)
		(end 51.919124 -79.333598)
		(width 0.1397)
		(layer "In2.Cu")
		(net "I210_REFCLK_D_P")
	)
	(segment
		(start 59.394344 -79.6544)
		(end 66.709798 -81.209388)
		(width 0.1397)
		(layer "In2.Cu")
		(net "I210_REFCLK_D_P")
	)
	(segment
		(start 78.333346 -80.896206)
		(end 79.186786 -80.71485)
		(width 0.1397)
		(layer "In2.Cu")
		(net "I210_REFCLK_D_P")
	)
	(segment
		(start 85.110574 -76.869036)
		(end 86.500208 -76.869036)
		(width 0.1397)
		(layer "In2.Cu")
		(net "I210_REFCLK_D_P")
	)
	(segment
		(start 51.919124 -79.333598)
		(end 51.919378 -79.333598)
		(width 0.1397)
		(layer "In2.Cu")
		(net "I210_REFCLK_D_P")
	)
	(segment
		(start 18.047208 -84.979764)
		(end 19.179032 -84.738972)
		(width 0.1397)
		(layer "In2.Cu")
		(net "I210_REFCLK_D_P")
	)
	(segment
		(start 26.274268 -80.855566)
		(end 27.285442 -80.640428)
		(width 0.1397)
		(layer "In2.Cu")
		(net "I210_REFCLK_D_P")
	)
	(segment
		(start 33.54705 -81.421986)
		(end 35.811206 -81.9023)
		(width 0.1397)
		(layer "In2.Cu")
		(net "I210_REFCLK_D_P")
	)
	(segment
		(start 66.709798 -81.209388)
		(end 74.131932 -79.631794)
		(width 0.1397)
		(layer "In2.Cu")
		(net "I210_REFCLK_D_P")
	)
	(segment
		(start 35.811206 -81.902046)
		(end 37.938456 -82.353404)
		(width 0.1397)
		(layer "In2.Cu")
		(net "I210_REFCLK_D_P")
	)
	(segment
		(start 15.8496 -87.0458)
		(end 16.2433 -86.6521)
		(width 0.1397)
		(layer "In2.Cu")
		(net "I210_REFCLK_D_P")
	)
	(segment
		(start 19.179032 -84.738972)
		(end 21.357336 -85.202268)
		(width 0.1397)
		(layer "In2.Cu")
		(net "I210_REFCLK_D_P")
	)
	(segment
		(start 27.285442 -80.640428)
		(end 32.253682 -81.696814)
		(width 0.1397)
		(layer "In2.Cu")
		(net "I210_REFCLK_D_P")
	)
	(segment
		(start 76.16698 -80.06461)
		(end 77.017118 -80.616552)
		(width 0.1397)
		(layer "In2.Cu")
		(net "I210_REFCLK_D_P")
	)
	(segment
		(start 32.253682 -81.696814)
		(end 33.54705 -81.421986)
		(width 0.1397)
		(layer "In2.Cu")
		(net "I210_REFCLK_D_P")
	)
	(segment
		(start 35.811206 -81.9023)
		(end 35.811206 -81.902046)
		(width 0.1397)
		(layer "In2.Cu")
		(net "I210_REFCLK_D_P")
	)
	(segment
		(start 16.2433 -86.6521)
		(end 16.2433 -86.235794)
		(width 0.1397)
		(layer "In2.Cu")
		(net "I210_REFCLK_D_P")
	)
	(segment
		(start 21.704046 -85.128354)
		(end 22.15007 -84.838794)
		(width 0.1397)
		(layer "In2.Cu")
		(net "I210_REFCLK_D_P")
	)
	(segment
		(start 23.616412 -82.581242)
		(end 26.274268 -80.855566)
		(width 0.1397)
		(layer "In2.Cu")
		(net "I210_REFCLK_D_P")
	)
	(segment
		(start 56.411368 -80.288384)
		(end 59.394344 -79.6544)
		(width 0.1397)
		(layer "In2.Cu")
		(net "I210_REFCLK_D_P")
	)
	(segment
		(start 22.15007 -84.838794)
		(end 23.616412 -82.581242)
		(width 0.1397)
		(layer "In2.Cu")
		(net "I210_REFCLK_D_P")
	)
	(segment
		(start 16.2433 -86.235794)
		(end 16.559784 -85.91931)
		(width 0.1397)
		(layer "In2.Cu")
		(net "I210_REFCLK_D_P")
	)
	(segment
		(start 74.131932 -79.631794)
		(end 76.16698 -80.06461)
		(width 0.1397)
		(layer "In2.Cu")
		(net "I210_REFCLK_D_P")
	)
	(segment
		(start 18.047208 -84.97951)
		(end 18.047208 -84.979764)
		(width 0.1397)
		(layer "In2.Cu")
		(net "I210_REFCLK_D_P")
	)
	(segment
		(start 79.186786 -80.71485)
		(end 85.110574 -76.869036)
		(width 0.1397)
		(layer "In2.Cu")
		(net "I210_REFCLK_D_P")
	)
	(segment
		(start 45.527976 -79.526892)
		(end 49.17567 -78.751176)
		(width 0.1397)
		(layer "In2.Cu")
		(net "I210_REFCLK_D_P")
	)
	(segment
		(start 42.74947 -81.3308)
		(end 45.527976 -79.526892)
		(width 0.1397)
		(layer "In2.Cu")
		(net "I210_REFCLK_D_P")
	)
	(segment
		(start 37.938456 -82.353404)
		(end 42.74947 -81.3308)
		(width 0.1397)
		(layer "In2.Cu")
		(net "I210_REFCLK_D_P")
	)
	(segment
		(start 51.919378 -79.333598)
		(end 56.411368 -80.288384)
		(width 0.1397)
		(layer "In2.Cu")
		(net "I210_REFCLK_D_P")
	)
	(segment
		(start 17.987264 -84.992464)
		(end 18.047208 -84.97951)
		(width 0.1397)
		(layer "In2.Cu")
		(net "I210_REFCLK_D_P")
	)
	(segment
		(start 86.500208 -76.869036)
		(end 86.779608 -76.589636)
		(width 0.1397)
		(layer "In2.Cu")
		(net "I210_REFCLK_D_P")
	)
	(segment
		(start 16.559784 -85.91931)
		(end 17.987264 -84.992464)
		(width 0.1397)
		(layer "In2.Cu")
		(net "I210_REFCLK_D_P")
	)
	(segment
		(start 77.017118 -80.616552)
		(end 78.333346 -80.896206)
		(width 0.1397)
		(layer "In2.Cu")
		(net "I210_REFCLK_D_P")
	)
	(segment
		(start 167.111172 -88.889078)
		(end 167.458898 -88.889078)
		(width 0.1397)
		(layer "In5.Cu")
		(net "I210_REFCLK_D_P")
	)
	(segment
		(start 165.165024 -87.625174)
		(end 167.111172 -88.889078)
		(width 0.1397)
		(layer "In5.Cu")
		(net "I210_REFCLK_D_P")
	)
	(segment
		(start 136.682226 -79.281274)
		(end 136.72566 -79.290672)
		(width 0.1397)
		(layer "In5.Cu")
		(net "I210_REFCLK_D_P")
	)
	(segment
		(start 136.64819 -79.274162)
		(end 136.682226 -79.281274)
		(width 0.1397)
		(layer "In5.Cu")
		(net "I210_REFCLK_D_P")
	)
	(segment
		(start 86.779608 -76.589636)
		(end 87.059008 -76.869036)
		(width 0.1397)
		(layer "In5.Cu")
		(net "I210_REFCLK_D_P")
	)
	(segment
		(start 137.52322 -79.46009)
		(end 138.616944 -80.170274)
		(width 0.1397)
		(layer "In5.Cu")
		(net "I210_REFCLK_D_P")
	)
	(segment
		(start 140.953998 -81.9912)
		(end 143.620998 -81.9912)
		(width 0.1397)
		(layer "In5.Cu")
		(net "I210_REFCLK_D_P")
	)
	(segment
		(start 143.804894 -81.914746)
		(end 144.192244 -81.527396)
		(width 0.1397)
		(layer "In5.Cu")
		(net "I210_REFCLK_D_P")
	)
	(segment
		(start 121.610374 -76.074778)
		(end 136.642348 -79.272892)
		(width 0.1397)
		(layer "In5.Cu")
		(net "I210_REFCLK_D_P")
	)
	(segment
		(start 138.655044 -80.228694)
		(end 138.655044 -80.228948)
		(width 0.1397)
		(layer "In5.Cu")
		(net "I210_REFCLK_D_P")
	)
	(segment
		(start 110.96117 -78.351126)
		(end 121.610374 -76.074778)
		(width 0.1397)
		(layer "In5.Cu")
		(net "I210_REFCLK_D_P")
	)
	(segment
		(start 138.655044 -80.228948)
		(end 139.319 -81.251298)
		(width 0.1397)
		(layer "In5.Cu")
		(net "I210_REFCLK_D_P")
	)
	(segment
		(start 139.319 -81.251298)
		(end 140.21689 -81.834228)
		(width 0.1397)
		(layer "In5.Cu")
		(net "I210_REFCLK_D_P")
	)
	(segment
		(start 140.21689 -81.834228)
		(end 140.953998 -81.9912)
		(width 0.1397)
		(layer "In5.Cu")
		(net "I210_REFCLK_D_P")
	)
	(segment
		(start 136.72566 -79.290672)
		(end 137.52322 -79.46009)
		(width 0.1397)
		(layer "In5.Cu")
		(net "I210_REFCLK_D_P")
	)
	(segment
		(start 144.891252 -81.23809)
		(end 159.516318 -81.23809)
		(width 0.1397)
		(layer "In5.Cu")
		(net "I210_REFCLK_D_P")
	)
	(segment
		(start 92.837 -76.869036)
		(end 98.63201 -75.637136)
		(width 0.1397)
		(layer "In5.Cu")
		(net "I210_REFCLK_D_P")
	)
	(segment
		(start 87.059008 -76.869036)
		(end 92.837 -76.869036)
		(width 0.1397)
		(layer "In5.Cu")
		(net "I210_REFCLK_D_P")
	)
	(segment
		(start 98.63201 -75.637136)
		(end 104.79659 -76.994258)
		(width 0.1397)
		(layer "In5.Cu")
		(net "I210_REFCLK_D_P")
	)
	(segment
		(start 104.79659 -76.994258)
		(end 110.96117 -78.351126)
		(width 0.1397)
		(layer "In5.Cu")
		(net "I210_REFCLK_D_P")
	)
	(segment
		(start 138.616944 -80.170274)
		(end 138.655044 -80.228694)
		(width 0.1397)
		(layer "In5.Cu")
		(net "I210_REFCLK_D_P")
	)
	(segment
		(start 160.948878 -81.957672)
		(end 165.165024 -87.625174)
		(width 0.1397)
		(layer "In5.Cu")
		(net "I210_REFCLK_D_P")
	)
	(segment
		(start 136.642348 -79.272892)
		(end 136.64819 -79.274162)
		(width 0.1397)
		(layer "In5.Cu")
		(net "I210_REFCLK_D_P")
	)
	(segment
		(start 167.458898 -88.889078)
		(end 167.701976 -88.646)
		(width 0.1397)
		(layer "In5.Cu")
		(net "I210_REFCLK_D_P")
	)
	(arc
		(start 159.516318 -81.23809)
		(mid 160.317919 -81.428033)
		(end 160.948878 -81.957672)
		(width 0.1397)
		(layer "In5.Cu")
		(net "I210_REFCLK_D_P")
	)
	(arc
		(start 144.192244 -81.527396)
		(mid 144.512995 -81.313296)
		(end 144.891252 -81.23809)
		(width 0.1397)
		(layer "In5.Cu")
		(net "I210_REFCLK_D_P")
	)
	(arc
		(start 143.620998 -81.9912)
		(mid 143.720562 -81.971284)
		(end 143.804894 -81.914746)
		(width 0.1397)
		(layer "In5.Cu")
		(net "I210_REFCLK_D_P")
	)
	(segment
		(start 17.911064 -80.743044)
		(end 17.911064 -80.090518)
		(width 0.136652)
		(layer "F.Cu")
		(net "I210_REFCLK_D_N")
	)
	(segment
		(start 16.9672 -87.0458)
		(end 16.5862 -86.6648)
		(width 0.136652)
		(layer "F.Cu")
		(net "I210_REFCLK_D_N")
	)
	(segment
		(start 17.436592 -86.0806)
		(end 18.034 -85.483192)
		(width 0.136652)
		(layer "F.Cu")
		(net "I210_REFCLK_D_N")
	)
	(segment
		(start 17.82572 -80.828388)
		(end 17.911064 -80.743044)
		(width 0.136652)
		(layer "F.Cu")
		(net "I210_REFCLK_D_N")
	)
	(segment
		(start 18.034 -85.483192)
		(end 18.034 -82.28838)
		(width 0.136652)
		(layer "F.Cu")
		(net "I210_REFCLK_D_N")
	)
	(segment
		(start 166.5605 -89.5604)
		(end 166.90848 -89.21242)
		(width 0.136652)
		(layer "F.Cu")
		(net "I210_REFCLK_D_N")
	)
	(segment
		(start 16.846296 -86.0806)
		(end 17.436592 -86.0806)
		(width 0.136652)
		(layer "F.Cu")
		(net "I210_REFCLK_D_N")
	)
	(segment
		(start 16.5862 -86.340696)
		(end 16.846296 -86.0806)
		(width 0.136652)
		(layer "F.Cu")
		(net "I210_REFCLK_D_N")
	)
	(segment
		(start 166.90848 -89.21242)
		(end 167.455596 -89.21242)
		(width 0.136652)
		(layer "F.Cu")
		(net "I210_REFCLK_D_N")
	)
	(segment
		(start 16.5862 -86.6648)
		(end 16.5862 -86.340696)
		(width 0.136652)
		(layer "F.Cu")
		(net "I210_REFCLK_D_N")
	)
	(segment
		(start 17.82572 -82.0801)
		(end 17.82572 -80.828388)
		(width 0.136652)
		(layer "F.Cu")
		(net "I210_REFCLK_D_N")
	)
	(segment
		(start 167.455596 -89.21242)
		(end 167.701976 -89.4588)
		(width 0.136652)
		(layer "F.Cu")
		(net "I210_REFCLK_D_N")
	)
	(segment
		(start 18.034 -82.28838)
		(end 17.82572 -82.0801)
		(width 0.136652)
		(layer "F.Cu")
		(net "I210_REFCLK_D_N")
	)
	(via
		(at 167.701976 -89.4588)
		(size 0.508)
		(drill 0.254)
		(layers "F.Cu" "B.Cu")
		(net "I210_REFCLK_D_N")
	)
	(via
		(at 16.9672 -87.0458)
		(size 0.508)
		(drill 0.254)
		(layers "F.Cu" "B.Cu")
		(net "I210_REFCLK_D_N")
	)
	(via
		(at 86.779608 -77.478636)
		(size 0.508)
		(drill 0.254)
		(layers "F.Cu" "B.Cu")
		(net "I210_REFCLK_D_N")
	)
	(segment
		(start 78.333346 -81.234026)
		(end 79.31531 -81.025238)
		(width 0.1397)
		(layer "In2.Cu")
		(net "I210_REFCLK_D_N")
	)
	(segment
		(start 32.253682 -82.034634)
		(end 33.54705 -81.759806)
		(width 0.1397)
		(layer "In2.Cu")
		(net "I210_REFCLK_D_N")
	)
	(segment
		(start 21.357336 -85.540088)
		(end 21.832824 -85.438742)
		(width 0.1397)
		(layer "In2.Cu")
		(net "I210_REFCLK_D_N")
	)
	(segment
		(start 74.131932 -79.969614)
		(end 76.038456 -80.374998)
		(width 0.1397)
		(layer "In2.Cu")
		(net "I210_REFCLK_D_N")
	)
	(segment
		(start 79.31531 -81.025238)
		(end 85.208364 -77.199236)
		(width 0.1397)
		(layer "In2.Cu")
		(net "I210_REFCLK_D_N")
	)
	(segment
		(start 18.115788 -85.302852)
		(end 19.179032 -85.076792)
		(width 0.1397)
		(layer "In2.Cu")
		(net "I210_REFCLK_D_N")
	)
	(segment
		(start 33.54705 -81.759806)
		(end 37.938456 -82.691224)
		(width 0.1397)
		(layer "In2.Cu")
		(net "I210_REFCLK_D_N")
	)
	(segment
		(start 22.38883 -85.077554)
		(end 23.855172 -82.820002)
		(width 0.1397)
		(layer "In2.Cu")
		(net "I210_REFCLK_D_N")
	)
	(segment
		(start 76.888594 -80.92694)
		(end 78.333346 -81.234026)
		(width 0.1397)
		(layer "In2.Cu")
		(net "I210_REFCLK_D_N")
	)
	(segment
		(start 16.768826 -86.177374)
		(end 18.115788 -85.302852)
		(width 0.1397)
		(layer "In2.Cu")
		(net "I210_REFCLK_D_N")
	)
	(segment
		(start 16.5735 -86.3727)
		(end 16.768826 -86.177374)
		(width 0.1397)
		(layer "In2.Cu")
		(net "I210_REFCLK_D_N")
	)
	(segment
		(start 49.17567 -79.088996)
		(end 56.411368 -80.626204)
		(width 0.1397)
		(layer "In2.Cu")
		(net "I210_REFCLK_D_N")
	)
	(segment
		(start 86.500208 -77.199236)
		(end 86.779608 -77.478636)
		(width 0.1397)
		(layer "In2.Cu")
		(net "I210_REFCLK_D_N")
	)
	(segment
		(start 59.394344 -79.99222)
		(end 66.709798 -81.547208)
		(width 0.1397)
		(layer "In2.Cu")
		(net "I210_REFCLK_D_N")
	)
	(segment
		(start 85.208364 -77.199236)
		(end 86.500208 -77.199236)
		(width 0.1397)
		(layer "In2.Cu")
		(net "I210_REFCLK_D_N")
	)
	(segment
		(start 19.179032 -85.076792)
		(end 21.357336 -85.540088)
		(width 0.1397)
		(layer "In2.Cu")
		(net "I210_REFCLK_D_N")
	)
	(segment
		(start 26.402792 -81.165954)
		(end 27.285442 -80.978248)
		(width 0.1397)
		(layer "In2.Cu")
		(net "I210_REFCLK_D_N")
	)
	(segment
		(start 37.938456 -82.691224)
		(end 42.877994 -81.641188)
		(width 0.1397)
		(layer "In2.Cu")
		(net "I210_REFCLK_D_N")
	)
	(segment
		(start 66.709798 -81.547208)
		(end 74.131932 -79.969614)
		(width 0.1397)
		(layer "In2.Cu")
		(net "I210_REFCLK_D_N")
	)
	(segment
		(start 23.855172 -82.820002)
		(end 26.402792 -81.165954)
		(width 0.1397)
		(layer "In2.Cu")
		(net "I210_REFCLK_D_N")
	)
	(segment
		(start 27.285442 -80.978248)
		(end 32.253682 -82.034634)
		(width 0.1397)
		(layer "In2.Cu")
		(net "I210_REFCLK_D_N")
	)
	(segment
		(start 76.038456 -80.374998)
		(end 76.888594 -80.92694)
		(width 0.1397)
		(layer "In2.Cu")
		(net "I210_REFCLK_D_N")
	)
	(segment
		(start 42.877994 -81.641188)
		(end 45.6565 -79.83728)
		(width 0.1397)
		(layer "In2.Cu")
		(net "I210_REFCLK_D_N")
	)
	(segment
		(start 45.6565 -79.83728)
		(end 49.17567 -79.088996)
		(width 0.1397)
		(layer "In2.Cu")
		(net "I210_REFCLK_D_N")
	)
	(segment
		(start 21.832824 -85.438742)
		(end 22.38883 -85.077554)
		(width 0.1397)
		(layer "In2.Cu")
		(net "I210_REFCLK_D_N")
	)
	(segment
		(start 16.9672 -87.0458)
		(end 16.5735 -86.6521)
		(width 0.1397)
		(layer "In2.Cu")
		(net "I210_REFCLK_D_N")
	)
	(segment
		(start 56.411368 -80.626204)
		(end 59.394344 -79.99222)
		(width 0.1397)
		(layer "In2.Cu")
		(net "I210_REFCLK_D_N")
	)
	(segment
		(start 16.5735 -86.6521)
		(end 16.5735 -86.3727)
		(width 0.1397)
		(layer "In2.Cu")
		(net "I210_REFCLK_D_N")
	)
	(segment
		(start 149.648672 -81.56829)
		(end 149.826472 -81.74609)
		(width 0.1397)
		(layer "In5.Cu")
		(net "I210_REFCLK_D_N")
	)
	(segment
		(start 149.826472 -81.74609)
		(end 150.245572 -81.74609)
		(width 0.1397)
		(layer "In5.Cu")
		(net "I210_REFCLK_D_N")
	)
	(segment
		(start 151.617172 -81.56829)
		(end 152.036272 -81.56829)
		(width 0.1397)
		(layer "In5.Cu")
		(net "I210_REFCLK_D_N")
	)
	(segment
		(start 86.779608 -77.478636)
		(end 87.059008 -77.199236)
		(width 0.1397)
		(layer "In5.Cu")
		(net "I210_REFCLK_D_N")
	)
	(segment
		(start 144.891252 -81.56829)
		(end 149.648672 -81.56829)
		(width 0.1397)
		(layer "In5.Cu")
		(net "I210_REFCLK_D_N")
	)
	(segment
		(start 164.935408 -87.87003)
		(end 167.013128 -89.219278)
		(width 0.1397)
		(layer "In5.Cu")
		(net "I210_REFCLK_D_N")
	)
	(segment
		(start 87.059008 -77.199236)
		(end 91.677998 -77.199236)
		(width 0.1397)
		(layer "In5.Cu")
		(net "I210_REFCLK_D_N")
	)
	(segment
		(start 92.871798 -77.199236)
		(end 98.63074 -75.97521)
		(width 0.1397)
		(layer "In5.Cu")
		(net "I210_REFCLK_D_N")
	)
	(segment
		(start 91.855798 -77.377036)
		(end 92.274898 -77.377036)
		(width 0.1397)
		(layer "In5.Cu")
		(net "I210_REFCLK_D_N")
	)
	(segment
		(start 110.960154 -78.6892)
		(end 121.610628 -76.412598)
		(width 0.1397)
		(layer "In5.Cu")
		(net "I210_REFCLK_D_N")
	)
	(segment
		(start 92.452698 -77.199236)
		(end 92.871798 -77.199236)
		(width 0.1397)
		(layer "In5.Cu")
		(net "I210_REFCLK_D_N")
	)
	(segment
		(start 167.013128 -89.219278)
		(end 167.462454 -89.219278)
		(width 0.1397)
		(layer "In5.Cu")
		(net "I210_REFCLK_D_N")
	)
	(segment
		(start 91.677998 -77.199236)
		(end 91.855798 -77.377036)
		(width 0.1397)
		(layer "In5.Cu")
		(net "I210_REFCLK_D_N")
	)
	(segment
		(start 167.462454 -89.219278)
		(end 167.701976 -89.4588)
		(width 0.1397)
		(layer "In5.Cu")
		(net "I210_REFCLK_D_N")
	)
	(segment
		(start 151.439372 -81.74609)
		(end 151.617172 -81.56829)
		(width 0.1397)
		(layer "In5.Cu")
		(net "I210_REFCLK_D_N")
	)
	(segment
		(start 138.378184 -80.409034)
		(end 139.08024 -81.490058)
		(width 0.1397)
		(layer "In5.Cu")
		(net "I210_REFCLK_D_N")
	)
	(segment
		(start 121.610628 -76.412598)
		(end 136.572244 -79.595726)
		(width 0.1397)
		(layer "In5.Cu")
		(net "I210_REFCLK_D_N")
	)
	(segment
		(start 139.08024 -81.490058)
		(end 140.088366 -82.144616)
		(width 0.1397)
		(layer "In5.Cu")
		(net "I210_REFCLK_D_N")
	)
	(segment
		(start 137.394696 -79.770478)
		(end 138.378184 -80.409034)
		(width 0.1397)
		(layer "In5.Cu")
		(net "I210_REFCLK_D_N")
	)
	(segment
		(start 140.088366 -82.144616)
		(end 140.9192 -82.3214)
		(width 0.1397)
		(layer "In5.Cu")
		(net "I210_REFCLK_D_N")
	)
	(segment
		(start 137.026142 -79.692246)
		(end 137.026142 -79.6925)
		(width 0.1397)
		(layer "In5.Cu")
		(net "I210_REFCLK_D_N")
	)
	(segment
		(start 136.572244 -79.595726)
		(end 137.026142 -79.692246)
		(width 0.1397)
		(layer "In5.Cu")
		(net "I210_REFCLK_D_N")
	)
	(segment
		(start 151.020272 -81.74609)
		(end 151.439372 -81.74609)
		(width 0.1397)
		(layer "In5.Cu")
		(net "I210_REFCLK_D_N")
	)
	(segment
		(start 160.683956 -82.154776)
		(end 164.935408 -87.87003)
		(width 0.1397)
		(layer "In5.Cu")
		(net "I210_REFCLK_D_N")
	)
	(segment
		(start 150.842472 -81.56829)
		(end 151.020272 -81.74609)
		(width 0.1397)
		(layer "In5.Cu")
		(net "I210_REFCLK_D_N")
	)
	(segment
		(start 150.245572 -81.74609)
		(end 150.423372 -81.56829)
		(width 0.1397)
		(layer "In5.Cu")
		(net "I210_REFCLK_D_N")
	)
	(segment
		(start 144.038574 -82.148172)
		(end 144.425924 -81.761076)
		(width 0.1397)
		(layer "In5.Cu")
		(net "I210_REFCLK_D_N")
	)
	(segment
		(start 137.026142 -79.6925)
		(end 137.394696 -79.770478)
		(width 0.1397)
		(layer "In5.Cu")
		(net "I210_REFCLK_D_N")
	)
	(segment
		(start 140.9192 -82.3214)
		(end 143.621252 -82.3214)
		(width 0.1397)
		(layer "In5.Cu")
		(net "I210_REFCLK_D_N")
	)
	(segment
		(start 152.036272 -81.56829)
		(end 152.214072 -81.74609)
		(width 0.1397)
		(layer "In5.Cu")
		(net "I210_REFCLK_D_N")
	)
	(segment
		(start 92.274898 -77.377036)
		(end 92.452698 -77.199236)
		(width 0.1397)
		(layer "In5.Cu")
		(net "I210_REFCLK_D_N")
	)
	(segment
		(start 152.633172 -81.74609)
		(end 152.810972 -81.56829)
		(width 0.1397)
		(layer "In5.Cu")
		(net "I210_REFCLK_D_N")
	)
	(segment
		(start 98.63074 -75.97521)
		(end 110.960154 -78.6892)
		(width 0.1397)
		(layer "In5.Cu")
		(net "I210_REFCLK_D_N")
	)
	(segment
		(start 152.810972 -81.56829)
		(end 159.516572 -81.56829)
		(width 0.1397)
		(layer "In5.Cu")
		(net "I210_REFCLK_D_N")
	)
	(segment
		(start 152.214072 -81.74609)
		(end 152.633172 -81.74609)
		(width 0.1397)
		(layer "In5.Cu")
		(net "I210_REFCLK_D_N")
	)
	(segment
		(start 150.423372 -81.56829)
		(end 150.842472 -81.56829)
		(width 0.1397)
		(layer "In5.Cu")
		(net "I210_REFCLK_D_N")
	)
	(arc
		(start 143.621252 -82.3214)
		(mid 143.847124 -82.276266)
		(end 144.038574 -82.148172)
		(width 0.1397)
		(layer "In5.Cu")
		(net "I210_REFCLK_D_N")
	)
	(arc
		(start 144.425924 -81.761076)
		(mid 144.639417 -81.618394)
		(end 144.891252 -81.56829)
		(width 0.1397)
		(layer "In5.Cu")
		(net "I210_REFCLK_D_N")
	)
	(arc
		(start 159.516572 -81.56829)
		(mid 160.169795 -81.723145)
		(end 160.683956 -82.154776)
		(width 0.1397)
		(layer "In5.Cu")
		(net "I210_REFCLK_D_N")
	)
	(segment
		(start 27.75839 -89.512394)
		(end 28.021788 -89.248996)
		(width 0.12065)
		(layer "F.Cu")
		(net "I210_PERST_N")
	)
	(segment
		(start 27.166824 -87.4395)
		(end 26.428192 -87.4395)
		(width 0.12065)
		(layer "F.Cu")
		(net "I210_PERST_N")
	)
	(segment
		(start 28.021788 -89.248996)
		(end 28.021788 -88.294464)
		(width 0.12065)
		(layer "F.Cu")
		(net "I210_PERST_N")
	)
	(segment
		(start 28.160472 -89.914476)
		(end 27.75839 -89.512394)
		(width 0.12065)
		(layer "F.Cu")
		(net "I210_PERST_N")
	)
	(segment
		(start 26.428192 -87.4395)
		(end 26.415492 -87.4522)
		(width 0.12065)
		(layer "F.Cu")
		(net "I210_PERST_N")
	)
	(segment
		(start 28.189936 -89.914476)
		(end 28.160472 -89.914476)
		(width 0.12065)
		(layer "F.Cu")
		(net "I210_PERST_N")
	)
	(segment
		(start 28.548584 -90.273124)
		(end 28.189936 -89.914476)
		(width 0.12065)
		(layer "F.Cu")
		(net "I210_PERST_N")
	)
	(segment
		(start 28.548584 -90.663776)
		(end 28.548584 -90.273124)
		(width 0.12065)
		(layer "F.Cu")
		(net "I210_PERST_N")
	)
	(segment
		(start 28.021788 -88.294464)
		(end 27.166824 -87.4395)
		(width 0.12065)
		(layer "F.Cu")
		(net "I210_PERST_N")
	)
	(via
		(at 27.75839 -89.512394)
		(size 0.7112)
		(drill 0.3556)
		(layers "F.Cu" "B.Cu")
		(net "I210_PERST_N")
	)
	(segment
		(start 266.954 -10.541)
		(end 266.954 -11.049)
		(width 0.12065)
		(layer "F.Cu")
		(net "HOST8_RST_N_C")
	)
	(segment
		(start 266.954 -11.049)
		(end 266.573 -11.43)
		(width 0.12065)
		(layer "F.Cu")
		(net "HOST8_RST_N_C")
	)
	(via
		(at 266.573 -11.43)
		(size 0.7112)
		(drill 0.3556)
		(layers "F.Cu" "B.Cu")
		(net "HOST8_RST_N_C")
	)
	(via
		(at 266.954 -10.541)
		(size 0.508)
		(drill 0.254)
		(layers "F.Cu" "B.Cu")
		(net "HOST8_RST_N_C")
	)
	(segment
		(start 266.954 -10.541)
		(end 266.954 -9.41451)
		(width 0.12065)
		(layer "B.Cu")
		(net "HOST8_RST_N_C")
	)
	(segment
		(start 266.954 -9.41451)
		(end 267.0683 -9.30021)
		(width 0.12065)
		(layer "B.Cu")
		(net "HOST8_RST_N_C")
	)
	(segment
		(start 291.0459 -14.7701)
		(end 284.0101 -14.7701)
		(width 0.127)
		(layer "In5.Cu")
		(net "HOST8_RST_N_C")
	)
	(segment
		(start 268.456664 -12.07897)
		(end 266.954 -10.576306)
		(width 0.127)
		(layer "In5.Cu")
		(net "HOST8_RST_N_C")
	)
	(segment
		(start 302.3743 -14.7447)
		(end 295.5417 -14.7447)
		(width 0.127)
		(layer "In5.Cu")
		(net "HOST8_RST_N_C")
	)
	(segment
		(start 319.13449 -17.50949)
		(end 317.627 -16.002)
		(width 0.127)
		(layer "In5.Cu")
		(net "HOST8_RST_N_C")
	)
	(segment
		(start 317.627 -16.002)
		(end 314.325 -16.002)
		(width 0.127)
		(layer "In5.Cu")
		(net "HOST8_RST_N_C")
	)
	(segment
		(start 306.705 -15.367)
		(end 305.816 -14.478)
		(width 0.127)
		(layer "In5.Cu")
		(net "HOST8_RST_N_C")
	)
	(segment
		(start 284.0101 -14.7701)
		(end 280.797 -11.557)
		(width 0.127)
		(layer "In5.Cu")
		(net "HOST8_RST_N_C")
	)
	(segment
		(start 313.69 -15.367)
		(end 306.705 -15.367)
		(width 0.127)
		(layer "In5.Cu")
		(net "HOST8_RST_N_C")
	)
	(segment
		(start 295.5417 -14.7447)
		(end 295.402 -14.605)
		(width 0.127)
		(layer "In5.Cu")
		(net "HOST8_RST_N_C")
	)
	(segment
		(start 278.261572 -11.557)
		(end 277.242016 -12.576556)
		(width 0.127)
		(layer "In5.Cu")
		(net "HOST8_RST_N_C")
	)
	(segment
		(start 269.845028 -12.07897)
		(end 268.456664 -12.07897)
		(width 0.127)
		(layer "In5.Cu")
		(net "HOST8_RST_N_C")
	)
	(segment
		(start 291.211 -14.605)
		(end 291.0459 -14.7701)
		(width 0.127)
		(layer "In5.Cu")
		(net "HOST8_RST_N_C")
	)
	(segment
		(start 270.65859 -12.576556)
		(end 270.342868 -12.57681)
		(width 0.127)
		(layer "In5.Cu")
		(net "HOST8_RST_N_C")
	)
	(segment
		(start 295.402 -14.605)
		(end 291.211 -14.605)
		(width 0.127)
		(layer "In5.Cu")
		(net "HOST8_RST_N_C")
	)
	(segment
		(start 277.242016 -12.576556)
		(end 270.65859 -12.576556)
		(width 0.127)
		(layer "In5.Cu")
		(net "HOST8_RST_N_C")
	)
	(segment
		(start 314.325 -16.002)
		(end 313.69 -15.367)
		(width 0.127)
		(layer "In5.Cu")
		(net "HOST8_RST_N_C")
	)
	(segment
		(start 302.641 -14.478)
		(end 302.3743 -14.7447)
		(width 0.127)
		(layer "In5.Cu")
		(net "HOST8_RST_N_C")
	)
	(segment
		(start 266.954 -10.576306)
		(end 266.954 -10.541)
		(width 0.127)
		(layer "In5.Cu")
		(net "HOST8_RST_N_C")
	)
	(segment
		(start 319.13449 -17.729962)
		(end 319.13449 -17.50949)
		(width 0.127)
		(layer "In5.Cu")
		(net "HOST8_RST_N_C")
	)
	(segment
		(start 305.816 -14.478)
		(end 302.641 -14.478)
		(width 0.127)
		(layer "In5.Cu")
		(net "HOST8_RST_N_C")
	)
	(segment
		(start 280.797 -11.557)
		(end 278.261572 -11.557)
		(width 0.127)
		(layer "In5.Cu")
		(net "HOST8_RST_N_C")
	)
	(segment
		(start 270.342868 -12.57681)
		(end 269.845028 -12.07897)
		(width 0.127)
		(layer "In5.Cu")
		(net "HOST8_RST_N_C")
	)
	(segment
		(start 264.8966 -11.7094)
		(end 264.8204 -11.7094)
		(width 0.12065)
		(layer "F.Cu")
		(net "HOST7_RST_N_C")
	)
	(segment
		(start 266.065 -10.541)
		(end 264.8966 -11.7094)
		(width 0.12065)
		(layer "F.Cu")
		(net "HOST7_RST_N_C")
	)
	(via
		(at 266.065 -10.541)
		(size 0.508)
		(drill 0.254)
		(layers "F.Cu" "B.Cu")
		(net "HOST7_RST_N_C")
	)
	(via
		(at 264.8204 -11.7094)
		(size 0.7112)
		(drill 0.3556)
		(layers "F.Cu" "B.Cu")
		(net "HOST7_RST_N_C")
	)
	(segment
		(start 266.065 -10.541)
		(end 266.065 -9.43991)
		(width 0.12065)
		(layer "B.Cu")
		(net "HOST7_RST_N_C")
	)
	(segment
		(start 266.065 -9.43991)
		(end 265.9253 -9.30021)
		(width 0.12065)
		(layer "B.Cu")
		(net "HOST7_RST_N_C")
	)
	(segment
		(start 305.390296 -14.985746)
		(end 308.134512 -17.729962)
		(width 0.127)
		(layer "In5.Cu")
		(net "HOST7_RST_N_C")
	)
	(segment
		(start 283.852112 -15.1511)
		(end 283.852366 -15.151354)
		(width 0.127)
		(layer "In5.Cu")
		(net "HOST7_RST_N_C")
	)
	(segment
		(start 302.532288 -15.1257)
		(end 302.672242 -14.985746)
		(width 0.127)
		(layer "In5.Cu")
		(net "HOST7_RST_N_C")
	)
	(segment
		(start 283.787088 -15.1511)
		(end 283.852112 -15.1511)
		(width 0.127)
		(layer "In5.Cu")
		(net "HOST7_RST_N_C")
	)
	(segment
		(start 266.92352 -11.39952)
		(end 267.238226 -11.39952)
		(width 0.127)
		(layer "In5.Cu")
		(net "HOST7_RST_N_C")
	)
	(segment
		(start 267.238226 -11.39952)
		(end 268.29893 -12.460224)
		(width 0.127)
		(layer "In5.Cu")
		(net "HOST7_RST_N_C")
	)
	(segment
		(start 283.852366 -15.151354)
		(end 284.167834 -15.151354)
		(width 0.127)
		(layer "In5.Cu")
		(net "HOST7_RST_N_C")
	)
	(segment
		(start 295.244012 -14.986)
		(end 295.383712 -15.1257)
		(width 0.127)
		(layer "In5.Cu")
		(net "HOST7_RST_N_C")
	)
	(segment
		(start 269.687294 -12.460224)
		(end 270.18488 -12.95781)
		(width 0.127)
		(layer "In5.Cu")
		(net "HOST7_RST_N_C")
	)
	(segment
		(start 268.29893 -12.460224)
		(end 269.687294 -12.460224)
		(width 0.127)
		(layer "In5.Cu")
		(net "HOST7_RST_N_C")
	)
	(segment
		(start 280.573988 -11.938)
		(end 283.787088 -15.1511)
		(width 0.127)
		(layer "In5.Cu")
		(net "HOST7_RST_N_C")
	)
	(segment
		(start 291.368988 -14.986)
		(end 295.244012 -14.986)
		(width 0.127)
		(layer "In5.Cu")
		(net "HOST7_RST_N_C")
	)
	(segment
		(start 270.18488 -12.95781)
		(end 270.816324 -12.95781)
		(width 0.127)
		(layer "In5.Cu")
		(net "HOST7_RST_N_C")
	)
	(segment
		(start 270.816324 -12.95781)
		(end 274.538186 -12.957556)
		(width 0.127)
		(layer "In5.Cu")
		(net "HOST7_RST_N_C")
	)
	(segment
		(start 274.538186 -12.957556)
		(end 277.578566 -12.957556)
		(width 0.127)
		(layer "In5.Cu")
		(net "HOST7_RST_N_C")
	)
	(segment
		(start 284.168088 -15.1511)
		(end 291.203888 -15.1511)
		(width 0.127)
		(layer "In5.Cu")
		(net "HOST7_RST_N_C")
	)
	(segment
		(start 284.167834 -15.151354)
		(end 284.168088 -15.1511)
		(width 0.127)
		(layer "In5.Cu")
		(net "HOST7_RST_N_C")
	)
	(segment
		(start 302.672242 -14.985746)
		(end 305.390296 -14.985746)
		(width 0.127)
		(layer "In5.Cu")
		(net "HOST7_RST_N_C")
	)
	(segment
		(start 266.065 -10.541)
		(end 266.92352 -11.39952)
		(width 0.127)
		(layer "In5.Cu")
		(net "HOST7_RST_N_C")
	)
	(segment
		(start 295.383712 -15.1257)
		(end 302.532288 -15.1257)
		(width 0.127)
		(layer "In5.Cu")
		(net "HOST7_RST_N_C")
	)
	(segment
		(start 291.203888 -15.1511)
		(end 291.368988 -14.986)
		(width 0.127)
		(layer "In5.Cu")
		(net "HOST7_RST_N_C")
	)
	(segment
		(start 277.578566 -12.957556)
		(end 278.598122 -11.938)
		(width 0.127)
		(layer "In5.Cu")
		(net "HOST7_RST_N_C")
	)
	(segment
		(start 278.598122 -11.938)
		(end 280.573988 -11.938)
		(width 0.127)
		(layer "In5.Cu")
		(net "HOST7_RST_N_C")
	)
	(via
		(at 271.751806 -11.469116)
		(size 0.7112)
		(drill 0.3556)
		(layers "F.Cu" "B.Cu")
		(net "HOST6_RST_N_C")
	)
	(via
		(at 278.509984 -13.011404)
		(size 0.508)
		(drill 0.254)
		(layers "F.Cu" "B.Cu")
		(net "HOST6_RST_N_C")
	)
	(segment
		(start 271.751806 -11.469116)
		(end 272.22069 -11.938)
		(width 0.12065)
		(layer "B.Cu")
		(net "HOST6_RST_N_C")
	)
	(segment
		(start 274.64893 -13.040614)
		(end 278.480774 -13.040614)
		(width 0.12065)
		(layer "B.Cu")
		(net "HOST6_RST_N_C")
	)
	(segment
		(start 273.546316 -11.938)
		(end 274.64893 -13.040614)
		(width 0.12065)
		(layer "B.Cu")
		(net "HOST6_RST_N_C")
	)
	(segment
		(start 271.540732 -11.258042)
		(end 271.751806 -11.469116)
		(width 0.12065)
		(layer "B.Cu")
		(net "HOST6_RST_N_C")
	)
	(segment
		(start 270.63065 -11.258042)
		(end 271.540732 -11.258042)
		(width 0.12065)
		(layer "B.Cu")
		(net "HOST6_RST_N_C")
	)
	(segment
		(start 272.22069 -11.938)
		(end 273.546316 -11.938)
		(width 0.12065)
		(layer "B.Cu")
		(net "HOST6_RST_N_C")
	)
	(segment
		(start 278.480774 -13.040614)
		(end 278.509984 -13.011404)
		(width 0.12065)
		(layer "B.Cu")
		(net "HOST6_RST_N_C")
	)
	(segment
		(start 291.285676 -15.6083)
		(end 283.7053 -15.6083)
		(width 0.127)
		(layer "In5.Cu")
		(net "HOST6_RST_N_C")
	)
	(segment
		(start 295.213024 -15.494)
		(end 295.086024 -15.367)
		(width 0.127)
		(layer "In5.Cu")
		(net "HOST6_RST_N_C")
	)
	(segment
		(start 295.275 -15.494)
		(end 295.213024 -15.494)
		(width 0.127)
		(layer "In5.Cu")
		(net "HOST6_RST_N_C")
	)
	(segment
		(start 280.416 -12.319)
		(end 279.202388 -12.319)
		(width 0.127)
		(layer "In5.Cu")
		(net "HOST6_RST_N_C")
	)
	(segment
		(start 297.13428 -17.729962)
		(end 297.13428 -17.35328)
		(width 0.127)
		(layer "In5.Cu")
		(net "HOST6_RST_N_C")
	)
	(segment
		(start 295.086024 -15.367)
		(end 291.526976 -15.367)
		(width 0.127)
		(layer "In5.Cu")
		(net "HOST6_RST_N_C")
	)
	(segment
		(start 291.526976 -15.367)
		(end 291.285676 -15.6083)
		(width 0.127)
		(layer "In5.Cu")
		(net "HOST6_RST_N_C")
	)
	(segment
		(start 279.202388 -12.319)
		(end 278.509984 -13.011404)
		(width 0.127)
		(layer "In5.Cu")
		(net "HOST6_RST_N_C")
	)
	(segment
		(start 297.13428 -17.35328)
		(end 295.275 -15.494)
		(width 0.127)
		(layer "In5.Cu")
		(net "HOST6_RST_N_C")
	)
	(segment
		(start 283.7053 -15.6083)
		(end 280.416 -12.319)
		(width 0.127)
		(layer "In5.Cu")
		(net "HOST6_RST_N_C")
	)
	(via
		(at 276.424898 -14.202918)
		(size 0.508)
		(drill 0.254)
		(layers "F.Cu" "B.Cu")
		(net "HOST5_RST_N_C")
	)
	(via
		(at 272.330418 -12.644628)
		(size 0.7112)
		(drill 0.3556)
		(layers "F.Cu" "B.Cu")
		(net "HOST5_RST_N_C")
	)
	(segment
		(start 270.63065 -12.401042)
		(end 271.247362 -12.401042)
		(width 0.12065)
		(layer "B.Cu")
		(net "HOST5_RST_N_C")
	)
	(segment
		(start 272.330418 -12.644628)
		(end 273.529044 -12.644628)
		(width 0.12065)
		(layer "B.Cu")
		(net "HOST5_RST_N_C")
	)
	(segment
		(start 275.087334 -14.202918)
		(end 276.424898 -14.202918)
		(width 0.12065)
		(layer "B.Cu")
		(net "HOST5_RST_N_C")
	)
	(segment
		(start 273.529044 -12.644628)
		(end 275.087334 -14.202918)
		(width 0.12065)
		(layer "B.Cu")
		(net "HOST5_RST_N_C")
	)
	(segment
		(start 271.490948 -12.644628)
		(end 272.330418 -12.644628)
		(width 0.12065)
		(layer "B.Cu")
		(net "HOST5_RST_N_C")
	)
	(segment
		(start 271.247362 -12.401042)
		(end 271.490948 -12.644628)
		(width 0.12065)
		(layer "B.Cu")
		(net "HOST5_RST_N_C")
	)
	(segment
		(start 279.513792 -12.7)
		(end 280.258012 -12.7)
		(width 0.127)
		(layer "In5.Cu")
		(net "HOST5_RST_N_C")
	)
	(segment
		(start 276.424898 -14.202918)
		(end 276.79142 -13.836396)
		(width 0.127)
		(layer "In5.Cu")
		(net "HOST5_RST_N_C")
	)
	(segment
		(start 285.287974 -17.729962)
		(end 286.134302 -17.729962)
		(width 0.127)
		(layer "In5.Cu")
		(net "HOST5_RST_N_C")
	)
	(segment
		(start 278.377396 -13.836396)
		(end 279.513792 -12.7)
		(width 0.127)
		(layer "In5.Cu")
		(net "HOST5_RST_N_C")
	)
	(segment
		(start 276.79142 -13.836396)
		(end 278.377396 -13.836396)
		(width 0.127)
		(layer "In5.Cu")
		(net "HOST5_RST_N_C")
	)
	(segment
		(start 280.258012 -12.7)
		(end 285.287974 -17.729962)
		(width 0.127)
		(layer "In5.Cu")
		(net "HOST5_RST_N_C")
	)
	(segment
		(start 32.104838 -125.284992)
		(end 31.705042 -125.684788)
		(width 0.12065)
		(layer "F.Cu")
		(net "FM_PCH_LAN1_DISABLE_N_R")
	)
	(via
		(at 26.81097 -122.712226)
		(size 0.7112)
		(drill 0.3556)
		(layers "F.Cu" "B.Cu")
		(net "FM_PCH_LAN1_DISABLE_N_R")
	)
	(via
		(at 31.705042 -125.684788)
		(size 0.4572)
		(drill 0.2032)
		(layers "F.Cu" "B.Cu")
		(net "FM_PCH_LAN1_DISABLE_N_R")
	)
	(segment
		(start 29.696918 -125.294136)
		(end 31.31439 -125.294136)
		(width 0.12065)
		(layer "B.Cu")
		(net "FM_PCH_LAN1_DISABLE_N_R")
	)
	(segment
		(start 26.662126 -122.712226)
		(end 26.81097 -122.712226)
		(width 0.12065)
		(layer "B.Cu")
		(net "FM_PCH_LAN1_DISABLE_N_R")
	)
	(segment
		(start 24.5745 -121.0056)
		(end 24.9555 -121.0056)
		(width 0.12065)
		(layer "B.Cu")
		(net "FM_PCH_LAN1_DISABLE_N_R")
	)
	(segment
		(start 24.9555 -121.0056)
		(end 26.662126 -122.712226)
		(width 0.12065)
		(layer "B.Cu")
		(net "FM_PCH_LAN1_DISABLE_N_R")
	)
	(segment
		(start 27.115008 -122.712226)
		(end 29.696918 -125.294136)
		(width 0.12065)
		(layer "B.Cu")
		(net "FM_PCH_LAN1_DISABLE_N_R")
	)
	(segment
		(start 26.81097 -122.712226)
		(end 27.115008 -122.712226)
		(width 0.12065)
		(layer "B.Cu")
		(net "FM_PCH_LAN1_DISABLE_N_R")
	)
	(segment
		(start 31.31439 -125.294136)
		(end 31.705042 -125.684788)
		(width 0.12065)
		(layer "B.Cu")
		(net "FM_PCH_LAN1_DISABLE_N_R")
	)
	(segment
		(start 317.418466 -34.980372)
		(end 316.539372 -35.859466)
		(width 0.12065)
		(layer "F.Cu")
		(net "CLK_P_8_R")
	)
	(segment
		(start 317.051436 -36.37153)
		(end 316.539372 -35.859466)
		(width 0.12065)
		(layer "F.Cu")
		(net "CLK_P_8_R")
	)
	(segment
		(start 317.418466 -33.86963)
		(end 317.418466 -34.980372)
		(width 0.12065)
		(layer "F.Cu")
		(net "CLK_P_8_R")
	)
	(segment
		(start 317.051436 -36.885118)
		(end 317.051436 -36.37153)
		(width 0.12065)
		(layer "F.Cu")
		(net "CLK_P_8_R")
	)
	(segment
		(start 271.442942 -6.18363)
		(end 271.442942 -6.19633)
		(width 0.12065)
		(layer "F.Cu")
		(net "CLK_P_7_R")
	)
	(segment
		(start 271.477486 -4.265168)
		(end 271.464786 -4.265168)
		(width 0.12065)
		(layer "F.Cu")
		(net "CLK_P_7_R")
	)
	(segment
		(start 271.442942 -7.053072)
		(end 271.14373 -7.352284)
		(width 0.12065)
		(layer "F.Cu")
		(net "CLK_P_7_R")
	)
	(segment
		(start 271.14373 -7.352284)
		(end 270.676878 -7.352284)
		(width 0.12065)
		(layer "F.Cu")
		(net "CLK_P_7_R")
	)
	(segment
		(start 271.442942 -6.19633)
		(end 271.442942 -7.053072)
		(width 0.12065)
		(layer "F.Cu")
		(net "CLK_P_7_R")
	)
	(segment
		(start 270.934688 -4.795266)
		(end 270.934688 -5.675376)
		(width 0.12065)
		(layer "F.Cu")
		(net "CLK_P_7_R")
	)
	(segment
		(start 270.934688 -5.675376)
		(end 271.442942 -6.18363)
		(width 0.12065)
		(layer "F.Cu")
		(net "CLK_P_7_R")
	)
	(segment
		(start 271.464786 -4.265168)
		(end 270.934688 -4.795266)
		(width 0.12065)
		(layer "F.Cu")
		(net "CLK_P_7_R")
	)
	(via
		(at 270.676878 -7.352284)
		(size 0.508)
		(drill 0.254)
		(layers "F.Cu" "B.Cu")
		(net "CLK_P_7_R")
	)
	(segment
		(start 270.917162 -7.112)
		(end 270.676878 -7.352284)
		(width 0.12065)
		(layer "B.Cu")
		(net "CLK_P_7_R")
	)
	(segment
		(start 271.4625 -7.112)
		(end 270.917162 -7.112)
		(width 0.12065)
		(layer "B.Cu")
		(net "CLK_P_7_R")
	)
	(segment
		(start 273.961606 -4.477766)
		(end 274.123404 -4.639564)
		(width 0.12065)
		(layer "F.Cu")
		(net "CLK_P_6_R")
	)
	(segment
		(start 274.123404 -4.639564)
		(end 274.18919 -4.70535)
		(width 0.12065)
		(layer "F.Cu")
		(net "CLK_P_6_R")
	)
	(segment
		(start 273.961606 -3.57378)
		(end 273.961606 -4.477766)
		(width 0.12065)
		(layer "F.Cu")
		(net "CLK_P_6_R")
	)
	(segment
		(start 274.18919 -4.70535)
		(end 276.015958 -4.70535)
		(width 0.12065)
		(layer "F.Cu")
		(net "CLK_P_6_R")
	)
	(segment
		(start 272.736564 -10.457942)
		(end 273.995134 -11.716512)
		(width 0.12065)
		(layer "F.Cu")
		(net "CLK_P_5_R")
	)
	(segment
		(start 273.995134 -11.716512)
		(end 276.248368 -11.716512)
		(width 0.12065)
		(layer "F.Cu")
		(net "CLK_P_5_R")
	)
	(segment
		(start 270.746982 -11.339322)
		(end 270.746982 -12.403328)
		(width 0.12065)
		(layer "F.Cu")
		(net "CLK_P_5_R")
	)
	(segment
		(start 276.248368 -11.716512)
		(end 276.35327 -11.821414)
		(width 0.12065)
		(layer "F.Cu")
		(net "CLK_P_5_R")
	)
	(segment
		(start 271.628362 -10.457942)
		(end 270.746982 -11.339322)
		(width 0.12065)
		(layer "F.Cu")
		(net "CLK_P_5_R")
	)
	(segment
		(start 271.966182 -10.457942)
		(end 271.628362 -10.457942)
		(width 0.12065)
		(layer "F.Cu")
		(net "CLK_P_5_R")
	)
	(segment
		(start 271.966182 -10.457942)
		(end 272.736564 -10.457942)
		(width 0.12065)
		(layer "F.Cu")
		(net "CLK_P_5_R")
	)
	(via
		(at 276.35327 -11.821414)
		(size 0.508)
		(drill 0.254)
		(layers "F.Cu" "B.Cu")
		(net "CLK_P_5_R")
	)
	(segment
		(start 272.6055 -10.16)
		(end 273.778472 -10.16)
		(width 0.12065)
		(layer "B.Cu")
		(net "CLK_P_5_R")
	)
	(segment
		(start 276.347682 -11.808968)
		(end 276.35327 -11.814556)
		(width 0.12065)
		(layer "B.Cu")
		(net "CLK_P_5_R")
	)
	(segment
		(start 273.778472 -10.16)
		(end 275.42744 -11.808968)
		(width 0.12065)
		(layer "B.Cu")
		(net "CLK_P_5_R")
	)
	(segment
		(start 276.35327 -11.814556)
		(end 276.35327 -11.821414)
		(width 0.12065)
		(layer "B.Cu")
		(net "CLK_P_5_R")
	)
	(segment
		(start 275.42744 -11.808968)
		(end 276.347682 -11.808968)
		(width 0.12065)
		(layer "B.Cu")
		(net "CLK_P_5_R")
	)
	(segment
		(start 58.637424 -143.57223)
		(end 58.637424 -143.882872)
		(width 0.12065)
		(layer "F.Cu")
		(net "BMC_I210_PERST_N")
	)
	(segment
		(start 58.243216 -144.27708)
		(end 57.43448 -144.27708)
		(width 0.12065)
		(layer "F.Cu")
		(net "BMC_I210_PERST_N")
	)
	(segment
		(start 57.434988 -143.254476)
		(end 58.31967 -143.254476)
		(width 0.12065)
		(layer "F.Cu")
		(net "BMC_I210_PERST_N")
	)
	(segment
		(start 58.637424 -143.882872)
		(end 58.243216 -144.27708)
		(width 0.12065)
		(layer "F.Cu")
		(net "BMC_I210_PERST_N")
	)
	(segment
		(start 58.31967 -143.254476)
		(end 58.637424 -143.57223)
		(width 0.12065)
		(layer "F.Cu")
		(net "BMC_I210_PERST_N")
	)
	(segment
		(start 56.720232 -145.392648)
		(end 57.4548 -145.392648)
		(width 0.12065)
		(layer "F.Cu")
		(net "BMC_I210_PERST_N")
	)
	(segment
		(start 57.4548 -145.392648)
		(end 57.4548 -144.9324)
		(width 0.12065)
		(layer "F.Cu")
		(net "BMC_I210_PERST_N")
	)
	(segment
		(start 29.236416 -91.314016)
		(end 26.897584 -91.314016)
		(width 0.12065)
		(layer "F.Cu")
		(net "BMC_I210_PERST_N")
	)
	(segment
		(start 57.43448 -144.91208)
		(end 57.43448 -144.27708)
		(width 0.12065)
		(layer "F.Cu")
		(net "BMC_I210_PERST_N")
	)
	(segment
		(start 57.4548 -144.9324)
		(end 57.43448 -144.91208)
		(width 0.12065)
		(layer "F.Cu")
		(net "BMC_I210_PERST_N")
	)
	(segment
		(start 56.515 -145.59788)
		(end 56.720232 -145.392648)
		(width 0.12065)
		(layer "F.Cu")
		(net "BMC_I210_PERST_N")
	)
	(segment
		(start 29.7942 -91.8718)
		(end 29.236416 -91.314016)
		(width 0.12065)
		(layer "F.Cu")
		(net "BMC_I210_PERST_N")
	)
	(via
		(at 58.637424 -143.882872)
		(size 0.7112)
		(drill 0.3556)
		(layers "F.Cu" "B.Cu")
		(net "BMC_I210_PERST_N")
	)
	(via
		(at 49.022254 -145.975832)
		(size 0.508)
		(drill 0.254)
		(layers "F.Cu" "B.Cu")
		(net "BMC_I210_PERST_N")
	)
	(via
		(at 56.515 -145.59788)
		(size 0.508)
		(drill 0.254)
		(layers "F.Cu" "B.Cu")
		(net "BMC_I210_PERST_N")
	)
	(via
		(at 29.7942 -91.8718)
		(size 0.508)
		(drill 0.254)
		(layers "F.Cu" "B.Cu")
		(net "BMC_I210_PERST_N")
	)
	(segment
		(start 49.022254 -145.975832)
		(end 49.400206 -145.59788)
		(width 0.127)
		(layer "In2.Cu")
		(net "BMC_I210_PERST_N")
	)
	(segment
		(start 49.400206 -145.59788)
		(end 56.515 -145.59788)
		(width 0.127)
		(layer "In2.Cu")
		(net "BMC_I210_PERST_N")
	)
	(segment
		(start 34.60496 -104.219502)
		(end 43.3705 -112.985042)
		(width 0.127)
		(layer "In5.Cu")
		(net "BMC_I210_PERST_N")
	)
	(segment
		(start 48.503078 -122.239532)
		(end 48.503078 -142.434056)
		(width 0.127)
		(layer "In5.Cu")
		(net "BMC_I210_PERST_N")
	)
	(segment
		(start 49.022254 -142.953232)
		(end 49.022254 -145.975832)
		(width 0.127)
		(layer "In5.Cu")
		(net "BMC_I210_PERST_N")
	)
	(segment
		(start 43.3705 -112.985042)
		(end 43.3705 -117.106954)
		(width 0.127)
		(layer "In5.Cu")
		(net "BMC_I210_PERST_N")
	)
	(segment
		(start 34.60496 -95.43796)
		(end 34.60496 -104.219502)
		(width 0.127)
		(layer "In5.Cu")
		(net "BMC_I210_PERST_N")
	)
	(segment
		(start 31.0388 -91.8718)
		(end 34.60496 -95.43796)
		(width 0.127)
		(layer "In5.Cu")
		(net "BMC_I210_PERST_N")
	)
	(segment
		(start 43.3705 -117.106954)
		(end 48.503078 -122.239532)
		(width 0.127)
		(layer "In5.Cu")
		(net "BMC_I210_PERST_N")
	)
	(segment
		(start 29.7942 -91.8718)
		(end 31.0388 -91.8718)
		(width 0.127)
		(layer "In5.Cu")
		(net "BMC_I210_PERST_N")
	)
	(segment
		(start 48.503078 -142.434056)
		(end 49.022254 -142.953232)
		(width 0.127)
		(layer "In5.Cu")
		(net "BMC_I210_PERST_N")
	)
	(segment
		(start 194.0941 -6.6548)
		(end 194.0941 -6.1849)
		(width 0.12065)
		(layer "F.Cu")
		(net "WP_ENABLE")
	)
	(segment
		(start 194.0941 -6.1849)
		(end 196.1642 -4.1148)
		(width 0.12065)
		(layer "F.Cu")
		(net "WP_ENABLE")
	)
	(segment
		(start 189.9031 -2.9337)
		(end 188.6458 -2.9337)
		(width 0.12065)
		(layer "F.Cu")
		(net "WP_DISABLE")
	)
	(segment
		(start 191.0842 -4.1148)
		(end 189.9031 -2.9337)
		(width 0.12065)
		(layer "F.Cu")
		(net "WP_DISABLE")
	)
	(segment
		(start 35.571938 -100.5713)
		(end 35.571938 -101.148642)
		(width 0.12065)
		(layer "F.Cu")
		(net "SPI_FLASH_SELECT_R")
	)
	(segment
		(start 34.181034 -103.211884)
		(end 33.725612 -102.756462)
		(width 0.12065)
		(layer "F.Cu")
		(net "SPI_FLASH_SELECT_R")
	)
	(segment
		(start 33.725612 -101.883464)
		(end 33.725612 -102.033324)
		(width 0.12065)
		(layer "F.Cu")
		(net "SPI_FLASH_SELECT_R")
	)
	(segment
		(start 35.39744 -101.32314)
		(end 34.285936 -101.32314)
		(width 0.12065)
		(layer "F.Cu")
		(net "SPI_FLASH_SELECT_R")
	)
	(segment
		(start 35.571938 -101.148642)
		(end 35.39744 -101.32314)
		(width 0.12065)
		(layer "F.Cu")
		(net "SPI_FLASH_SELECT_R")
	)
	(segment
		(start 34.285936 -101.32314)
		(end 33.725612 -101.883464)
		(width 0.12065)
		(layer "F.Cu")
		(net "SPI_FLASH_SELECT_R")
	)
	(segment
		(start 33.725612 -102.756462)
		(end 33.725612 -102.033324)
		(width 0.12065)
		(layer "F.Cu")
		(net "SPI_FLASH_SELECT_R")
	)
	(via
		(at 33.725612 -102.033324)
		(size 0.7112)
		(drill 0.3556)
		(layers "F.Cu" "B.Cu")
		(net "SPI_FLASH_SELECT_R")
	)
	(segment
		(start 155.316682 -13.299694)
		(end 155.316682 -13.299948)
		(width 0.136652)
		(layer "B.Cu")
		(net "PCIE_REFCLK_H3_P_R")
	)
	(segment
		(start 154.259534 -7.876032)
		(end 154.259534 -12.249912)
		(width 0.136652)
		(layer "B.Cu")
		(net "PCIE_REFCLK_H3_P_R")
	)
	(segment
		(start 155.32481 -6.432804)
		(end 154.526488 -7.231126)
		(width 0.136652)
		(layer "B.Cu")
		(net "PCIE_REFCLK_H3_P_R")
	)
	(segment
		(start 180.21935 -12.66952)
		(end 174.048928 -6.499098)
		(width 0.136652)
		(layer "B.Cu")
		(net "PCIE_REFCLK_H3_P_R")
	)
	(segment
		(start 154.694128 -12.966954)
		(end 155.316682 -13.299694)
		(width 0.136652)
		(layer "B.Cu")
		(net "PCIE_REFCLK_H3_P_R")
	)
	(segment
		(start 154.458924 -12.73175)
		(end 154.694128 -12.966954)
		(width 0.136652)
		(layer "B.Cu")
		(net "PCIE_REFCLK_H3_P_R")
	)
	(segment
		(start 181.31028 -12.79144)
		(end 180.513736 -12.79144)
		(width 0.136652)
		(layer "B.Cu")
		(net "PCIE_REFCLK_H3_P_R")
	)
	(segment
		(start 173.116494 -6.113018)
		(end 156.096716 -6.113018)
		(width 0.136652)
		(layer "B.Cu")
		(net "PCIE_REFCLK_H3_P_R")
	)
	(segment
		(start 181.63032 -12.4714)
		(end 181.31028 -12.79144)
		(width 0.136652)
		(layer "B.Cu")
		(net "PCIE_REFCLK_H3_P_R")
	)
	(segment
		(start 155.372816 -13.485114)
		(end 155.134564 -13.930122)
		(width 0.136652)
		(layer "B.Cu")
		(net "PCIE_REFCLK_H3_P_R")
	)
	(arc
		(start 155.316682 -13.299948)
		(mid 155.383223 -13.38089)
		(end 155.372816 -13.485114)
		(width 0.136652)
		(layer "B.Cu")
		(net "PCIE_REFCLK_H3_P_R")
	)
	(arc
		(start 154.259534 -12.249912)
		(mid 154.311291 -12.510675)
		(end 154.458924 -12.73175)
		(width 0.136652)
		(layer "B.Cu")
		(net "PCIE_REFCLK_H3_P_R")
	)
	(arc
		(start 180.513736 -12.79144)
		(mid 180.354423 -12.759751)
		(end 180.21935 -12.66952)
		(width 0.136652)
		(layer "B.Cu")
		(net "PCIE_REFCLK_H3_P_R")
	)
	(arc
		(start 154.526488 -7.231126)
		(mid 154.328867 -7.527026)
		(end 154.259534 -7.876032)
		(width 0.136652)
		(layer "B.Cu")
		(net "PCIE_REFCLK_H3_P_R")
	)
	(arc
		(start 174.048928 -6.499098)
		(mid 173.621109 -6.213331)
		(end 173.116494 -6.113018)
		(width 0.136652)
		(layer "B.Cu")
		(net "PCIE_REFCLK_H3_P_R")
	)
	(arc
		(start 156.096716 -6.113018)
		(mid 155.678983 -6.196186)
		(end 155.32481 -6.432804)
		(width 0.136652)
		(layer "B.Cu")
		(net "PCIE_REFCLK_H3_P_R")
	)
	(segment
		(start 154.67457 -12.516104)
		(end 154.87777 -12.719304)
		(width 0.136652)
		(layer "B.Cu")
		(net "PCIE_REFCLK_H3_N_R")
	)
	(segment
		(start 173.116494 -6.417818)
		(end 156.09697 -6.417818)
		(width 0.136652)
		(layer "B.Cu")
		(net "PCIE_REFCLK_H3_N_R")
	)
	(segment
		(start 176.805336 -9.686798)
		(end 173.833282 -6.714744)
		(width 0.136652)
		(layer "B.Cu")
		(net "PCIE_REFCLK_H3_N_R")
	)
	(segment
		(start 154.719782 -11.274552)
		(end 154.719782 -11.684508)
		(width 0.136652)
		(layer "B.Cu")
		(net "PCIE_REFCLK_H3_N_R")
	)
	(segment
		(start 180.003704 -12.885166)
		(end 179.71389 -12.595352)
		(width 0.136652)
		(layer "B.Cu")
		(net "PCIE_REFCLK_H3_N_R")
	)
	(segment
		(start 154.564334 -7.876032)
		(end 154.564334 -9.988296)
		(width 0.136652)
		(layer "B.Cu")
		(net "PCIE_REFCLK_H3_N_R")
	)
	(segment
		(start 177.604928 -10.7061)
		(end 177.604928 -10.48639)
		(width 0.136652)
		(layer "B.Cu")
		(net "PCIE_REFCLK_H3_N_R")
	)
	(segment
		(start 154.564334 -10.709148)
		(end 154.564334 -11.119104)
		(width 0.136652)
		(layer "B.Cu")
		(net "PCIE_REFCLK_H3_N_R")
	)
	(segment
		(start 177.09515 -10.196576)
		(end 176.805336 -9.906508)
		(width 0.136652)
		(layer "B.Cu")
		(net "PCIE_REFCLK_H3_N_R")
	)
	(segment
		(start 178.914298 -11.79576)
		(end 178.694334 -11.79576)
		(width 0.136652)
		(layer "B.Cu")
		(net "PCIE_REFCLK_H3_N_R")
	)
	(segment
		(start 177.315114 -10.196576)
		(end 177.09515 -10.196576)
		(width 0.136652)
		(layer "B.Cu")
		(net "PCIE_REFCLK_H3_N_R")
	)
	(segment
		(start 154.564334 -9.988296)
		(end 154.719782 -10.143744)
		(width 0.136652)
		(layer "B.Cu")
		(net "PCIE_REFCLK_H3_N_R")
	)
	(segment
		(start 177.604928 -10.48639)
		(end 177.315114 -10.196576)
		(width 0.136652)
		(layer "B.Cu")
		(net "PCIE_REFCLK_H3_N_R")
	)
	(segment
		(start 155.64612 -12.975336)
		(end 155.884372 -12.530074)
		(width 0.136652)
		(layer "B.Cu")
		(net "PCIE_REFCLK_H3_N_R")
	)
	(segment
		(start 155.540456 -6.64845)
		(end 154.742134 -7.446772)
		(width 0.136652)
		(layer "B.Cu")
		(net "PCIE_REFCLK_H3_N_R")
	)
	(segment
		(start 178.40452 -11.285982)
		(end 178.114706 -10.996168)
		(width 0.136652)
		(layer "B.Cu")
		(net "PCIE_REFCLK_H3_N_R")
	)
	(segment
		(start 155.460446 -13.030708)
		(end 155.461208 -13.031216)
		(width 0.136652)
		(layer "B.Cu")
		(net "PCIE_REFCLK_H3_N_R")
	)
	(segment
		(start 179.71389 -12.595352)
		(end 179.493926 -12.595352)
		(width 0.136652)
		(layer "B.Cu")
		(net "PCIE_REFCLK_H3_N_R")
	)
	(segment
		(start 179.493926 -12.595352)
		(end 179.204112 -12.305284)
		(width 0.136652)
		(layer "B.Cu")
		(net "PCIE_REFCLK_H3_N_R")
	)
	(segment
		(start 154.564334 -11.119104)
		(end 154.719782 -11.274552)
		(width 0.136652)
		(layer "B.Cu")
		(net "PCIE_REFCLK_H3_N_R")
	)
	(segment
		(start 154.719782 -11.684508)
		(end 154.564334 -11.839956)
		(width 0.136652)
		(layer "B.Cu")
		(net "PCIE_REFCLK_H3_N_R")
	)
	(segment
		(start 179.204112 -12.305284)
		(end 179.204112 -12.085574)
		(width 0.136652)
		(layer "B.Cu")
		(net "PCIE_REFCLK_H3_N_R")
	)
	(segment
		(start 178.40452 -11.505692)
		(end 178.40452 -11.285982)
		(width 0.136652)
		(layer "B.Cu")
		(net "PCIE_REFCLK_H3_N_R")
	)
	(segment
		(start 154.87777 -12.719304)
		(end 155.460446 -13.030708)
		(width 0.136652)
		(layer "B.Cu")
		(net "PCIE_REFCLK_H3_N_R")
	)
	(segment
		(start 154.719782 -10.5537)
		(end 154.564334 -10.709148)
		(width 0.136652)
		(layer "B.Cu")
		(net "PCIE_REFCLK_H3_N_R")
	)
	(segment
		(start 177.894742 -10.996168)
		(end 177.604928 -10.7061)
		(width 0.136652)
		(layer "B.Cu")
		(net "PCIE_REFCLK_H3_N_R")
	)
	(segment
		(start 154.719782 -10.143744)
		(end 154.719782 -10.5537)
		(width 0.136652)
		(layer "B.Cu")
		(net "PCIE_REFCLK_H3_N_R")
	)
	(segment
		(start 181.21376 -13.09624)
		(end 180.513736 -13.09624)
		(width 0.136652)
		(layer "B.Cu")
		(net "PCIE_REFCLK_H3_N_R")
	)
	(segment
		(start 181.63032 -13.5128)
		(end 181.21376 -13.09624)
		(width 0.136652)
		(layer "B.Cu")
		(net "PCIE_REFCLK_H3_N_R")
	)
	(segment
		(start 154.564334 -11.839956)
		(end 154.564334 -12.249912)
		(width 0.136652)
		(layer "B.Cu")
		(net "PCIE_REFCLK_H3_N_R")
	)
	(segment
		(start 178.114706 -10.996168)
		(end 177.894742 -10.996168)
		(width 0.136652)
		(layer "B.Cu")
		(net "PCIE_REFCLK_H3_N_R")
	)
	(segment
		(start 178.694334 -11.79576)
		(end 178.40452 -11.505692)
		(width 0.136652)
		(layer "B.Cu")
		(net "PCIE_REFCLK_H3_N_R")
	)
	(segment
		(start 176.805336 -9.906508)
		(end 176.805336 -9.686798)
		(width 0.136652)
		(layer "B.Cu")
		(net "PCIE_REFCLK_H3_N_R")
	)
	(segment
		(start 179.204112 -12.085574)
		(end 178.914298 -11.79576)
		(width 0.136652)
		(layer "B.Cu")
		(net "PCIE_REFCLK_H3_N_R")
	)
	(arc
		(start 154.742134 -7.446772)
		(mid 154.610539 -7.643718)
		(end 154.564334 -7.876032)
		(width 0.136652)
		(layer "B.Cu")
		(net "PCIE_REFCLK_H3_N_R")
	)
	(arc
		(start 180.513736 -13.09624)
		(mid 180.237713 -13.041447)
		(end 180.003704 -12.885166)
		(width 0.136652)
		(layer "B.Cu")
		(net "PCIE_REFCLK_H3_N_R")
	)
	(arc
		(start 156.09697 -6.417818)
		(mid 155.795796 -6.477819)
		(end 155.540456 -6.64845)
		(width 0.136652)
		(layer "B.Cu")
		(net "PCIE_REFCLK_H3_N_R")
	)
	(arc
		(start 154.564334 -12.249912)
		(mid 154.592988 -12.393965)
		(end 154.67457 -12.516104)
		(width 0.136652)
		(layer "B.Cu")
		(net "PCIE_REFCLK_H3_N_R")
	)
	(arc
		(start 155.461208 -13.031216)
		(mid 155.565237 -13.041573)
		(end 155.64612 -12.975336)
		(width 0.136652)
		(layer "B.Cu")
		(net "PCIE_REFCLK_H3_N_R")
	)
	(arc
		(start 173.833282 -6.714744)
		(mid 173.504417 -6.495003)
		(end 173.116494 -6.417818)
		(width 0.136652)
		(layer "B.Cu")
		(net "PCIE_REFCLK_H3_N_R")
	)
	(segment
		(start 134.941564 -5.076444)
		(end 132.22478 -7.793228)
		(width 0.136652)
		(layer "B.Cu")
		(net "PCIE_REFCLK_H2_P_R")
	)
	(segment
		(start 132.255768 -12.555982)
		(end 132.63245 -12.932664)
		(width 0.136652)
		(layer "B.Cu")
		(net "PCIE_REFCLK_H2_P_R")
	)
	(segment
		(start 133.316726 -13.300202)
		(end 133.31698 -13.300456)
		(width 0.136652)
		(layer "B.Cu")
		(net "PCIE_REFCLK_H2_P_R")
	)
	(segment
		(start 180.8861 -6.824472)
		(end 179.628038 -6.824472)
		(width 0.136652)
		(layer "B.Cu")
		(net "PCIE_REFCLK_H2_P_R")
	)
	(segment
		(start 133.316218 -13.299948)
		(end 133.316726 -13.300202)
		(width 0.136652)
		(layer "B.Cu")
		(net "PCIE_REFCLK_H2_P_R")
	)
	(segment
		(start 131.922774 -8.522208)
		(end 131.922774 -11.751564)
		(width 0.136652)
		(layer "B.Cu")
		(net "PCIE_REFCLK_H2_P_R")
	)
	(segment
		(start 132.63245 -12.932664)
		(end 133.316472 -13.299948)
		(width 0.136652)
		(layer "B.Cu")
		(net "PCIE_REFCLK_H2_P_R")
	)
	(segment
		(start 179.158392 -6.629908)
		(end 177.634392 -5.105908)
		(width 0.136652)
		(layer "B.Cu")
		(net "PCIE_REFCLK_H2_P_R")
	)
	(segment
		(start 133.37286 -13.485368)
		(end 133.134354 -13.930122)
		(width 0.136652)
		(layer "B.Cu")
		(net "PCIE_REFCLK_H2_P_R")
	)
	(segment
		(start 176.463452 -4.621022)
		(end 136.041384 -4.621022)
		(width 0.136652)
		(layer "B.Cu")
		(net "PCIE_REFCLK_H2_P_R")
	)
	(segment
		(start 133.316472 -13.299948)
		(end 133.316218 -13.299948)
		(width 0.136652)
		(layer "B.Cu")
		(net "PCIE_REFCLK_H2_P_R")
	)
	(arc
		(start 133.31698 -13.300456)
		(mid 133.383217 -13.381339)
		(end 133.37286 -13.485368)
		(width 0.136652)
		(layer "B.Cu")
		(net "PCIE_REFCLK_H2_P_R")
	)
	(arc
		(start 136.041384 -4.621022)
		(mid 135.446165 -4.739325)
		(end 134.941564 -5.076444)
		(width 0.136652)
		(layer "B.Cu")
		(net "PCIE_REFCLK_H2_P_R")
	)
	(arc
		(start 131.922774 -11.751564)
		(mid 132.009256 -12.186901)
		(end 132.255768 -12.555982)
		(width 0.136652)
		(layer "B.Cu")
		(net "PCIE_REFCLK_H2_P_R")
	)
	(arc
		(start 179.628038 -6.824472)
		(mid 179.373856 -6.773912)
		(end 179.158392 -6.629908)
		(width 0.136652)
		(layer "B.Cu")
		(net "PCIE_REFCLK_H2_P_R")
	)
	(arc
		(start 181.70652 -6.48462)
		(mid 181.330108 -6.73613)
		(end 180.8861 -6.824472)
		(width 0.136652)
		(layer "B.Cu")
		(net "PCIE_REFCLK_H2_P_R")
	)
	(arc
		(start 132.22478 -7.793228)
		(mid 132.001272 -8.127686)
		(end 131.922774 -8.522208)
		(width 0.136652)
		(layer "B.Cu")
		(net "PCIE_REFCLK_H2_P_R")
	)
	(arc
		(start 177.634392 -5.105908)
		(mid 177.097145 -4.747024)
		(end 176.463452 -4.621022)
		(width 0.136652)
		(layer "B.Cu")
		(net "PCIE_REFCLK_H2_P_R")
	)
	(segment
		(start 176.053496 -4.925822)
		(end 175.898048 -5.08127)
		(width 0.136652)
		(layer "B.Cu")
		(net "PCIE_REFCLK_H2_N_R")
	)
	(segment
		(start 133.777736 -6.891274)
		(end 133.558026 -6.891274)
		(width 0.136652)
		(layer "B.Cu")
		(net "PCIE_REFCLK_H2_N_R")
	)
	(segment
		(start 175.898048 -5.08127)
		(end 175.488092 -5.08127)
		(width 0.136652)
		(layer "B.Cu")
		(net "PCIE_REFCLK_H2_N_R")
	)
	(segment
		(start 132.816346 -12.685268)
		(end 133.46049 -13.031216)
		(width 0.136652)
		(layer "B.Cu")
		(net "PCIE_REFCLK_H2_N_R")
	)
	(segment
		(start 174.357284 -5.08127)
		(end 174.201836 -4.925822)
		(width 0.136652)
		(layer "B.Cu")
		(net "PCIE_REFCLK_H2_N_R")
	)
	(segment
		(start 133.558026 -6.891274)
		(end 132.440426 -8.008874)
		(width 0.136652)
		(layer "B.Cu")
		(net "PCIE_REFCLK_H2_N_R")
	)
	(segment
		(start 174.201836 -4.925822)
		(end 173.79188 -4.925822)
		(width 0.136652)
		(layer "B.Cu")
		(net "PCIE_REFCLK_H2_N_R")
	)
	(segment
		(start 173.79188 -4.925822)
		(end 173.636432 -5.08127)
		(width 0.136652)
		(layer "B.Cu")
		(net "PCIE_REFCLK_H2_N_R")
	)
	(segment
		(start 171.94022 -4.925822)
		(end 136.041384 -4.925822)
		(width 0.136652)
		(layer "B.Cu")
		(net "PCIE_REFCLK_H2_N_R")
	)
	(segment
		(start 173.226476 -5.08127)
		(end 173.071028 -4.925822)
		(width 0.136652)
		(layer "B.Cu")
		(net "PCIE_REFCLK_H2_N_R")
	)
	(segment
		(start 172.661072 -4.925822)
		(end 172.505624 -5.08127)
		(width 0.136652)
		(layer "B.Cu")
		(net "PCIE_REFCLK_H2_N_R")
	)
	(segment
		(start 134.357618 -6.091682)
		(end 134.067804 -6.381496)
		(width 0.136652)
		(layer "B.Cu")
		(net "PCIE_REFCLK_H2_N_R")
	)
	(segment
		(start 134.067804 -6.60146)
		(end 133.777736 -6.891274)
		(width 0.136652)
		(layer "B.Cu")
		(net "PCIE_REFCLK_H2_N_R")
	)
	(segment
		(start 134.577328 -6.091682)
		(end 134.357618 -6.091682)
		(width 0.136652)
		(layer "B.Cu")
		(net "PCIE_REFCLK_H2_N_R")
	)
	(segment
		(start 181.0004 -7.129272)
		(end 179.628038 -7.129272)
		(width 0.136652)
		(layer "B.Cu")
		(net "PCIE_REFCLK_H2_N_R")
	)
	(segment
		(start 175.488092 -5.08127)
		(end 175.332644 -4.925822)
		(width 0.136652)
		(layer "B.Cu")
		(net "PCIE_REFCLK_H2_N_R")
	)
	(segment
		(start 172.095668 -5.08127)
		(end 171.94022 -4.925822)
		(width 0.136652)
		(layer "B.Cu")
		(net "PCIE_REFCLK_H2_N_R")
	)
	(segment
		(start 173.636432 -5.08127)
		(end 173.226476 -5.08127)
		(width 0.136652)
		(layer "B.Cu")
		(net "PCIE_REFCLK_H2_N_R")
	)
	(segment
		(start 173.071028 -4.925822)
		(end 172.661072 -4.925822)
		(width 0.136652)
		(layer "B.Cu")
		(net "PCIE_REFCLK_H2_N_R")
	)
	(segment
		(start 135.15721 -5.29209)
		(end 134.867396 -5.581904)
		(width 0.136652)
		(layer "B.Cu")
		(net "PCIE_REFCLK_H2_N_R")
	)
	(segment
		(start 133.645402 -12.97559)
		(end 133.884416 -12.530074)
		(width 0.136652)
		(layer "B.Cu")
		(net "PCIE_REFCLK_H2_N_R")
	)
	(segment
		(start 132.227574 -8.522462)
		(end 132.227574 -11.751564)
		(width 0.136652)
		(layer "B.Cu")
		(net "PCIE_REFCLK_H2_N_R")
	)
	(segment
		(start 175.332644 -4.925822)
		(end 174.922688 -4.925822)
		(width 0.136652)
		(layer "B.Cu")
		(net "PCIE_REFCLK_H2_N_R")
	)
	(segment
		(start 174.76724 -5.08127)
		(end 174.357284 -5.08127)
		(width 0.136652)
		(layer "B.Cu")
		(net "PCIE_REFCLK_H2_N_R")
	)
	(segment
		(start 174.922688 -4.925822)
		(end 174.76724 -5.08127)
		(width 0.136652)
		(layer "B.Cu")
		(net "PCIE_REFCLK_H2_N_R")
	)
	(segment
		(start 181.69128 -7.5438)
		(end 181.472332 -7.324598)
		(width 0.136652)
		(layer "B.Cu")
		(net "PCIE_REFCLK_H2_N_R")
	)
	(segment
		(start 134.867396 -5.581904)
		(end 134.867396 -5.801868)
		(width 0.136652)
		(layer "B.Cu")
		(net "PCIE_REFCLK_H2_N_R")
	)
	(segment
		(start 134.867396 -5.801868)
		(end 134.577328 -6.091682)
		(width 0.136652)
		(layer "B.Cu")
		(net "PCIE_REFCLK_H2_N_R")
	)
	(segment
		(start 132.471414 -12.340336)
		(end 132.816346 -12.685268)
		(width 0.136652)
		(layer "B.Cu")
		(net "PCIE_REFCLK_H2_N_R")
	)
	(segment
		(start 176.463452 -4.925822)
		(end 176.053496 -4.925822)
		(width 0.136652)
		(layer "B.Cu")
		(net "PCIE_REFCLK_H2_N_R")
	)
	(segment
		(start 172.505624 -5.08127)
		(end 172.095668 -5.08127)
		(width 0.136652)
		(layer "B.Cu")
		(net "PCIE_REFCLK_H2_N_R")
	)
	(segment
		(start 134.067804 -6.381496)
		(end 134.067804 -6.60146)
		(width 0.136652)
		(layer "B.Cu")
		(net "PCIE_REFCLK_H2_N_R")
	)
	(segment
		(start 178.942746 -6.845554)
		(end 177.418746 -5.321554)
		(width 0.136652)
		(layer "B.Cu")
		(net "PCIE_REFCLK_H2_N_R")
	)
	(arc
		(start 177.418746 -5.321554)
		(mid 176.980453 -5.028696)
		(end 176.463452 -4.925822)
		(width 0.136652)
		(layer "B.Cu")
		(net "PCIE_REFCLK_H2_N_R")
	)
	(arc
		(start 132.227574 -11.751564)
		(mid 132.290938 -12.070205)
		(end 132.471414 -12.340336)
		(width 0.136652)
		(layer "B.Cu")
		(net "PCIE_REFCLK_H2_N_R")
	)
	(arc
		(start 181.472332 -7.324598)
		(mid 181.255793 -7.180004)
		(end 181.0004 -7.129272)
		(width 0.136652)
		(layer "B.Cu")
		(net "PCIE_REFCLK_H2_N_R")
	)
	(arc
		(start 132.440426 -8.008874)
		(mid 132.282896 -8.244495)
		(end 132.227574 -8.522462)
		(width 0.136652)
		(layer "B.Cu")
		(net "PCIE_REFCLK_H2_N_R")
	)
	(arc
		(start 133.46049 -13.031216)
		(mid 133.564412 -13.041605)
		(end 133.645402 -12.97559)
		(width 0.136652)
		(layer "B.Cu")
		(net "PCIE_REFCLK_H2_N_R")
	)
	(arc
		(start 179.628038 -7.129272)
		(mid 179.25716 -7.055593)
		(end 178.942746 -6.845554)
		(width 0.136652)
		(layer "B.Cu")
		(net "PCIE_REFCLK_H2_N_R")
	)
	(arc
		(start 136.041384 -4.925822)
		(mid 135.562861 -5.021006)
		(end 135.15721 -5.29209)
		(width 0.136652)
		(layer "B.Cu")
		(net "PCIE_REFCLK_H2_N_R")
	)
	(segment
		(start 20.410932 -69.68744)
		(end 20.410932 -68.373752)
		(width 0.12065)
		(layer "F.Cu")
		(net "PCIE_DIS")
	)
	(segment
		(start 19.35226 -66.7131)
		(end 19.34718 -66.71818)
		(width 0.12065)
		(layer "F.Cu")
		(net "PCIE_DIS")
	)
	(segment
		(start 20.3962 -66.7131)
		(end 19.35226 -66.7131)
		(width 0.12065)
		(layer "F.Cu")
		(net "PCIE_DIS")
	)
	(segment
		(start 20.410932 -68.373752)
		(end 19.34718 -67.31)
		(width 0.12065)
		(layer "F.Cu")
		(net "PCIE_DIS")
	)
	(segment
		(start 20.410932 -71.242682)
		(end 20.410932 -69.68744)
		(width 0.12065)
		(layer "F.Cu")
		(net "PCIE_DIS")
	)
	(segment
		(start 19.34718 -67.31)
		(end 19.34718 -66.71818)
		(width 0.12065)
		(layer "F.Cu")
		(net "PCIE_DIS")
	)
	(via
		(at 20.410932 -69.68744)
		(size 0.7112)
		(drill 0.3556)
		(layers "F.Cu" "B.Cu")
		(net "PCIE_DIS")
	)
	(segment
		(start 196.504052 -21.0058)
		(end 195.8848 -21.0058)
		(width 0.12065)
		(layer "F.Cu")
		(net "MINISAS_CN15_D_I2C_INT#")
	)
	(segment
		(start 182.08244 -13.156184)
		(end 182.08244 -11.371326)
		(width 0.12065)
		(layer "F.Cu")
		(net "MINISAS_CN15_D_I2C_INT#")
	)
	(segment
		(start 194.9323 -16.841978)
		(end 194.9323 -17.39011)
		(width 0.12065)
		(layer "F.Cu")
		(net "MINISAS_CN15_D_I2C_INT#")
	)
	(segment
		(start 187.003436 -11.079226)
		(end 187.003436 -11.508486)
		(width 0.12065)
		(layer "F.Cu")
		(net "MINISAS_CN15_D_I2C_INT#")
	)
	(segment
		(start 182.08244 -11.371326)
		(end 183.538876 -9.91489)
		(width 0.12065)
		(layer "F.Cu")
		(net "MINISAS_CN15_D_I2C_INT#")
	)
	(segment
		(start 194.8942 -18.8341)
		(end 194.9323 -18.796)
		(width 0.12065)
		(layer "F.Cu")
		(net "MINISAS_CN15_D_I2C_INT#")
	)
	(segment
		(start 183.538876 -9.91489)
		(end 185.8391 -9.91489)
		(width 0.12065)
		(layer "F.Cu")
		(net "MINISAS_CN15_D_I2C_INT#")
	)
	(segment
		(start 194.8942 -20.0152)
		(end 194.8942 -18.8341)
		(width 0.12065)
		(layer "F.Cu")
		(net "MINISAS_CN15_D_I2C_INT#")
	)
	(segment
		(start 192.561972 -14.47165)
		(end 194.9323 -16.841978)
		(width 0.12065)
		(layer "F.Cu")
		(net "MINISAS_CN15_D_I2C_INT#")
	)
	(segment
		(start 185.8391 -9.91489)
		(end 187.003436 -11.079226)
		(width 0.12065)
		(layer "F.Cu")
		(net "MINISAS_CN15_D_I2C_INT#")
	)
	(segment
		(start 189.9666 -14.47165)
		(end 192.561972 -14.47165)
		(width 0.12065)
		(layer "F.Cu")
		(net "MINISAS_CN15_D_I2C_INT#")
	)
	(segment
		(start 195.8848 -21.0058)
		(end 194.8942 -20.0152)
		(width 0.12065)
		(layer "F.Cu")
		(net "MINISAS_CN15_D_I2C_INT#")
	)
	(segment
		(start 194.9323 -18.796)
		(end 194.9323 -17.39011)
		(width 0.12065)
		(layer "F.Cu")
		(net "MINISAS_CN15_D_I2C_INT#")
	)
	(segment
		(start 187.003436 -11.508486)
		(end 189.9666 -14.47165)
		(width 0.12065)
		(layer "F.Cu")
		(net "MINISAS_CN15_D_I2C_INT#")
	)
	(via
		(at 194.9323 -17.39011)
		(size 0.7112)
		(drill 0.3556)
		(layers "F.Cu" "B.Cu")
		(net "MINISAS_CN15_D_I2C_INT#")
	)
	(segment
		(start 185.5343 -10.5156)
		(end 185.927746 -10.5156)
		(width 0.12065)
		(layer "F.Cu")
		(net "MINISAS_CN15_C_I2C_INT#")
	)
	(segment
		(start 193.4972 -19.2786)
		(end 193.3448 -19.2786)
		(width 0.12065)
		(layer "F.Cu")
		(net "MINISAS_CN15_C_I2C_INT#")
	)
	(segment
		(start 186.623452 -11.640566)
		(end 189.816486 -14.8336)
		(width 0.12065)
		(layer "F.Cu")
		(net "MINISAS_CN15_C_I2C_INT#")
	)
	(segment
		(start 193.3448 -19.2786)
		(end 193.3448 -18.78584)
		(width 0.12065)
		(layer "F.Cu")
		(net "MINISAS_CN15_C_I2C_INT#")
	)
	(segment
		(start 189.816486 -14.8336)
		(end 192.18275 -14.8336)
		(width 0.12065)
		(layer "F.Cu")
		(net "MINISAS_CN15_C_I2C_INT#")
	)
	(segment
		(start 185.425334 -10.624566)
		(end 185.5343 -10.5156)
		(width 0.12065)
		(layer "F.Cu")
		(net "MINISAS_CN15_C_I2C_INT#")
	)
	(segment
		(start 196.504052 -21.65604)
		(end 195.87464 -21.65604)
		(width 0.12065)
		(layer "F.Cu")
		(net "MINISAS_CN15_C_I2C_INT#")
	)
	(segment
		(start 185.425334 -10.72769)
		(end 185.425334 -10.624566)
		(width 0.12065)
		(layer "F.Cu")
		(net "MINISAS_CN15_C_I2C_INT#")
	)
	(segment
		(start 192.18275 -14.8336)
		(end 193.839338 -16.490188)
		(width 0.12065)
		(layer "F.Cu")
		(net "MINISAS_CN15_C_I2C_INT#")
	)
	(segment
		(start 186.623452 -11.211306)
		(end 186.623452 -11.640566)
		(width 0.12065)
		(layer "F.Cu")
		(net "MINISAS_CN15_C_I2C_INT#")
	)
	(segment
		(start 195.87464 -21.65604)
		(end 193.4972 -19.2786)
		(width 0.12065)
		(layer "F.Cu")
		(net "MINISAS_CN15_C_I2C_INT#")
	)
	(segment
		(start 193.3448 -18.78584)
		(end 193.839338 -18.291302)
		(width 0.12065)
		(layer "F.Cu")
		(net "MINISAS_CN15_C_I2C_INT#")
	)
	(segment
		(start 193.839338 -18.291302)
		(end 193.839338 -16.552926)
		(width 0.12065)
		(layer "F.Cu")
		(net "MINISAS_CN15_C_I2C_INT#")
	)
	(segment
		(start 193.839338 -16.490188)
		(end 193.839338 -16.552926)
		(width 0.12065)
		(layer "F.Cu")
		(net "MINISAS_CN15_C_I2C_INT#")
	)
	(segment
		(start 185.927746 -10.5156)
		(end 186.623452 -11.211306)
		(width 0.12065)
		(layer "F.Cu")
		(net "MINISAS_CN15_C_I2C_INT#")
	)
	(via
		(at 185.425334 -10.72769)
		(size 0.508)
		(drill 0.254)
		(layers "F.Cu" "B.Cu")
		(net "MINISAS_CN15_C_I2C_INT#")
	)
	(via
		(at 193.839338 -16.552926)
		(size 0.7112)
		(drill 0.3556)
		(layers "F.Cu" "B.Cu")
		(net "MINISAS_CN15_C_I2C_INT#")
	)
	(segment
		(start 185.425334 -10.72769)
		(end 185.41365 -10.72769)
		(width 0.12065)
		(layer "B.Cu")
		(net "MINISAS_CN15_C_I2C_INT#")
	)
	(segment
		(start 185.41365 -10.72769)
		(end 185.293 -10.84834)
		(width 0.12065)
		(layer "B.Cu")
		(net "MINISAS_CN15_C_I2C_INT#")
	)
	(segment
		(start 181.96052 -14.7066)
		(end 181.64302 -14.3891)
		(width 0.12065)
		(layer "B.Cu")
		(net "MINISAS_CN15_C_I2C_INT#")
	)
	(segment
		(start 185.293 -10.84834)
		(end 185.293 -13.8938)
		(width 0.12065)
		(layer "B.Cu")
		(net "MINISAS_CN15_C_I2C_INT#")
	)
	(segment
		(start 185.293 -13.8938)
		(end 184.4802 -14.7066)
		(width 0.12065)
		(layer "B.Cu")
		(net "MINISAS_CN15_C_I2C_INT#")
	)
	(segment
		(start 184.4802 -14.7066)
		(end 181.96052 -14.7066)
		(width 0.12065)
		(layer "B.Cu")
		(net "MINISAS_CN15_C_I2C_INT#")
	)
	(segment
		(start 139.4714 -32.2326)
		(end 139.4206 -32.2834)
		(width 0.12065)
		(layer "F.Cu")
		(net "MINISAS_CN15_B_I2C_INT#")
	)
	(segment
		(start 193.3829 -20.5613)
		(end 192.9384 -20.1168)
		(width 0.12065)
		(layer "F.Cu")
		(net "MINISAS_CN15_B_I2C_INT#")
	)
	(segment
		(start 139.4206 -33.45688)
		(end 139.88542 -33.9217)
		(width 0.12065)
		(layer "F.Cu")
		(net "MINISAS_CN15_B_I2C_INT#")
	)
	(segment
		(start 193.3829 -20.9042)
		(end 193.7004 -20.9042)
		(width 0.12065)
		(layer "F.Cu")
		(net "MINISAS_CN15_B_I2C_INT#")
	)
	(segment
		(start 195.10248 -22.30628)
		(end 196.504052 -22.30628)
		(width 0.12065)
		(layer "F.Cu")
		(net "MINISAS_CN15_B_I2C_INT#")
	)
	(segment
		(start 194.564 -21.7678)
		(end 195.10248 -22.30628)
		(width 0.12065)
		(layer "F.Cu")
		(net "MINISAS_CN15_B_I2C_INT#")
	)
	(segment
		(start 139.4206 -32.2834)
		(end 139.4206 -33.45688)
		(width 0.12065)
		(layer "F.Cu")
		(net "MINISAS_CN15_B_I2C_INT#")
	)
	(segment
		(start 193.3829 -20.9042)
		(end 193.3829 -20.5613)
		(width 0.12065)
		(layer "F.Cu")
		(net "MINISAS_CN15_B_I2C_INT#")
	)
	(segment
		(start 193.7004 -20.9042)
		(end 194.564 -21.7678)
		(width 0.12065)
		(layer "F.Cu")
		(net "MINISAS_CN15_B_I2C_INT#")
	)
	(via
		(at 139.4714 -32.2326)
		(size 0.508)
		(drill 0.254)
		(layers "F.Cu" "B.Cu")
		(net "MINISAS_CN15_B_I2C_INT#")
	)
	(via
		(at 192.9384 -20.1168)
		(size 0.508)
		(drill 0.254)
		(layers "F.Cu" "B.Cu")
		(net "MINISAS_CN15_B_I2C_INT#")
	)
	(via
		(at 194.564 -21.7678)
		(size 0.7112)
		(drill 0.3556)
		(layers "F.Cu" "B.Cu")
		(net "MINISAS_CN15_B_I2C_INT#")
	)
	(segment
		(start 181.14137 -18.542)
		(end 189.133988 -18.542)
		(width 0.127)
		(layer "In5.Cu")
		(net "MINISAS_CN15_B_I2C_INT#")
	)
	(segment
		(start 142.5956 -32.978852)
		(end 142.740126 -32.834326)
		(width 0.127)
		(layer "In5.Cu")
		(net "MINISAS_CN15_B_I2C_INT#")
	)
	(segment
		(start 142.061438 -32.834326)
		(end 142.205964 -32.978852)
		(width 0.127)
		(layer "In5.Cu")
		(net "MINISAS_CN15_B_I2C_INT#")
	)
	(segment
		(start 142.003526 -32.834326)
		(end 142.061438 -32.834326)
		(width 0.127)
		(layer "In5.Cu")
		(net "MINISAS_CN15_B_I2C_INT#")
	)
	(segment
		(start 189.133988 -18.542)
		(end 190.200788 -19.6088)
		(width 0.127)
		(layer "In5.Cu")
		(net "MINISAS_CN15_B_I2C_INT#")
	)
	(segment
		(start 190.200788 -19.6088)
		(end 192.4304 -19.6088)
		(width 0.127)
		(layer "In5.Cu")
		(net "MINISAS_CN15_B_I2C_INT#")
	)
	(segment
		(start 154.719274 -32.834326)
		(end 156.1592 -31.3944)
		(width 0.127)
		(layer "In5.Cu")
		(net "MINISAS_CN15_B_I2C_INT#")
	)
	(segment
		(start 156.1592 -31.3944)
		(end 169.666412 -31.3944)
		(width 0.127)
		(layer "In5.Cu")
		(net "MINISAS_CN15_B_I2C_INT#")
	)
	(segment
		(start 139.4714 -32.2326)
		(end 141.4018 -32.2326)
		(width 0.127)
		(layer "In5.Cu")
		(net "MINISAS_CN15_B_I2C_INT#")
	)
	(segment
		(start 141.4018 -32.2326)
		(end 142.003526 -32.834326)
		(width 0.127)
		(layer "In5.Cu")
		(net "MINISAS_CN15_B_I2C_INT#")
	)
	(segment
		(start 178.926744 -22.134068)
		(end 178.926744 -20.756626)
		(width 0.127)
		(layer "In5.Cu")
		(net "MINISAS_CN15_B_I2C_INT#")
	)
	(segment
		(start 169.666412 -31.3944)
		(end 178.926744 -22.134068)
		(width 0.127)
		(layer "In5.Cu")
		(net "MINISAS_CN15_B_I2C_INT#")
	)
	(segment
		(start 192.4304 -19.6088)
		(end 192.9384 -20.1168)
		(width 0.127)
		(layer "In5.Cu")
		(net "MINISAS_CN15_B_I2C_INT#")
	)
	(segment
		(start 142.740126 -32.834326)
		(end 154.719274 -32.834326)
		(width 0.127)
		(layer "In5.Cu")
		(net "MINISAS_CN15_B_I2C_INT#")
	)
	(segment
		(start 178.926744 -20.756626)
		(end 181.14137 -18.542)
		(width 0.127)
		(layer "In5.Cu")
		(net "MINISAS_CN15_B_I2C_INT#")
	)
	(segment
		(start 142.205964 -32.978852)
		(end 142.5956 -32.978852)
		(width 0.127)
		(layer "In5.Cu")
		(net "MINISAS_CN15_B_I2C_INT#")
	)
	(segment
		(start 192.153286 -15.3162)
		(end 193.100452 -16.263366)
		(width 0.12065)
		(layer "F.Cu")
		(net "MINISAS_CN15_A_I2C_INT#")
	)
	(segment
		(start 193.1162 -21.4122)
		(end 193.3829 -21.6789)
		(width 0.12065)
		(layer "F.Cu")
		(net "MINISAS_CN15_A_I2C_INT#")
	)
	(segment
		(start 194.36842 -22.95652)
		(end 193.3829 -21.971)
		(width 0.12065)
		(layer "F.Cu")
		(net "MINISAS_CN15_A_I2C_INT#")
	)
	(segment
		(start 188.561218 -14.694408)
		(end 189.18301 -15.3162)
		(width 0.12065)
		(layer "F.Cu")
		(net "MINISAS_CN15_A_I2C_INT#")
	)
	(segment
		(start 192.216024 -21.4122)
		(end 193.1162 -21.4122)
		(width 0.12065)
		(layer "F.Cu")
		(net "MINISAS_CN15_A_I2C_INT#")
	)
	(segment
		(start 196.504052 -22.95652)
		(end 194.36842 -22.95652)
		(width 0.12065)
		(layer "F.Cu")
		(net "MINISAS_CN15_A_I2C_INT#")
	)
	(segment
		(start 191.392048 -19.342862)
		(end 191.392048 -20.588224)
		(width 0.12065)
		(layer "F.Cu")
		(net "MINISAS_CN15_A_I2C_INT#")
	)
	(segment
		(start 193.100452 -17.634458)
		(end 191.392048 -19.342862)
		(width 0.12065)
		(layer "F.Cu")
		(net "MINISAS_CN15_A_I2C_INT#")
	)
	(segment
		(start 186.1566 -11.4046)
		(end 186.1566 -12.28979)
		(width 0.12065)
		(layer "F.Cu")
		(net "MINISAS_CN15_A_I2C_INT#")
	)
	(segment
		(start 189.18301 -15.3162)
		(end 192.153286 -15.3162)
		(width 0.12065)
		(layer "F.Cu")
		(net "MINISAS_CN15_A_I2C_INT#")
	)
	(segment
		(start 186.1566 -12.28979)
		(end 188.561218 -14.694408)
		(width 0.12065)
		(layer "F.Cu")
		(net "MINISAS_CN15_A_I2C_INT#")
	)
	(segment
		(start 193.3829 -21.6789)
		(end 193.3829 -21.971)
		(width 0.12065)
		(layer "F.Cu")
		(net "MINISAS_CN15_A_I2C_INT#")
	)
	(segment
		(start 191.392048 -20.588224)
		(end 192.216024 -21.4122)
		(width 0.12065)
		(layer "F.Cu")
		(net "MINISAS_CN15_A_I2C_INT#")
	)
	(segment
		(start 193.100452 -16.263366)
		(end 193.100452 -17.634458)
		(width 0.12065)
		(layer "F.Cu")
		(net "MINISAS_CN15_A_I2C_INT#")
	)
	(via
		(at 186.1566 -11.4046)
		(size 0.508)
		(drill 0.254)
		(layers "F.Cu" "B.Cu")
		(net "MINISAS_CN15_A_I2C_INT#")
	)
	(via
		(at 188.561218 -14.694408)
		(size 0.7112)
		(drill 0.3556)
		(layers "F.Cu" "B.Cu")
		(net "MINISAS_CN15_A_I2C_INT#")
	)
	(segment
		(start 181.82082 -8.41502)
		(end 182.499 -9.0932)
		(width 0.12065)
		(layer "B.Cu")
		(net "MINISAS_CN15_A_I2C_INT#")
	)
	(segment
		(start 183.372252 -9.373362)
		(end 184.999122 -9.373362)
		(width 0.12065)
		(layer "B.Cu")
		(net "MINISAS_CN15_A_I2C_INT#")
	)
	(segment
		(start 182.499 -9.0932)
		(end 183.09209 -9.0932)
		(width 0.12065)
		(layer "B.Cu")
		(net "MINISAS_CN15_A_I2C_INT#")
	)
	(segment
		(start 181.70906 -8.41502)
		(end 181.82082 -8.41502)
		(width 0.12065)
		(layer "B.Cu")
		(net "MINISAS_CN15_A_I2C_INT#")
	)
	(segment
		(start 186.1566 -10.53084)
		(end 186.1566 -11.4046)
		(width 0.12065)
		(layer "B.Cu")
		(net "MINISAS_CN15_A_I2C_INT#")
	)
	(segment
		(start 184.999122 -9.373362)
		(end 186.1566 -10.53084)
		(width 0.12065)
		(layer "B.Cu")
		(net "MINISAS_CN15_A_I2C_INT#")
	)
	(segment
		(start 183.09209 -9.0932)
		(end 183.372252 -9.373362)
		(width 0.12065)
		(layer "B.Cu")
		(net "MINISAS_CN15_A_I2C_INT#")
	)
	(segment
		(start 162.8267 -8.817864)
		(end 162.8267 -14.42212)
		(width 0.12065)
		(layer "F.Cu")
		(net "HOST4_RST_N_C")
	)
	(segment
		(start 180.546248 -7.099808)
		(end 180.296566 -6.850126)
		(width 0.12065)
		(layer "F.Cu")
		(net "HOST4_RST_N_C")
	)
	(segment
		(start 182.295292 -7.267702)
		(end 182.20055 -7.17296)
		(width 0.12065)
		(layer "F.Cu")
		(net "HOST4_RST_N_C")
	)
	(segment
		(start 181.19725 -7.099808)
		(end 182.127398 -7.099808)
		(width 0.12065)
		(layer "F.Cu")
		(net "HOST4_RST_N_C")
	)
	(segment
		(start 180.296566 -6.850126)
		(end 164.794438 -6.850126)
		(width 0.12065)
		(layer "F.Cu")
		(net "HOST4_RST_N_C")
	)
	(segment
		(start 183.110886 -7.267702)
		(end 182.295292 -7.267702)
		(width 0.12065)
		(layer "F.Cu")
		(net "HOST4_RST_N_C")
	)
	(segment
		(start 164.794438 -6.850126)
		(end 162.8267 -8.817864)
		(width 0.12065)
		(layer "F.Cu")
		(net "HOST4_RST_N_C")
	)
	(segment
		(start 182.127398 -7.099808)
		(end 182.20055 -7.17296)
		(width 0.12065)
		(layer "F.Cu")
		(net "HOST4_RST_N_C")
	)
	(segment
		(start 162.8267 -14.42212)
		(end 166.134542 -17.729962)
		(width 0.12065)
		(layer "F.Cu")
		(net "HOST4_RST_N_C")
	)
	(segment
		(start 181.19725 -7.099808)
		(end 180.546248 -7.099808)
		(width 0.12065)
		(layer "F.Cu")
		(net "HOST4_RST_N_C")
	)
	(via
		(at 182.20055 -7.17296)
		(size 0.7112)
		(drill 0.3556)
		(layers "F.Cu" "B.Cu")
		(net "HOST4_RST_N_C")
	)
	(segment
		(start 154.449272 -16.052038)
		(end 155.134564 -16.73733)
		(width 0.12065)
		(layer "F.Cu")
		(net "HOST3_RST_N_C")
	)
	(segment
		(start 156.916628 -6.380734)
		(end 154.449272 -8.84809)
		(width 0.12065)
		(layer "F.Cu")
		(net "HOST3_RST_N_C")
	)
	(segment
		(start 179.22494 -2.201672)
		(end 175.045878 -6.380734)
		(width 0.12065)
		(layer "F.Cu")
		(net "HOST3_RST_N_C")
	)
	(segment
		(start 183.07177 -3.370072)
		(end 182.459122 -2.757424)
		(width 0.12065)
		(layer "F.Cu")
		(net "HOST3_RST_N_C")
	)
	(segment
		(start 182.459122 -2.757424)
		(end 180.641752 -2.757424)
		(width 0.12065)
		(layer "F.Cu")
		(net "HOST3_RST_N_C")
	)
	(segment
		(start 180.086 -2.201672)
		(end 179.22494 -2.201672)
		(width 0.12065)
		(layer "F.Cu")
		(net "HOST3_RST_N_C")
	)
	(segment
		(start 154.449272 -8.84809)
		(end 154.449272 -16.052038)
		(width 0.12065)
		(layer "F.Cu")
		(net "HOST3_RST_N_C")
	)
	(segment
		(start 180.641752 -2.757424)
		(end 180.086 -2.201672)
		(width 0.12065)
		(layer "F.Cu")
		(net "HOST3_RST_N_C")
	)
	(segment
		(start 175.045878 -6.380734)
		(end 156.916628 -6.380734)
		(width 0.12065)
		(layer "F.Cu")
		(net "HOST3_RST_N_C")
	)
	(segment
		(start 155.134564 -16.73733)
		(end 155.134564 -17.729962)
		(width 0.12065)
		(layer "F.Cu")
		(net "HOST3_RST_N_C")
	)
	(segment
		(start 183.07177 -3.800856)
		(end 183.07177 -3.370072)
		(width 0.12065)
		(layer "F.Cu")
		(net "HOST3_RST_N_C")
	)
	(via
		(at 182.459122 -2.757424)
		(size 0.7112)
		(drill 0.3556)
		(layers "F.Cu" "B.Cu")
		(net "HOST3_RST_N_C")
	)
	(segment
		(start 179.553362 -1.213358)
		(end 174.747936 -6.018784)
		(width 0.12065)
		(layer "F.Cu")
		(net "HOST2_RST_N_C")
	)
	(segment
		(start 149.569932 -15.1892)
		(end 145.239486 -15.1892)
		(width 0.12065)
		(layer "F.Cu")
		(net "HOST2_RST_N_C")
	)
	(segment
		(start 183.164988 -2.436876)
		(end 182.448708 -1.720596)
		(width 0.12065)
		(layer "F.Cu")
		(net "HOST2_RST_N_C")
	)
	(segment
		(start 144.134332 -16.294354)
		(end 144.134332 -17.729962)
		(width 0.12065)
		(layer "F.Cu")
		(net "HOST2_RST_N_C")
	)
	(segment
		(start 154.087322 -10.67181)
		(end 149.569932 -15.1892)
		(width 0.12065)
		(layer "F.Cu")
		(net "HOST2_RST_N_C")
	)
	(segment
		(start 145.239486 -15.1892)
		(end 144.134332 -16.294354)
		(width 0.12065)
		(layer "F.Cu")
		(net "HOST2_RST_N_C")
	)
	(segment
		(start 182.448708 -1.720596)
		(end 181.94147 -1.213358)
		(width 0.12065)
		(layer "F.Cu")
		(net "HOST2_RST_N_C")
	)
	(segment
		(start 183.82996 -2.436876)
		(end 183.164988 -2.436876)
		(width 0.12065)
		(layer "F.Cu")
		(net "HOST2_RST_N_C")
	)
	(segment
		(start 154.087322 -8.697976)
		(end 154.087322 -10.67181)
		(width 0.12065)
		(layer "F.Cu")
		(net "HOST2_RST_N_C")
	)
	(segment
		(start 156.766514 -6.018784)
		(end 154.087322 -8.697976)
		(width 0.12065)
		(layer "F.Cu")
		(net "HOST2_RST_N_C")
	)
	(segment
		(start 184.10428 -2.711196)
		(end 183.82996 -2.436876)
		(width 0.12065)
		(layer "F.Cu")
		(net "HOST2_RST_N_C")
	)
	(segment
		(start 174.747936 -6.018784)
		(end 156.766514 -6.018784)
		(width 0.12065)
		(layer "F.Cu")
		(net "HOST2_RST_N_C")
	)
	(segment
		(start 181.94147 -1.213358)
		(end 179.553362 -1.213358)
		(width 0.12065)
		(layer "F.Cu")
		(net "HOST2_RST_N_C")
	)
	(segment
		(start 184.10428 -3.80746)
		(end 184.10428 -2.711196)
		(width 0.12065)
		(layer "F.Cu")
		(net "HOST2_RST_N_C")
	)
	(via
		(at 183.82996 -2.436876)
		(size 0.7112)
		(drill 0.3556)
		(layers "F.Cu" "B.Cu")
		(net "HOST2_RST_N_C")
	)
	(segment
		(start 181.186328 -0.465074)
		(end 179.789582 -0.465074)
		(width 0.12065)
		(layer "F.Cu")
		(net "HOST1_RST_N_C")
	)
	(segment
		(start 183.83885 -0.048768)
		(end 181.602634 -0.048768)
		(width 0.12065)
		(layer "F.Cu")
		(net "HOST1_RST_N_C")
	)
	(segment
		(start 179.789582 -0.465074)
		(end 174.752 -5.502656)
		(width 0.12065)
		(layer "F.Cu")
		(net "HOST1_RST_N_C")
	)
	(segment
		(start 184.501028 -0.710946)
		(end 184.394602 -0.60452)
		(width 0.12065)
		(layer "F.Cu")
		(net "HOST1_RST_N_C")
	)
	(segment
		(start 185.15584 -3.83032)
		(end 184.501028 -3.175508)
		(width 0.12065)
		(layer "F.Cu")
		(net "HOST1_RST_N_C")
	)
	(segment
		(start 132.226812 -9.62533)
		(end 132.226812 -16.82242)
		(width 0.12065)
		(layer "F.Cu")
		(net "HOST1_RST_N_C")
	)
	(segment
		(start 174.752 -5.502656)
		(end 136.349486 -5.502656)
		(width 0.12065)
		(layer "F.Cu")
		(net "HOST1_RST_N_C")
	)
	(segment
		(start 181.602634 -0.048768)
		(end 181.186328 -0.465074)
		(width 0.12065)
		(layer "F.Cu")
		(net "HOST1_RST_N_C")
	)
	(segment
		(start 184.394602 -0.60452)
		(end 183.83885 -0.048768)
		(width 0.12065)
		(layer "F.Cu")
		(net "HOST1_RST_N_C")
	)
	(segment
		(start 132.226812 -16.82242)
		(end 133.134354 -17.729962)
		(width 0.12065)
		(layer "F.Cu")
		(net "HOST1_RST_N_C")
	)
	(segment
		(start 184.501028 -3.175508)
		(end 184.501028 -0.710946)
		(width 0.12065)
		(layer "F.Cu")
		(net "HOST1_RST_N_C")
	)
	(segment
		(start 136.349486 -5.502656)
		(end 132.226812 -9.62533)
		(width 0.12065)
		(layer "F.Cu")
		(net "HOST1_RST_N_C")
	)
	(via
		(at 181.186328 -0.465074)
		(size 0.7112)
		(drill 0.3556)
		(layers "F.Cu" "B.Cu")
		(net "HOST1_RST_N_C")
	)
	(segment
		(start 184.12206 -15.20952)
		(end 184.11952 -15.21206)
		(width 0.12065)
		(layer "F.Cu")
		(net "CLK_P_4_R")
	)
	(segment
		(start 183.09336 -15.21206)
		(end 182.08244 -14.20114)
		(width 0.12065)
		(layer "F.Cu")
		(net "CLK_P_4_R")
	)
	(segment
		(start 184.11952 -15.21206)
		(end 183.09336 -15.21206)
		(width 0.12065)
		(layer "F.Cu")
		(net "CLK_P_4_R")
	)
	(segment
		(start 182.08244 -14.20114)
		(end 182.08244 -14.18844)
		(width 0.12065)
		(layer "F.Cu")
		(net "CLK_P_4_R")
	)
	(segment
		(start 182.9054 -9.6647)
		(end 182.42661 -9.6647)
		(width 0.12065)
		(layer "B.Cu")
		(net "CLK_P_3_R")
	)
	(segment
		(start 182.42661 -9.6647)
		(end 182.219854 -9.457944)
		(width 0.12065)
		(layer "B.Cu")
		(net "CLK_P_3_R")
	)
	(segment
		(start 182.219854 -9.457944)
		(end 181.765702 -9.457944)
		(width 0.12065)
		(layer "B.Cu")
		(net "CLK_P_3_R")
	)
	(segment
		(start 181.765702 -9.457944)
		(end 181.64302 -9.580626)
		(width 0.12065)
		(layer "B.Cu")
		(net "CLK_P_3_R")
	)
	(segment
		(start 181.64302 -9.580626)
		(end 181.64302 -11.5951)
		(width 0.12065)
		(layer "B.Cu")
		(net "CLK_P_3_R")
	)
	(segment
		(start 140.7795 -34.949638)
		(end 141.613128 -34.949638)
		(width 0.12065)
		(layer "F.Cu")
		(net "CLK_P_2_R")
	)
	(segment
		(start 141.613128 -34.949638)
		(end 141.78788 -34.774886)
		(width 0.12065)
		(layer "F.Cu")
		(net "CLK_P_2_R")
	)
	(segment
		(start 181.70652 -5.59562)
		(end 181.70652 -4.572)
		(width 0.12065)
		(layer "B.Cu")
		(net "CLK_P_1_R")
	)
	(segment
		(start 180.72354 -3.53822)
		(end 180.72354 -3.58902)
		(width 0.12065)
		(layer "B.Cu")
		(net "CLK_P_1_R")
	)
	(segment
		(start 181.70652 -4.572)
		(end 181.6862 -4.55168)
		(width 0.12065)
		(layer "B.Cu")
		(net "CLK_P_1_R")
	)
	(segment
		(start 180.72354 -3.58902)
		(end 181.6862 -4.55168)
		(width 0.12065)
		(layer "B.Cu")
		(net "CLK_P_1_R")
	)
	(segment
		(start 49.788572 -61.303916)
		(end 49.788572 -63.254128)
		(width 0.12065)
		(layer "F.Cu")
		(net "U44_WP_N")
	)
	(segment
		(start 49.788572 -63.254128)
		(end 49.2633 -63.7794)
		(width 0.12065)
		(layer "F.Cu")
		(net "U44_WP_N")
	)
	(segment
		(start 51.058572 -50.944272)
		(end 50.8762 -50.7619)
		(width 0.12065)
		(layer "F.Cu")
		(net "U44_HOLD_N")
	)
	(segment
		(start 51.058572 -53.303932)
		(end 51.058572 -50.944272)
		(width 0.12065)
		(layer "F.Cu")
		(net "U44_HOLD_N")
	)
	(segment
		(start 32.904938 -123.684792)
		(end 32.505142 -123.284996)
		(width 0.12065)
		(layer "F.Cu")
		(net "SPIDO_R")
	)
	(via
		(at 32.505142 -123.284996)
		(size 0.4572)
		(drill 0.2032)
		(layers "F.Cu" "B.Cu")
		(net "SPIDO_R")
	)
	(via
		(at 29.515816 -120.524016)
		(size 0.7112)
		(drill 0.3556)
		(layers "F.Cu" "B.Cu")
		(net "SPIDO_R")
	)
	(segment
		(start 32.276796 -123.284996)
		(end 32.505142 -123.284996)
		(width 0.12065)
		(layer "B.Cu")
		(net "SPIDO_R")
	)
	(segment
		(start 28.702 -119.7102)
		(end 29.515816 -120.524016)
		(width 0.12065)
		(layer "B.Cu")
		(net "SPIDO_R")
	)
	(segment
		(start 29.515816 -120.524016)
		(end 32.276796 -123.284996)
		(width 0.12065)
		(layer "B.Cu")
		(net "SPIDO_R")
	)
	(segment
		(start 28.702 -117.4115)
		(end 28.702 -119.7102)
		(width 0.12065)
		(layer "B.Cu")
		(net "SPIDO_R")
	)
	(segment
		(start 39.536878 -97.609914)
		(end 39.344854 -97.801938)
		(width 0.12065)
		(layer "F.Cu")
		(net "SPIDO")
	)
	(segment
		(start 39.344854 -97.801938)
		(end 38.1 -97.801938)
		(width 0.12065)
		(layer "F.Cu")
		(net "SPIDO")
	)
	(via
		(at 24.9936 -115.4176)
		(size 0.508)
		(drill 0.254)
		(layers "F.Cu" "B.Cu")
		(net "SPIDO")
	)
	(via
		(at 27.403806 -116.329206)
		(size 0.7112)
		(drill 0.3556)
		(layers "F.Cu" "B.Cu")
		(net "SPIDO")
	)
	(via
		(at 39.536878 -97.609914)
		(size 0.508)
		(drill 0.254)
		(layers "F.Cu" "B.Cu")
		(net "SPIDO")
	)
	(segment
		(start 26.483818 -115.0239)
		(end 26.496518 -115.0366)
		(width 0.12065)
		(layer "B.Cu")
		(net "SPIDO")
	)
	(segment
		(start 25.3746 -115.0366)
		(end 26.081482 -115.0366)
		(width 0.12065)
		(layer "B.Cu")
		(net "SPIDO")
	)
	(segment
		(start 26.094182 -115.0239)
		(end 26.483818 -115.0239)
		(width 0.12065)
		(layer "B.Cu")
		(net "SPIDO")
	)
	(segment
		(start 26.7208 -115.0366)
		(end 27.1526 -115.4684)
		(width 0.12065)
		(layer "B.Cu")
		(net "SPIDO")
	)
	(segment
		(start 26.081482 -115.0366)
		(end 26.094182 -115.0239)
		(width 0.12065)
		(layer "B.Cu")
		(net "SPIDO")
	)
	(segment
		(start 27.1526 -116.078)
		(end 27.403806 -116.329206)
		(width 0.12065)
		(layer "B.Cu")
		(net "SPIDO")
	)
	(segment
		(start 27.403806 -116.329206)
		(end 27.5971 -116.5225)
		(width 0.12065)
		(layer "B.Cu")
		(net "SPIDO")
	)
	(segment
		(start 27.5971 -116.5225)
		(end 28.702 -116.5225)
		(width 0.12065)
		(layer "B.Cu")
		(net "SPIDO")
	)
	(segment
		(start 27.1526 -115.4684)
		(end 27.1526 -116.078)
		(width 0.12065)
		(layer "B.Cu")
		(net "SPIDO")
	)
	(segment
		(start 26.496518 -115.0366)
		(end 26.7208 -115.0366)
		(width 0.12065)
		(layer "B.Cu")
		(net "SPIDO")
	)
	(segment
		(start 24.9936 -115.4176)
		(end 25.3746 -115.0366)
		(width 0.12065)
		(layer "B.Cu")
		(net "SPIDO")
	)
	(segment
		(start 32.88919 -99.828096)
		(end 37.105336 -99.828096)
		(width 0.127)
		(layer "In2.Cu")
		(net "SPIDO")
	)
	(segment
		(start 37.105336 -99.828096)
		(end 38.76167 -98.171762)
		(width 0.127)
		(layer "In2.Cu")
		(net "SPIDO")
	)
	(segment
		(start 28.06827 -104.050084)
		(end 28.667202 -104.050084)
		(width 0.127)
		(layer "In2.Cu")
		(net "SPIDO")
	)
	(segment
		(start 25.528524 -106.090466)
		(end 25.87752 -106.090466)
		(width 0.127)
		(layer "In2.Cu")
		(net "SPIDO")
	)
	(segment
		(start 22.83714 -111.977678)
		(end 22.83714 -108.78185)
		(width 0.127)
		(layer "In2.Cu")
		(net "SPIDO")
	)
	(segment
		(start 22.83714 -108.78185)
		(end 25.528524 -106.090466)
		(width 0.127)
		(layer "In2.Cu")
		(net "SPIDO")
	)
	(segment
		(start 27.130248 -104.837738)
		(end 27.280616 -104.837738)
		(width 0.127)
		(layer "In2.Cu")
		(net "SPIDO")
	)
	(segment
		(start 21.7932 -113.021618)
		(end 22.83714 -111.977678)
		(width 0.127)
		(layer "In2.Cu")
		(net "SPIDO")
	)
	(segment
		(start 28.667202 -104.050084)
		(end 32.88919 -99.828096)
		(width 0.127)
		(layer "In2.Cu")
		(net "SPIDO")
	)
	(segment
		(start 38.76167 -98.171762)
		(end 38.97503 -98.171762)
		(width 0.127)
		(layer "In2.Cu")
		(net "SPIDO")
	)
	(segment
		(start 27.280616 -104.837738)
		(end 28.06827 -104.050084)
		(width 0.127)
		(layer "In2.Cu")
		(net "SPIDO")
	)
	(segment
		(start 38.97503 -98.171762)
		(end 39.536878 -97.609914)
		(width 0.127)
		(layer "In2.Cu")
		(net "SPIDO")
	)
	(segment
		(start 23.490174 -116.921026)
		(end 22.67458 -116.921026)
		(width 0.127)
		(layer "In2.Cu")
		(net "SPIDO")
	)
	(segment
		(start 24.9936 -115.4176)
		(end 23.490174 -116.921026)
		(width 0.127)
		(layer "In2.Cu")
		(net "SPIDO")
	)
	(segment
		(start 21.7932 -116.039646)
		(end 21.7932 -113.021618)
		(width 0.127)
		(layer "In2.Cu")
		(net "SPIDO")
	)
	(segment
		(start 22.67458 -116.921026)
		(end 21.7932 -116.039646)
		(width 0.127)
		(layer "In2.Cu")
		(net "SPIDO")
	)
	(segment
		(start 25.87752 -106.090466)
		(end 27.130248 -104.837738)
		(width 0.127)
		(layer "In2.Cu")
		(net "SPIDO")
	)
	(segment
		(start 31.304738 -125.284992)
		(end 31.305246 -125.284992)
		(width 0.12065)
		(layer "F.Cu")
		(net "SPIDI_R")
	)
	(segment
		(start 31.305246 -125.284992)
		(end 31.705042 -124.885196)
		(width 0.12065)
		(layer "F.Cu")
		(net "SPIDI_R")
	)
	(via
		(at 28.956 -122.8598)
		(size 0.7112)
		(drill 0.3556)
		(layers "F.Cu" "B.Cu")
		(net "SPIDI_R")
	)
	(via
		(at 31.705042 -124.885196)
		(size 0.4572)
		(drill 0.2032)
		(layers "F.Cu" "B.Cu")
		(net "SPIDI_R")
	)
	(segment
		(start 29.5656 -122.8598)
		(end 31.590996 -124.885196)
		(width 0.12065)
		(layer "B.Cu")
		(net "SPIDI_R")
	)
	(segment
		(start 22.618192 -117.741446)
		(end 23.827994 -118.951248)
		(width 0.12065)
		(layer "B.Cu")
		(net "SPIDI_R")
	)
	(segment
		(start 24.449786 -118.951248)
		(end 28.358338 -122.8598)
		(width 0.12065)
		(layer "B.Cu")
		(net "SPIDI_R")
	)
	(segment
		(start 31.590996 -124.885196)
		(end 31.705042 -124.885196)
		(width 0.12065)
		(layer "B.Cu")
		(net "SPIDI_R")
	)
	(segment
		(start 23.827994 -118.951248)
		(end 24.449786 -118.951248)
		(width 0.12065)
		(layer "B.Cu")
		(net "SPIDI_R")
	)
	(segment
		(start 21.359368 -117.741446)
		(end 22.618192 -117.741446)
		(width 0.12065)
		(layer "B.Cu")
		(net "SPIDI_R")
	)
	(segment
		(start 28.956 -122.8598)
		(end 29.5656 -122.8598)
		(width 0.12065)
		(layer "B.Cu")
		(net "SPIDI_R")
	)
	(segment
		(start 28.358338 -122.8598)
		(end 28.956 -122.8598)
		(width 0.12065)
		(layer "B.Cu")
		(net "SPIDI_R")
	)
	(segment
		(start 38.1 -99.302062)
		(end 40.778938 -99.302062)
		(width 0.12065)
		(layer "F.Cu")
		(net "SPIDI")
	)
	(segment
		(start 41.0972 -98.9838)
		(end 41.893998 -98.9838)
		(width 0.12065)
		(layer "F.Cu")
		(net "SPIDI")
	)
	(segment
		(start 41.893998 -98.9838)
		(end 42.245534 -98.632264)
		(width 0.12065)
		(layer "F.Cu")
		(net "SPIDI")
	)
	(segment
		(start 40.778938 -99.302062)
		(end 41.0972 -98.9838)
		(width 0.12065)
		(layer "F.Cu")
		(net "SPIDI")
	)
	(via
		(at 21.600668 -111.542576)
		(size 0.508)
		(drill 0.254)
		(layers "F.Cu" "B.Cu")
		(net "SPIDI")
	)
	(via
		(at 42.245534 -98.632264)
		(size 0.508)
		(drill 0.254)
		(layers "F.Cu" "B.Cu")
		(net "SPIDI")
	)
	(via
		(at 41.0972 -98.9838)
		(size 0.7112)
		(drill 0.3556)
		(layers "F.Cu" "B.Cu")
		(net "SPIDI")
	)
	(segment
		(start 20.470368 -112.672876)
		(end 21.600668 -111.542576)
		(width 0.12065)
		(layer "B.Cu")
		(net "SPIDI")
	)
	(segment
		(start 20.470368 -117.741446)
		(end 20.470368 -112.672876)
		(width 0.12065)
		(layer "B.Cu")
		(net "SPIDI")
	)
	(segment
		(start 21.820886 -108.33608)
		(end 21.82114 -110.185454)
		(width 0.127)
		(layer "In2.Cu")
		(net "SPIDI")
	)
	(segment
		(start 39.732966 -97.0661)
		(end 39.732712 -97.066354)
		(width 0.127)
		(layer "In2.Cu")
		(net "SPIDI")
	)
	(segment
		(start 40.679116 -97.065846)
		(end 40.048688 -97.065846)
		(width 0.127)
		(layer "In2.Cu")
		(net "SPIDI")
	)
	(segment
		(start 34.55289 -99.23272)
		(end 32.766254 -99.232466)
		(width 0.127)
		(layer "In2.Cu")
		(net "SPIDI")
	)
	(segment
		(start 37.140388 -97.065846)
		(end 34.973514 -99.23272)
		(width 0.127)
		(layer "In2.Cu")
		(net "SPIDI")
	)
	(segment
		(start 39.732712 -97.066354)
		(end 38.680136 -97.066354)
		(width 0.127)
		(layer "In2.Cu")
		(net "SPIDI")
	)
	(segment
		(start 40.048688 -97.065846)
		(end 40.048434 -97.0661)
		(width 0.127)
		(layer "In2.Cu")
		(net "SPIDI")
	)
	(segment
		(start 21.82114 -110.185454)
		(end 21.82114 -111.322104)
		(width 0.127)
		(layer "In2.Cu")
		(net "SPIDI")
	)
	(segment
		(start 32.766254 -99.232466)
		(end 28.456636 -103.542084)
		(width 0.127)
		(layer "In2.Cu")
		(net "SPIDI")
	)
	(segment
		(start 38.679628 -97.065846)
		(end 37.140388 -97.065846)
		(width 0.127)
		(layer "In2.Cu")
		(net "SPIDI")
	)
	(segment
		(start 21.82114 -111.322104)
		(end 21.600668 -111.542576)
		(width 0.127)
		(layer "In2.Cu")
		(net "SPIDI")
	)
	(segment
		(start 40.048434 -97.0661)
		(end 39.732966 -97.0661)
		(width 0.127)
		(layer "In2.Cu")
		(net "SPIDI")
	)
	(segment
		(start 26.98877 -103.542084)
		(end 25.456388 -105.074466)
		(width 0.127)
		(layer "In2.Cu")
		(net "SPIDI")
	)
	(segment
		(start 34.973514 -99.23272)
		(end 34.55289 -99.23272)
		(width 0.127)
		(layer "In2.Cu")
		(net "SPIDI")
	)
	(segment
		(start 25.456388 -105.074466)
		(end 25.0825 -105.074466)
		(width 0.127)
		(layer "In2.Cu")
		(net "SPIDI")
	)
	(segment
		(start 42.245534 -98.632264)
		(end 40.679116 -97.065846)
		(width 0.127)
		(layer "In2.Cu")
		(net "SPIDI")
	)
	(segment
		(start 38.680136 -97.066354)
		(end 38.679628 -97.065846)
		(width 0.127)
		(layer "In2.Cu")
		(net "SPIDI")
	)
	(segment
		(start 25.0825 -105.074466)
		(end 21.820886 -108.33608)
		(width 0.127)
		(layer "In2.Cu")
		(net "SPIDI")
	)
	(segment
		(start 28.456636 -103.542084)
		(end 26.98877 -103.542084)
		(width 0.127)
		(layer "In2.Cu")
		(net "SPIDI")
	)
	(segment
		(start 26.775918 -119.663718)
		(end 27.178 -120.0658)
		(width 0.12065)
		(layer "F.Cu")
		(net "SPICS0_N_R")
	)
	(segment
		(start 25.117552 -119.624348)
		(end 25.117552 -119.179848)
		(width 0.12065)
		(layer "F.Cu")
		(net "SPICS0_N_R")
	)
	(segment
		(start 24.5618 -120.1801)
		(end 25.117552 -119.624348)
		(width 0.12065)
		(layer "F.Cu")
		(net "SPICS0_N_R")
	)
	(segment
		(start 25.358852 -118.938548)
		(end 26.133044 -118.938548)
		(width 0.12065)
		(layer "F.Cu")
		(net "SPICS0_N_R")
	)
	(segment
		(start 26.133044 -118.938548)
		(end 26.775918 -119.581422)
		(width 0.12065)
		(layer "F.Cu")
		(net "SPICS0_N_R")
	)
	(segment
		(start 26.775918 -119.581422)
		(end 26.775918 -119.663718)
		(width 0.12065)
		(layer "F.Cu")
		(net "SPICS0_N_R")
	)
	(segment
		(start 27.178 -120.0658)
		(end 27.178 -120.424956)
		(width 0.12065)
		(layer "F.Cu")
		(net "SPICS0_N_R")
	)
	(segment
		(start 29.63799 -122.884946)
		(end 29.704792 -122.884946)
		(width 0.12065)
		(layer "F.Cu")
		(net "SPICS0_N_R")
	)
	(segment
		(start 27.178 -120.424956)
		(end 29.63799 -122.884946)
		(width 0.12065)
		(layer "F.Cu")
		(net "SPICS0_N_R")
	)
	(segment
		(start 25.117552 -119.179848)
		(end 25.358852 -118.938548)
		(width 0.12065)
		(layer "F.Cu")
		(net "SPICS0_N_R")
	)
	(via
		(at 27.178 -120.0658)
		(size 0.7112)
		(drill 0.3556)
		(layers "F.Cu" "B.Cu")
		(net "SPICS0_N_R")
	)
	(segment
		(start 27.268932 -104.125268)
		(end 27.268932 -104.118664)
		(width 0.12065)
		(layer "F.Cu")
		(net "SPICS0_N")
	)
	(segment
		(start 27.837638 -104.26446)
		(end 30.92704 -104.26446)
		(width 0.12065)
		(layer "F.Cu")
		(net "SPICS0_N")
	)
	(segment
		(start 27.691842 -104.118664)
		(end 27.837638 -104.26446)
		(width 0.12065)
		(layer "F.Cu")
		(net "SPICS0_N")
	)
	(segment
		(start 34.544 -99.801934)
		(end 34.544 -100.2284)
		(width 0.12065)
		(layer "F.Cu")
		(net "SPICS0_N")
	)
	(segment
		(start 32.36214 -101.49586)
		(end 33.02 -100.838)
		(width 0.12065)
		(layer "F.Cu")
		(net "SPICS0_N")
	)
	(segment
		(start 33.9344 -100.838)
		(end 33.02 -100.838)
		(width 0.12065)
		(layer "F.Cu")
		(net "SPICS0_N")
	)
	(segment
		(start 24.5618 -119.2911)
		(end 24.5618 -118.5926)
		(width 0.12065)
		(layer "F.Cu")
		(net "SPICS0_N")
	)
	(segment
		(start 32.36214 -102.82936)
		(end 32.36214 -101.49586)
		(width 0.12065)
		(layer "F.Cu")
		(net "SPICS0_N")
	)
	(segment
		(start 27.268932 -104.118664)
		(end 27.691842 -104.118664)
		(width 0.12065)
		(layer "F.Cu")
		(net "SPICS0_N")
	)
	(segment
		(start 30.92704 -104.26446)
		(end 32.3596 -102.8319)
		(width 0.12065)
		(layer "F.Cu")
		(net "SPICS0_N")
	)
	(segment
		(start 34.544 -100.2284)
		(end 33.9344 -100.838)
		(width 0.12065)
		(layer "F.Cu")
		(net "SPICS0_N")
	)
	(segment
		(start 32.3596 -102.8319)
		(end 32.36214 -102.82936)
		(width 0.12065)
		(layer "F.Cu")
		(net "SPICS0_N")
	)
	(segment
		(start 24.5618 -118.5926)
		(end 24.6634 -118.491)
		(width 0.12065)
		(layer "F.Cu")
		(net "SPICS0_N")
	)
	(via
		(at 24.6634 -118.491)
		(size 0.508)
		(drill 0.254)
		(layers "F.Cu" "B.Cu")
		(net "SPICS0_N")
	)
	(via
		(at 33.02 -100.838)
		(size 0.7112)
		(drill 0.3556)
		(layers "F.Cu" "B.Cu")
		(net "SPICS0_N")
	)
	(via
		(at 27.268932 -104.125268)
		(size 0.508)
		(drill 0.254)
		(layers "F.Cu" "B.Cu")
		(net "SPICS0_N")
	)
	(segment
		(start 21.2852 -118.749318)
		(end 21.572982 -119.0371)
		(width 0.127)
		(layer "In2.Cu")
		(net "SPICS0_N")
	)
	(segment
		(start 27.268932 -104.125268)
		(end 27.124152 -104.125268)
		(width 0.127)
		(layer "In2.Cu")
		(net "SPICS0_N")
	)
	(segment
		(start 21.284946 -113.23193)
		(end 21.2852 -113.232184)
		(width 0.127)
		(layer "In2.Cu")
		(net "SPICS0_N")
	)
	(segment
		(start 21.2852 -112.875568)
		(end 21.284946 -112.875822)
		(width 0.127)
		(layer "In2.Cu")
		(net "SPICS0_N")
	)
	(segment
		(start 22.978618 -119.0117)
		(end 23.499318 -118.491)
		(width 0.127)
		(layer "In2.Cu")
		(net "SPICS0_N")
	)
	(segment
		(start 25.666954 -105.582466)
		(end 25.317958 -105.582466)
		(width 0.127)
		(layer "In2.Cu")
		(net "SPICS0_N")
	)
	(segment
		(start 21.2852 -113.232184)
		(end 21.2852 -118.749318)
		(width 0.127)
		(layer "In2.Cu")
		(net "SPICS0_N")
	)
	(segment
		(start 22.512782 -119.0371)
		(end 22.538182 -119.0117)
		(width 0.127)
		(layer "In2.Cu")
		(net "SPICS0_N")
	)
	(segment
		(start 22.32914 -108.571284)
		(end 22.32914 -111.767112)
		(width 0.127)
		(layer "In2.Cu")
		(net "SPICS0_N")
	)
	(segment
		(start 27.124152 -104.125268)
		(end 25.666954 -105.582466)
		(width 0.127)
		(layer "In2.Cu")
		(net "SPICS0_N")
	)
	(segment
		(start 23.499318 -118.491)
		(end 24.6634 -118.491)
		(width 0.127)
		(layer "In2.Cu")
		(net "SPICS0_N")
	)
	(segment
		(start 21.284946 -112.875822)
		(end 21.284946 -113.23193)
		(width 0.127)
		(layer "In2.Cu")
		(net "SPICS0_N")
	)
	(segment
		(start 22.538182 -119.0117)
		(end 22.978618 -119.0117)
		(width 0.127)
		(layer "In2.Cu")
		(net "SPICS0_N")
	)
	(segment
		(start 21.2852 -112.811052)
		(end 21.2852 -112.875568)
		(width 0.127)
		(layer "In2.Cu")
		(net "SPICS0_N")
	)
	(segment
		(start 22.32914 -111.767112)
		(end 21.2852 -112.811052)
		(width 0.127)
		(layer "In2.Cu")
		(net "SPICS0_N")
	)
	(segment
		(start 21.572982 -119.0371)
		(end 22.512782 -119.0371)
		(width 0.127)
		(layer "In2.Cu")
		(net "SPICS0_N")
	)
	(segment
		(start 25.317958 -105.582466)
		(end 22.32914 -108.571284)
		(width 0.127)
		(layer "In2.Cu")
		(net "SPICS0_N")
	)
	(segment
		(start 31.705042 -126.485142)
		(end 32.104838 -126.884938)
		(width 0.12065)
		(layer "F.Cu")
		(net "SPICK_R")
	)
	(via
		(at 27.1526 -124.186442)
		(size 0.7112)
		(drill 0.3556)
		(layers "F.Cu" "B.Cu")
		(net "SPICK_R")
	)
	(via
		(at 31.705042 -126.485142)
		(size 0.4572)
		(drill 0.2032)
		(layers "F.Cu" "B.Cu")
		(net "SPICK_R")
	)
	(segment
		(start 24.8031 -123.317)
		(end 25.914604 -123.317)
		(width 0.12065)
		(layer "B.Cu")
		(net "SPICK_R")
	)
	(segment
		(start 29.041598 -126.07544)
		(end 30.738572 -126.07544)
		(width 0.12065)
		(layer "B.Cu")
		(net "SPICK_R")
	)
	(segment
		(start 31.298388 -126.078488)
		(end 31.705042 -126.485142)
		(width 0.12065)
		(layer "B.Cu")
		(net "SPICK_R")
	)
	(segment
		(start 25.914604 -123.317)
		(end 26.542492 -123.944888)
		(width 0.12065)
		(layer "B.Cu")
		(net "SPICK_R")
	)
	(segment
		(start 26.542492 -123.944888)
		(end 26.911046 -123.944888)
		(width 0.12065)
		(layer "B.Cu")
		(net "SPICK_R")
	)
	(segment
		(start 27.1526 -124.186442)
		(end 29.041598 -126.07544)
		(width 0.12065)
		(layer "B.Cu")
		(net "SPICK_R")
	)
	(segment
		(start 26.911046 -123.944888)
		(end 27.1526 -124.186442)
		(width 0.12065)
		(layer "B.Cu")
		(net "SPICK_R")
	)
	(segment
		(start 30.738572 -126.07544)
		(end 30.74162 -126.078488)
		(width 0.12065)
		(layer "B.Cu")
		(net "SPICK_R")
	)
	(segment
		(start 30.74162 -126.078488)
		(end 31.298388 -126.078488)
		(width 0.12065)
		(layer "B.Cu")
		(net "SPICK_R")
	)
	(segment
		(start 24.5745 -123.0884)
		(end 24.8031 -123.317)
		(width 0.12065)
		(layer "B.Cu")
		(net "SPICK_R")
	)
	(segment
		(start 31.9024 -98.2218)
		(end 32.31642 -98.2218)
		(width 0.12065)
		(layer "F.Cu")
		(net "SPICK")
	)
	(segment
		(start 32.396684 -98.302064)
		(end 34.544 -98.302064)
		(width 0.12065)
		(layer "F.Cu")
		(net "SPICK")
	)
	(segment
		(start 32.31642 -98.2218)
		(end 32.396684 -98.302064)
		(width 0.12065)
		(layer "F.Cu")
		(net "SPICK")
	)
	(via
		(at 31.9024 -98.2218)
		(size 0.508)
		(drill 0.254)
		(layers "F.Cu" "B.Cu")
		(net "SPICK")
	)
	(via
		(at 21.936202 -121.809002)
		(size 0.7112)
		(drill 0.3556)
		(layers "F.Cu" "B.Cu")
		(net "SPICK")
	)
	(via
		(at 18.600928 -121.135648)
		(size 0.508)
		(drill 0.254)
		(layers "F.Cu" "B.Cu")
		(net "SPICK")
	)
	(segment
		(start 18.994628 -120.741948)
		(end 20.628102 -120.741948)
		(width 0.12065)
		(layer "B.Cu")
		(net "SPICK")
	)
	(segment
		(start 22.4536 -122.3264)
		(end 21.936202 -121.809002)
		(width 0.12065)
		(layer "B.Cu")
		(net "SPICK")
	)
	(segment
		(start 22.4536 -122.7074)
		(end 22.4536 -122.3264)
		(width 0.12065)
		(layer "B.Cu")
		(net "SPICK")
	)
	(segment
		(start 20.628102 -120.741948)
		(end 21.695156 -121.809002)
		(width 0.12065)
		(layer "B.Cu")
		(net "SPICK")
	)
	(segment
		(start 23.6855 -123.0884)
		(end 22.8346 -123.0884)
		(width 0.12065)
		(layer "B.Cu")
		(net "SPICK")
	)
	(segment
		(start 18.600928 -121.135648)
		(end 18.994628 -120.741948)
		(width 0.12065)
		(layer "B.Cu")
		(net "SPICK")
	)
	(segment
		(start 21.695156 -121.809002)
		(end 21.936202 -121.809002)
		(width 0.12065)
		(layer "B.Cu")
		(net "SPICK")
	)
	(segment
		(start 22.8346 -123.0884)
		(end 22.4536 -122.7074)
		(width 0.12065)
		(layer "B.Cu")
		(net "SPICK")
	)
	(segment
		(start 19.177 -120.559576)
		(end 19.177 -113.6523)
		(width 0.127)
		(layer "In2.Cu")
		(net "SPICK")
	)
	(segment
		(start 23.98522 -104.528112)
		(end 23.98522 -103.98506)
		(width 0.127)
		(layer "In2.Cu")
		(net "SPICK")
	)
	(segment
		(start 23.98522 -103.98506)
		(end 24.945086 -103.025194)
		(width 0.127)
		(layer "In2.Cu")
		(net "SPICK")
	)
	(segment
		(start 18.600928 -121.135648)
		(end 19.177 -120.559576)
		(width 0.127)
		(layer "In2.Cu")
		(net "SPICK")
	)
	(segment
		(start 25.88895 -103.025194)
		(end 27.1526 -101.761544)
		(width 0.127)
		(layer "In2.Cu")
		(net "SPICK")
	)
	(segment
		(start 31.920688 -98.461322)
		(end 31.920688 -98.240088)
		(width 0.127)
		(layer "In2.Cu")
		(net "SPICK")
	)
	(segment
		(start 19.62785 -110.050834)
		(end 20.677886 -109.000798)
		(width 0.127)
		(layer "In2.Cu")
		(net "SPICK")
	)
	(segment
		(start 27.1526 -101.761544)
		(end 28.620466 -101.761544)
		(width 0.127)
		(layer "In2.Cu")
		(net "SPICK")
	)
	(segment
		(start 19.177 -113.6523)
		(end 19.62785 -113.20145)
		(width 0.127)
		(layer "In2.Cu")
		(net "SPICK")
	)
	(segment
		(start 20.677886 -109.000798)
		(end 20.677886 -107.835446)
		(width 0.127)
		(layer "In2.Cu")
		(net "SPICK")
	)
	(segment
		(start 24.945086 -103.025194)
		(end 25.88895 -103.025194)
		(width 0.127)
		(layer "In2.Cu")
		(net "SPICK")
	)
	(segment
		(start 31.920688 -98.240088)
		(end 31.9024 -98.2218)
		(width 0.127)
		(layer "In2.Cu")
		(net "SPICK")
	)
	(segment
		(start 20.677886 -107.835446)
		(end 23.98522 -104.528112)
		(width 0.127)
		(layer "In2.Cu")
		(net "SPICK")
	)
	(segment
		(start 19.62785 -113.20145)
		(end 19.62785 -110.050834)
		(width 0.127)
		(layer "In2.Cu")
		(net "SPICK")
	)
	(segment
		(start 28.620466 -101.761544)
		(end 31.920688 -98.461322)
		(width 0.127)
		(layer "In2.Cu")
		(net "SPICK")
	)
	(segment
		(start 38.1 -97.302066)
		(end 38.1 -94.989396)
		(width 0.12065)
		(layer "F.Cu")
		(net "I210_SO_R")
	)
	(segment
		(start 29.168852 -85.379052)
		(end 30.988 -87.1982)
		(width 0.12065)
		(layer "F.Cu")
		(net "I210_SO_R")
	)
	(segment
		(start 38.1 -94.989396)
		(end 38.54704 -94.542356)
		(width 0.12065)
		(layer "F.Cu")
		(net "I210_SO_R")
	)
	(segment
		(start 39.769542 -94.436946)
		(end 38.65245 -94.436946)
		(width 0.12065)
		(layer "F.Cu")
		(net "I210_SO_R")
	)
	(segment
		(start 27.6479 -82.3214)
		(end 29.168852 -83.842352)
		(width 0.12065)
		(layer "F.Cu")
		(net "I210_SO_R")
	)
	(segment
		(start 38.65245 -94.436946)
		(end 38.54704 -94.542356)
		(width 0.12065)
		(layer "F.Cu")
		(net "I210_SO_R")
	)
	(segment
		(start 26.4541 -82.3214)
		(end 27.6479 -82.3214)
		(width 0.12065)
		(layer "F.Cu")
		(net "I210_SO_R")
	)
	(segment
		(start 29.168852 -83.842352)
		(end 29.168852 -85.379052)
		(width 0.12065)
		(layer "F.Cu")
		(net "I210_SO_R")
	)
	(via
		(at 38.54704 -94.542356)
		(size 0.7112)
		(drill 0.3556)
		(layers "F.Cu" "B.Cu")
		(net "I210_SO_R")
	)
	(via
		(at 39.769542 -94.436946)
		(size 0.508)
		(drill 0.254)
		(layers "F.Cu" "B.Cu")
		(net "I210_SO_R")
	)
	(via
		(at 30.988 -87.1982)
		(size 0.508)
		(drill 0.254)
		(layers "F.Cu" "B.Cu")
		(net "I210_SO_R")
	)
	(segment
		(start 36.728654 -94.436946)
		(end 39.769542 -94.436946)
		(width 0.127)
		(layer "In5.Cu")
		(net "I210_SO_R")
	)
	(segment
		(start 30.988 -88.696292)
		(end 36.728654 -94.436946)
		(width 0.127)
		(layer "In5.Cu")
		(net "I210_SO_R")
	)
	(segment
		(start 30.988 -87.1982)
		(end 30.988 -88.696292)
		(width 0.127)
		(layer "In5.Cu")
		(net "I210_SO_R")
	)
	(segment
		(start 26.713688 -81.537048)
		(end 27.319732 -81.537048)
		(width 0.12065)
		(layer "F.Cu")
		(net "I210_SK_R")
	)
	(segment
		(start 26.40076 -81.22412)
		(end 26.713688 -81.537048)
		(width 0.12065)
		(layer "F.Cu")
		(net "I210_SK_R")
	)
	(segment
		(start 31.932372 -97.358708)
		(end 31.932372 -97.369122)
		(width 0.12065)
		(layer "F.Cu")
		(net "I210_SK_R")
	)
	(segment
		(start 32.04845 -97.4852)
		(end 33.113218 -97.4852)
		(width 0.12065)
		(layer "F.Cu")
		(net "I210_SK_R")
	)
	(segment
		(start 33.429956 -97.801938)
		(end 34.544 -97.801938)
		(width 0.12065)
		(layer "F.Cu")
		(net "I210_SK_R")
	)
	(segment
		(start 33.113218 -97.4852)
		(end 33.429956 -97.801938)
		(width 0.12065)
		(layer "F.Cu")
		(net "I210_SK_R")
	)
	(segment
		(start 31.932372 -97.369122)
		(end 32.04845 -97.4852)
		(width 0.12065)
		(layer "F.Cu")
		(net "I210_SK_R")
	)
	(via
		(at 27.319732 -81.537048)
		(size 0.508)
		(drill 0.254)
		(layers "F.Cu" "B.Cu")
		(net "I210_SK_R")
	)
	(via
		(at 31.932372 -97.358708)
		(size 0.508)
		(drill 0.254)
		(layers "F.Cu" "B.Cu")
		(net "I210_SK_R")
	)
	(via
		(at 28.194 -82.3468)
		(size 0.7112)
		(drill 0.3556)
		(layers "F.Cu" "B.Cu")
		(net "I210_SK_R")
	)
	(segment
		(start 31.9278 -96.63176)
		(end 31.9278 -97.354136)
		(width 0.12065)
		(layer "B.Cu")
		(net "I210_SK_R")
	)
	(segment
		(start 28.194 -82.3468)
		(end 29.448252 -83.601052)
		(width 0.12065)
		(layer "B.Cu")
		(net "I210_SK_R")
	)
	(segment
		(start 28.129484 -82.3468)
		(end 28.194 -82.3468)
		(width 0.12065)
		(layer "B.Cu")
		(net "I210_SK_R")
	)
	(segment
		(start 30.3911 -91.6051)
		(end 30.3911 -95.09506)
		(width 0.12065)
		(layer "B.Cu")
		(net "I210_SK_R")
	)
	(segment
		(start 31.9278 -97.354136)
		(end 31.932372 -97.358708)
		(width 0.12065)
		(layer "B.Cu")
		(net "I210_SK_R")
	)
	(segment
		(start 27.319732 -81.537048)
		(end 28.129484 -82.3468)
		(width 0.12065)
		(layer "B.Cu")
		(net "I210_SK_R")
	)
	(segment
		(start 30.3911 -95.09506)
		(end 31.9278 -96.63176)
		(width 0.12065)
		(layer "B.Cu")
		(net "I210_SK_R")
	)
	(segment
		(start 29.448252 -90.662252)
		(end 30.3911 -91.6051)
		(width 0.12065)
		(layer "B.Cu")
		(net "I210_SK_R")
	)
	(segment
		(start 29.448252 -83.601052)
		(end 29.448252 -90.662252)
		(width 0.12065)
		(layer "B.Cu")
		(net "I210_SK_R")
	)
	(segment
		(start 30.962346 -85.267546)
		(end 30.962346 -84.3026)
		(width 0.12065)
		(layer "F.Cu")
		(net "I210_SI_R")
	)
	(segment
		(start 38.1 -98.801936)
		(end 40.29837 -98.801936)
		(width 0.12065)
		(layer "F.Cu")
		(net "I210_SI_R")
	)
	(segment
		(start 41.6306 -97.469706)
		(end 41.6306 -93.7006)
		(width 0.12065)
		(layer "F.Cu")
		(net "I210_SI_R")
	)
	(segment
		(start 30.404816 -83.74507)
		(end 30.38094 -83.74507)
		(width 0.12065)
		(layer "F.Cu")
		(net "I210_SI_R")
	)
	(segment
		(start 40.29837 -98.801936)
		(end 41.6306 -97.469706)
		(width 0.12065)
		(layer "F.Cu")
		(net "I210_SI_R")
	)
	(segment
		(start 26.834846 -80.1751)
		(end 26.41346 -80.1751)
		(width 0.12065)
		(layer "F.Cu")
		(net "I210_SI_R")
	)
	(segment
		(start 34.7218 -89.027)
		(end 30.962346 -85.267546)
		(width 0.12065)
		(layer "F.Cu")
		(net "I210_SI_R")
	)
	(segment
		(start 36.957 -89.027)
		(end 34.7218 -89.027)
		(width 0.12065)
		(layer "F.Cu")
		(net "I210_SI_R")
	)
	(segment
		(start 30.962346 -84.3026)
		(end 30.404816 -83.74507)
		(width 0.12065)
		(layer "F.Cu")
		(net "I210_SI_R")
	)
	(segment
		(start 40.716962 -92.786962)
		(end 36.957 -89.027)
		(width 0.12065)
		(layer "F.Cu")
		(net "I210_SI_R")
	)
	(segment
		(start 28.323794 -81.687924)
		(end 28.323794 -81.664048)
		(width 0.12065)
		(layer "F.Cu")
		(net "I210_SI_R")
	)
	(segment
		(start 41.6306 -93.7006)
		(end 40.716962 -92.786962)
		(width 0.12065)
		(layer "F.Cu")
		(net "I210_SI_R")
	)
	(segment
		(start 28.323794 -81.664048)
		(end 26.834846 -80.1751)
		(width 0.12065)
		(layer "F.Cu")
		(net "I210_SI_R")
	)
	(segment
		(start 30.38094 -83.74507)
		(end 28.323794 -81.687924)
		(width 0.12065)
		(layer "F.Cu")
		(net "I210_SI_R")
	)
	(via
		(at 40.716962 -92.786962)
		(size 0.7112)
		(drill 0.3556)
		(layers "F.Cu" "B.Cu")
		(net "I210_SI_R")
	)
	(segment
		(start 26.827988 -83.876388)
		(end 26.4287 -83.4771)
		(width 0.12065)
		(layer "F.Cu")
		(net "I210_CS_N_R")
	)
	(segment
		(start 26.909268 -83.876388)
		(end 26.827988 -83.876388)
		(width 0.12065)
		(layer "F.Cu")
		(net "I210_CS_N_R")
	)
	(segment
		(start 28.64485 -85.40115)
		(end 28.43403 -85.40115)
		(width 0.12065)
		(layer "F.Cu")
		(net "I210_CS_N_R")
	)
	(segment
		(start 33.616138 -99.302062)
		(end 34.544 -99.302062)
		(width 0.12065)
		(layer "F.Cu")
		(net "I210_CS_N_R")
	)
	(segment
		(start 31.56966 -101.34854)
		(end 33.616138 -99.302062)
		(width 0.12065)
		(layer "F.Cu")
		(net "I210_CS_N_R")
	)
	(segment
		(start 28.702 -85.344)
		(end 28.64485 -85.40115)
		(width 0.12065)
		(layer "F.Cu")
		(net "I210_CS_N_R")
	)
	(segment
		(start 28.43403 -85.40115)
		(end 26.909268 -83.876388)
		(width 0.12065)
		(layer "F.Cu")
		(net "I210_CS_N_R")
	)
	(segment
		(start 26.4287 -83.4771)
		(end 26.4287 -83.4644)
		(width 0.12065)
		(layer "F.Cu")
		(net "I210_CS_N_R")
	)
	(segment
		(start 31.56966 -102.08514)
		(end 31.56966 -101.34854)
		(width 0.12065)
		(layer "F.Cu")
		(net "I210_CS_N_R")
	)
	(via
		(at 31.56966 -102.08514)
		(size 0.508)
		(drill 0.254)
		(layers "F.Cu" "B.Cu")
		(net "I210_CS_N_R")
	)
	(via
		(at 26.024078 -88.31326)
		(size 0.7112)
		(drill 0.3556)
		(layers "F.Cu" "B.Cu")
		(net "I210_CS_N_R")
	)
	(via
		(at 28.702 -85.344)
		(size 0.508)
		(drill 0.254)
		(layers "F.Cu" "B.Cu")
		(net "I210_CS_N_R")
	)
	(segment
		(start 26.024078 -88.636602)
		(end 26.024078 -88.31326)
		(width 0.12065)
		(layer "B.Cu")
		(net "I210_CS_N_R")
	)
	(segment
		(start 31.56966 -101.16566)
		(end 28.702 -98.298)
		(width 0.12065)
		(layer "B.Cu")
		(net "I210_CS_N_R")
	)
	(segment
		(start 26.024078 -88.199722)
		(end 28.702 -85.5218)
		(width 0.12065)
		(layer "B.Cu")
		(net "I210_CS_N_R")
	)
	(segment
		(start 28.702 -98.298)
		(end 28.702 -91.314524)
		(width 0.12065)
		(layer "B.Cu")
		(net "I210_CS_N_R")
	)
	(segment
		(start 31.56966 -102.08514)
		(end 31.56966 -101.16566)
		(width 0.12065)
		(layer "B.Cu")
		(net "I210_CS_N_R")
	)
	(segment
		(start 28.702 -91.314524)
		(end 26.024078 -88.636602)
		(width 0.12065)
		(layer "B.Cu")
		(net "I210_CS_N_R")
	)
	(segment
		(start 26.024078 -88.31326)
		(end 26.024078 -88.199722)
		(width 0.12065)
		(layer "B.Cu")
		(net "I210_CS_N_R")
	)
	(segment
		(start 28.702 -85.5218)
		(end 28.702 -85.344)
		(width 0.12065)
		(layer "B.Cu")
		(net "I210_CS_N_R")
	)
	(segment
		(start 36.53663 -121.932192)
		(end 36.53663 -122.516646)
		(width 0.12065)
		(layer "F.Cu")
		(net "FM_TPM_PRES_N_R")
	)
	(segment
		(start 36.6522 -116.586)
		(end 36.0807 -116.0145)
		(width 0.12065)
		(layer "F.Cu")
		(net "FM_TPM_PRES_N_R")
	)
	(segment
		(start 36.6522 -118.3259)
		(end 36.6522 -116.586)
		(width 0.12065)
		(layer "F.Cu")
		(net "FM_TPM_PRES_N_R")
	)
	(segment
		(start 36.70808 -118.38178)
		(end 36.9316 -118.6053)
		(width 0.12065)
		(layer "F.Cu")
		(net "FM_TPM_PRES_N_R")
	)
	(segment
		(start 36.53663 -122.516646)
		(end 36.90493 -122.884946)
		(width 0.12065)
		(layer "F.Cu")
		(net "FM_TPM_PRES_N_R")
	)
	(segment
		(start 36.0807 -116.0145)
		(end 36.068 -116.0145)
		(width 0.12065)
		(layer "F.Cu")
		(net "FM_TPM_PRES_N_R")
	)
	(segment
		(start 36.9316 -121.537222)
		(end 36.53663 -121.932192)
		(width 0.12065)
		(layer "F.Cu")
		(net "FM_TPM_PRES_N_R")
	)
	(segment
		(start 36.9316 -118.6053)
		(end 36.9316 -121.537222)
		(width 0.12065)
		(layer "F.Cu")
		(net "FM_TPM_PRES_N_R")
	)
	(segment
		(start 36.70808 -118.38178)
		(end 36.6522 -118.3259)
		(width 0.12065)
		(layer "F.Cu")
		(net "FM_TPM_PRES_N_R")
	)
	(via
		(at 36.70808 -118.38178)
		(size 0.7112)
		(drill 0.3556)
		(layers "F.Cu" "B.Cu")
		(net "FM_TPM_PRES_N_R")
	)
	(segment
		(start 25.551638 -139.874752)
		(end 24.260048 -139.874752)
		(width 0.12065)
		(layer "F.Cu")
		(net "BMC_SELF_HW_RST_R")
	)
	(segment
		(start 28.83535 -137.859262)
		(end 27.172412 -139.5222)
		(width 0.12065)
		(layer "F.Cu")
		(net "BMC_SELF_HW_RST_R")
	)
	(segment
		(start 23.60676 -139.88796)
		(end 22.00656 -139.88796)
		(width 0.12065)
		(layer "F.Cu")
		(net "BMC_SELF_HW_RST_R")
	)
	(segment
		(start 25.625044 -139.801346)
		(end 25.551638 -139.874752)
		(width 0.12065)
		(layer "F.Cu")
		(net "BMC_SELF_HW_RST_R")
	)
	(segment
		(start 30.11424 -137.67562)
		(end 29.871162 -137.67562)
		(width 0.12065)
		(layer "F.Cu")
		(net "BMC_SELF_HW_RST_R")
	)
	(segment
		(start 27.172412 -139.5222)
		(end 25.9842 -139.5222)
		(width 0.12065)
		(layer "F.Cu")
		(net "BMC_SELF_HW_RST_R")
	)
	(segment
		(start 23.7236 -140.0048)
		(end 23.60676 -139.88796)
		(width 0.12065)
		(layer "F.Cu")
		(net "BMC_SELF_HW_RST_R")
	)
	(segment
		(start 30.504892 -137.284968)
		(end 30.11424 -137.67562)
		(width 0.12065)
		(layer "F.Cu")
		(net "BMC_SELF_HW_RST_R")
	)
	(segment
		(start 24.13 -140.0048)
		(end 23.7236 -140.0048)
		(width 0.12065)
		(layer "F.Cu")
		(net "BMC_SELF_HW_RST_R")
	)
	(segment
		(start 29.538422 -137.67562)
		(end 29.028136 -137.67562)
		(width 0.12065)
		(layer "F.Cu")
		(net "BMC_SELF_HW_RST_R")
	)
	(segment
		(start 22.00656 -139.88796)
		(end 21.9202 -139.8016)
		(width 0.12065)
		(layer "F.Cu")
		(net "BMC_SELF_HW_RST_R")
	)
	(segment
		(start 25.705054 -139.801346)
		(end 25.625044 -139.801346)
		(width 0.12065)
		(layer "F.Cu")
		(net "BMC_SELF_HW_RST_R")
	)
	(segment
		(start 28.844494 -137.859262)
		(end 28.83535 -137.859262)
		(width 0.12065)
		(layer "F.Cu")
		(net "BMC_SELF_HW_RST_R")
	)
	(segment
		(start 29.868114 -137.678668)
		(end 29.54147 -137.678668)
		(width 0.12065)
		(layer "F.Cu")
		(net "BMC_SELF_HW_RST_R")
	)
	(segment
		(start 29.028136 -137.67562)
		(end 28.844494 -137.859262)
		(width 0.12065)
		(layer "F.Cu")
		(net "BMC_SELF_HW_RST_R")
	)
	(segment
		(start 29.871162 -137.67562)
		(end 29.868114 -137.678668)
		(width 0.12065)
		(layer "F.Cu")
		(net "BMC_SELF_HW_RST_R")
	)
	(segment
		(start 24.260048 -139.874752)
		(end 24.13 -140.0048)
		(width 0.12065)
		(layer "F.Cu")
		(net "BMC_SELF_HW_RST_R")
	)
	(segment
		(start 25.9842 -139.5222)
		(end 25.705054 -139.801346)
		(width 0.12065)
		(layer "F.Cu")
		(net "BMC_SELF_HW_RST_R")
	)
	(segment
		(start 21.9202 -139.8016)
		(end 21.3741 -139.8016)
		(width 0.12065)
		(layer "F.Cu")
		(net "BMC_SELF_HW_RST_R")
	)
	(segment
		(start 29.54147 -137.678668)
		(end 29.538422 -137.67562)
		(width 0.12065)
		(layer "F.Cu")
		(net "BMC_SELF_HW_RST_R")
	)
	(via
		(at 23.7236 -140.0048)
		(size 0.7112)
		(drill 0.3556)
		(layers "F.Cu" "B.Cu")
		(net "BMC_SELF_HW_RST_R")
	)
	(segment
		(start 9.779 -71.3359)
		(end 10.7188 -71.3359)
		(width 0.1524)
		(layer "F.Cu")
		(net "XTAL_OUT_I210_R")
	)
	(segment
		(start 7.2136 -72.009)
		(end 7.8867 -71.3359)
		(width 0.1524)
		(layer "F.Cu")
		(net "XTAL_OUT_I210_R")
	)
	(segment
		(start 7.8867 -71.3359)
		(end 9.779 -71.3359)
		(width 0.1524)
		(layer "F.Cu")
		(net "XTAL_OUT_I210_R")
	)
	(segment
		(start 10.7188 -71.3359)
		(end 10.7315 -71.3486)
		(width 0.1524)
		(layer "F.Cu")
		(net "XTAL_OUT_I210_R")
	)
	(segment
		(start 7.2136 -73.13295)
		(end 7.2136 -72.009)
		(width 0.1524)
		(layer "F.Cu")
		(net "XTAL_OUT_I210_R")
	)
	(segment
		(start 13.737082 -73.416668)
		(end 13.066776 -73.416668)
		(width 0.1524)
		(layer "F.Cu")
		(net "XTAL_OUT_I210")
	)
	(segment
		(start 11.8364 -71.5645)
		(end 11.6205 -71.3486)
		(width 0.1524)
		(layer "F.Cu")
		(net "XTAL_OUT_I210")
	)
	(segment
		(start 13.066776 -73.416668)
		(end 11.8364 -72.186292)
		(width 0.1524)
		(layer "F.Cu")
		(net "XTAL_OUT_I210")
	)
	(segment
		(start 11.8364 -72.186292)
		(end 11.8364 -71.5645)
		(width 0.1524)
		(layer "F.Cu")
		(net "XTAL_OUT_I210")
	)
	(segment
		(start 10.7188 -70.2945)
		(end 9.779 -70.2945)
		(width 0.1524)
		(layer "F.Cu")
		(net "XTAL_IN_I210_R")
	)
	(segment
		(start 9.0805 -70.993)
		(end 7.747 -70.993)
		(width 0.1524)
		(layer "F.Cu")
		(net "XTAL_IN_I210_R")
	)
	(segment
		(start 7.747 -70.993)
		(end 7.2136 -70.4596)
		(width 0.1524)
		(layer "F.Cu")
		(net "XTAL_IN_I210_R")
	)
	(segment
		(start 9.779 -70.2945)
		(end 9.0805 -70.993)
		(width 0.1524)
		(layer "F.Cu")
		(net "XTAL_IN_I210_R")
	)
	(segment
		(start 10.7315 -70.3072)
		(end 10.7188 -70.2945)
		(width 0.1524)
		(layer "F.Cu")
		(net "XTAL_IN_I210_R")
	)
	(segment
		(start 7.2136 -70.4596)
		(end 7.2136 -68.80225)
		(width 0.1524)
		(layer "F.Cu")
		(net "XTAL_IN_I210_R")
	)
	(segment
		(start 12.997942 -72.916542)
		(end 12.1412 -72.0598)
		(width 0.1524)
		(layer "F.Cu")
		(net "XTAL_IN_I210")
	)
	(segment
		(start 13.737082 -72.916542)
		(end 12.997942 -72.916542)
		(width 0.1524)
		(layer "F.Cu")
		(net "XTAL_IN_I210")
	)
	(segment
		(start 12.1412 -70.8279)
		(end 11.6205 -70.3072)
		(width 0.1524)
		(layer "F.Cu")
		(net "XTAL_IN_I210")
	)
	(segment
		(start 12.1412 -72.0598)
		(end 12.1412 -70.8279)
		(width 0.1524)
		(layer "F.Cu")
		(net "XTAL_IN_I210")
	)
	(segment
		(start 22.1996 -103.251)
		(end 21.4376 -103.251)
		(width 0.12065)
		(layer "F.Cu")
		(net "VREF_2V2")
	)
	(segment
		(start 22.867112 -103.02621)
		(end 22.42439 -103.02621)
		(width 0.12065)
		(layer "F.Cu")
		(net "VREF_2V2")
	)
	(segment
		(start 21.4376 -103.251)
		(end 21.405596 -103.218996)
		(width 0.12065)
		(layer "F.Cu")
		(net "VREF_2V2")
	)
	(segment
		(start 21.405596 -102.258114)
		(end 20.538186 -102.258114)
		(width 0.12065)
		(layer "F.Cu")
		(net "VREF_2V2")
	)
	(segment
		(start 21.405596 -103.218996)
		(end 21.405596 -102.258114)
		(width 0.12065)
		(layer "F.Cu")
		(net "VREF_2V2")
	)
	(segment
		(start 22.42439 -103.02621)
		(end 22.1996 -103.251)
		(width 0.12065)
		(layer "F.Cu")
		(net "VREF_2V2")
	)
	(segment
		(start 20.538186 -102.258114)
		(end 20.32 -102.4763)
		(width 0.12065)
		(layer "F.Cu")
		(net "VREF_2V2")
	)
	(via
		(at 21.4376 -103.251)
		(size 0.7112)
		(drill 0.3556)
		(layers "F.Cu" "B.Cu")
		(net "VREF_2V2")
	)
	(segment
		(start 19.84248 -69.922898)
		(end 19.84248 -69.06768)
		(width 0.12065)
		(layer "F.Cu")
		(net "TP_SDP3")
	)
	(segment
		(start 19.91106 -71.242682)
		(end 19.91106 -69.991478)
		(width 0.12065)
		(layer "F.Cu")
		(net "TP_SDP3")
	)
	(segment
		(start 19.84248 -69.06768)
		(end 19.2532 -68.4784)
		(width 0.12065)
		(layer "F.Cu")
		(net "TP_SDP3")
	)
	(segment
		(start 19.91106 -69.991478)
		(end 19.84248 -69.922898)
		(width 0.12065)
		(layer "F.Cu")
		(net "TP_SDP3")
	)
	(segment
		(start 20.911058 -70.224142)
		(end 21.0058 -70.1294)
		(width 0.12065)
		(layer "F.Cu")
		(net "TP_SDP2")
	)
	(segment
		(start 21.0058 -67.9196)
		(end 21.1582 -67.7672)
		(width 0.12065)
		(layer "F.Cu")
		(net "TP_SDP2")
	)
	(segment
		(start 21.0058 -70.1294)
		(end 21.0058 -67.9196)
		(width 0.12065)
		(layer "F.Cu")
		(net "TP_SDP2")
	)
	(segment
		(start 20.911058 -71.242682)
		(end 20.911058 -70.224142)
		(width 0.12065)
		(layer "F.Cu")
		(net "TP_SDP2")
	)
	(segment
		(start 21.41093 -69.14007)
		(end 22.8854 -67.6656)
		(width 0.12065)
		(layer "F.Cu")
		(net "TP_SDP0")
	)
	(segment
		(start 21.41093 -71.242682)
		(end 21.41093 -69.14007)
		(width 0.12065)
		(layer "F.Cu")
		(net "TP_SDP0")
	)
	(segment
		(start 32.904938 -125.284992)
		(end 32.505142 -124.885196)
		(width 0.12065)
		(layer "F.Cu")
		(net "RST_BMC_EXTRST_N_R")
	)
	(via
		(at 22.252432 -141.65199)
		(size 0.508)
		(drill 0.254)
		(layers "F.Cu" "B.Cu")
		(net "RST_BMC_EXTRST_N_R")
	)
	(via
		(at 32.505142 -124.885196)
		(size 0.4572)
		(drill 0.2032)
		(layers "F.Cu" "B.Cu")
		(net "RST_BMC_EXTRST_N_R")
	)
	(segment
		(start 21.77288 -142.317216)
		(end 21.77288 -142.278354)
		(width 0.12065)
		(layer "B.Cu")
		(net "RST_BMC_EXTRST_N_R")
	)
	(segment
		(start 22.046438 -142.004796)
		(end 22.0853 -142.004796)
		(width 0.12065)
		(layer "B.Cu")
		(net "RST_BMC_EXTRST_N_R")
	)
	(segment
		(start 22.252432 -141.837664)
		(end 22.252432 -141.65199)
		(width 0.12065)
		(layer "B.Cu")
		(net "RST_BMC_EXTRST_N_R")
	)
	(segment
		(start 22.0853 -142.004796)
		(end 22.252432 -141.837664)
		(width 0.12065)
		(layer "B.Cu")
		(net "RST_BMC_EXTRST_N_R")
	)
	(segment
		(start 21.354288 -142.948406)
		(end 21.354288 -142.735808)
		(width 0.12065)
		(layer "B.Cu")
		(net "RST_BMC_EXTRST_N_R")
	)
	(segment
		(start 21.77288 -142.278354)
		(end 22.046438 -142.004796)
		(width 0.12065)
		(layer "B.Cu")
		(net "RST_BMC_EXTRST_N_R")
	)
	(segment
		(start 21.354288 -142.735808)
		(end 21.77288 -142.317216)
		(width 0.12065)
		(layer "B.Cu")
		(net "RST_BMC_EXTRST_N_R")
	)
	(segment
		(start 32.505142 -124.885196)
		(end 32.490664 -124.885196)
		(width 0.127)
		(layer "In5.Cu")
		(net "RST_BMC_EXTRST_N_R")
	)
	(segment
		(start 32.110934 -128.315466)
		(end 31.82874 -128.59766)
		(width 0.127)
		(layer "In5.Cu")
		(net "RST_BMC_EXTRST_N_R")
	)
	(segment
		(start 32.110934 -125.264926)
		(end 32.110934 -128.315466)
		(width 0.127)
		(layer "In5.Cu")
		(net "RST_BMC_EXTRST_N_R")
	)
	(segment
		(start 27.98064 -134.26948)
		(end 22.52472 -139.7254)
		(width 0.127)
		(layer "In5.Cu")
		(net "RST_BMC_EXTRST_N_R")
	)
	(segment
		(start 32.490664 -124.885196)
		(end 32.110934 -125.264926)
		(width 0.127)
		(layer "In5.Cu")
		(net "RST_BMC_EXTRST_N_R")
	)
	(segment
		(start 27.98064 -131.63804)
		(end 27.98064 -134.26948)
		(width 0.127)
		(layer "In5.Cu")
		(net "RST_BMC_EXTRST_N_R")
	)
	(segment
		(start 22.52472 -141.379702)
		(end 22.252432 -141.65199)
		(width 0.127)
		(layer "In5.Cu")
		(net "RST_BMC_EXTRST_N_R")
	)
	(segment
		(start 31.02102 -128.59766)
		(end 27.98064 -131.63804)
		(width 0.127)
		(layer "In5.Cu")
		(net "RST_BMC_EXTRST_N_R")
	)
	(segment
		(start 22.52472 -139.7254)
		(end 22.52472 -141.379702)
		(width 0.127)
		(layer "In5.Cu")
		(net "RST_BMC_EXTRST_N_R")
	)
	(segment
		(start 31.82874 -128.59766)
		(end 31.02102 -128.59766)
		(width 0.127)
		(layer "In5.Cu")
		(net "RST_BMC_EXTRST_N_R")
	)
	(segment
		(start 32.693864 -90.819224)
		(end 30.43682 -88.56218)
		(width 0.12065)
		(layer "F.Cu")
		(net "RST_BMC_EXTRST_N")
	)
	(segment
		(start 29.923994 -94.616524)
		(end 30.378146 -94.616524)
		(width 0.12065)
		(layer "F.Cu")
		(net "RST_BMC_EXTRST_N")
	)
	(segment
		(start 29.555694 -94.273624)
		(end 27.494738 -94.273624)
		(width 0.12065)
		(layer "F.Cu")
		(net "RST_BMC_EXTRST_N")
	)
	(segment
		(start 32.693864 -93.763846)
		(end 32.693864 -90.819224)
		(width 0.12065)
		(layer "F.Cu")
		(net "RST_BMC_EXTRST_N")
	)
	(segment
		(start 28.4226 -87.4268)
		(end 29.30144 -87.4268)
		(width 0.12065)
		(layer "F.Cu")
		(net "RST_BMC_EXTRST_N")
	)
	(segment
		(start 30.390846 -94.629224)
		(end 31.828486 -94.629224)
		(width 0.12065)
		(layer "F.Cu")
		(net "RST_BMC_EXTRST_N")
	)
	(segment
		(start 29.911294 -94.629224)
		(end 29.923994 -94.616524)
		(width 0.12065)
		(layer "F.Cu")
		(net "RST_BMC_EXTRST_N")
	)
	(segment
		(start 29.30144 -87.4268)
		(end 30.43682 -88.56218)
		(width 0.12065)
		(layer "F.Cu")
		(net "RST_BMC_EXTRST_N")
	)
	(segment
		(start 30.378146 -94.616524)
		(end 30.390846 -94.629224)
		(width 0.12065)
		(layer "F.Cu")
		(net "RST_BMC_EXTRST_N")
	)
	(segment
		(start 31.828486 -94.629224)
		(end 32.693864 -93.763846)
		(width 0.12065)
		(layer "F.Cu")
		(net "RST_BMC_EXTRST_N")
	)
	(segment
		(start 29.911294 -94.629224)
		(end 29.555694 -94.273624)
		(width 0.12065)
		(layer "F.Cu")
		(net "RST_BMC_EXTRST_N")
	)
	(via
		(at 30.43682 -88.56218)
		(size 0.7112)
		(drill 0.3556)
		(layers "F.Cu" "B.Cu")
		(net "RST_BMC_EXTRST_N")
	)
	(via
		(at 28.4226 -87.4268)
		(size 0.508)
		(drill 0.254)
		(layers "F.Cu" "B.Cu")
		(net "RST_BMC_EXTRST_N")
	)
	(via
		(at 16.002 -141.96822)
		(size 0.508)
		(drill 0.254)
		(layers "F.Cu" "B.Cu")
		(net "RST_BMC_EXTRST_N")
	)
	(segment
		(start 17.578832 -143.545052)
		(end 20.344638 -143.545052)
		(width 0.12065)
		(layer "B.Cu")
		(net "RST_BMC_EXTRST_N")
	)
	(segment
		(start 20.465288 -142.948406)
		(end 20.465288 -141.93012)
		(width 0.12065)
		(layer "B.Cu")
		(net "RST_BMC_EXTRST_N")
	)
	(segment
		(start 20.465288 -143.424402)
		(end 20.465288 -142.948406)
		(width 0.12065)
		(layer "B.Cu")
		(net "RST_BMC_EXTRST_N")
	)
	(segment
		(start 16.002 -141.96822)
		(end 17.578832 -143.545052)
		(width 0.12065)
		(layer "B.Cu")
		(net "RST_BMC_EXTRST_N")
	)
	(segment
		(start 20.465288 -141.93012)
		(end 20.500848 -141.89456)
		(width 0.12065)
		(layer "B.Cu")
		(net "RST_BMC_EXTRST_N")
	)
	(segment
		(start 20.344638 -143.545052)
		(end 20.465288 -143.424402)
		(width 0.12065)
		(layer "B.Cu")
		(net "RST_BMC_EXTRST_N")
	)
	(segment
		(start 9.83361 -103.650034)
		(end 9.83361 -103.965502)
		(width 0.127)
		(layer "In2.Cu")
		(net "RST_BMC_EXTRST_N")
	)
	(segment
		(start 28.4226 -87.4268)
		(end 28.406598 -87.4268)
		(width 0.127)
		(layer "In2.Cu")
		(net "RST_BMC_EXTRST_N")
	)
	(segment
		(start 12.62253 -139.573254)
		(end 15.017496 -141.96822)
		(width 0.127)
		(layer "In2.Cu")
		(net "RST_BMC_EXTRST_N")
	)
	(segment
		(start 4.950206 -111.661194)
		(end 4.950206 -132.138928)
		(width 0.127)
		(layer "In2.Cu")
		(net "RST_BMC_EXTRST_N")
	)
	(segment
		(start 4.950206 -132.138928)
		(end 12.384532 -139.573254)
		(width 0.127)
		(layer "In2.Cu")
		(net "RST_BMC_EXTRST_N")
	)
	(segment
		(start 9.833864 -104.042464)
		(end 8.125206 -105.751122)
		(width 0.127)
		(layer "In2.Cu")
		(net "RST_BMC_EXTRST_N")
	)
	(segment
		(start 12.384532 -139.573254)
		(end 12.62253 -139.573254)
		(width 0.127)
		(layer "In2.Cu")
		(net "RST_BMC_EXTRST_N")
	)
	(segment
		(start 23.861522 -91.097354)
		(end 23.04542 -91.097354)
		(width 0.127)
		(layer "In2.Cu")
		(net "RST_BMC_EXTRST_N")
	)
	(segment
		(start 9.834118 -103.51262)
		(end 9.834118 -103.649526)
		(width 0.127)
		(layer "In2.Cu")
		(net "RST_BMC_EXTRST_N")
	)
	(segment
		(start 9.834118 -103.649526)
		(end 9.83361 -103.650034)
		(width 0.127)
		(layer "In2.Cu")
		(net "RST_BMC_EXTRST_N")
	)
	(segment
		(start 19.034506 -93.345)
		(end 15.929356 -96.45015)
		(width 0.127)
		(layer "In2.Cu")
		(net "RST_BMC_EXTRST_N")
	)
	(segment
		(start 8.125206 -105.751122)
		(end 8.125206 -108.486194)
		(width 0.127)
		(layer "In2.Cu")
		(net "RST_BMC_EXTRST_N")
	)
	(segment
		(start 27.252676 -87.7062)
		(end 23.861522 -91.097354)
		(width 0.127)
		(layer "In2.Cu")
		(net "RST_BMC_EXTRST_N")
	)
	(segment
		(start 8.125206 -108.486194)
		(end 4.950206 -111.661194)
		(width 0.127)
		(layer "In2.Cu")
		(net "RST_BMC_EXTRST_N")
	)
	(segment
		(start 9.83361 -103.965502)
		(end 9.833864 -103.965756)
		(width 0.127)
		(layer "In2.Cu")
		(net "RST_BMC_EXTRST_N")
	)
	(segment
		(start 9.833864 -103.965756)
		(end 9.833864 -104.042464)
		(width 0.127)
		(layer "In2.Cu")
		(net "RST_BMC_EXTRST_N")
	)
	(segment
		(start 28.127198 -87.7062)
		(end 27.252676 -87.7062)
		(width 0.127)
		(layer "In2.Cu")
		(net "RST_BMC_EXTRST_N")
	)
	(segment
		(start 20.797774 -93.345)
		(end 19.034506 -93.345)
		(width 0.127)
		(layer "In2.Cu")
		(net "RST_BMC_EXTRST_N")
	)
	(segment
		(start 15.017496 -141.96822)
		(end 16.002 -141.96822)
		(width 0.127)
		(layer "In2.Cu")
		(net "RST_BMC_EXTRST_N")
	)
	(segment
		(start 15.929356 -97.417382)
		(end 9.834118 -103.51262)
		(width 0.127)
		(layer "In2.Cu")
		(net "RST_BMC_EXTRST_N")
	)
	(segment
		(start 23.04542 -91.097354)
		(end 20.797774 -93.345)
		(width 0.127)
		(layer "In2.Cu")
		(net "RST_BMC_EXTRST_N")
	)
	(segment
		(start 15.929356 -96.45015)
		(end 15.929356 -97.417382)
		(width 0.127)
		(layer "In2.Cu")
		(net "RST_BMC_EXTRST_N")
	)
	(segment
		(start 28.406598 -87.4268)
		(end 28.127198 -87.7062)
		(width 0.127)
		(layer "In2.Cu")
		(net "RST_BMC_EXTRST_N")
	)
	(segment
		(start 12.697206 -72.076818)
		(end 13.037058 -72.41667)
		(width 0.3048)
		(layer "F.Cu")
		(net "P1V5_I210")
	)
	(segment
		(start 13.037058 -72.41667)
		(end 13.737082 -72.41667)
		(width 0.3048)
		(layer "F.Cu")
		(net "P1V5_I210")
	)
	(segment
		(start 12.683236 -70.315836)
		(end 12.683236 -71.325994)
		(width 0.381)
		(layer "F.Cu")
		(net "P1V5_I210")
	)
	(segment
		(start 15.4432 -64.6684)
		(end 17.1958 -64.6684)
		(width 0.508)
		(layer "F.Cu")
		(net "P1V5_I210")
	)
	(segment
		(start 13.6271 -66.4845)
		(end 15.4432 -64.6684)
		(width 0.508)
		(layer "F.Cu")
		(net "P1V5_I210")
	)
	(segment
		(start 12.2936 -69.2785)
		(end 12.2936 -69.9262)
		(width 0.381)
		(layer "F.Cu")
		(net "P1V5_I210")
	)
	(segment
		(start 12.697206 -71.339964)
		(end 12.697206 -72.076818)
		(width 0.3048)
		(layer "F.Cu")
		(net "P1V5_I210")
	)
	(segment
		(start 17.1958 -64.6684)
		(end 17.2974 -64.77)
		(width 0.508)
		(layer "F.Cu")
		(net "P1V5_I210")
	)
	(segment
		(start 10.541 -66.4845)
		(end 11.4046 -66.4845)
		(width 0.508)
		(layer "F.Cu")
		(net "P1V5_I210")
	)
	(segment
		(start 12.417044 -76.416662)
		(end 12.189714 -76.189332)
		(width 0.254)
		(layer "F.Cu")
		(net "P1V5_I210")
	)
	(segment
		(start 13.737082 -76.416662)
		(end 12.417044 -76.416662)
		(width 0.254)
		(layer "F.Cu")
		(net "P1V5_I210")
	)
	(segment
		(start 11.4046 -66.4845)
		(end 13.6271 -66.4845)
		(width 0.508)
		(layer "F.Cu")
		(net "P1V5_I210")
	)
	(segment
		(start 17.2974 -65.8622)
		(end 17.2974 -64.77)
		(width 0.508)
		(layer "F.Cu")
		(net "P1V5_I210")
	)
	(segment
		(start 12.2936 -69.9262)
		(end 12.683236 -70.315836)
		(width 0.381)
		(layer "F.Cu")
		(net "P1V5_I210")
	)
	(segment
		(start 12.683236 -71.325994)
		(end 12.697206 -71.339964)
		(width 0.3048)
		(layer "F.Cu")
		(net "P1V5_I210")
	)
	(via
		(at 17.2974 -67.2338)
		(size 0.7112)
		(drill 0.3556)
		(layers "F.Cu" "B.Cu")
		(net "P1V5_I210")
	)
	(via
		(at 12.683236 -71.325994)
		(size 0.508)
		(drill 0.254)
		(layers "F.Cu" "B.Cu")
		(net "P1V5_I210")
	)
	(via
		(at 11.4046 -66.4845)
		(size 0.508)
		(drill 0.254)
		(layers "F.Cu" "B.Cu")
		(net "P1V5_I210")
	)
	(via
		(at 12.189714 -76.189332)
		(size 0.508)
		(drill 0.254)
		(layers "F.Cu" "B.Cu")
		(net "P1V5_I210")
	)
	(via
		(at 17.2974 -64.77)
		(size 0.508)
		(drill 0.254)
		(layers "F.Cu" "B.Cu")
		(net "P1V5_I210")
	)
	(segment
		(start 12.592812 -75.786234)
		(end 13.062458 -75.786234)
		(width 0.508)
		(layer "B.Cu")
		(net "P1V5_I210")
	)
	(segment
		(start 12.189714 -76.189332)
		(end 12.592812 -75.786234)
		(width 0.508)
		(layer "B.Cu")
		(net "P1V5_I210")
	)
	(segment
		(start 12.189714 -76.189332)
		(end 12.661646 -76.661264)
		(width 0.508)
		(layer "B.Cu")
		(net "P1V5_I210")
	)
	(segment
		(start 17.2974 -68.1736)
		(end 17.1196 -68.3514)
		(width 0.508)
		(layer "B.Cu")
		(net "P1V5_I210")
	)
	(segment
		(start 17.2974 -67.2338)
		(end 17.2974 -68.1736)
		(width 0.508)
		(layer "B.Cu")
		(net "P1V5_I210")
	)
	(segment
		(start 17.2974 -64.77)
		(end 17.2974 -67.2338)
		(width 0.508)
		(layer "B.Cu")
		(net "P1V5_I210")
	)
	(segment
		(start 12.661646 -76.661264)
		(end 13.06068 -76.661264)
		(width 0.508)
		(layer "B.Cu")
		(net "P1V5_I210")
	)
	(segment
		(start 13.8684 -81.6991)
		(end 12.9667 -81.6991)
		(width 0.508)
		(layer "F.Cu")
		(net "P0V9_I210")
	)
	(segment
		(start 14.1605 -81.407)
		(end 13.8684 -81.6991)
		(width 0.254)
		(layer "F.Cu")
		(net "P0V9_I210")
	)
	(segment
		(start 13.737082 -74.916538)
		(end 14.829282 -74.916538)
		(width 0.254)
		(layer "F.Cu")
		(net "P0V9_I210")
	)
	(segment
		(start 14.410944 -80.458056)
		(end 14.1605 -80.7085)
		(width 0.254)
		(layer "F.Cu")
		(net "P0V9_I210")
	)
	(segment
		(start 19.410934 -70.133718)
		(end 19.388328 -70.111112)
		(width 0.3048)
		(layer "F.Cu")
		(net "P0V9_I210")
	)
	(segment
		(start 21.4884 -76.962)
		(end 21.800312 -76.962)
		(width 0.254)
		(layer "F.Cu")
		(net "P0V9_I210")
	)
	(segment
		(start 19.388328 -69.781928)
		(end 19.2278 -69.6214)
		(width 0.3048)
		(layer "F.Cu")
		(net "P0V9_I210")
	)
	(segment
		(start 18.3642 -67.4243)
		(end 18.3642 -68.707)
		(width 0.3048)
		(layer "F.Cu")
		(net "P0V9_I210")
	)
	(segment
		(start 19.410934 -71.242682)
		(end 19.410934 -70.133718)
		(width 0.3048)
		(layer "F.Cu")
		(net "P0V9_I210")
	)
	(segment
		(start 19.388328 -70.111112)
		(end 19.388328 -69.781928)
		(width 0.3048)
		(layer "F.Cu")
		(net "P0V9_I210")
	)
	(segment
		(start 19.2278 -69.5706)
		(end 19.2278 -69.6214)
		(width 0.3048)
		(layer "F.Cu")
		(net "P0V9_I210")
	)
	(segment
		(start 21.845778 -76.916534)
		(end 22.584918 -76.916534)
		(width 0.254)
		(layer "F.Cu")
		(net "P0V9_I210")
	)
	(segment
		(start 14.1605 -80.7085)
		(end 14.1605 -81.407)
		(width 0.254)
		(layer "F.Cu")
		(net "P0V9_I210")
	)
	(segment
		(start 14.410944 -80.090518)
		(end 14.410944 -80.458056)
		(width 0.254)
		(layer "F.Cu")
		(net "P0V9_I210")
	)
	(segment
		(start 12.16914 -76.916534)
		(end 13.737082 -76.916534)
		(width 0.3048)
		(layer "F.Cu")
		(net "P0V9_I210")
	)
	(segment
		(start 19.2278 -69.6214)
		(end 19.2532 -69.6214)
		(width 0.3048)
		(layer "F.Cu")
		(net "P0V9_I210")
	)
	(segment
		(start 12.02817 -77.057504)
		(end 12.16914 -76.916534)
		(width 0.3048)
		(layer "F.Cu")
		(net "P0V9_I210")
	)
	(segment
		(start 21.800312 -76.962)
		(end 21.845778 -76.916534)
		(width 0.254)
		(layer "F.Cu")
		(net "P0V9_I210")
	)
	(segment
		(start 18.3642 -68.707)
		(end 19.2278 -69.5706)
		(width 0.3048)
		(layer "F.Cu")
		(net "P0V9_I210")
	)
	(via
		(at 12.02817 -77.057504)
		(size 0.508)
		(drill 0.254)
		(layers "F.Cu" "B.Cu")
		(net "P0V9_I210")
	)
	(via
		(at 19.2532 -69.6214)
		(size 0.508)
		(drill 0.254)
		(layers "F.Cu" "B.Cu")
		(net "P0V9_I210")
	)
	(via
		(at 12.9667 -81.6991)
		(size 0.508)
		(drill 0.254)
		(layers "F.Cu" "B.Cu")
		(net "P0V9_I210")
	)
	(via
		(at 21.4884 -76.962)
		(size 0.508)
		(drill 0.254)
		(layers "F.Cu" "B.Cu")
		(net "P0V9_I210")
	)
	(via
		(at 17.811496 -70.960996)
		(size 0.7112)
		(drill 0.3556)
		(layers "F.Cu" "B.Cu")
		(net "P0V9_I210")
	)
	(via
		(at 19.939 -70.5866)
		(size 0.7112)
		(drill 0.3556)
		(layers "F.Cu" "B.Cu")
		(net "P0V9_I210")
	)
	(via
		(at 14.829282 -74.916538)
		(size 0.508)
		(drill 0.254)
		(layers "F.Cu" "B.Cu")
		(net "P0V9_I210")
	)
	(segment
		(start 12.974066 -78.0034)
		(end 13.0175 -78.0034)
		(width 0.508)
		(layer "B.Cu")
		(net "P0V9_I210")
	)
	(segment
		(start 12.02817 -77.057504)
		(end 12.974066 -78.0034)
		(width 0.508)
		(layer "B.Cu")
		(net "P0V9_I210")
	)
	(segment
		(start 51.058572 -61.303916)
		(end 51.058572 -62.399672)
		(width 0.12065)
		(layer "F.Cu")
		(net "NVM_SO_R")
	)
	(segment
		(start 37.8206 -93.00591)
		(end 37.54501 -93.2815)
		(width 0.12065)
		(layer "F.Cu")
		(net "NVM_SO_R")
	)
	(segment
		(start 36.836858 -91.735402)
		(end 37.303202 -91.735402)
		(width 0.12065)
		(layer "F.Cu")
		(net "NVM_SO_R")
	)
	(segment
		(start 37.54501 -93.2815)
		(end 37.084 -93.2815)
		(width 0.12065)
		(layer "F.Cu")
		(net "NVM_SO_R")
	)
	(segment
		(start 51.058572 -62.399672)
		(end 52.4129 -63.754)
		(width 0.12065)
		(layer "F.Cu")
		(net "NVM_SO_R")
	)
	(segment
		(start 37.303202 -91.735402)
		(end 37.8206 -92.2528)
		(width 0.12065)
		(layer "F.Cu")
		(net "NVM_SO_R")
	)
	(segment
		(start 37.8206 -92.2528)
		(end 37.8206 -93.00591)
		(width 0.12065)
		(layer "F.Cu")
		(net "NVM_SO_R")
	)
	(segment
		(start 52.8701 -64.2112)
		(end 53.1368 -64.2112)
		(width 0.12065)
		(layer "F.Cu")
		(net "NVM_SO_R")
	)
	(segment
		(start 52.4129 -63.754)
		(end 52.8701 -64.2112)
		(width 0.12065)
		(layer "F.Cu")
		(net "NVM_SO_R")
	)
	(via
		(at 37.8206 -92.2528)
		(size 0.7112)
		(drill 0.3556)
		(layers "F.Cu" "B.Cu")
		(net "NVM_SO_R")
	)
	(via
		(at 36.836858 -91.735402)
		(size 0.508)
		(drill 0.254)
		(layers "F.Cu" "B.Cu")
		(net "NVM_SO_R")
	)
	(via
		(at 53.1368 -64.2112)
		(size 0.508)
		(drill 0.254)
		(layers "F.Cu" "B.Cu")
		(net "NVM_SO_R")
	)
	(segment
		(start 39.126414 -85.137244)
		(end 39.126414 -86.289642)
		(width 0.127)
		(layer "In5.Cu")
		(net "NVM_SO_R")
	)
	(segment
		(start 48.133 -69.215)
		(end 48.133 -76.130658)
		(width 0.127)
		(layer "In5.Cu")
		(net "NVM_SO_R")
	)
	(segment
		(start 53.1368 -64.2112)
		(end 48.133 -69.215)
		(width 0.127)
		(layer "In5.Cu")
		(net "NVM_SO_R")
	)
	(segment
		(start 39.126414 -86.289642)
		(end 36.836858 -88.579198)
		(width 0.127)
		(layer "In5.Cu")
		(net "NVM_SO_R")
	)
	(segment
		(start 36.836858 -88.579198)
		(end 36.836858 -91.735402)
		(width 0.127)
		(layer "In5.Cu")
		(net "NVM_SO_R")
	)
	(segment
		(start 48.133 -76.130658)
		(end 39.126414 -85.137244)
		(width 0.127)
		(layer "In5.Cu")
		(net "NVM_SO_R")
	)
	(segment
		(start 25.5651 -82.540602)
		(end 25.5651 -82.3214)
		(width 0.12065)
		(layer "F.Cu")
		(net "NVM_SO")
	)
	(segment
		(start 23.315422 -78.416658)
		(end 23.86076 -78.961996)
		(width 0.12065)
		(layer "F.Cu")
		(net "NVM_SO")
	)
	(segment
		(start 25.979374 -82.954876)
		(end 25.5651 -82.540602)
		(width 0.12065)
		(layer "F.Cu")
		(net "NVM_SO")
	)
	(segment
		(start 24.981916 -81.85277)
		(end 25.10917 -81.85277)
		(width 0.12065)
		(layer "F.Cu")
		(net "NVM_SO")
	)
	(segment
		(start 23.86076 -80.731614)
		(end 24.981916 -81.85277)
		(width 0.12065)
		(layer "F.Cu")
		(net "NVM_SO")
	)
	(segment
		(start 23.86076 -78.961996)
		(end 23.86076 -80.731614)
		(width 0.12065)
		(layer "F.Cu")
		(net "NVM_SO")
	)
	(segment
		(start 27.208988 -82.954876)
		(end 25.979374 -82.954876)
		(width 0.12065)
		(layer "F.Cu")
		(net "NVM_SO")
	)
	(segment
		(start 22.584918 -78.416658)
		(end 23.315422 -78.416658)
		(width 0.12065)
		(layer "F.Cu")
		(net "NVM_SO")
	)
	(segment
		(start 25.5651 -82.3087)
		(end 25.5651 -82.3214)
		(width 0.12065)
		(layer "F.Cu")
		(net "NVM_SO")
	)
	(segment
		(start 27.52979 -83.275678)
		(end 27.208988 -82.954876)
		(width 0.12065)
		(layer "F.Cu")
		(net "NVM_SO")
	)
	(segment
		(start 25.10917 -81.85277)
		(end 25.5651 -82.3087)
		(width 0.12065)
		(layer "F.Cu")
		(net "NVM_SO")
	)
	(via
		(at 27.52979 -83.275678)
		(size 0.7112)
		(drill 0.3556)
		(layers "F.Cu" "B.Cu")
		(net "NVM_SO")
	)
	(segment
		(start 49.788572 -51.8668)
		(end 49.788572 -50.750724)
		(width 0.12065)
		(layer "F.Cu")
		(net "NVM_SK_R")
	)
	(segment
		(start 35.868864 -91.735402)
		(end 35.868864 -93.028516)
		(width 0.12065)
		(layer "F.Cu")
		(net "NVM_SK_R")
	)
	(segment
		(start 35.28187 -94.321376)
		(end 35.28187 -93.61551)
		(width 0.12065)
		(layer "F.Cu")
		(net "NVM_SK_R")
	)
	(segment
		(start 35.868864 -93.028516)
		(end 35.28187 -93.61551)
		(width 0.12065)
		(layer "F.Cu")
		(net "NVM_SK_R")
	)
	(segment
		(start 49.788572 -53.303932)
		(end 49.788572 -51.8668)
		(width 0.12065)
		(layer "F.Cu")
		(net "NVM_SK_R")
	)
	(segment
		(start 34.611056 -94.99219)
		(end 35.28187 -94.321376)
		(width 0.12065)
		(layer "F.Cu")
		(net "NVM_SK_R")
	)
	(via
		(at 35.868864 -91.735402)
		(size 0.508)
		(drill 0.254)
		(layers "F.Cu" "B.Cu")
		(net "NVM_SK_R")
	)
	(via
		(at 49.098962 -67.13474)
		(size 0.508)
		(drill 0.254)
		(layers "F.Cu" "B.Cu")
		(net "NVM_SK_R")
	)
	(via
		(at 49.788572 -51.8668)
		(size 0.508)
		(drill 0.254)
		(layers "F.Cu" "B.Cu")
		(net "NVM_SK_R")
	)
	(via
		(at 35.28187 -93.61551)
		(size 0.7112)
		(drill 0.3556)
		(layers "F.Cu" "B.Cu")
		(net "NVM_SK_R")
	)
	(segment
		(start 49.098962 -67.13474)
		(end 49.263046 -66.970656)
		(width 0.12065)
		(layer "B.Cu")
		(net "NVM_SK_R")
	)
	(segment
		(start 49.263046 -66.970656)
		(end 49.263046 -52.392326)
		(width 0.12065)
		(layer "B.Cu")
		(net "NVM_SK_R")
	)
	(segment
		(start 49.263046 -52.392326)
		(end 49.788572 -51.8668)
		(width 0.12065)
		(layer "B.Cu")
		(net "NVM_SK_R")
	)
	(segment
		(start 48.771556 -67.462146)
		(end 49.098962 -67.13474)
		(width 0.127)
		(layer "In5.Cu")
		(net "NVM_SK_R")
	)
	(segment
		(start 39.00932 -82.055208)
		(end 41.310306 -82.055208)
		(width 0.127)
		(layer "In5.Cu")
		(net "NVM_SK_R")
	)
	(segment
		(start 37.934646 -86.583266)
		(end 37.934646 -83.129882)
		(width 0.127)
		(layer "In5.Cu")
		(net "NVM_SK_R")
	)
	(segment
		(start 35.868864 -88.649048)
		(end 37.934646 -86.583266)
		(width 0.127)
		(layer "In5.Cu")
		(net "NVM_SK_R")
	)
	(segment
		(start 37.934646 -83.129882)
		(end 39.00932 -82.055208)
		(width 0.127)
		(layer "In5.Cu")
		(net "NVM_SK_R")
	)
	(segment
		(start 41.310306 -82.055208)
		(end 45.228764 -78.13675)
		(width 0.127)
		(layer "In5.Cu")
		(net "NVM_SK_R")
	)
	(segment
		(start 35.868864 -91.735402)
		(end 35.868864 -88.649048)
		(width 0.127)
		(layer "In5.Cu")
		(net "NVM_SK_R")
	)
	(segment
		(start 46.45279 -67.462146)
		(end 48.771556 -67.462146)
		(width 0.127)
		(layer "In5.Cu")
		(net "NVM_SK_R")
	)
	(segment
		(start 45.228764 -78.13675)
		(end 45.228764 -68.686172)
		(width 0.127)
		(layer "In5.Cu")
		(net "NVM_SK_R")
	)
	(segment
		(start 45.228764 -68.686172)
		(end 46.45279 -67.462146)
		(width 0.127)
		(layer "In5.Cu")
		(net "NVM_SK_R")
	)
	(segment
		(start 24.22271 -78.763114)
		(end 24.22271 -80.20431)
		(width 0.12065)
		(layer "F.Cu")
		(net "NVM_SK")
	)
	(segment
		(start 25.51176 -81.22412)
		(end 25.24252 -81.22412)
		(width 0.12065)
		(layer "F.Cu")
		(net "NVM_SK")
	)
	(segment
		(start 25.24252 -81.22412)
		(end 24.511 -80.4926)
		(width 0.12065)
		(layer "F.Cu")
		(net "NVM_SK")
	)
	(segment
		(start 23.376128 -77.916532)
		(end 24.22271 -78.763114)
		(width 0.12065)
		(layer "F.Cu")
		(net "NVM_SK")
	)
	(segment
		(start 22.584918 -77.916532)
		(end 23.376128 -77.916532)
		(width 0.12065)
		(layer "F.Cu")
		(net "NVM_SK")
	)
	(segment
		(start 24.22271 -80.20431)
		(end 24.511 -80.4926)
		(width 0.12065)
		(layer "F.Cu")
		(net "NVM_SK")
	)
	(via
		(at 24.511 -80.4926)
		(size 0.7112)
		(drill 0.3556)
		(layers "F.Cu" "B.Cu")
		(net "NVM_SK")
	)
	(segment
		(start 48.518572 -50.750724)
		(end 47.350172 -50.750724)
		(width 0.12065)
		(layer "F.Cu")
		(net "NVM_SI_R")
	)
	(segment
		(start 40.970962 -94.344744)
		(end 40.972994 -94.342712)
		(width 0.12065)
		(layer "F.Cu")
		(net "NVM_SI_R")
	)
	(segment
		(start 40.8559 -95.3008)
		(end 40.8559 -94.47403)
		(width 0.12065)
		(layer "F.Cu")
		(net "NVM_SI_R")
	)
	(segment
		(start 40.8559 -94.47403)
		(end 40.970962 -94.358968)
		(width 0.12065)
		(layer "F.Cu")
		(net "NVM_SI_R")
	)
	(segment
		(start 40.970962 -94.358968)
		(end 40.970962 -94.344744)
		(width 0.12065)
		(layer "F.Cu")
		(net "NVM_SI_R")
	)
	(segment
		(start 40.8559 -96.3168)
		(end 40.8559 -95.3008)
		(width 0.12065)
		(layer "F.Cu")
		(net "NVM_SI_R")
	)
	(segment
		(start 46.5836 -56.2864)
		(end 47.350172 -55.519828)
		(width 0.12065)
		(layer "F.Cu")
		(net "NVM_SI_R")
	)
	(segment
		(start 48.518572 -53.303932)
		(end 48.518572 -50.750724)
		(width 0.12065)
		(layer "F.Cu")
		(net "NVM_SI_R")
	)
	(segment
		(start 47.350172 -55.519828)
		(end 47.350172 -50.750724)
		(width 0.12065)
		(layer "F.Cu")
		(net "NVM_SI_R")
	)
	(via
		(at 46.5836 -56.2864)
		(size 0.508)
		(drill 0.254)
		(layers "F.Cu" "B.Cu")
		(net "NVM_SI_R")
	)
	(via
		(at 40.8559 -95.3008)
		(size 0.7112)
		(drill 0.3556)
		(layers "F.Cu" "B.Cu")
		(net "NVM_SI_R")
	)
	(via
		(at 40.972994 -94.342712)
		(size 0.508)
		(drill 0.254)
		(layers "F.Cu" "B.Cu")
		(net "NVM_SI_R")
	)
	(segment
		(start 45.787564 -79.195168)
		(end 45.78731 -79.195168)
		(width 0.127)
		(layer "In5.Cu")
		(net "NVM_SI_R")
	)
	(segment
		(start 43.912028 -81.070196)
		(end 43.912028 -84.413852)
		(width 0.127)
		(layer "In5.Cu")
		(net "NVM_SI_R")
	)
	(segment
		(start 43.912028 -84.413852)
		(end 40.972994 -87.352886)
		(width 0.127)
		(layer "In5.Cu")
		(net "NVM_SI_R")
	)
	(segment
		(start 46.4566 -78.525878)
		(end 46.4566 -78.526132)
		(width 0.127)
		(layer "In5.Cu")
		(net "NVM_SI_R")
	)
	(segment
		(start 45.415454 -79.567024)
		(end 45.4152 -79.567024)
		(width 0.127)
		(layer "In5.Cu")
		(net "NVM_SI_R")
	)
	(segment
		(start 48.641 -76.341224)
		(end 48.641 -76.341478)
		(width 0.127)
		(layer "In5.Cu")
		(net "NVM_SI_R")
	)
	(segment
		(start 46.5836 -56.2864)
		(end 53.836824 -63.539624)
		(width 0.127)
		(layer "In5.Cu")
		(net "NVM_SI_R")
	)
	(segment
		(start 46.4566 -78.526132)
		(end 45.787564 -79.195168)
		(width 0.127)
		(layer "In5.Cu")
		(net "NVM_SI_R")
	)
	(segment
		(start 45.78731 -79.195168)
		(end 45.415454 -79.567024)
		(width 0.127)
		(layer "In5.Cu")
		(net "NVM_SI_R")
	)
	(segment
		(start 48.641 -76.341478)
		(end 46.4566 -78.525878)
		(width 0.127)
		(layer "In5.Cu")
		(net "NVM_SI_R")
	)
	(segment
		(start 50.87874 -74.103484)
		(end 48.641 -76.341224)
		(width 0.127)
		(layer "In5.Cu")
		(net "NVM_SI_R")
	)
	(segment
		(start 50.87874 -69.17436)
		(end 50.87874 -74.103484)
		(width 0.127)
		(layer "In5.Cu")
		(net "NVM_SI_R")
	)
	(segment
		(start 45.4152 -79.567024)
		(end 43.912028 -81.070196)
		(width 0.127)
		(layer "In5.Cu")
		(net "NVM_SI_R")
	)
	(segment
		(start 40.972994 -87.352886)
		(end 40.972994 -94.342712)
		(width 0.127)
		(layer "In5.Cu")
		(net "NVM_SI_R")
	)
	(segment
		(start 53.836824 -66.216276)
		(end 50.87874 -69.17436)
		(width 0.127)
		(layer "In5.Cu")
		(net "NVM_SI_R")
	)
	(segment
		(start 53.836824 -63.539624)
		(end 53.836824 -66.216276)
		(width 0.127)
		(layer "In5.Cu")
		(net "NVM_SI_R")
	)
	(segment
		(start 24.84882 -79.29118)
		(end 24.850852 -79.289148)
		(width 0.12065)
		(layer "F.Cu")
		(net "NVM_SI")
	)
	(segment
		(start 25.301702 -80.16494)
		(end 24.84882 -79.712058)
		(width 0.12065)
		(layer "F.Cu")
		(net "NVM_SI")
	)
	(segment
		(start 24.84882 -78.872588)
		(end 24.84882 -79.20482)
		(width 0.12065)
		(layer "F.Cu")
		(net "NVM_SI")
	)
	(segment
		(start 25.301702 -80.165702)
		(end 25.301702 -80.16494)
		(width 0.12065)
		(layer "F.Cu")
		(net "NVM_SI")
	)
	(segment
		(start 25.3111 -80.1751)
		(end 25.301702 -80.165702)
		(width 0.12065)
		(layer "F.Cu")
		(net "NVM_SI")
	)
	(segment
		(start 24.850852 -79.289148)
		(end 24.850852 -79.245206)
		(width 0.12065)
		(layer "F.Cu")
		(net "NVM_SI")
	)
	(segment
		(start 24.850852 -79.206852)
		(end 24.850852 -79.245206)
		(width 0.12065)
		(layer "F.Cu")
		(net "NVM_SI")
	)
	(segment
		(start 22.584918 -77.41666)
		(end 23.392892 -77.41666)
		(width 0.12065)
		(layer "F.Cu")
		(net "NVM_SI")
	)
	(segment
		(start 24.84882 -79.712058)
		(end 24.84882 -79.29118)
		(width 0.12065)
		(layer "F.Cu")
		(net "NVM_SI")
	)
	(segment
		(start 24.84882 -79.20482)
		(end 24.850852 -79.206852)
		(width 0.12065)
		(layer "F.Cu")
		(net "NVM_SI")
	)
	(segment
		(start 23.392892 -77.41666)
		(end 24.84882 -78.872588)
		(width 0.12065)
		(layer "F.Cu")
		(net "NVM_SI")
	)
	(segment
		(start 25.52446 -80.1751)
		(end 25.3111 -80.1751)
		(width 0.12065)
		(layer "F.Cu")
		(net "NVM_SI")
	)
	(via
		(at 24.850852 -79.245206)
		(size 0.7112)
		(drill 0.3556)
		(layers "F.Cu" "B.Cu")
		(net "NVM_SI")
	)
	(segment
		(start 52.3748 -62.865)
		(end 52.328572 -62.818772)
		(width 0.12065)
		(layer "F.Cu")
		(net "NVM_CS_N_R")
	)
	(segment
		(start 31.232602 -95.934784)
		(end 31.232602 -99.640898)
		(width 0.12065)
		(layer "F.Cu")
		(net "NVM_CS_N_R")
	)
	(segment
		(start 34.467546 -91.8718)
		(end 34.073084 -92.266262)
		(width 0.12065)
		(layer "F.Cu")
		(net "NVM_CS_N_R")
	)
	(segment
		(start 52.328572 -62.818772)
		(end 52.328572 -61.303916)
		(width 0.12065)
		(layer "F.Cu")
		(net "NVM_CS_N_R")
	)
	(segment
		(start 34.073084 -92.266262)
		(end 34.073084 -93.094302)
		(width 0.12065)
		(layer "F.Cu")
		(net "NVM_CS_N_R")
	)
	(segment
		(start 31.232602 -99.640898)
		(end 31.2293 -99.6442)
		(width 0.12065)
		(layer "F.Cu")
		(net "NVM_CS_N_R")
	)
	(segment
		(start 35.016948 -91.877642)
		(end 35.011106 -91.8718)
		(width 0.12065)
		(layer "F.Cu")
		(net "NVM_CS_N_R")
	)
	(segment
		(start 34.073084 -93.094302)
		(end 31.232602 -95.934784)
		(width 0.12065)
		(layer "F.Cu")
		(net "NVM_CS_N_R")
	)
	(segment
		(start 35.011106 -91.8718)
		(end 34.467546 -91.8718)
		(width 0.12065)
		(layer "F.Cu")
		(net "NVM_CS_N_R")
	)
	(via
		(at 31.232602 -95.934784)
		(size 0.7112)
		(drill 0.3556)
		(layers "F.Cu" "B.Cu")
		(net "NVM_CS_N_R")
	)
	(via
		(at 35.016948 -91.877642)
		(size 0.508)
		(drill 0.254)
		(layers "F.Cu" "B.Cu")
		(net "NVM_CS_N_R")
	)
	(via
		(at 52.3748 -62.865)
		(size 0.508)
		(drill 0.254)
		(layers "F.Cu" "B.Cu")
		(net "NVM_CS_N_R")
	)
	(segment
		(start 44.593764 -68.105274)
		(end 49.834038 -62.865)
		(width 0.127)
		(layer "In5.Cu")
		(net "NVM_CS_N_R")
	)
	(segment
		(start 37.299392 -82.866992)
		(end 38.746176 -81.420208)
		(width 0.127)
		(layer "In5.Cu")
		(net "NVM_CS_N_R")
	)
	(segment
		(start 49.834038 -62.865)
		(end 52.3748 -62.865)
		(width 0.127)
		(layer "In5.Cu")
		(net "NVM_CS_N_R")
	)
	(segment
		(start 44.593764 -77.873606)
		(end 44.593764 -68.105274)
		(width 0.127)
		(layer "In5.Cu")
		(net "NVM_CS_N_R")
	)
	(segment
		(start 35.016948 -91.877642)
		(end 35.016948 -87.450422)
		(width 0.127)
		(layer "In5.Cu")
		(net "NVM_CS_N_R")
	)
	(segment
		(start 35.016948 -87.450422)
		(end 37.299392 -85.167978)
		(width 0.127)
		(layer "In5.Cu")
		(net "NVM_CS_N_R")
	)
	(segment
		(start 37.299392 -85.167978)
		(end 37.299392 -82.866992)
		(width 0.127)
		(layer "In5.Cu")
		(net "NVM_CS_N_R")
	)
	(segment
		(start 41.047162 -81.420208)
		(end 44.593764 -77.873606)
		(width 0.127)
		(layer "In5.Cu")
		(net "NVM_CS_N_R")
	)
	(segment
		(start 38.746176 -81.420208)
		(end 41.047162 -81.420208)
		(width 0.127)
		(layer "In5.Cu")
		(net "NVM_CS_N_R")
	)
	(segment
		(start 23.26513 -78.91653)
		(end 22.584918 -78.91653)
		(width 0.12065)
		(layer "F.Cu")
		(net "NVM_CS_N")
	)
	(segment
		(start 24.411178 -81.991708)
		(end 23.495508 -81.076038)
		(width 0.12065)
		(layer "F.Cu")
		(net "NVM_CS_N")
	)
	(segment
		(start 23.495508 -79.146908)
		(end 23.26513 -78.91653)
		(width 0.12065)
		(layer "F.Cu")
		(net "NVM_CS_N")
	)
	(segment
		(start 24.411178 -82.494374)
		(end 25.381204 -83.4644)
		(width 0.12065)
		(layer "F.Cu")
		(net "NVM_CS_N")
	)
	(segment
		(start 23.495508 -81.076038)
		(end 23.495508 -79.146908)
		(width 0.12065)
		(layer "F.Cu")
		(net "NVM_CS_N")
	)
	(segment
		(start 25.381204 -83.4644)
		(end 25.5397 -83.4644)
		(width 0.12065)
		(layer "F.Cu")
		(net "NVM_CS_N")
	)
	(segment
		(start 24.411178 -82.494374)
		(end 24.411178 -81.991708)
		(width 0.12065)
		(layer "F.Cu")
		(net "NVM_CS_N")
	)
	(via
		(at 24.411178 -82.494374)
		(size 0.7112)
		(drill 0.3556)
		(layers "F.Cu" "B.Cu")
		(net "NVM_CS_N")
	)
	(segment
		(start 19.165316 -48.895)
		(end 18.868644 -48.598328)
		(width 0.104902)
		(layer "F.Cu")
		(net "NIC0_MDI0_P3_R")
	)
	(segment
		(start 23.13305 -49.79416)
		(end 22.23389 -48.895)
		(width 0.104902)
		(layer "F.Cu")
		(net "NIC0_MDI0_P3_R")
	)
	(segment
		(start 23.1521 -51.0286)
		(end 23.1521 -51.4604)
		(width 0.104902)
		(layer "F.Cu")
		(net "NIC0_MDI0_P3_R")
	)
	(segment
		(start 19.122644 -47.649892)
		(end 19.712178 -47.649892)
		(width 0.104902)
		(layer "F.Cu")
		(net "NIC0_MDI0_P3_R")
	)
	(segment
		(start 22.23389 -48.895)
		(end 19.165316 -48.895)
		(width 0.104902)
		(layer "F.Cu")
		(net "NIC0_MDI0_P3_R")
	)
	(segment
		(start 23.5331 -50.6476)
		(end 23.1521 -51.0286)
		(width 0.104902)
		(layer "F.Cu")
		(net "NIC0_MDI0_P3_R")
	)
	(segment
		(start 18.868644 -47.903892)
		(end 19.122644 -47.649892)
		(width 0.104902)
		(layer "F.Cu")
		(net "NIC0_MDI0_P3_R")
	)
	(segment
		(start 18.868644 -48.598328)
		(end 18.868644 -47.903892)
		(width 0.104902)
		(layer "F.Cu")
		(net "NIC0_MDI0_P3_R")
	)
	(segment
		(start 23.5331 -50.6476)
		(end 23.13305 -50.24755)
		(width 0.104902)
		(layer "F.Cu")
		(net "NIC0_MDI0_P3_R")
	)
	(segment
		(start 23.13305 -50.24755)
		(end 23.13305 -49.79416)
		(width 0.104902)
		(layer "F.Cu")
		(net "NIC0_MDI0_P3_R")
	)
	(segment
		(start 23.1521 -51.4604)
		(end 23.4696 -51.7779)
		(width 0.104902)
		(layer "F.Cu")
		(net "NIC0_MDI0_P3_R")
	)
	(segment
		(start 14.91107 -70.569836)
		(end 14.8463 -70.505066)
		(width 0.104902)
		(layer "F.Cu")
		(net "NIC0_MDI0_P3")
	)
	(segment
		(start 23.114 -53.302154)
		(end 23.114 -53.0225)
		(width 0.104902)
		(layer "F.Cu")
		(net "NIC0_MDI0_P3")
	)
	(segment
		(start 14.91107 -71.242682)
		(end 14.91107 -70.569836)
		(width 0.104902)
		(layer "F.Cu")
		(net "NIC0_MDI0_P3")
	)
	(segment
		(start 23.368 -53.556154)
		(end 23.114 -53.302154)
		(width 0.104902)
		(layer "F.Cu")
		(net "NIC0_MDI0_P3")
	)
	(segment
		(start 23.114 -53.0225)
		(end 23.4696 -52.6669)
		(width 0.104902)
		(layer "F.Cu")
		(net "NIC0_MDI0_P3")
	)
	(segment
		(start 14.8463 -70.0913)
		(end 13.6398 -68.8848)
		(width 0.104902)
		(layer "F.Cu")
		(net "NIC0_MDI0_P3")
	)
	(segment
		(start 13.6398 -68.8848)
		(end 13.6398 -68.292472)
		(width 0.104902)
		(layer "F.Cu")
		(net "NIC0_MDI0_P3")
	)
	(segment
		(start 13.714984 -68.217288)
		(end 13.939266 -68.217288)
		(width 0.104902)
		(layer "F.Cu")
		(net "NIC0_MDI0_P3")
	)
	(segment
		(start 23.368 -53.556154)
		(end 23.13305 -53.791104)
		(width 0.104902)
		(layer "F.Cu")
		(net "NIC0_MDI0_P3")
	)
	(segment
		(start 14.8463 -70.505066)
		(end 14.8463 -70.0913)
		(width 0.104902)
		(layer "F.Cu")
		(net "NIC0_MDI0_P3")
	)
	(segment
		(start 23.13305 -54.33695)
		(end 23.4696 -54.6735)
		(width 0.104902)
		(layer "F.Cu")
		(net "NIC0_MDI0_P3")
	)
	(segment
		(start 13.6398 -68.292472)
		(end 13.714984 -68.217288)
		(width 0.104902)
		(layer "F.Cu")
		(net "NIC0_MDI0_P3")
	)
	(segment
		(start 13.939266 -68.217288)
		(end 14.1732 -68.451222)
		(width 0.104902)
		(layer "F.Cu")
		(net "NIC0_MDI0_P3")
	)
	(segment
		(start 23.13305 -53.791104)
		(end 23.13305 -54.33695)
		(width 0.104902)
		(layer "F.Cu")
		(net "NIC0_MDI0_P3")
	)
	(via
		(at 14.1732 -68.451222)
		(size 0.508)
		(drill 0.254)
		(layers "F.Cu" "B.Cu")
		(net "NIC0_MDI0_P3")
	)
	(via
		(at 23.368 -53.556154)
		(size 0.508)
		(drill 0.254)
		(layers "F.Cu" "B.Cu")
		(net "NIC0_MDI0_P3")
	)
	(segment
		(start 23.0886 -53.835554)
		(end 23.0886 -54.5338)
		(width 0.1016)
		(layer "In5.Cu")
		(net "NIC0_MDI0_P3")
	)
	(segment
		(start 23.368 -53.556154)
		(end 23.0886 -53.835554)
		(width 0.1016)
		(layer "In5.Cu")
		(net "NIC0_MDI0_P3")
	)
	(segment
		(start 19.234658 -66.864738)
		(end 17.214596 -68.8848)
		(width 0.1016)
		(layer "In5.Cu")
		(net "NIC0_MDI0_P3")
	)
	(segment
		(start 19.234658 -63.162942)
		(end 19.234658 -66.864738)
		(width 0.1016)
		(layer "In5.Cu")
		(net "NIC0_MDI0_P3")
	)
	(segment
		(start 15.545308 -68.8848)
		(end 14.859508 -68.199)
		(width 0.1016)
		(layer "In5.Cu")
		(net "NIC0_MDI0_P3")
	)
	(segment
		(start 17.214596 -68.8848)
		(end 15.545308 -68.8848)
		(width 0.1016)
		(layer "In5.Cu")
		(net "NIC0_MDI0_P3")
	)
	(segment
		(start 21.717 -60.6806)
		(end 19.234658 -63.162942)
		(width 0.1016)
		(layer "In5.Cu")
		(net "NIC0_MDI0_P3")
	)
	(segment
		(start 14.425422 -68.199)
		(end 14.1732 -68.451222)
		(width 0.1016)
		(layer "In5.Cu")
		(net "NIC0_MDI0_P3")
	)
	(segment
		(start 23.0886 -54.5338)
		(end 21.717 -55.9054)
		(width 0.1016)
		(layer "In5.Cu")
		(net "NIC0_MDI0_P3")
	)
	(segment
		(start 14.859508 -68.199)
		(end 14.425422 -68.199)
		(width 0.1016)
		(layer "In5.Cu")
		(net "NIC0_MDI0_P3")
	)
	(segment
		(start 21.717 -55.9054)
		(end 21.717 -60.6806)
		(width 0.1016)
		(layer "In5.Cu")
		(net "NIC0_MDI0_P3")
	)
	(segment
		(start 17.5006 -45.7708)
		(end 16.1671 -47.1043)
		(width 0.104902)
		(layer "F.Cu")
		(net "NIC0_MDI0_P2_R")
	)
	(segment
		(start 16.1671 -48.27524)
		(end 19.09445 -51.20259)
		(width 0.104902)
		(layer "F.Cu")
		(net "NIC0_MDI0_P2_R")
	)
	(segment
		(start 19.094196 -51.61915)
		(end 19.094196 -51.619404)
		(width 0.104902)
		(layer "F.Cu")
		(net "NIC0_MDI0_P2_R")
	)
	(segment
		(start 19.08175 -52.83835)
		(end 18.7452 -53.1749)
		(width 0.104902)
		(layer "F.Cu")
		(net "NIC0_MDI0_P2_R")
	)
	(segment
		(start 19.094196 -51.619404)
		(end 18.6944 -52.0192)
		(width 0.104902)
		(layer "F.Cu")
		(net "NIC0_MDI0_P2_R")
	)
	(segment
		(start 19.09445 -51.618896)
		(end 19.094196 -51.61915)
		(width 0.104902)
		(layer "F.Cu")
		(net "NIC0_MDI0_P2_R")
	)
	(segment
		(start 17.5006 -45.339)
		(end 17.5006 -45.7708)
		(width 0.104902)
		(layer "F.Cu")
		(net "NIC0_MDI0_P2_R")
	)
	(segment
		(start 18.6944 -52.0192)
		(end 19.08175 -52.40655)
		(width 0.104902)
		(layer "F.Cu")
		(net "NIC0_MDI0_P2_R")
	)
	(segment
		(start 19.09445 -51.20259)
		(end 19.09445 -51.618896)
		(width 0.104902)
		(layer "F.Cu")
		(net "NIC0_MDI0_P2_R")
	)
	(segment
		(start 16.1671 -47.1043)
		(end 16.1671 -48.27524)
		(width 0.104902)
		(layer "F.Cu")
		(net "NIC0_MDI0_P2_R")
	)
	(segment
		(start 17.271492 -45.109892)
		(end 17.5006 -45.339)
		(width 0.104902)
		(layer "F.Cu")
		(net "NIC0_MDI0_P2_R")
	)
	(segment
		(start 16.657066 -45.109892)
		(end 17.271492 -45.109892)
		(width 0.104902)
		(layer "F.Cu")
		(net "NIC0_MDI0_P2_R")
	)
	(segment
		(start 19.08175 -52.40655)
		(end 19.08175 -52.83835)
		(width 0.104902)
		(layer "F.Cu")
		(net "NIC0_MDI0_P2_R")
	)
	(segment
		(start 18.8468 -54.998112)
		(end 19.08175 -55.233062)
		(width 0.104902)
		(layer "F.Cu")
		(net "NIC0_MDI0_P2")
	)
	(segment
		(start 16.41094 -70.58914)
		(end 16.41094 -71.242682)
		(width 0.104902)
		(layer "F.Cu")
		(net "NIC0_MDI0_P2")
	)
	(segment
		(start 15.945612 -66.802762)
		(end 15.571978 -66.802762)
		(width 0.104902)
		(layer "F.Cu")
		(net "NIC0_MDI0_P2")
	)
	(segment
		(start 16.1798 -67.03695)
		(end 15.945612 -66.802762)
		(width 0.104902)
		(layer "F.Cu")
		(net "NIC0_MDI0_P2")
	)
	(segment
		(start 19.08175 -54.763162)
		(end 18.8468 -54.998112)
		(width 0.104902)
		(layer "F.Cu")
		(net "NIC0_MDI0_P2")
	)
	(segment
		(start 15.571978 -66.802762)
		(end 15.4432 -66.93154)
		(width 0.104902)
		(layer "F.Cu")
		(net "NIC0_MDI0_P2")
	)
	(segment
		(start 16.319754 -69.177154)
		(end 16.319754 -70.497954)
		(width 0.104902)
		(layer "F.Cu")
		(net "NIC0_MDI0_P2")
	)
	(segment
		(start 15.4432 -68.3006)
		(end 16.319754 -69.177154)
		(width 0.104902)
		(layer "F.Cu")
		(net "NIC0_MDI0_P2")
	)
	(segment
		(start 19.08175 -54.40045)
		(end 19.08175 -54.763162)
		(width 0.104902)
		(layer "F.Cu")
		(net "NIC0_MDI0_P2")
	)
	(segment
		(start 19.08175 -55.75935)
		(end 18.7452 -56.0959)
		(width 0.104902)
		(layer "F.Cu")
		(net "NIC0_MDI0_P2")
	)
	(segment
		(start 18.7452 -54.0639)
		(end 19.08175 -54.40045)
		(width 0.104902)
		(layer "F.Cu")
		(net "NIC0_MDI0_P2")
	)
	(segment
		(start 19.08175 -55.233062)
		(end 19.08175 -55.75935)
		(width 0.104902)
		(layer "F.Cu")
		(net "NIC0_MDI0_P2")
	)
	(segment
		(start 15.4432 -66.93154)
		(end 15.4432 -68.3006)
		(width 0.104902)
		(layer "F.Cu")
		(net "NIC0_MDI0_P2")
	)
	(segment
		(start 16.319754 -70.497954)
		(end 16.41094 -70.58914)
		(width 0.104902)
		(layer "F.Cu")
		(net "NIC0_MDI0_P2")
	)
	(via
		(at 16.1798 -67.03695)
		(size 0.508)
		(drill 0.254)
		(layers "F.Cu" "B.Cu")
		(net "NIC0_MDI0_P2")
	)
	(via
		(at 18.8468 -54.998112)
		(size 0.508)
		(drill 0.254)
		(layers "F.Cu" "B.Cu")
		(net "NIC0_MDI0_P2")
	)
	(segment
		(start 18.8468 -54.998112)
		(end 19.1008 -55.252112)
		(width 0.1016)
		(layer "In5.Cu")
		(net "NIC0_MDI0_P2")
	)
	(segment
		(start 15.9258 -66.78295)
		(end 16.1798 -67.03695)
		(width 0.1016)
		(layer "In5.Cu")
		(net "NIC0_MDI0_P2")
	)
	(segment
		(start 20.4978 -57.682892)
		(end 20.4978 -59.512708)
		(width 0.1016)
		(layer "In5.Cu")
		(net "NIC0_MDI0_P2")
	)
	(segment
		(start 14.9098 -66.417444)
		(end 15.275306 -66.78295)
		(width 0.1016)
		(layer "In5.Cu")
		(net "NIC0_MDI0_P2")
	)
	(segment
		(start 15.275306 -66.78295)
		(end 15.9258 -66.78295)
		(width 0.1016)
		(layer "In5.Cu")
		(net "NIC0_MDI0_P2")
	)
	(segment
		(start 19.1008 -55.252112)
		(end 19.1008 -56.285892)
		(width 0.1016)
		(layer "In5.Cu")
		(net "NIC0_MDI0_P2")
	)
	(segment
		(start 20.4978 -59.512708)
		(end 14.9098 -65.100708)
		(width 0.1016)
		(layer "In5.Cu")
		(net "NIC0_MDI0_P2")
	)
	(segment
		(start 19.1008 -56.285892)
		(end 20.4978 -57.682892)
		(width 0.1016)
		(layer "In5.Cu")
		(net "NIC0_MDI0_P2")
	)
	(segment
		(start 14.9098 -65.100708)
		(end 14.9098 -66.417444)
		(width 0.1016)
		(layer "In5.Cu")
		(net "NIC0_MDI0_P2")
	)
	(segment
		(start 14.1224 -51.5747)
		(end 14.478 -51.9303)
		(width 0.104902)
		(layer "F.Cu")
		(net "NIC0_MDI0_P1_R")
	)
	(segment
		(start 15.2146 -47.16526)
		(end 13.783564 -45.734224)
		(width 0.104902)
		(layer "F.Cu")
		(net "NIC0_MDI0_P1_R")
	)
	(segment
		(start 14.037564 -45.109892)
		(end 14.627098 -45.109892)
		(width 0.104902)
		(layer "F.Cu")
		(net "NIC0_MDI0_P1_R")
	)
	(segment
		(start 15.2146 -48.4124)
		(end 15.2146 -47.16526)
		(width 0.104902)
		(layer "F.Cu")
		(net "NIC0_MDI0_P1_R")
	)
	(segment
		(start 14.1224 -51.2445)
		(end 14.1224 -51.5747)
		(width 0.104902)
		(layer "F.Cu")
		(net "NIC0_MDI0_P1_R")
	)
	(segment
		(start 14.5415 -50.8254)
		(end 14.1224 -51.2445)
		(width 0.104902)
		(layer "F.Cu")
		(net "NIC0_MDI0_P1_R")
	)
	(segment
		(start 13.783564 -45.734224)
		(end 13.783564 -45.363892)
		(width 0.104902)
		(layer "F.Cu")
		(net "NIC0_MDI0_P1_R")
	)
	(segment
		(start 13.783564 -45.363892)
		(end 14.037564 -45.109892)
		(width 0.104902)
		(layer "F.Cu")
		(net "NIC0_MDI0_P1_R")
	)
	(segment
		(start 14.14145 -50.42535)
		(end 14.14145 -49.48555)
		(width 0.104902)
		(layer "F.Cu")
		(net "NIC0_MDI0_P1_R")
	)
	(segment
		(start 14.14145 -49.48555)
		(end 15.2146 -48.4124)
		(width 0.104902)
		(layer "F.Cu")
		(net "NIC0_MDI0_P1_R")
	)
	(segment
		(start 14.5415 -50.8254)
		(end 14.14145 -50.42535)
		(width 0.104902)
		(layer "F.Cu")
		(net "NIC0_MDI0_P1_R")
	)
	(segment
		(start 16.517366 -72.633332)
		(end 16.376396 -72.774302)
		(width 0.104902)
		(layer "F.Cu")
		(net "NIC0_MDI0_P1")
	)
	(segment
		(start 16.376396 -72.98182)
		(end 16.6116 -73.217024)
		(width 0.104902)
		(layer "F.Cu")
		(net "NIC0_MDI0_P1")
	)
	(segment
		(start 17.410938 -71.242682)
		(end 17.410938 -71.91629)
		(width 0.104902)
		(layer "F.Cu")
		(net "NIC0_MDI0_P1")
	)
	(segment
		(start 17.332452 -71.994776)
		(end 17.332452 -72.32777)
		(width 0.104902)
		(layer "F.Cu")
		(net "NIC0_MDI0_P1")
	)
	(segment
		(start 17.410938 -71.91629)
		(end 17.332452 -71.994776)
		(width 0.104902)
		(layer "F.Cu")
		(net "NIC0_MDI0_P1")
	)
	(segment
		(start 14.14145 -53.15585)
		(end 14.14145 -53.594762)
		(width 0.104902)
		(layer "F.Cu")
		(net "NIC0_MDI0_P1")
	)
	(segment
		(start 16.376396 -72.774302)
		(end 16.376396 -72.98182)
		(width 0.104902)
		(layer "F.Cu")
		(net "NIC0_MDI0_P1")
	)
	(segment
		(start 17.02689 -72.633332)
		(end 16.517366 -72.633332)
		(width 0.104902)
		(layer "F.Cu")
		(net "NIC0_MDI0_P1")
	)
	(segment
		(start 14.478 -52.8193)
		(end 14.14145 -53.15585)
		(width 0.104902)
		(layer "F.Cu")
		(net "NIC0_MDI0_P1")
	)
	(segment
		(start 14.14145 -53.594762)
		(end 14.3764 -53.829712)
		(width 0.104902)
		(layer "F.Cu")
		(net "NIC0_MDI0_P1")
	)
	(segment
		(start 17.332452 -72.32777)
		(end 17.02689 -72.633332)
		(width 0.104902)
		(layer "F.Cu")
		(net "NIC0_MDI0_P1")
	)
	(via
		(at 14.3764 -53.829712)
		(size 0.508)
		(drill 0.254)
		(layers "F.Cu" "B.Cu")
		(net "NIC0_MDI0_P1")
	)
	(via
		(at 16.6116 -73.217024)
		(size 0.508)
		(drill 0.254)
		(layers "F.Cu" "B.Cu")
		(net "NIC0_MDI0_P1")
	)
	(segment
		(start 9.7028 -61.925708)
		(end 9.7028 -58.343292)
		(width 0.1016)
		(layer "In5.Cu")
		(net "NIC0_MDI0_P1")
	)
	(segment
		(start 14.223492 -69.088)
		(end 13.6398 -69.088)
		(width 0.1016)
		(layer "In5.Cu")
		(net "NIC0_MDI0_P1")
	)
	(segment
		(start 16.6116 -73.217024)
		(end 16.3576 -72.963024)
		(width 0.1016)
		(layer "In5.Cu")
		(net "NIC0_MDI0_P1")
	)
	(segment
		(start 13.1572 -65.380108)
		(end 9.7028 -61.925708)
		(width 0.1016)
		(layer "In5.Cu")
		(net "NIC0_MDI0_P1")
	)
	(segment
		(start 16.3576 -72.963024)
		(end 16.3576 -71.222108)
		(width 0.1016)
		(layer "In5.Cu")
		(net "NIC0_MDI0_P1")
	)
	(segment
		(start 13.301472 -56.134)
		(end 14.1224 -55.313072)
		(width 0.1016)
		(layer "In5.Cu")
		(net "NIC0_MDI0_P1")
	)
	(segment
		(start 13.6398 -69.088)
		(end 13.1572 -68.6054)
		(width 0.1016)
		(layer "In5.Cu")
		(net "NIC0_MDI0_P1")
	)
	(segment
		(start 16.3576 -71.222108)
		(end 14.223492 -69.088)
		(width 0.1016)
		(layer "In5.Cu")
		(net "NIC0_MDI0_P1")
	)
	(segment
		(start 11.912092 -56.134)
		(end 13.301472 -56.134)
		(width 0.1016)
		(layer "In5.Cu")
		(net "NIC0_MDI0_P1")
	)
	(segment
		(start 9.7028 -58.343292)
		(end 11.912092 -56.134)
		(width 0.1016)
		(layer "In5.Cu")
		(net "NIC0_MDI0_P1")
	)
	(segment
		(start 13.1572 -68.6054)
		(end 13.1572 -65.380108)
		(width 0.1016)
		(layer "In5.Cu")
		(net "NIC0_MDI0_P1")
	)
	(segment
		(start 14.1224 -55.313072)
		(end 14.1224 -54.083712)
		(width 0.1016)
		(layer "In5.Cu")
		(net "NIC0_MDI0_P1")
	)
	(segment
		(start 14.1224 -54.083712)
		(end 14.3764 -53.829712)
		(width 0.1016)
		(layer "In5.Cu")
		(net "NIC0_MDI0_P1")
	)
	(segment
		(start 9.89965 -51.64455)
		(end 9.89965 -50.06721)
		(width 0.104902)
		(layer "F.Cu")
		(net "NIC0_MDI0_P0_R")
	)
	(segment
		(start 11.405108 -49.4665)
		(end 12.41552 -48.456088)
		(width 0.104902)
		(layer "F.Cu")
		(net "NIC0_MDI0_P0_R")
	)
	(segment
		(start 9.89965 -50.06721)
		(end 10.50036 -49.4665)
		(width 0.104902)
		(layer "F.Cu")
		(net "NIC0_MDI0_P0_R")
	)
	(segment
		(start 9.4996 -52.0446)
		(end 9.8933 -52.4383)
		(width 0.104902)
		(layer "F.Cu")
		(net "NIC0_MDI0_P0_R")
	)
	(segment
		(start 10.50036 -49.4665)
		(end 11.405108 -49.4665)
		(width 0.104902)
		(layer "F.Cu")
		(net "NIC0_MDI0_P0_R")
	)
	(segment
		(start 9.4996 -52.0446)
		(end 9.89965 -51.64455)
		(width 0.104902)
		(layer "F.Cu")
		(net "NIC0_MDI0_P0_R")
	)
	(segment
		(start 9.8933 -52.8193)
		(end 9.5631 -53.1495)
		(width 0.104902)
		(layer "F.Cu")
		(net "NIC0_MDI0_P0_R")
	)
	(segment
		(start 12.41552 -48.456088)
		(end 12.41552 -47.84852)
		(width 0.104902)
		(layer "F.Cu")
		(net "NIC0_MDI0_P0_R")
	)
	(segment
		(start 9.8933 -52.4383)
		(end 9.8933 -52.8193)
		(width 0.104902)
		(layer "F.Cu")
		(net "NIC0_MDI0_P0_R")
	)
	(segment
		(start 12.216892 -47.649892)
		(end 11.571986 -47.649892)
		(width 0.104902)
		(layer "F.Cu")
		(net "NIC0_MDI0_P0_R")
	)
	(segment
		(start 12.41552 -47.84852)
		(end 12.216892 -47.649892)
		(width 0.104902)
		(layer "F.Cu")
		(net "NIC0_MDI0_P0_R")
	)
	(segment
		(start 9.5631 -54.0385)
		(end 9.89965 -54.37505)
		(width 0.104902)
		(layer "F.Cu")
		(net "NIC0_MDI0_P0")
	)
	(segment
		(start 19.154648 -72.634094)
		(end 18.832068 -72.311514)
		(width 0.104902)
		(layer "F.Cu")
		(net "NIC0_MDI0_P0")
	)
	(segment
		(start 19.154648 -72.978772)
		(end 19.154648 -72.634094)
		(width 0.104902)
		(layer "F.Cu")
		(net "NIC0_MDI0_P0")
	)
	(segment
		(start 18.911062 -71.891398)
		(end 18.911062 -71.242682)
		(width 0.104902)
		(layer "F.Cu")
		(net "NIC0_MDI0_P0")
	)
	(segment
		(start 18.832068 -72.311514)
		(end 18.832068 -71.970392)
		(width 0.104902)
		(layer "F.Cu")
		(net "NIC0_MDI0_P0")
	)
	(segment
		(start 18.832068 -71.970392)
		(end 18.911062 -71.891398)
		(width 0.104902)
		(layer "F.Cu")
		(net "NIC0_MDI0_P0")
	)
	(segment
		(start 19.38655 -73.210674)
		(end 19.154648 -72.978772)
		(width 0.104902)
		(layer "F.Cu")
		(net "NIC0_MDI0_P0")
	)
	(segment
		(start 9.89965 -54.813962)
		(end 9.6647 -55.048912)
		(width 0.104902)
		(layer "F.Cu")
		(net "NIC0_MDI0_P0")
	)
	(segment
		(start 9.89965 -54.37505)
		(end 9.89965 -54.813962)
		(width 0.104902)
		(layer "F.Cu")
		(net "NIC0_MDI0_P0")
	)
	(via
		(at 19.38655 -73.210674)
		(size 0.508)
		(drill 0.254)
		(layers "F.Cu" "B.Cu")
		(net "NIC0_MDI0_P0")
	)
	(via
		(at 9.6647 -55.048912)
		(size 0.508)
		(drill 0.254)
		(layers "F.Cu" "B.Cu")
		(net "NIC0_MDI0_P0")
	)
	(segment
		(start 9.9187 -56.172608)
		(end 8.000238 -58.09107)
		(width 0.1016)
		(layer "In5.Cu")
		(net "NIC0_MDI0_P0")
	)
	(segment
		(start 15.570708 -74.9554)
		(end 17.2466 -74.9554)
		(width 0.1016)
		(layer "In5.Cu")
		(net "NIC0_MDI0_P0")
	)
	(segment
		(start 17.2466 -74.9554)
		(end 17.8308 -74.3712)
		(width 0.1016)
		(layer "In5.Cu")
		(net "NIC0_MDI0_P0")
	)
	(segment
		(start 17.8308 -74.3712)
		(end 18.617692 -74.3712)
		(width 0.1016)
		(layer "In5.Cu")
		(net "NIC0_MDI0_P0")
	)
	(segment
		(start 11.937746 -66.191892)
		(end 11.937746 -69.11086)
		(width 0.1016)
		(layer "In5.Cu")
		(net "NIC0_MDI0_P0")
	)
	(segment
		(start 9.9187 -55.302912)
		(end 9.9187 -56.172608)
		(width 0.1016)
		(layer "In5.Cu")
		(net "NIC0_MDI0_P0")
	)
	(segment
		(start 19.13255 -73.464674)
		(end 19.38655 -73.210674)
		(width 0.1016)
		(layer "In5.Cu")
		(net "NIC0_MDI0_P0")
	)
	(segment
		(start 13.969746 -73.354438)
		(end 15.570708 -74.9554)
		(width 0.1016)
		(layer "In5.Cu")
		(net "NIC0_MDI0_P0")
	)
	(segment
		(start 13.487654 -70.3072)
		(end 13.969746 -70.789292)
		(width 0.1016)
		(layer "In5.Cu")
		(net "NIC0_MDI0_P0")
	)
	(segment
		(start 13.969746 -70.789292)
		(end 13.969746 -73.354438)
		(width 0.1016)
		(layer "In5.Cu")
		(net "NIC0_MDI0_P0")
	)
	(segment
		(start 8.000238 -58.09107)
		(end 8.000238 -62.254384)
		(width 0.1016)
		(layer "In5.Cu")
		(net "NIC0_MDI0_P0")
	)
	(segment
		(start 11.937746 -69.11086)
		(end 13.134086 -70.3072)
		(width 0.1016)
		(layer "In5.Cu")
		(net "NIC0_MDI0_P0")
	)
	(segment
		(start 8.000238 -62.254384)
		(end 11.937746 -66.191892)
		(width 0.1016)
		(layer "In5.Cu")
		(net "NIC0_MDI0_P0")
	)
	(segment
		(start 19.13255 -73.856342)
		(end 19.13255 -73.464674)
		(width 0.1016)
		(layer "In5.Cu")
		(net "NIC0_MDI0_P0")
	)
	(segment
		(start 13.134086 -70.3072)
		(end 13.487654 -70.3072)
		(width 0.1016)
		(layer "In5.Cu")
		(net "NIC0_MDI0_P0")
	)
	(segment
		(start 9.6647 -55.048912)
		(end 9.9187 -55.302912)
		(width 0.1016)
		(layer "In5.Cu")
		(net "NIC0_MDI0_P0")
	)
	(segment
		(start 18.617692 -74.3712)
		(end 19.13255 -73.856342)
		(width 0.1016)
		(layer "In5.Cu")
		(net "NIC0_MDI0_P0")
	)
	(segment
		(start 18.525744 -47.938944)
		(end 18.525744 -48.740568)
		(width 0.104902)
		(layer "F.Cu")
		(net "NIC0_MDI0_N3_R")
	)
	(segment
		(start 18.236692 -47.649892)
		(end 18.525744 -47.938944)
		(width 0.104902)
		(layer "F.Cu")
		(net "NIC0_MDI0_N3_R")
	)
	(segment
		(start 22.8092 -51.4223)
		(end 22.4536 -51.7779)
		(width 0.104902)
		(layer "F.Cu")
		(net "NIC0_MDI0_N3_R")
	)
	(segment
		(start 17.68221 -47.649892)
		(end 18.236692 -47.649892)
		(width 0.104902)
		(layer "F.Cu")
		(net "NIC0_MDI0_N3_R")
	)
	(segment
		(start 22.79015 -50.24755)
		(end 22.3901 -50.6476)
		(width 0.104902)
		(layer "F.Cu")
		(net "NIC0_MDI0_N3_R")
	)
	(segment
		(start 22.8092 -51.0667)
		(end 22.8092 -51.4223)
		(width 0.104902)
		(layer "F.Cu")
		(net "NIC0_MDI0_N3_R")
	)
	(segment
		(start 22.3901 -50.6476)
		(end 22.8092 -51.0667)
		(width 0.104902)
		(layer "F.Cu")
		(net "NIC0_MDI0_N3_R")
	)
	(segment
		(start 22.09165 -49.2379)
		(end 22.79015 -49.9364)
		(width 0.104902)
		(layer "F.Cu")
		(net "NIC0_MDI0_N3_R")
	)
	(segment
		(start 18.525744 -48.740568)
		(end 19.023076 -49.2379)
		(width 0.104902)
		(layer "F.Cu")
		(net "NIC0_MDI0_N3_R")
	)
	(segment
		(start 22.79015 -49.9364)
		(end 22.79015 -50.24755)
		(width 0.104902)
		(layer "F.Cu")
		(net "NIC0_MDI0_N3_R")
	)
	(segment
		(start 19.023076 -49.2379)
		(end 22.09165 -49.2379)
		(width 0.104902)
		(layer "F.Cu")
		(net "NIC0_MDI0_N3_R")
	)
	(segment
		(start 13.572744 -67.874388)
		(end 13.2969 -68.150232)
		(width 0.104902)
		(layer "F.Cu")
		(net "NIC0_MDI0_N3")
	)
	(segment
		(start 14.410944 -70.588632)
		(end 14.410944 -71.242682)
		(width 0.104902)
		(layer "F.Cu")
		(net "NIC0_MDI0_N3")
	)
	(segment
		(start 13.937234 -67.874388)
		(end 13.572744 -67.874388)
		(width 0.104902)
		(layer "F.Cu")
		(net "NIC0_MDI0_N3")
	)
	(segment
		(start 22.7711 -52.9844)
		(end 22.4536 -52.6669)
		(width 0.104902)
		(layer "F.Cu")
		(net "NIC0_MDI0_N3")
	)
	(segment
		(start 14.5034 -70.23354)
		(end 14.5034 -70.496176)
		(width 0.104902)
		(layer "F.Cu")
		(net "NIC0_MDI0_N3")
	)
	(segment
		(start 13.2969 -68.150232)
		(end 13.2969 -69.02704)
		(width 0.104902)
		(layer "F.Cu")
		(net "NIC0_MDI0_N3")
	)
	(segment
		(start 22.79015 -53.791104)
		(end 22.79015 -54.33695)
		(width 0.104902)
		(layer "F.Cu")
		(net "NIC0_MDI0_N3")
	)
	(segment
		(start 22.5552 -53.556154)
		(end 22.7711 -53.340254)
		(width 0.104902)
		(layer "F.Cu")
		(net "NIC0_MDI0_N3")
	)
	(segment
		(start 22.7711 -53.340254)
		(end 22.7711 -52.9844)
		(width 0.104902)
		(layer "F.Cu")
		(net "NIC0_MDI0_N3")
	)
	(segment
		(start 22.5552 -53.556154)
		(end 22.79015 -53.791104)
		(width 0.104902)
		(layer "F.Cu")
		(net "NIC0_MDI0_N3")
	)
	(segment
		(start 14.1732 -67.638422)
		(end 13.937234 -67.874388)
		(width 0.104902)
		(layer "F.Cu")
		(net "NIC0_MDI0_N3")
	)
	(segment
		(start 14.5034 -70.496176)
		(end 14.410944 -70.588632)
		(width 0.104902)
		(layer "F.Cu")
		(net "NIC0_MDI0_N3")
	)
	(segment
		(start 13.2969 -69.02704)
		(end 14.5034 -70.23354)
		(width 0.104902)
		(layer "F.Cu")
		(net "NIC0_MDI0_N3")
	)
	(segment
		(start 22.79015 -54.33695)
		(end 22.4536 -54.6735)
		(width 0.104902)
		(layer "F.Cu")
		(net "NIC0_MDI0_N3")
	)
	(via
		(at 14.1732 -67.638422)
		(size 0.508)
		(drill 0.254)
		(layers "F.Cu" "B.Cu")
		(net "NIC0_MDI0_N3")
	)
	(via
		(at 22.5552 -53.556154)
		(size 0.508)
		(drill 0.254)
		(layers "F.Cu" "B.Cu")
		(net "NIC0_MDI0_N3")
	)
	(segment
		(start 15.6718 -68.58)
		(end 14.986 -67.8942)
		(width 0.1016)
		(layer "In5.Cu")
		(net "NIC0_MDI0_N3")
	)
	(segment
		(start 21.4122 -55.778908)
		(end 21.4122 -60.554108)
		(width 0.1016)
		(layer "In5.Cu")
		(net "NIC0_MDI0_N3")
	)
	(segment
		(start 17.088104 -68.58)
		(end 15.6718 -68.58)
		(width 0.1016)
		(layer "In5.Cu")
		(net "NIC0_MDI0_N3")
	)
	(segment
		(start 22.7838 -53.784754)
		(end 22.7838 -54.407308)
		(width 0.1016)
		(layer "In5.Cu")
		(net "NIC0_MDI0_N3")
	)
	(segment
		(start 18.929858 -63.03645)
		(end 18.929858 -66.738246)
		(width 0.1016)
		(layer "In5.Cu")
		(net "NIC0_MDI0_N3")
	)
	(segment
		(start 18.929858 -66.738246)
		(end 17.088104 -68.58)
		(width 0.1016)
		(layer "In5.Cu")
		(net "NIC0_MDI0_N3")
	)
	(segment
		(start 22.7838 -54.407308)
		(end 21.4122 -55.778908)
		(width 0.1016)
		(layer "In5.Cu")
		(net "NIC0_MDI0_N3")
	)
	(segment
		(start 14.428978 -67.8942)
		(end 14.1732 -67.638422)
		(width 0.1016)
		(layer "In5.Cu")
		(net "NIC0_MDI0_N3")
	)
	(segment
		(start 21.4122 -60.554108)
		(end 18.929858 -63.03645)
		(width 0.1016)
		(layer "In5.Cu")
		(net "NIC0_MDI0_N3")
	)
	(segment
		(start 14.986 -67.8942)
		(end 14.428978 -67.8942)
		(width 0.1016)
		(layer "In5.Cu")
		(net "NIC0_MDI0_N3")
	)
	(segment
		(start 22.5552 -53.556154)
		(end 22.7838 -53.784754)
		(width 0.1016)
		(layer "In5.Cu")
		(net "NIC0_MDI0_N3")
	)
	(segment
		(start 17.8435 -45.363892)
		(end 18.0975 -45.109892)
		(width 0.104902)
		(layer "F.Cu")
		(net "NIC0_MDI0_N2_R")
	)
	(segment
		(start 19.42465 -52.43195)
		(end 19.42465 -52.83835)
		(width 0.104902)
		(layer "F.Cu")
		(net "NIC0_MDI0_N2_R")
	)
	(segment
		(start 16.51 -48.133)
		(end 16.51 -47.24654)
		(width 0.104902)
		(layer "F.Cu")
		(net "NIC0_MDI0_N2_R")
	)
	(segment
		(start 19.43735 -51.61915)
		(end 19.43735 -51.06035)
		(width 0.104902)
		(layer "F.Cu")
		(net "NIC0_MDI0_N2_R")
	)
	(segment
		(start 17.8435 -45.91304)
		(end 17.8435 -45.363892)
		(width 0.104902)
		(layer "F.Cu")
		(net "NIC0_MDI0_N2_R")
	)
	(segment
		(start 19.43735 -51.06035)
		(end 16.51 -48.133)
		(width 0.104902)
		(layer "F.Cu")
		(net "NIC0_MDI0_N2_R")
	)
	(segment
		(start 16.51 -47.24654)
		(end 17.8435 -45.91304)
		(width 0.104902)
		(layer "F.Cu")
		(net "NIC0_MDI0_N2_R")
	)
	(segment
		(start 19.8374 -52.0192)
		(end 19.43735 -51.61915)
		(width 0.104902)
		(layer "F.Cu")
		(net "NIC0_MDI0_N2_R")
	)
	(segment
		(start 19.8374 -52.0192)
		(end 19.42465 -52.43195)
		(width 0.104902)
		(layer "F.Cu")
		(net "NIC0_MDI0_N2_R")
	)
	(segment
		(start 18.0975 -45.109892)
		(end 18.687034 -45.109892)
		(width 0.104902)
		(layer "F.Cu")
		(net "NIC0_MDI0_N2_R")
	)
	(segment
		(start 19.42465 -52.83835)
		(end 19.7612 -53.1749)
		(width 0.104902)
		(layer "F.Cu")
		(net "NIC0_MDI0_N2_R")
	)
	(segment
		(start 19.42465 -55.75935)
		(end 19.7612 -56.0959)
		(width 0.104902)
		(layer "F.Cu")
		(net "NIC0_MDI0_N2")
	)
	(segment
		(start 19.42465 -54.763162)
		(end 19.6596 -54.998112)
		(width 0.104902)
		(layer "F.Cu")
		(net "NIC0_MDI0_N2")
	)
	(segment
		(start 15.976854 -70.510146)
		(end 15.911068 -70.575932)
		(width 0.104902)
		(layer "F.Cu")
		(net "NIC0_MDI0_N2")
	)
	(segment
		(start 16.1798 -66.22415)
		(end 15.944088 -66.459862)
		(width 0.104902)
		(layer "F.Cu")
		(net "NIC0_MDI0_N2")
	)
	(segment
		(start 15.1003 -66.7893)
		(end 15.1003 -68.44284)
		(width 0.104902)
		(layer "F.Cu")
		(net "NIC0_MDI0_N2")
	)
	(segment
		(start 15.976854 -69.319394)
		(end 15.976854 -70.510146)
		(width 0.104902)
		(layer "F.Cu")
		(net "NIC0_MDI0_N2")
	)
	(segment
		(start 19.6596 -54.998112)
		(end 19.42465 -55.233062)
		(width 0.104902)
		(layer "F.Cu")
		(net "NIC0_MDI0_N2")
	)
	(segment
		(start 15.911068 -70.575932)
		(end 15.911068 -71.242682)
		(width 0.104902)
		(layer "F.Cu")
		(net "NIC0_MDI0_N2")
	)
	(segment
		(start 19.7612 -54.0639)
		(end 19.42465 -54.40045)
		(width 0.104902)
		(layer "F.Cu")
		(net "NIC0_MDI0_N2")
	)
	(segment
		(start 19.42465 -55.233062)
		(end 19.42465 -55.75935)
		(width 0.104902)
		(layer "F.Cu")
		(net "NIC0_MDI0_N2")
	)
	(segment
		(start 19.42465 -54.40045)
		(end 19.42465 -54.763162)
		(width 0.104902)
		(layer "F.Cu")
		(net "NIC0_MDI0_N2")
	)
	(segment
		(start 15.944088 -66.459862)
		(end 15.429738 -66.459862)
		(width 0.104902)
		(layer "F.Cu")
		(net "NIC0_MDI0_N2")
	)
	(segment
		(start 15.429738 -66.459862)
		(end 15.1003 -66.7893)
		(width 0.104902)
		(layer "F.Cu")
		(net "NIC0_MDI0_N2")
	)
	(segment
		(start 15.1003 -68.44284)
		(end 15.976854 -69.319394)
		(width 0.104902)
		(layer "F.Cu")
		(net "NIC0_MDI0_N2")
	)
	(via
		(at 16.1798 -66.22415)
		(size 0.508)
		(drill 0.254)
		(layers "F.Cu" "B.Cu")
		(net "NIC0_MDI0_N2")
	)
	(via
		(at 19.6596 -54.998112)
		(size 0.508)
		(drill 0.254)
		(layers "F.Cu" "B.Cu")
		(net "NIC0_MDI0_N2")
	)
	(segment
		(start 15.2146 -65.2272)
		(end 15.2146 -66.290952)
		(width 0.1016)
		(layer "In5.Cu")
		(net "NIC0_MDI0_N2")
	)
	(segment
		(start 19.4056 -55.252112)
		(end 19.4056 -56.1594)
		(width 0.1016)
		(layer "In5.Cu")
		(net "NIC0_MDI0_N2")
	)
	(segment
		(start 19.4056 -56.1594)
		(end 20.8026 -57.5564)
		(width 0.1016)
		(layer "In5.Cu")
		(net "NIC0_MDI0_N2")
	)
	(segment
		(start 20.8026 -59.6392)
		(end 15.2146 -65.2272)
		(width 0.1016)
		(layer "In5.Cu")
		(net "NIC0_MDI0_N2")
	)
	(segment
		(start 20.8026 -57.5564)
		(end 20.8026 -59.6392)
		(width 0.1016)
		(layer "In5.Cu")
		(net "NIC0_MDI0_N2")
	)
	(segment
		(start 15.401798 -66.47815)
		(end 15.9258 -66.47815)
		(width 0.1016)
		(layer "In5.Cu")
		(net "NIC0_MDI0_N2")
	)
	(segment
		(start 15.9258 -66.47815)
		(end 16.1798 -66.22415)
		(width 0.1016)
		(layer "In5.Cu")
		(net "NIC0_MDI0_N2")
	)
	(segment
		(start 15.2146 -66.290952)
		(end 15.401798 -66.47815)
		(width 0.1016)
		(layer "In5.Cu")
		(net "NIC0_MDI0_N2")
	)
	(segment
		(start 19.6596 -54.998112)
		(end 19.4056 -55.252112)
		(width 0.1016)
		(layer "In5.Cu")
		(net "NIC0_MDI0_N2")
	)
	(segment
		(start 13.79855 -50.42535)
		(end 13.3985 -50.8254)
		(width 0.104902)
		(layer "F.Cu")
		(net "NIC0_MDI0_N1_R")
	)
	(segment
		(start 14.8717 -48.27016)
		(end 13.79855 -49.34331)
		(width 0.104902)
		(layer "F.Cu")
		(net "NIC0_MDI0_N1_R")
	)
	(segment
		(start 13.7795 -51.6128)
		(end 13.462 -51.9303)
		(width 0.104902)
		(layer "F.Cu")
		(net "NIC0_MDI0_N1_R")
	)
	(segment
		(start 13.207492 -45.109892)
		(end 13.440664 -45.343064)
		(width 0.104902)
		(layer "F.Cu")
		(net "NIC0_MDI0_N1_R")
	)
	(segment
		(start 13.79855 -49.34331)
		(end 13.79855 -50.42535)
		(width 0.104902)
		(layer "F.Cu")
		(net "NIC0_MDI0_N1_R")
	)
	(segment
		(start 13.440664 -45.876464)
		(end 14.8717 -47.3075)
		(width 0.104902)
		(layer "F.Cu")
		(net "NIC0_MDI0_N1_R")
	)
	(segment
		(start 13.3985 -50.8254)
		(end 13.7795 -51.2064)
		(width 0.104902)
		(layer "F.Cu")
		(net "NIC0_MDI0_N1_R")
	)
	(segment
		(start 12.59713 -45.109892)
		(end 13.207492 -45.109892)
		(width 0.104902)
		(layer "F.Cu")
		(net "NIC0_MDI0_N1_R")
	)
	(segment
		(start 13.440664 -45.343064)
		(end 13.440664 -45.876464)
		(width 0.104902)
		(layer "F.Cu")
		(net "NIC0_MDI0_N1_R")
	)
	(segment
		(start 14.8717 -47.3075)
		(end 14.8717 -48.27016)
		(width 0.104902)
		(layer "F.Cu")
		(net "NIC0_MDI0_N1_R")
	)
	(segment
		(start 13.7795 -51.2064)
		(end 13.7795 -51.6128)
		(width 0.104902)
		(layer "F.Cu")
		(net "NIC0_MDI0_N1_R")
	)
	(segment
		(start 16.375126 -72.290432)
		(end 16.033496 -72.632062)
		(width 0.104902)
		(layer "F.Cu")
		(net "NIC0_MDI0_N1")
	)
	(segment
		(start 16.033496 -72.982328)
		(end 15.7988 -73.217024)
		(width 0.104902)
		(layer "F.Cu")
		(net "NIC0_MDI0_N1")
	)
	(segment
		(start 16.033496 -72.632062)
		(end 16.033496 -72.982328)
		(width 0.104902)
		(layer "F.Cu")
		(net "NIC0_MDI0_N1")
	)
	(segment
		(start 16.911066 -71.242682)
		(end 16.911066 -71.907908)
		(width 0.104902)
		(layer "F.Cu")
		(net "NIC0_MDI0_N1")
	)
	(segment
		(start 16.88465 -72.290432)
		(end 16.375126 -72.290432)
		(width 0.104902)
		(layer "F.Cu")
		(net "NIC0_MDI0_N1")
	)
	(segment
		(start 13.79855 -53.15585)
		(end 13.79855 -53.594762)
		(width 0.104902)
		(layer "F.Cu")
		(net "NIC0_MDI0_N1")
	)
	(segment
		(start 13.79855 -53.594762)
		(end 13.5636 -53.829712)
		(width 0.104902)
		(layer "F.Cu")
		(net "NIC0_MDI0_N1")
	)
	(segment
		(start 16.911066 -71.907908)
		(end 16.989552 -71.986394)
		(width 0.104902)
		(layer "F.Cu")
		(net "NIC0_MDI0_N1")
	)
	(segment
		(start 16.989552 -71.986394)
		(end 16.989552 -72.18553)
		(width 0.104902)
		(layer "F.Cu")
		(net "NIC0_MDI0_N1")
	)
	(segment
		(start 16.989552 -72.18553)
		(end 16.88465 -72.290432)
		(width 0.104902)
		(layer "F.Cu")
		(net "NIC0_MDI0_N1")
	)
	(segment
		(start 13.462 -52.8193)
		(end 13.79855 -53.15585)
		(width 0.104902)
		(layer "F.Cu")
		(net "NIC0_MDI0_N1")
	)
	(via
		(at 13.5636 -53.829712)
		(size 0.508)
		(drill 0.254)
		(layers "F.Cu" "B.Cu")
		(net "NIC0_MDI0_N1")
	)
	(via
		(at 15.7988 -73.217024)
		(size 0.508)
		(drill 0.254)
		(layers "F.Cu" "B.Cu")
		(net "NIC0_MDI0_N1")
	)
	(segment
		(start 13.8176 -55.18658)
		(end 13.8176 -54.083712)
		(width 0.1016)
		(layer "In5.Cu")
		(net "NIC0_MDI0_N1")
	)
	(segment
		(start 13.513308 -69.3928)
		(end 12.8524 -68.731892)
		(width 0.1016)
		(layer "In5.Cu")
		(net "NIC0_MDI0_N1")
	)
	(segment
		(start 13.8176 -54.083712)
		(end 13.5636 -53.829712)
		(width 0.1016)
		(layer "In5.Cu")
		(net "NIC0_MDI0_N1")
	)
	(segment
		(start 9.398 -58.2168)
		(end 11.7856 -55.8292)
		(width 0.1016)
		(layer "In5.Cu")
		(net "NIC0_MDI0_N1")
	)
	(segment
		(start 16.0528 -72.963024)
		(end 16.0528 -71.3486)
		(width 0.1016)
		(layer "In5.Cu")
		(net "NIC0_MDI0_N1")
	)
	(segment
		(start 12.8524 -65.5066)
		(end 9.398 -62.0522)
		(width 0.1016)
		(layer "In5.Cu")
		(net "NIC0_MDI0_N1")
	)
	(segment
		(start 15.7988 -73.217024)
		(end 16.0528 -72.963024)
		(width 0.1016)
		(layer "In5.Cu")
		(net "NIC0_MDI0_N1")
	)
	(segment
		(start 11.7856 -55.8292)
		(end 13.17498 -55.8292)
		(width 0.1016)
		(layer "In5.Cu")
		(net "NIC0_MDI0_N1")
	)
	(segment
		(start 12.8524 -68.731892)
		(end 12.8524 -65.5066)
		(width 0.1016)
		(layer "In5.Cu")
		(net "NIC0_MDI0_N1")
	)
	(segment
		(start 14.097 -69.3928)
		(end 13.513308 -69.3928)
		(width 0.1016)
		(layer "In5.Cu")
		(net "NIC0_MDI0_N1")
	)
	(segment
		(start 16.0528 -71.3486)
		(end 14.097 -69.3928)
		(width 0.1016)
		(layer "In5.Cu")
		(net "NIC0_MDI0_N1")
	)
	(segment
		(start 13.17498 -55.8292)
		(end 13.8176 -55.18658)
		(width 0.1016)
		(layer "In5.Cu")
		(net "NIC0_MDI0_N1")
	)
	(segment
		(start 9.398 -62.0522)
		(end 9.398 -58.2168)
		(width 0.1016)
		(layer "In5.Cu")
		(net "NIC0_MDI0_N1")
	)
	(segment
		(start 12.75842 -47.84598)
		(end 12.954508 -47.649892)
		(width 0.104902)
		(layer "F.Cu")
		(net "NIC0_MDI0_N0_R")
	)
	(segment
		(start 10.6426 -49.8094)
		(end 11.547348 -49.8094)
		(width 0.104902)
		(layer "F.Cu")
		(net "NIC0_MDI0_N0_R")
	)
	(segment
		(start 10.24255 -51.64455)
		(end 10.24255 -50.20945)
		(width 0.104902)
		(layer "F.Cu")
		(net "NIC0_MDI0_N0_R")
	)
	(segment
		(start 10.2362 -52.8066)
		(end 10.5791 -53.1495)
		(width 0.104902)
		(layer "F.Cu")
		(net "NIC0_MDI0_N0_R")
	)
	(segment
		(start 10.2362 -52.451)
		(end 10.2362 -52.8066)
		(width 0.104902)
		(layer "F.Cu")
		(net "NIC0_MDI0_N0_R")
	)
	(segment
		(start 12.954508 -47.649892)
		(end 13.601954 -47.649892)
		(width 0.104902)
		(layer "F.Cu")
		(net "NIC0_MDI0_N0_R")
	)
	(segment
		(start 10.24255 -50.20945)
		(end 10.6426 -49.8094)
		(width 0.104902)
		(layer "F.Cu")
		(net "NIC0_MDI0_N0_R")
	)
	(segment
		(start 10.6426 -52.0446)
		(end 10.2362 -52.451)
		(width 0.104902)
		(layer "F.Cu")
		(net "NIC0_MDI0_N0_R")
	)
	(segment
		(start 11.547348 -49.8094)
		(end 12.75842 -48.598328)
		(width 0.104902)
		(layer "F.Cu")
		(net "NIC0_MDI0_N0_R")
	)
	(segment
		(start 10.6426 -52.0446)
		(end 10.24255 -51.64455)
		(width 0.104902)
		(layer "F.Cu")
		(net "NIC0_MDI0_N0_R")
	)
	(segment
		(start 12.75842 -48.598328)
		(end 12.75842 -47.84598)
		(width 0.104902)
		(layer "F.Cu")
		(net "NIC0_MDI0_N0_R")
	)
	(segment
		(start 18.811748 -72.972676)
		(end 18.811748 -72.776334)
		(width 0.104902)
		(layer "F.Cu")
		(net "NIC0_MDI0_N0")
	)
	(segment
		(start 10.5791 -54.0385)
		(end 10.24255 -54.37505)
		(width 0.104902)
		(layer "F.Cu")
		(net "NIC0_MDI0_N0")
	)
	(segment
		(start 10.24255 -54.37505)
		(end 10.24255 -54.813962)
		(width 0.104902)
		(layer "F.Cu")
		(net "NIC0_MDI0_N0")
	)
	(segment
		(start 18.811748 -72.776334)
		(end 18.489168 -72.453754)
		(width 0.104902)
		(layer "F.Cu")
		(net "NIC0_MDI0_N0")
	)
	(segment
		(start 18.489168 -71.966328)
		(end 18.410936 -71.888096)
		(width 0.104902)
		(layer "F.Cu")
		(net "NIC0_MDI0_N0")
	)
	(segment
		(start 18.489168 -72.453754)
		(end 18.489168 -71.966328)
		(width 0.104902)
		(layer "F.Cu")
		(net "NIC0_MDI0_N0")
	)
	(segment
		(start 10.24255 -54.813962)
		(end 10.4775 -55.048912)
		(width 0.104902)
		(layer "F.Cu")
		(net "NIC0_MDI0_N0")
	)
	(segment
		(start 18.57375 -73.210674)
		(end 18.811748 -72.972676)
		(width 0.104902)
		(layer "F.Cu")
		(net "NIC0_MDI0_N0")
	)
	(segment
		(start 18.410936 -71.888096)
		(end 18.410936 -71.242682)
		(width 0.104902)
		(layer "F.Cu")
		(net "NIC0_MDI0_N0")
	)
	(via
		(at 18.57375 -73.210674)
		(size 0.508)
		(drill 0.254)
		(layers "F.Cu" "B.Cu")
		(net "NIC0_MDI0_N0")
	)
	(via
		(at 10.4775 -55.048912)
		(size 0.508)
		(drill 0.254)
		(layers "F.Cu" "B.Cu")
		(net "NIC0_MDI0_N0")
	)
	(segment
		(start 12.242546 -68.984368)
		(end 13.260578 -70.0024)
		(width 0.1016)
		(layer "In5.Cu")
		(net "NIC0_MDI0_N0")
	)
	(segment
		(start 10.336784 -63.890398)
		(end 10.336784 -64.159638)
		(width 0.1016)
		(layer "In5.Cu")
		(net "NIC0_MDI0_N0")
	)
	(segment
		(start 8.305038 -58.217562)
		(end 8.305038 -59.925966)
		(width 0.1016)
		(layer "In5.Cu")
		(net "NIC0_MDI0_N0")
	)
	(segment
		(start 8.495538 -61.107066)
		(end 8.495538 -61.411866)
		(width 0.1016)
		(layer "In5.Cu")
		(net "NIC0_MDI0_N0")
	)
	(segment
		(start 18.82775 -73.72985)
		(end 18.82775 -73.464674)
		(width 0.1016)
		(layer "In5.Cu")
		(net "NIC0_MDI0_N0")
	)
	(segment
		(start 11.037316 -64.590676)
		(end 11.037316 -64.86017)
		(width 0.1016)
		(layer "In5.Cu")
		(net "NIC0_MDI0_N0")
	)
	(segment
		(start 9.636506 -63.45936)
		(end 9.851898 -63.674752)
		(width 0.1016)
		(layer "In5.Cu")
		(net "NIC0_MDI0_N0")
	)
	(segment
		(start 10.336784 -64.159638)
		(end 10.55243 -64.375284)
		(width 0.1016)
		(layer "In5.Cu")
		(net "NIC0_MDI0_N0")
	)
	(segment
		(start 9.151366 -62.97422)
		(end 9.42086 -62.97422)
		(width 0.1016)
		(layer "In5.Cu")
		(net "NIC0_MDI0_N0")
	)
	(segment
		(start 8.495538 -60.116466)
		(end 8.495538 -60.421266)
		(width 0.1016)
		(layer "In5.Cu")
		(net "NIC0_MDI0_N0")
	)
	(segment
		(start 9.636506 -63.189866)
		(end 9.636506 -63.45936)
		(width 0.1016)
		(layer "In5.Cu")
		(net "NIC0_MDI0_N0")
	)
	(segment
		(start 8.305038 -60.916566)
		(end 8.495538 -61.107066)
		(width 0.1016)
		(layer "In5.Cu")
		(net "NIC0_MDI0_N0")
	)
	(segment
		(start 9.851898 -63.674752)
		(end 10.121392 -63.674752)
		(width 0.1016)
		(layer "In5.Cu")
		(net "NIC0_MDI0_N0")
	)
	(segment
		(start 10.2235 -56.2991)
		(end 8.305038 -58.217562)
		(width 0.1016)
		(layer "In5.Cu")
		(net "NIC0_MDI0_N0")
	)
	(segment
		(start 13.614146 -70.0024)
		(end 14.274546 -70.6628)
		(width 0.1016)
		(layer "In5.Cu")
		(net "NIC0_MDI0_N0")
	)
	(segment
		(start 8.495538 -61.411866)
		(end 8.305038 -61.602366)
		(width 0.1016)
		(layer "In5.Cu")
		(net "NIC0_MDI0_N0")
	)
	(segment
		(start 11.522202 -65.075562)
		(end 11.737848 -65.291208)
		(width 0.1016)
		(layer "In5.Cu")
		(net "NIC0_MDI0_N0")
	)
	(segment
		(start 12.242546 -66.0654)
		(end 12.242546 -68.984368)
		(width 0.1016)
		(layer "In5.Cu")
		(net "NIC0_MDI0_N0")
	)
	(segment
		(start 17.704308 -74.0664)
		(end 18.4912 -74.0664)
		(width 0.1016)
		(layer "In5.Cu")
		(net "NIC0_MDI0_N0")
	)
	(segment
		(start 8.495538 -60.421266)
		(end 8.305038 -60.611766)
		(width 0.1016)
		(layer "In5.Cu")
		(net "NIC0_MDI0_N0")
	)
	(segment
		(start 11.737848 -65.560702)
		(end 12.242546 -66.0654)
		(width 0.1016)
		(layer "In5.Cu")
		(net "NIC0_MDI0_N0")
	)
	(segment
		(start 10.55243 -64.375284)
		(end 10.82167 -64.375284)
		(width 0.1016)
		(layer "In5.Cu")
		(net "NIC0_MDI0_N0")
	)
	(segment
		(start 18.82775 -73.464674)
		(end 18.57375 -73.210674)
		(width 0.1016)
		(layer "In5.Cu")
		(net "NIC0_MDI0_N0")
	)
	(segment
		(start 11.252708 -65.075562)
		(end 11.522202 -65.075562)
		(width 0.1016)
		(layer "In5.Cu")
		(net "NIC0_MDI0_N0")
	)
	(segment
		(start 15.6972 -74.6506)
		(end 17.120108 -74.6506)
		(width 0.1016)
		(layer "In5.Cu")
		(net "NIC0_MDI0_N0")
	)
	(segment
		(start 10.82167 -64.375284)
		(end 11.037316 -64.590676)
		(width 0.1016)
		(layer "In5.Cu")
		(net "NIC0_MDI0_N0")
	)
	(segment
		(start 10.2235 -55.302912)
		(end 10.2235 -56.2991)
		(width 0.1016)
		(layer "In5.Cu")
		(net "NIC0_MDI0_N0")
	)
	(segment
		(start 9.42086 -62.97422)
		(end 9.636506 -63.189866)
		(width 0.1016)
		(layer "In5.Cu")
		(net "NIC0_MDI0_N0")
	)
	(segment
		(start 13.260578 -70.0024)
		(end 13.614146 -70.0024)
		(width 0.1016)
		(layer "In5.Cu")
		(net "NIC0_MDI0_N0")
	)
	(segment
		(start 8.305038 -61.602366)
		(end 8.305038 -62.127892)
		(width 0.1016)
		(layer "In5.Cu")
		(net "NIC0_MDI0_N0")
	)
	(segment
		(start 14.274546 -73.227946)
		(end 15.6972 -74.6506)
		(width 0.1016)
		(layer "In5.Cu")
		(net "NIC0_MDI0_N0")
	)
	(segment
		(start 10.121392 -63.674752)
		(end 10.336784 -63.890398)
		(width 0.1016)
		(layer "In5.Cu")
		(net "NIC0_MDI0_N0")
	)
	(segment
		(start 11.037316 -64.86017)
		(end 11.252708 -65.075562)
		(width 0.1016)
		(layer "In5.Cu")
		(net "NIC0_MDI0_N0")
	)
	(segment
		(start 14.274546 -70.6628)
		(end 14.274546 -73.227946)
		(width 0.1016)
		(layer "In5.Cu")
		(net "NIC0_MDI0_N0")
	)
	(segment
		(start 8.305038 -59.925966)
		(end 8.495538 -60.116466)
		(width 0.1016)
		(layer "In5.Cu")
		(net "NIC0_MDI0_N0")
	)
	(segment
		(start 18.4912 -74.0664)
		(end 18.82775 -73.72985)
		(width 0.1016)
		(layer "In5.Cu")
		(net "NIC0_MDI0_N0")
	)
	(segment
		(start 10.4775 -55.048912)
		(end 10.2235 -55.302912)
		(width 0.1016)
		(layer "In5.Cu")
		(net "NIC0_MDI0_N0")
	)
	(segment
		(start 11.737848 -65.291208)
		(end 11.737848 -65.560702)
		(width 0.1016)
		(layer "In5.Cu")
		(net "NIC0_MDI0_N0")
	)
	(segment
		(start 8.305038 -62.127892)
		(end 9.151366 -62.97422)
		(width 0.1016)
		(layer "In5.Cu")
		(net "NIC0_MDI0_N0")
	)
	(segment
		(start 17.120108 -74.6506)
		(end 17.704308 -74.0664)
		(width 0.1016)
		(layer "In5.Cu")
		(net "NIC0_MDI0_N0")
	)
	(segment
		(start 8.305038 -60.611766)
		(end 8.305038 -60.916566)
		(width 0.1016)
		(layer "In5.Cu")
		(net "NIC0_MDI0_N0")
	)
	(segment
		(start 9.542018 -47.649892)
		(end 9.542018 -48.6664)
		(width 0.508)
		(layer "F.Cu")
		(net "NIC0_CT_POWER")
	)
	(segment
		(start 20.717002 -44.093384)
		(end 20.717002 -45.109892)
		(width 0.508)
		(layer "F.Cu")
		(net "NIC0_CT_POWER")
	)
	(segment
		(start 9.550654 -45.109892)
		(end 10.567162 -45.109892)
		(width 0.508)
		(layer "F.Cu")
		(net "NIC0_CT_POWER")
	)
	(segment
		(start 20.717002 -45.109892)
		(end 20.717002 -46.1264)
		(width 0.508)
		(layer "F.Cu")
		(net "NIC0_CT_POWER")
	)
	(segment
		(start 20.717002 -45.109892)
		(end 21.73351 -45.109892)
		(width 0.508)
		(layer "F.Cu")
		(net "NIC0_CT_POWER")
	)
	(segment
		(start 21.742146 -47.649892)
		(end 22.758654 -47.649892)
		(width 0.508)
		(layer "F.Cu")
		(net "NIC0_CT_POWER")
	)
	(segment
		(start 10.567162 -44.093384)
		(end 10.567162 -45.109892)
		(width 0.508)
		(layer "F.Cu")
		(net "NIC0_CT_POWER")
	)
	(segment
		(start 9.542018 -46.633384)
		(end 9.542018 -47.649892)
		(width 0.508)
		(layer "F.Cu")
		(net "NIC0_CT_POWER")
	)
	(segment
		(start 10.567162 -45.109892)
		(end 10.567162 -46.1264)
		(width 0.508)
		(layer "F.Cu")
		(net "NIC0_CT_POWER")
	)
	(segment
		(start 21.742146 -46.633384)
		(end 21.742146 -47.649892)
		(width 0.508)
		(layer "F.Cu")
		(net "NIC0_CT_POWER")
	)
	(segment
		(start 8.52551 -47.649892)
		(end 9.542018 -47.649892)
		(width 0.508)
		(layer "F.Cu")
		(net "NIC0_CT_POWER")
	)
	(segment
		(start 24.30018 -85.48878)
		(end 24.0538 -85.2424)
		(width 0.12065)
		(layer "F.Cu")
		(net "NIC_JTMS")
	)
	(segment
		(start 21.41093 -80.792066)
		(end 21.41093 -80.090518)
		(width 0.12065)
		(layer "F.Cu")
		(net "NIC_JTMS")
	)
	(segment
		(start 23.733252 -84.921852)
		(end 23.733252 -84.001356)
		(width 0.12065)
		(layer "F.Cu")
		(net "NIC_JTMS")
	)
	(segment
		(start 24.30018 -86.553294)
		(end 24.30018 -85.48878)
		(width 0.12065)
		(layer "F.Cu")
		(net "NIC_JTMS")
	)
	(segment
		(start 23.04415 -82.425286)
		(end 21.41093 -80.792066)
		(width 0.12065)
		(layer "F.Cu")
		(net "NIC_JTMS")
	)
	(segment
		(start 24.0538 -85.2424)
		(end 23.733252 -84.921852)
		(width 0.12065)
		(layer "F.Cu")
		(net "NIC_JTMS")
	)
	(segment
		(start 23.733252 -84.001356)
		(end 23.04415 -83.312254)
		(width 0.12065)
		(layer "F.Cu")
		(net "NIC_JTMS")
	)
	(segment
		(start 23.04415 -83.312254)
		(end 23.04415 -82.425286)
		(width 0.12065)
		(layer "F.Cu")
		(net "NIC_JTMS")
	)
	(segment
		(start 26.416 -72.6948)
		(end 25.715722 -73.395078)
		(width 0.12065)
		(layer "F.Cu")
		(net "NIC_JTDO")
	)
	(segment
		(start 26.8859 -72.2249)
		(end 26.8859 -71.9201)
		(width 0.12065)
		(layer "F.Cu")
		(net "NIC_JTDO")
	)
	(segment
		(start 25.715722 -73.395078)
		(end 23.658322 -73.395078)
		(width 0.12065)
		(layer "F.Cu")
		(net "NIC_JTDO")
	)
	(segment
		(start 23.658322 -73.395078)
		(end 23.636732 -73.416668)
		(width 0.12065)
		(layer "F.Cu")
		(net "NIC_JTDO")
	)
	(segment
		(start 26.8859 -71.9201)
		(end 27.051 -71.755)
		(width 0.12065)
		(layer "F.Cu")
		(net "NIC_JTDO")
	)
	(segment
		(start 23.636732 -73.416668)
		(end 22.584918 -73.416668)
		(width 0.12065)
		(layer "F.Cu")
		(net "NIC_JTDO")
	)
	(segment
		(start 27.051 -71.755)
		(end 27.051 -71.2851)
		(width 0.12065)
		(layer "F.Cu")
		(net "NIC_JTDO")
	)
	(segment
		(start 26.416 -72.6948)
		(end 26.8859 -72.2249)
		(width 0.12065)
		(layer "F.Cu")
		(net "NIC_JTDO")
	)
	(segment
		(start 14.8082 -83.1723)
		(end 14.8209 -83.1723)
		(width 0.12065)
		(layer "F.Cu")
		(net "NIC_JTDI")
	)
	(segment
		(start 15.911068 -81.798668)
		(end 15.9766 -81.8642)
		(width 0.12065)
		(layer "F.Cu")
		(net "NIC_JTDI")
	)
	(segment
		(start 15.911068 -80.090518)
		(end 15.911068 -81.798668)
		(width 0.12065)
		(layer "F.Cu")
		(net "NIC_JTDI")
	)
	(segment
		(start 14.8209 -83.1723)
		(end 15.220188 -82.773012)
		(width 0.12065)
		(layer "F.Cu")
		(net "NIC_JTDI")
	)
	(segment
		(start 15.220188 -82.773012)
		(end 15.220188 -82.620612)
		(width 0.12065)
		(layer "F.Cu")
		(net "NIC_JTDI")
	)
	(segment
		(start 15.220188 -82.620612)
		(end 15.9766 -81.8642)
		(width 0.12065)
		(layer "F.Cu")
		(net "NIC_JTDI")
	)
	(segment
		(start 20.911058 -80.804258)
		(end 20.911058 -80.090518)
		(width 0.12065)
		(layer "F.Cu")
		(net "NIC_JTCK")
	)
	(segment
		(start 23.2664 -84.3026)
		(end 23.1902 -84.2264)
		(width 0.12065)
		(layer "F.Cu")
		(net "NIC_JTCK")
	)
	(segment
		(start 22.6822 -82.5754)
		(end 20.911058 -80.804258)
		(width 0.12065)
		(layer "F.Cu")
		(net "NIC_JTCK")
	)
	(segment
		(start 22.6822 -83.7184)
		(end 22.6822 -82.5754)
		(width 0.12065)
		(layer "F.Cu")
		(net "NIC_JTCK")
	)
	(segment
		(start 23.2664 -86.5251)
		(end 23.2664 -84.3026)
		(width 0.12065)
		(layer "F.Cu")
		(net "NIC_JTCK")
	)
	(segment
		(start 23.1902 -84.2264)
		(end 22.6822 -83.7184)
		(width 0.12065)
		(layer "F.Cu")
		(net "NIC_JTCK")
	)
	(segment
		(start 12.636754 -73.91654)
		(end 13.737082 -73.91654)
		(width 0.12065)
		(layer "F.Cu")
		(net "NCSI_ARB_OUT")
	)
	(segment
		(start 11.654028 -72.933814)
		(end 12.636754 -73.91654)
		(width 0.12065)
		(layer "F.Cu")
		(net "NCSI_ARB_OUT")
	)
	(segment
		(start 13.737082 -74.416666)
		(end 12.447778 -74.416666)
		(width 0.12065)
		(layer "F.Cu")
		(net "NCSI_ARB_IN")
	)
	(segment
		(start 12.447778 -74.416666)
		(end 12.224512 -74.1934)
		(width 0.12065)
		(layer "F.Cu")
		(net "NCSI_ARB_IN")
	)
	(segment
		(start 12.224512 -74.1934)
		(end 11.684 -74.1934)
		(width 0.12065)
		(layer "F.Cu")
		(net "NCSI_ARB_IN")
	)
	(segment
		(start 19.08175 -57.32145)
		(end 19.08175 -57.852056)
		(width 0.104902)
		(layer "F.Cu")
		(net "MNG_TX_DP")
	)
	(segment
		(start 18.7452 -56.9849)
		(end 19.08175 -57.32145)
		(width 0.104902)
		(layer "F.Cu")
		(net "MNG_TX_DP")
	)
	(segment
		(start 59.871102 -17.421606)
		(end 57.953402 -17.421606)
		(width 0.104902)
		(layer "F.Cu")
		(net "MNG_TX_DP")
	)
	(segment
		(start 19.08175 -57.852056)
		(end 18.6944 -58.239406)
		(width 0.104902)
		(layer "F.Cu")
		(net "MNG_TX_DP")
	)
	(via
		(at 57.953402 -17.421606)
		(size 0.508)
		(drill 0.254)
		(layers "F.Cu" "B.Cu")
		(net "MNG_TX_DP")
	)
	(via
		(at 18.6944 -58.239406)
		(size 0.508)
		(drill 0.254)
		(layers "F.Cu" "B.Cu")
		(net "MNG_TX_DP")
	)
	(segment
		(start 60.540392 -19.046698)
		(end 61.559694 -18.027396)
		(width 0.1016)
		(layer "In2.Cu")
		(net "MNG_TX_DP")
	)
	(segment
		(start 19.1008 -57.150508)
		(end 21.85416 -54.397148)
		(width 0.1016)
		(layer "In2.Cu")
		(net "MNG_TX_DP")
	)
	(segment
		(start 42.89552 -45.453808)
		(end 49.3014 -39.047928)
		(width 0.1016)
		(layer "In2.Cu")
		(net "MNG_TX_DP")
	)
	(segment
		(start 19.1008 -57.833006)
		(end 19.1008 -57.150508)
		(width 0.1016)
		(layer "In2.Cu")
		(net "MNG_TX_DP")
	)
	(segment
		(start 54.2798 -22.015704)
		(end 57.248806 -19.046698)
		(width 0.1016)
		(layer "In2.Cu")
		(net "MNG_TX_DP")
	)
	(segment
		(start 21.85416 -54.397148)
		(end 34.645092 -54.397148)
		(width 0.1016)
		(layer "In2.Cu")
		(net "MNG_TX_DP")
	)
	(segment
		(start 34.645092 -54.397148)
		(end 42.89552 -46.14672)
		(width 0.1016)
		(layer "In2.Cu")
		(net "MNG_TX_DP")
	)
	(segment
		(start 49.3014 -33.095184)
		(end 54.2798 -28.116784)
		(width 0.1016)
		(layer "In2.Cu")
		(net "MNG_TX_DP")
	)
	(segment
		(start 18.6944 -58.239406)
		(end 19.1008 -57.833006)
		(width 0.1016)
		(layer "In2.Cu")
		(net "MNG_TX_DP")
	)
	(segment
		(start 49.3014 -39.047928)
		(end 49.3014 -33.095184)
		(width 0.1016)
		(layer "In2.Cu")
		(net "MNG_TX_DP")
	)
	(segment
		(start 42.89552 -46.14672)
		(end 42.89552 -45.453808)
		(width 0.1016)
		(layer "In2.Cu")
		(net "MNG_TX_DP")
	)
	(segment
		(start 61.559694 -18.027396)
		(end 61.559694 -17.523206)
		(width 0.1016)
		(layer "In2.Cu")
		(net "MNG_TX_DP")
	)
	(segment
		(start 61.559694 -17.523206)
		(end 61.458094 -17.421606)
		(width 0.1016)
		(layer "In2.Cu")
		(net "MNG_TX_DP")
	)
	(segment
		(start 61.458094 -17.421606)
		(end 57.953402 -17.421606)
		(width 0.1016)
		(layer "In2.Cu")
		(net "MNG_TX_DP")
	)
	(segment
		(start 54.2798 -28.116784)
		(end 54.2798 -22.015704)
		(width 0.1016)
		(layer "In2.Cu")
		(net "MNG_TX_DP")
	)
	(segment
		(start 57.248806 -19.046698)
		(end 60.540392 -19.046698)
		(width 0.1016)
		(layer "In2.Cu")
		(net "MNG_TX_DP")
	)
	(segment
		(start 19.42465 -57.32145)
		(end 19.42465 -57.852056)
		(width 0.104902)
		(layer "F.Cu")
		(net "MNG_TX_DN")
	)
	(segment
		(start 19.42465 -57.852056)
		(end 19.812 -58.239406)
		(width 0.104902)
		(layer "F.Cu")
		(net "MNG_TX_DN")
	)
	(segment
		(start 19.7612 -56.9849)
		(end 19.42465 -57.32145)
		(width 0.104902)
		(layer "F.Cu")
		(net "MNG_TX_DN")
	)
	(segment
		(start 63.545974 -17.421606)
		(end 65.470786 -17.421606)
		(width 0.104902)
		(layer "F.Cu")
		(net "MNG_TX_DN")
	)
	(via
		(at 65.470786 -17.421606)
		(size 0.508)
		(drill 0.254)
		(layers "F.Cu" "B.Cu")
		(net "MNG_TX_DN")
	)
	(via
		(at 19.812 -58.239406)
		(size 0.508)
		(drill 0.254)
		(layers "F.Cu" "B.Cu")
		(net "MNG_TX_DN")
	)
	(segment
		(start 54.5846 -28.243276)
		(end 54.5846 -22.142196)
		(width 0.1016)
		(layer "In2.Cu")
		(net "MNG_TX_DN")
	)
	(segment
		(start 21.980652 -54.701948)
		(end 34.771584 -54.701948)
		(width 0.1016)
		(layer "In2.Cu")
		(net "MNG_TX_DN")
	)
	(segment
		(start 34.771584 -54.701948)
		(end 43.20032 -46.273212)
		(width 0.1016)
		(layer "In2.Cu")
		(net "MNG_TX_DN")
	)
	(segment
		(start 19.812 -58.239406)
		(end 19.4056 -57.833006)
		(width 0.1016)
		(layer "In2.Cu")
		(net "MNG_TX_DN")
	)
	(segment
		(start 49.6062 -39.17442)
		(end 49.6062 -33.221676)
		(width 0.1016)
		(layer "In2.Cu")
		(net "MNG_TX_DN")
	)
	(segment
		(start 43.20032 -46.273212)
		(end 43.20032 -45.5803)
		(width 0.1016)
		(layer "In2.Cu")
		(net "MNG_TX_DN")
	)
	(segment
		(start 54.5846 -22.142196)
		(end 57.375298 -19.351498)
		(width 0.1016)
		(layer "In2.Cu")
		(net "MNG_TX_DN")
	)
	(segment
		(start 57.375298 -19.351498)
		(end 60.666884 -19.351498)
		(width 0.1016)
		(layer "In2.Cu")
		(net "MNG_TX_DN")
	)
	(segment
		(start 49.6062 -33.221676)
		(end 54.5846 -28.243276)
		(width 0.1016)
		(layer "In2.Cu")
		(net "MNG_TX_DN")
	)
	(segment
		(start 61.966094 -17.421606)
		(end 65.470786 -17.421606)
		(width 0.1016)
		(layer "In2.Cu")
		(net "MNG_TX_DN")
	)
	(segment
		(start 19.4056 -57.833006)
		(end 19.4056 -57.277)
		(width 0.1016)
		(layer "In2.Cu")
		(net "MNG_TX_DN")
	)
	(segment
		(start 61.864494 -18.153888)
		(end 61.864494 -17.523206)
		(width 0.1016)
		(layer "In2.Cu")
		(net "MNG_TX_DN")
	)
	(segment
		(start 19.4056 -57.277)
		(end 21.980652 -54.701948)
		(width 0.1016)
		(layer "In2.Cu")
		(net "MNG_TX_DN")
	)
	(segment
		(start 60.666884 -19.351498)
		(end 61.864494 -18.153888)
		(width 0.1016)
		(layer "In2.Cu")
		(net "MNG_TX_DN")
	)
	(segment
		(start 43.20032 -45.5803)
		(end 49.6062 -39.17442)
		(width 0.1016)
		(layer "In2.Cu")
		(net "MNG_TX_DN")
	)
	(segment
		(start 61.864494 -17.523206)
		(end 61.966094 -17.421606)
		(width 0.1016)
		(layer "In2.Cu")
		(net "MNG_TX_DN")
	)
	(segment
		(start 59.871102 -19.961606)
		(end 57.953402 -19.961606)
		(width 0.104902)
		(layer "F.Cu")
		(net "MNG_RX_DP")
	)
	(segment
		(start 23.535386 -56.688736)
		(end 23.146004 -56.299354)
		(width 0.104902)
		(layer "F.Cu")
		(net "MNG_RX_DP")
	)
	(segment
		(start 23.146004 -55.886096)
		(end 23.4696 -55.5625)
		(width 0.104902)
		(layer "F.Cu")
		(net "MNG_RX_DP")
	)
	(segment
		(start 23.146004 -56.299354)
		(end 23.146004 -55.886096)
		(width 0.104902)
		(layer "F.Cu")
		(net "MNG_RX_DP")
	)
	(via
		(at 23.535386 -56.688736)
		(size 0.508)
		(drill 0.254)
		(layers "F.Cu" "B.Cu")
		(net "MNG_RX_DP")
	)
	(via
		(at 57.953402 -19.961606)
		(size 0.508)
		(drill 0.254)
		(layers "F.Cu" "B.Cu")
		(net "MNG_RX_DP")
	)
	(segment
		(start 50.8762 -33.503108)
		(end 50.8762 -36.9316)
		(width 0.1016)
		(layer "In2.Cu")
		(net "MNG_RX_DP")
	)
	(segment
		(start 23.128986 -57.095136)
		(end 23.535386 -56.688736)
		(width 0.1016)
		(layer "In2.Cu")
		(net "MNG_RX_DP")
	)
	(segment
		(start 23.986744 -58.203338)
		(end 23.320248 -58.203338)
		(width 0.1016)
		(layer "In2.Cu")
		(net "MNG_RX_DP")
	)
	(segment
		(start 48.189388 -42.809922)
		(end 47.973742 -43.025314)
		(width 0.1016)
		(layer "In2.Cu")
		(net "MNG_RX_DP")
	)
	(segment
		(start 50.8762 -37.9222)
		(end 50.6857 -38.1127)
		(width 0.1016)
		(layer "In2.Cu")
		(net "MNG_RX_DP")
	)
	(segment
		(start 47.758096 -43.510454)
		(end 47.488856 -43.510454)
		(width 0.1016)
		(layer "In2.Cu")
		(net "MNG_RX_DP")
	)
	(segment
		(start 47.973742 -43.294808)
		(end 47.758096 -43.510454)
		(width 0.1016)
		(layer "In2.Cu")
		(net "MNG_RX_DP")
	)
	(segment
		(start 55.342536 -24.966422)
		(end 55.342536 -29.036772)
		(width 0.1016)
		(layer "In2.Cu")
		(net "MNG_RX_DP")
	)
	(segment
		(start 48.458628 -42.809922)
		(end 48.189388 -42.809922)
		(width 0.1016)
		(layer "In2.Cu")
		(net "MNG_RX_DP")
	)
	(segment
		(start 23.320248 -58.203338)
		(end 23.128986 -58.012076)
		(width 0.1016)
		(layer "In2.Cu")
		(net "MNG_RX_DP")
	)
	(segment
		(start 46.357286 -44.911264)
		(end 46.087792 -44.911264)
		(width 0.1016)
		(layer "In2.Cu")
		(net "MNG_RX_DP")
	)
	(segment
		(start 50.6857 -38.4175)
		(end 50.8762 -38.608)
		(width 0.1016)
		(layer "In2.Cu")
		(net "MNG_RX_DP")
	)
	(segment
		(start 47.27321 -43.725846)
		(end 47.27321 -43.99534)
		(width 0.1016)
		(layer "In2.Cu")
		(net "MNG_RX_DP")
	)
	(segment
		(start 61.454538 -19.961606)
		(end 61.556138 -20.063206)
		(width 0.1016)
		(layer "In2.Cu")
		(net "MNG_RX_DP")
	)
	(segment
		(start 61.556138 -20.063206)
		(end 61.556138 -21.4122)
		(width 0.1016)
		(layer "In2.Cu")
		(net "MNG_RX_DP")
	)
	(segment
		(start 59.981338 -22.987)
		(end 57.321958 -22.987)
		(width 0.1016)
		(layer "In2.Cu")
		(net "MNG_RX_DP")
	)
	(segment
		(start 47.27321 -43.99534)
		(end 47.057818 -44.210732)
		(width 0.1016)
		(layer "In2.Cu")
		(net "MNG_RX_DP")
	)
	(segment
		(start 57.953402 -19.961606)
		(end 61.454538 -19.961606)
		(width 0.1016)
		(layer "In2.Cu")
		(net "MNG_RX_DP")
	)
	(segment
		(start 35.842194 -55.426356)
		(end 26.763726 -55.426356)
		(width 0.1016)
		(layer "In2.Cu")
		(net "MNG_RX_DP")
	)
	(segment
		(start 50.8762 -38.608)
		(end 50.8762 -40.39235)
		(width 0.1016)
		(layer "In2.Cu")
		(net "MNG_RX_DP")
	)
	(segment
		(start 50.8762 -37.6174)
		(end 50.8762 -37.9222)
		(width 0.1016)
		(layer "In2.Cu")
		(net "MNG_RX_DP")
	)
	(segment
		(start 46.087792 -44.911264)
		(end 45.8724 -45.126656)
		(width 0.1016)
		(layer "In2.Cu")
		(net "MNG_RX_DP")
	)
	(segment
		(start 46.788324 -44.210732)
		(end 46.572932 -44.426378)
		(width 0.1016)
		(layer "In2.Cu")
		(net "MNG_RX_DP")
	)
	(segment
		(start 23.128986 -58.012076)
		(end 23.128986 -57.095136)
		(width 0.1016)
		(layer "In2.Cu")
		(net "MNG_RX_DP")
	)
	(segment
		(start 46.572932 -44.426378)
		(end 46.572932 -44.695618)
		(width 0.1016)
		(layer "In2.Cu")
		(net "MNG_RX_DP")
	)
	(segment
		(start 57.321958 -22.987)
		(end 55.342536 -24.966422)
		(width 0.1016)
		(layer "In2.Cu")
		(net "MNG_RX_DP")
	)
	(segment
		(start 46.572932 -44.695618)
		(end 46.357286 -44.911264)
		(width 0.1016)
		(layer "In2.Cu")
		(net "MNG_RX_DP")
	)
	(segment
		(start 47.973742 -43.025314)
		(end 47.973742 -43.294808)
		(width 0.1016)
		(layer "In2.Cu")
		(net "MNG_RX_DP")
	)
	(segment
		(start 45.8724 -45.39615)
		(end 35.842194 -55.426356)
		(width 0.1016)
		(layer "In2.Cu")
		(net "MNG_RX_DP")
	)
	(segment
		(start 50.8762 -36.9316)
		(end 50.6857 -37.1221)
		(width 0.1016)
		(layer "In2.Cu")
		(net "MNG_RX_DP")
	)
	(segment
		(start 55.342536 -29.036772)
		(end 50.8762 -33.503108)
		(width 0.1016)
		(layer "In2.Cu")
		(net "MNG_RX_DP")
	)
	(segment
		(start 26.763726 -55.426356)
		(end 23.986744 -58.203338)
		(width 0.1016)
		(layer "In2.Cu")
		(net "MNG_RX_DP")
	)
	(segment
		(start 61.556138 -21.4122)
		(end 59.981338 -22.987)
		(width 0.1016)
		(layer "In2.Cu")
		(net "MNG_RX_DP")
	)
	(segment
		(start 50.6857 -37.4269)
		(end 50.8762 -37.6174)
		(width 0.1016)
		(layer "In2.Cu")
		(net "MNG_RX_DP")
	)
	(segment
		(start 50.8762 -40.39235)
		(end 48.458628 -42.809922)
		(width 0.1016)
		(layer "In2.Cu")
		(net "MNG_RX_DP")
	)
	(segment
		(start 47.057818 -44.210732)
		(end 46.788324 -44.210732)
		(width 0.1016)
		(layer "In2.Cu")
		(net "MNG_RX_DP")
	)
	(segment
		(start 47.488856 -43.510454)
		(end 47.27321 -43.725846)
		(width 0.1016)
		(layer "In2.Cu")
		(net "MNG_RX_DP")
	)
	(segment
		(start 45.8724 -45.126656)
		(end 45.8724 -45.39615)
		(width 0.1016)
		(layer "In2.Cu")
		(net "MNG_RX_DP")
	)
	(segment
		(start 50.6857 -37.1221)
		(end 50.6857 -37.4269)
		(width 0.1016)
		(layer "In2.Cu")
		(net "MNG_RX_DP")
	)
	(segment
		(start 50.6857 -38.1127)
		(end 50.6857 -38.4175)
		(width 0.1016)
		(layer "In2.Cu")
		(net "MNG_RX_DP")
	)
	(segment
		(start 22.803104 -55.912004)
		(end 22.4536 -55.5625)
		(width 0.104902)
		(layer "F.Cu")
		(net "MNG_RX_DN")
	)
	(segment
		(start 63.545974 -19.961606)
		(end 65.463674 -19.961606)
		(width 0.104902)
		(layer "F.Cu")
		(net "MNG_RX_DN")
	)
	(segment
		(start 22.803104 -56.303418)
		(end 22.803104 -55.912004)
		(width 0.104902)
		(layer "F.Cu")
		(net "MNG_RX_DN")
	)
	(segment
		(start 22.417786 -56.688736)
		(end 22.803104 -56.303418)
		(width 0.104902)
		(layer "F.Cu")
		(net "MNG_RX_DN")
	)
	(via
		(at 22.417786 -56.688736)
		(size 0.508)
		(drill 0.254)
		(layers "F.Cu" "B.Cu")
		(net "MNG_RX_DN")
	)
	(via
		(at 65.463674 -19.961606)
		(size 0.508)
		(drill 0.254)
		(layers "F.Cu" "B.Cu")
		(net "MNG_RX_DN")
	)
	(segment
		(start 57.44845 -23.2918)
		(end 60.10783 -23.2918)
		(width 0.1016)
		(layer "In2.Cu")
		(net "MNG_RX_DN")
	)
	(segment
		(start 51.181 -40.518842)
		(end 51.181 -33.6296)
		(width 0.1016)
		(layer "In2.Cu")
		(net "MNG_RX_DN")
	)
	(segment
		(start 23.193756 -58.508138)
		(end 24.113236 -58.508138)
		(width 0.1016)
		(layer "In2.Cu")
		(net "MNG_RX_DN")
	)
	(segment
		(start 55.647336 -29.163264)
		(end 55.647336 -25.092914)
		(width 0.1016)
		(layer "In2.Cu")
		(net "MNG_RX_DN")
	)
	(segment
		(start 51.181 -33.6296)
		(end 55.647336 -29.163264)
		(width 0.1016)
		(layer "In2.Cu")
		(net "MNG_RX_DN")
	)
	(segment
		(start 55.647336 -25.092914)
		(end 57.44845 -23.2918)
		(width 0.1016)
		(layer "In2.Cu")
		(net "MNG_RX_DN")
	)
	(segment
		(start 61.860938 -20.063206)
		(end 61.962538 -19.961606)
		(width 0.1016)
		(layer "In2.Cu")
		(net "MNG_RX_DN")
	)
	(segment
		(start 26.890218 -55.731156)
		(end 35.968686 -55.731156)
		(width 0.1016)
		(layer "In2.Cu")
		(net "MNG_RX_DN")
	)
	(segment
		(start 22.824186 -58.138568)
		(end 23.193756 -58.508138)
		(width 0.1016)
		(layer "In2.Cu")
		(net "MNG_RX_DN")
	)
	(segment
		(start 60.10783 -23.2918)
		(end 61.860938 -21.538692)
		(width 0.1016)
		(layer "In2.Cu")
		(net "MNG_RX_DN")
	)
	(segment
		(start 35.968686 -55.731156)
		(end 51.181 -40.518842)
		(width 0.1016)
		(layer "In2.Cu")
		(net "MNG_RX_DN")
	)
	(segment
		(start 24.113236 -58.508138)
		(end 26.890218 -55.731156)
		(width 0.1016)
		(layer "In2.Cu")
		(net "MNG_RX_DN")
	)
	(segment
		(start 22.824186 -57.095136)
		(end 22.824186 -58.138568)
		(width 0.1016)
		(layer "In2.Cu")
		(net "MNG_RX_DN")
	)
	(segment
		(start 22.417786 -56.688736)
		(end 22.824186 -57.095136)
		(width 0.1016)
		(layer "In2.Cu")
		(net "MNG_RX_DN")
	)
	(segment
		(start 61.962538 -19.961606)
		(end 65.463674 -19.961606)
		(width 0.1016)
		(layer "In2.Cu")
		(net "MNG_RX_DN")
	)
	(segment
		(start 61.860938 -21.538692)
		(end 61.860938 -20.063206)
		(width 0.1016)
		(layer "In2.Cu")
		(net "MNG_RX_DN")
	)
	(segment
		(start 8.863076 -55.967376)
		(end 8.863076 -59.412124)
		(width 0.12065)
		(layer "F.Cu")
		(net "LED_MDI0_LINK_N")
	)
	(segment
		(start 15.6972 -78.722982)
		(end 15.410942 -79.00924)
		(width 0.12065)
		(layer "F.Cu")
		(net "LED_MDI0_LINK_N")
	)
	(segment
		(start 3.7592 -64.516)
		(end 3.7592 -75.031854)
		(width 0.12065)
		(layer "F.Cu")
		(net "LED_MDI0_LINK_N")
	)
	(segment
		(start 5.241798 -76.514452)
		(end 9.433052 -76.514452)
		(width 0.12065)
		(layer "F.Cu")
		(net "LED_MDI0_LINK_N")
	)
	(segment
		(start 3.7592 -75.031854)
		(end 5.241798 -76.514452)
		(width 0.12065)
		(layer "F.Cu")
		(net "LED_MDI0_LINK_N")
	)
	(segment
		(start 9.433052 -76.514452)
		(end 9.8552 -76.9366)
		(width 0.12065)
		(layer "F.Cu")
		(net "LED_MDI0_LINK_N")
	)
	(segment
		(start 3.429 -50.2158)
		(end 8.001 -54.7878)
		(width 0.12065)
		(layer "F.Cu")
		(net "LED_MDI0_LINK_N")
	)
	(segment
		(start 7.489444 -32.159956)
		(end 3.429 -36.2204)
		(width 0.12065)
		(layer "F.Cu")
		(net "LED_MDI0_LINK_N")
	)
	(segment
		(start 8.863076 -59.412124)
		(end 3.7592 -64.516)
		(width 0.12065)
		(layer "F.Cu")
		(net "LED_MDI0_LINK_N")
	)
	(segment
		(start 3.429 -36.2204)
		(end 3.429 -50.2158)
		(width 0.12065)
		(layer "F.Cu")
		(net "LED_MDI0_LINK_N")
	)
	(segment
		(start 8.001 -55.1053)
		(end 8.863076 -55.967376)
		(width 0.12065)
		(layer "F.Cu")
		(net "LED_MDI0_LINK_N")
	)
	(segment
		(start 8.122158 -32.159956)
		(end 7.489444 -32.159956)
		(width 0.12065)
		(layer "F.Cu")
		(net "LED_MDI0_LINK_N")
	)
	(segment
		(start 15.6972 -77.9526)
		(end 15.6972 -78.722982)
		(width 0.12065)
		(layer "F.Cu")
		(net "LED_MDI0_LINK_N")
	)
	(segment
		(start 15.410942 -79.00924)
		(end 15.410942 -80.090518)
		(width 0.12065)
		(layer "F.Cu")
		(net "LED_MDI0_LINK_N")
	)
	(segment
		(start 8.001 -54.7878)
		(end 8.001 -55.1053)
		(width 0.12065)
		(layer "F.Cu")
		(net "LED_MDI0_LINK_N")
	)
	(via
		(at 9.8552 -76.9366)
		(size 0.508)
		(drill 0.254)
		(layers "F.Cu" "B.Cu")
		(net "LED_MDI0_LINK_N")
	)
	(via
		(at 15.6972 -77.9526)
		(size 0.508)
		(drill 0.254)
		(layers "F.Cu" "B.Cu")
		(net "LED_MDI0_LINK_N")
	)
	(segment
		(start 10.6426 -77.724)
		(end 9.8552 -76.9366)
		(width 0.127)
		(layer "In2.Cu")
		(net "LED_MDI0_LINK_N")
	)
	(segment
		(start 15.6972 -77.9526)
		(end 15.4686 -77.724)
		(width 0.127)
		(layer "In2.Cu")
		(net "LED_MDI0_LINK_N")
	)
	(segment
		(start 15.4686 -77.724)
		(end 10.6426 -77.724)
		(width 0.127)
		(layer "In2.Cu")
		(net "LED_MDI0_LINK_N")
	)
	(segment
		(start 26.571194 -48.772064)
		(end 26.571194 -36.985194)
		(width 0.12065)
		(layer "F.Cu")
		(net "LED_MDI0_1G_N_R")
	)
	(segment
		(start 28.2067 -52.7558)
		(end 28.2067 -51.6382)
		(width 0.12065)
		(layer "F.Cu")
		(net "LED_MDI0_1G_N_R")
	)
	(segment
		(start 28.0797 -53.8988)
		(end 28.2067 -53.7718)
		(width 0.12065)
		(layer "F.Cu")
		(net "LED_MDI0_1G_N_R")
	)
	(segment
		(start 26.997152 -50.428652)
		(end 26.997152 -49.198022)
		(width 0.12065)
		(layer "F.Cu")
		(net "LED_MDI0_1G_N_R")
	)
	(segment
		(start 28.2067 -51.6382)
		(end 26.997152 -50.428652)
		(width 0.12065)
		(layer "F.Cu")
		(net "LED_MDI0_1G_N_R")
	)
	(segment
		(start 28.2067 -53.7718)
		(end 28.2067 -52.7558)
		(width 0.12065)
		(layer "F.Cu")
		(net "LED_MDI0_1G_N_R")
	)
	(segment
		(start 26.571194 -36.985194)
		(end 24.285956 -34.699956)
		(width 0.12065)
		(layer "F.Cu")
		(net "LED_MDI0_1G_N_R")
	)
	(segment
		(start 24.285956 -34.699956)
		(end 23.162006 -34.699956)
		(width 0.12065)
		(layer "F.Cu")
		(net "LED_MDI0_1G_N_R")
	)
	(segment
		(start 26.997152 -49.198022)
		(end 26.571194 -48.772064)
		(width 0.12065)
		(layer "F.Cu")
		(net "LED_MDI0_1G_N_R")
	)
	(via
		(at 28.2067 -52.7558)
		(size 0.7112)
		(drill 0.3556)
		(layers "F.Cu" "B.Cu")
		(net "LED_MDI0_1G_N_R")
	)
	(segment
		(start 27.1907 -53.8988)
		(end 27.1907 -53.1241)
		(width 0.12065)
		(layer "F.Cu")
		(net "LED_MDI0_1G_N")
	)
	(segment
		(start 26.1874 -53.0606)
		(end 26.1874 -53.7464)
		(width 0.12065)
		(layer "F.Cu")
		(net "LED_MDI0_1G_N")
	)
	(segment
		(start 27.1907 -53.1241)
		(end 26.8732 -52.8066)
		(width 0.12065)
		(layer "F.Cu")
		(net "LED_MDI0_1G_N")
	)
	(segment
		(start 26.7462 -52.8066)
		(end 26.4414 -52.8066)
		(width 0.12065)
		(layer "F.Cu")
		(net "LED_MDI0_1G_N")
	)
	(segment
		(start 13.737082 -79.773018)
		(end 13.737082 -79.416656)
		(width 0.12065)
		(layer "F.Cu")
		(net "LED_MDI0_1G_N")
	)
	(segment
		(start 26.8732 -52.8066)
		(end 26.7462 -52.8066)
		(width 0.12065)
		(layer "F.Cu")
		(net "LED_MDI0_1G_N")
	)
	(segment
		(start 26.4414 -52.8066)
		(end 26.1874 -53.0606)
		(width 0.12065)
		(layer "F.Cu")
		(net "LED_MDI0_1G_N")
	)
	(segment
		(start 13.2207 -80.2894)
		(end 13.737082 -79.773018)
		(width 0.12065)
		(layer "F.Cu")
		(net "LED_MDI0_1G_N")
	)
	(via
		(at 26.1874 -53.7464)
		(size 0.508)
		(drill 0.254)
		(layers "F.Cu" "B.Cu")
		(net "LED_MDI0_1G_N")
	)
	(via
		(at 26.7462 -52.8066)
		(size 0.7112)
		(drill 0.3556)
		(layers "F.Cu" "B.Cu")
		(net "LED_MDI0_1G_N")
	)
	(via
		(at 13.2207 -80.2894)
		(size 0.508)
		(drill 0.254)
		(layers "F.Cu" "B.Cu")
		(net "LED_MDI0_1G_N")
	)
	(segment
		(start 19.7104 -71.1327)
		(end 19.7104 -69.828918)
		(width 0.127)
		(layer "In5.Cu")
		(net "LED_MDI0_1G_N")
	)
	(segment
		(start 19.879818 -74.6125)
		(end 20.1549 -74.337418)
		(width 0.127)
		(layer "In5.Cu")
		(net "LED_MDI0_1G_N")
	)
	(segment
		(start 19.34083 -74.6125)
		(end 19.879818 -74.6125)
		(width 0.127)
		(layer "In5.Cu")
		(net "LED_MDI0_1G_N")
	)
	(segment
		(start 19.7231 -69.816218)
		(end 19.7231 -69.426582)
		(width 0.127)
		(layer "In5.Cu")
		(net "LED_MDI0_1G_N")
	)
	(segment
		(start 18.87093 -75.0824)
		(end 19.34083 -74.6125)
		(width 0.127)
		(layer "In5.Cu")
		(net "LED_MDI0_1G_N")
	)
	(segment
		(start 19.7104 -69.413882)
		(end 19.7104 -67.437)
		(width 0.127)
		(layer "In5.Cu")
		(net "LED_MDI0_1G_N")
	)
	(segment
		(start 20.1549 -72.968612)
		(end 20.3073 -72.816212)
		(width 0.127)
		(layer "In5.Cu")
		(net "LED_MDI0_1G_N")
	)
	(segment
		(start 20.0279 -65.301876)
		(end 20.161758 -65.168018)
		(width 0.127)
		(layer "In5.Cu")
		(net "LED_MDI0_1G_N")
	)
	(segment
		(start 13.6906 -79.8195)
		(end 13.6906 -78.755494)
		(width 0.127)
		(layer "In5.Cu")
		(net "LED_MDI0_1G_N")
	)
	(segment
		(start 19.7104 -69.828918)
		(end 19.7231 -69.816218)
		(width 0.127)
		(layer "In5.Cu")
		(net "LED_MDI0_1G_N")
	)
	(segment
		(start 13.2207 -80.2894)
		(end 13.6906 -79.8195)
		(width 0.127)
		(layer "In5.Cu")
		(net "LED_MDI0_1G_N")
	)
	(segment
		(start 20.161758 -63.115952)
		(end 26.1874 -57.09031)
		(width 0.127)
		(layer "In5.Cu")
		(net "LED_MDI0_1G_N")
	)
	(segment
		(start 13.6906 -78.755494)
		(end 16.423894 -76.0222)
		(width 0.127)
		(layer "In5.Cu")
		(net "LED_MDI0_1G_N")
	)
	(segment
		(start 18.080482 -75.0824)
		(end 18.87093 -75.0824)
		(width 0.127)
		(layer "In5.Cu")
		(net "LED_MDI0_1G_N")
	)
	(segment
		(start 19.7231 -69.426582)
		(end 19.7104 -69.413882)
		(width 0.127)
		(layer "In5.Cu")
		(net "LED_MDI0_1G_N")
	)
	(segment
		(start 26.1874 -57.09031)
		(end 26.1874 -53.7464)
		(width 0.127)
		(layer "In5.Cu")
		(net "LED_MDI0_1G_N")
	)
	(segment
		(start 19.7104 -67.437)
		(end 20.0279 -67.1195)
		(width 0.127)
		(layer "In5.Cu")
		(net "LED_MDI0_1G_N")
	)
	(segment
		(start 20.0279 -67.1195)
		(end 20.0279 -65.301876)
		(width 0.127)
		(layer "In5.Cu")
		(net "LED_MDI0_1G_N")
	)
	(segment
		(start 17.140682 -76.0222)
		(end 18.080482 -75.0824)
		(width 0.127)
		(layer "In5.Cu")
		(net "LED_MDI0_1G_N")
	)
	(segment
		(start 16.423894 -76.0222)
		(end 17.140682 -76.0222)
		(width 0.127)
		(layer "In5.Cu")
		(net "LED_MDI0_1G_N")
	)
	(segment
		(start 20.3073 -72.816212)
		(end 20.3073 -71.7296)
		(width 0.127)
		(layer "In5.Cu")
		(net "LED_MDI0_1G_N")
	)
	(segment
		(start 20.3073 -71.7296)
		(end 19.7104 -71.1327)
		(width 0.127)
		(layer "In5.Cu")
		(net "LED_MDI0_1G_N")
	)
	(segment
		(start 20.1549 -74.337418)
		(end 20.1549 -72.968612)
		(width 0.127)
		(layer "In5.Cu")
		(net "LED_MDI0_1G_N")
	)
	(segment
		(start 20.161758 -65.168018)
		(end 20.161758 -63.115952)
		(width 0.127)
		(layer "In5.Cu")
		(net "LED_MDI0_1G_N")
	)
	(segment
		(start 26.4287 -34.34334)
		(end 24.617426 -32.532066)
		(width 0.12065)
		(layer "F.Cu")
		(net "LED_MDI0_100M_N_R")
	)
	(segment
		(start 24.617426 -31.075376)
		(end 23.162006 -29.619956)
		(width 0.12065)
		(layer "F.Cu")
		(net "LED_MDI0_100M_N_R")
	)
	(segment
		(start 24.617426 -32.532066)
		(end 24.617426 -31.075376)
		(width 0.12065)
		(layer "F.Cu")
		(net "LED_MDI0_100M_N_R")
	)
	(segment
		(start 27.4447 -34.34334)
		(end 26.4287 -34.34334)
		(width 0.12065)
		(layer "F.Cu")
		(net "LED_MDI0_100M_N_R")
	)
	(segment
		(start 14.91107 -78.38567)
		(end 14.91107 -80.090518)
		(width 0.12065)
		(layer "F.Cu")
		(net "LED_MDI0_100M_N")
	)
	(segment
		(start 27.93238 -33.94202)
		(end 27.4447 -33.45434)
		(width 0.12065)
		(layer "F.Cu")
		(net "LED_MDI0_100M_N")
	)
	(segment
		(start 28.439618 -50.706528)
		(end 28.275026 -50.541936)
		(width 0.12065)
		(layer "F.Cu")
		(net "LED_MDI0_100M_N")
	)
	(segment
		(start 28.275026 -50.541936)
		(end 28.275026 -49.704752)
		(width 0.12065)
		(layer "F.Cu")
		(net "LED_MDI0_100M_N")
	)
	(segment
		(start 27.93238 -39.59606)
		(end 27.93238 -33.94202)
		(width 0.12065)
		(layer "F.Cu")
		(net "LED_MDI0_100M_N")
	)
	(segment
		(start 28.14828 -39.81196)
		(end 27.93238 -39.59606)
		(width 0.12065)
		(layer "F.Cu")
		(net "LED_MDI0_100M_N")
	)
	(segment
		(start 28.14828 -49.578006)
		(end 28.14828 -39.81196)
		(width 0.12065)
		(layer "F.Cu")
		(net "LED_MDI0_100M_N")
	)
	(segment
		(start 28.275026 -49.704752)
		(end 28.14828 -49.578006)
		(width 0.12065)
		(layer "F.Cu")
		(net "LED_MDI0_100M_N")
	)
	(segment
		(start 14.9098 -78.3844)
		(end 14.91107 -78.38567)
		(width 0.12065)
		(layer "F.Cu")
		(net "LED_MDI0_100M_N")
	)
	(via
		(at 28.439618 -50.706528)
		(size 0.508)
		(drill 0.254)
		(layers "F.Cu" "B.Cu")
		(net "LED_MDI0_100M_N")
	)
	(via
		(at 14.9098 -78.3844)
		(size 0.508)
		(drill 0.254)
		(layers "F.Cu" "B.Cu")
		(net "LED_MDI0_100M_N")
	)
	(via
		(at 28.275026 -49.704752)
		(size 0.7112)
		(drill 0.3556)
		(layers "F.Cu" "B.Cu")
		(net "LED_MDI0_100M_N")
	)
	(segment
		(start 20.4089 -67.277488)
		(end 20.4089 -65.459864)
		(width 0.127)
		(layer "In5.Cu")
		(net "LED_MDI0_100M_N")
	)
	(segment
		(start 20.1676 -67.518788)
		(end 20.4089 -67.277488)
		(width 0.127)
		(layer "In5.Cu")
		(net "LED_MDI0_100M_N")
	)
	(segment
		(start 20.542758 -63.27394)
		(end 27.633422 -56.183276)
		(width 0.127)
		(layer "In5.Cu")
		(net "LED_MDI0_100M_N")
	)
	(segment
		(start 20.5359 -74.495406)
		(end 20.5359 -73.1266)
		(width 0.127)
		(layer "In5.Cu")
		(net "LED_MDI0_100M_N")
	)
	(segment
		(start 20.4089 -65.459864)
		(end 20.542758 -65.326006)
		(width 0.127)
		(layer "In5.Cu")
		(net "LED_MDI0_100M_N")
	)
	(segment
		(start 27.633422 -54.929278)
		(end 28.439618 -54.123082)
		(width 0.127)
		(layer "In5.Cu")
		(net "LED_MDI0_100M_N")
	)
	(segment
		(start 14.9098 -78.3844)
		(end 14.9098 -78.075282)
		(width 0.127)
		(layer "In5.Cu")
		(net "LED_MDI0_100M_N")
	)
	(segment
		(start 20.037806 -74.9935)
		(end 20.5359 -74.495406)
		(width 0.127)
		(layer "In5.Cu")
		(net "LED_MDI0_100M_N")
	)
	(segment
		(start 20.5359 -73.1266)
		(end 20.6883 -72.9742)
		(width 0.127)
		(layer "In5.Cu")
		(net "LED_MDI0_100M_N")
	)
	(segment
		(start 17.911318 -76.581)
		(end 19.498818 -74.9935)
		(width 0.127)
		(layer "In5.Cu")
		(net "LED_MDI0_100M_N")
	)
	(segment
		(start 20.6883 -71.571612)
		(end 20.1676 -71.050912)
		(width 0.127)
		(layer "In5.Cu")
		(net "LED_MDI0_100M_N")
	)
	(segment
		(start 28.439618 -54.123082)
		(end 28.439618 -50.706528)
		(width 0.127)
		(layer "In5.Cu")
		(net "LED_MDI0_100M_N")
	)
	(segment
		(start 19.498818 -74.9935)
		(end 20.037806 -74.9935)
		(width 0.127)
		(layer "In5.Cu")
		(net "LED_MDI0_100M_N")
	)
	(segment
		(start 20.542758 -65.326006)
		(end 20.542758 -63.27394)
		(width 0.127)
		(layer "In5.Cu")
		(net "LED_MDI0_100M_N")
	)
	(segment
		(start 20.6883 -72.9742)
		(end 20.6883 -71.571612)
		(width 0.127)
		(layer "In5.Cu")
		(net "LED_MDI0_100M_N")
	)
	(segment
		(start 16.404082 -76.581)
		(end 17.911318 -76.581)
		(width 0.127)
		(layer "In5.Cu")
		(net "LED_MDI0_100M_N")
	)
	(segment
		(start 14.9098 -78.075282)
		(end 16.404082 -76.581)
		(width 0.127)
		(layer "In5.Cu")
		(net "LED_MDI0_100M_N")
	)
	(segment
		(start 27.633422 -56.183276)
		(end 27.633422 -54.929278)
		(width 0.127)
		(layer "In5.Cu")
		(net "LED_MDI0_100M_N")
	)
	(segment
		(start 20.1676 -71.050912)
		(end 20.1676 -67.518788)
		(width 0.127)
		(layer "In5.Cu")
		(net "LED_MDI0_100M_N")
	)
	(segment
		(start 27.488896 -40.230298)
		(end 27.488896 -36.683696)
		(width 0.12065)
		(layer "F.Cu")
		(net "LED_MDI0_100M_1G_N")
	)
	(segment
		(start 27.488896 -36.683696)
		(end 23.162006 -32.356806)
		(width 0.12065)
		(layer "F.Cu")
		(net "LED_MDI0_100M_1G_N")
	)
	(segment
		(start 23.162006 -32.356806)
		(end 23.162006 -32.159956)
		(width 0.12065)
		(layer "F.Cu")
		(net "LED_MDI0_100M_1G_N")
	)
	(segment
		(start 17.911064 -69.473064)
		(end 17.78 -69.342)
		(width 0.12065)
		(layer "F.Cu")
		(net "LAN1_56")
	)
	(segment
		(start 17.5514 -67.6402)
		(end 17.5514 -69.1134)
		(width 0.12065)
		(layer "F.Cu")
		(net "LAN1_56")
	)
	(segment
		(start 17.2974 -67.3862)
		(end 17.5514 -67.6402)
		(width 0.12065)
		(layer "F.Cu")
		(net "LAN1_56")
	)
	(segment
		(start 17.911064 -71.242682)
		(end 17.911064 -69.473064)
		(width 0.12065)
		(layer "F.Cu")
		(net "LAN1_56")
	)
	(segment
		(start 17.5514 -69.1134)
		(end 17.78 -69.342)
		(width 0.12065)
		(layer "F.Cu")
		(net "LAN1_56")
	)
	(via
		(at 17.78 -69.342)
		(size 0.7112)
		(drill 0.3556)
		(layers "F.Cu" "B.Cu")
		(net "LAN1_56")
	)
	(segment
		(start 15.410942 -69.729858)
		(end 15.461488 -69.679312)
		(width 0.12065)
		(layer "F.Cu")
		(net "LAN1_51")
	)
	(segment
		(start 15.410942 -71.242682)
		(end 15.410942 -69.729858)
		(width 0.12065)
		(layer "F.Cu")
		(net "LAN1_51")
	)
	(via
		(at 15.461488 -69.679312)
		(size 0.508)
		(drill 0.254)
		(layers "F.Cu" "B.Cu")
		(net "LAN1_51")
	)
	(segment
		(start 15.657576 -69.8754)
		(end 15.461488 -69.679312)
		(width 0.12065)
		(layer "B.Cu")
		(net "LAN1_51")
	)
	(segment
		(start 17.1196 -69.8754)
		(end 18.3134 -69.8754)
		(width 0.12065)
		(layer "B.Cu")
		(net "LAN1_51")
	)
	(segment
		(start 17.1196 -69.8754)
		(end 15.657576 -69.8754)
		(width 0.12065)
		(layer "B.Cu")
		(net "LAN1_51")
	)
	(segment
		(start 9.174226 -78.16215)
		(end 8.309102 -78.16215)
		(width 0.12065)
		(layer "F.Cu")
		(net "LAN_SMB_DAT")
	)
	(segment
		(start 8.042148 -77.895196)
		(end 8.042148 -77.028548)
		(width 0.12065)
		(layer "F.Cu")
		(net "LAN_SMB_DAT")
	)
	(segment
		(start 11.954002 -78.095094)
		(end 11.353546 -78.69555)
		(width 0.12065)
		(layer "F.Cu")
		(net "LAN_SMB_DAT")
	)
	(segment
		(start 12.901676 -77.916532)
		(end 12.723114 -78.095094)
		(width 0.12065)
		(layer "F.Cu")
		(net "LAN_SMB_DAT")
	)
	(segment
		(start 8.309102 -78.16215)
		(end 8.042148 -77.895196)
		(width 0.12065)
		(layer "F.Cu")
		(net "LAN_SMB_DAT")
	)
	(segment
		(start 9.707626 -78.69555)
		(end 9.174226 -78.16215)
		(width 0.12065)
		(layer "F.Cu")
		(net "LAN_SMB_DAT")
	)
	(segment
		(start 12.723114 -78.095094)
		(end 11.954002 -78.095094)
		(width 0.12065)
		(layer "F.Cu")
		(net "LAN_SMB_DAT")
	)
	(segment
		(start 13.737082 -77.916532)
		(end 12.901676 -77.916532)
		(width 0.12065)
		(layer "F.Cu")
		(net "LAN_SMB_DAT")
	)
	(segment
		(start 11.353546 -78.69555)
		(end 9.707626 -78.69555)
		(width 0.12065)
		(layer "F.Cu")
		(net "LAN_SMB_DAT")
	)
	(via
		(at 8.042148 -77.028548)
		(size 0.508)
		(drill 0.254)
		(layers "F.Cu" "B.Cu")
		(net "LAN_SMB_DAT")
	)
	(via
		(at 50.275998 -97.624138)
		(size 0.7112)
		(drill 0.3556)
		(layers "F.Cu" "B.Cu")
		(net "LAN_SMB_DAT")
	)
	(via
		(at 43.195748 -77.357224)
		(size 0.508)
		(drill 0.254)
		(layers "F.Cu" "B.Cu")
		(net "LAN_SMB_DAT")
	)
	(segment
		(start 47.9044 -97.9678)
		(end 50.275998 -97.9678)
		(width 0.12065)
		(layer "B.Cu")
		(net "LAN_SMB_DAT")
	)
	(segment
		(start 58.8264 -97.9678)
		(end 50.275998 -97.9678)
		(width 0.12065)
		(layer "B.Cu")
		(net "LAN_SMB_DAT")
	)
	(segment
		(start 68.853558 -121.3231)
		(end 68.853558 -120.334786)
		(width 0.12065)
		(layer "B.Cu")
		(net "LAN_SMB_DAT")
	)
	(segment
		(start 68.853558 -120.334786)
		(end 67.27825 -118.759478)
		(width 0.12065)
		(layer "B.Cu")
		(net "LAN_SMB_DAT")
	)
	(segment
		(start 42.9514 -80.1116)
		(end 43.96867 -81.12887)
		(width 0.12065)
		(layer "B.Cu")
		(net "LAN_SMB_DAT")
	)
	(segment
		(start 67.627754 -122.081798)
		(end 68.09486 -122.081798)
		(width 0.12065)
		(layer "B.Cu")
		(net "LAN_SMB_DAT")
	)
	(segment
		(start 42.9514 -77.601572)
		(end 42.9514 -80.1116)
		(width 0.12065)
		(layer "B.Cu")
		(net "LAN_SMB_DAT")
	)
	(segment
		(start 62.0522 -101.1936)
		(end 58.8264 -97.9678)
		(width 0.12065)
		(layer "B.Cu")
		(net "LAN_SMB_DAT")
	)
	(segment
		(start 67.27825 -116.377974)
		(end 66.0654 -115.165124)
		(width 0.12065)
		(layer "B.Cu")
		(net "LAN_SMB_DAT")
	)
	(segment
		(start 43.195748 -77.357224)
		(end 42.9514 -77.601572)
		(width 0.12065)
		(layer "B.Cu")
		(net "LAN_SMB_DAT")
	)
	(segment
		(start 50.275998 -97.9678)
		(end 50.275998 -97.624138)
		(width 0.12065)
		(layer "B.Cu")
		(net "LAN_SMB_DAT")
	)
	(segment
		(start 68.09486 -122.081798)
		(end 68.853558 -121.3231)
		(width 0.12065)
		(layer "B.Cu")
		(net "LAN_SMB_DAT")
	)
	(segment
		(start 67.383152 -122.3264)
		(end 67.627754 -122.081798)
		(width 0.12065)
		(layer "B.Cu")
		(net "LAN_SMB_DAT")
	)
	(segment
		(start 62.0522 -103.251)
		(end 62.0522 -101.1936)
		(width 0.12065)
		(layer "B.Cu")
		(net "LAN_SMB_DAT")
	)
	(segment
		(start 44.1452 -81.907634)
		(end 44.1452 -94.2086)
		(width 0.12065)
		(layer "B.Cu")
		(net "LAN_SMB_DAT")
	)
	(segment
		(start 66.0654 -115.165124)
		(end 66.0654 -107.2642)
		(width 0.12065)
		(layer "B.Cu")
		(net "LAN_SMB_DAT")
	)
	(segment
		(start 67.27825 -118.759478)
		(end 67.27825 -116.377974)
		(width 0.12065)
		(layer "B.Cu")
		(net "LAN_SMB_DAT")
	)
	(segment
		(start 66.0654 -107.2642)
		(end 62.0522 -103.251)
		(width 0.12065)
		(layer "B.Cu")
		(net "LAN_SMB_DAT")
	)
	(segment
		(start 43.96867 -81.12887)
		(end 43.96867 -81.731104)
		(width 0.12065)
		(layer "B.Cu")
		(net "LAN_SMB_DAT")
	)
	(segment
		(start 43.96867 -81.731104)
		(end 44.1452 -81.907634)
		(width 0.12065)
		(layer "B.Cu")
		(net "LAN_SMB_DAT")
	)
	(segment
		(start 44.1452 -94.2086)
		(end 47.9044 -97.9678)
		(width 0.12065)
		(layer "B.Cu")
		(net "LAN_SMB_DAT")
	)
	(segment
		(start 42.8244 -76.985876)
		(end 43.195748 -77.357224)
		(width 0.127)
		(layer "In2.Cu")
		(net "LAN_SMB_DAT")
	)
	(segment
		(start 26.354532 -75.524868)
		(end 27.823414 -75.524868)
		(width 0.127)
		(layer "In2.Cu")
		(net "LAN_SMB_DAT")
	)
	(segment
		(start 42.164254 -75.9714)
		(end 42.8244 -76.631546)
		(width 0.127)
		(layer "In2.Cu")
		(net "LAN_SMB_DAT")
	)
	(segment
		(start 27.823414 -75.524868)
		(end 28.269946 -75.9714)
		(width 0.127)
		(layer "In2.Cu")
		(net "LAN_SMB_DAT")
	)
	(segment
		(start 42.8244 -76.631546)
		(end 42.8244 -76.985876)
		(width 0.127)
		(layer "In2.Cu")
		(net "LAN_SMB_DAT")
	)
	(segment
		(start 22.502876 -79.376524)
		(end 26.354532 -75.524868)
		(width 0.127)
		(layer "In2.Cu")
		(net "LAN_SMB_DAT")
	)
	(segment
		(start 15.93469 -79.376524)
		(end 22.502876 -79.376524)
		(width 0.127)
		(layer "In2.Cu")
		(net "LAN_SMB_DAT")
	)
	(segment
		(start 8.042148 -77.028548)
		(end 9.2964 -78.2828)
		(width 0.127)
		(layer "In2.Cu")
		(net "LAN_SMB_DAT")
	)
	(segment
		(start 10.286746 -78.2828)
		(end 11.061446 -79.0575)
		(width 0.127)
		(layer "In2.Cu")
		(net "LAN_SMB_DAT")
	)
	(segment
		(start 11.061446 -79.0575)
		(end 15.615666 -79.0575)
		(width 0.127)
		(layer "In2.Cu")
		(net "LAN_SMB_DAT")
	)
	(segment
		(start 9.2964 -78.2828)
		(end 10.286746 -78.2828)
		(width 0.127)
		(layer "In2.Cu")
		(net "LAN_SMB_DAT")
	)
	(segment
		(start 28.269946 -75.9714)
		(end 42.164254 -75.9714)
		(width 0.127)
		(layer "In2.Cu")
		(net "LAN_SMB_DAT")
	)
	(segment
		(start 15.615666 -79.0575)
		(end 15.93469 -79.376524)
		(width 0.127)
		(layer "In2.Cu")
		(net "LAN_SMB_DAT")
	)
	(segment
		(start 8.32358 -78.6638)
		(end 8.025892 -78.961488)
		(width 0.12065)
		(layer "F.Cu")
		(net "LAN_SMB_CLK")
	)
	(segment
		(start 12.966446 -78.91653)
		(end 12.685776 -79.1972)
		(width 0.12065)
		(layer "F.Cu")
		(net "LAN_SMB_CLK")
	)
	(segment
		(start 13.737082 -78.91653)
		(end 12.966446 -78.91653)
		(width 0.12065)
		(layer "F.Cu")
		(net "LAN_SMB_CLK")
	)
	(segment
		(start 9.4996 -79.1972)
		(end 8.9662 -78.6638)
		(width 0.12065)
		(layer "F.Cu")
		(net "LAN_SMB_CLK")
	)
	(segment
		(start 8.9662 -78.6638)
		(end 8.32358 -78.6638)
		(width 0.12065)
		(layer "F.Cu")
		(net "LAN_SMB_CLK")
	)
	(segment
		(start 8.025892 -79.907892)
		(end 8.0518 -79.9338)
		(width 0.12065)
		(layer "F.Cu")
		(net "LAN_SMB_CLK")
	)
	(segment
		(start 8.025892 -78.961488)
		(end 8.025892 -79.907892)
		(width 0.12065)
		(layer "F.Cu")
		(net "LAN_SMB_CLK")
	)
	(segment
		(start 12.685776 -79.1972)
		(end 9.4996 -79.1972)
		(width 0.12065)
		(layer "F.Cu")
		(net "LAN_SMB_CLK")
	)
	(via
		(at 8.0518 -79.9338)
		(size 0.508)
		(drill 0.254)
		(layers "F.Cu" "B.Cu")
		(net "LAN_SMB_CLK")
	)
	(via
		(at 54.855872 -98.810572)
		(size 0.7112)
		(drill 0.3556)
		(layers "F.Cu" "B.Cu")
		(net "LAN_SMB_CLK")
	)
	(via
		(at 42.186098 -77.3049)
		(size 0.508)
		(drill 0.254)
		(layers "F.Cu" "B.Cu")
		(net "LAN_SMB_CLK")
	)
	(segment
		(start 43.64355 -82.11566)
		(end 43.64355 -94.416626)
		(width 0.12065)
		(layer "B.Cu")
		(net "LAN_SMB_CLK")
	)
	(segment
		(start 43.46702 -81.336896)
		(end 43.46702 -81.93913)
		(width 0.12065)
		(layer "B.Cu")
		(net "LAN_SMB_CLK")
	)
	(segment
		(start 42.186098 -77.3049)
		(end 42.44975 -77.568552)
		(width 0.12065)
		(layer "B.Cu")
		(net "LAN_SMB_CLK")
	)
	(segment
		(start 66.7766 -118.967504)
		(end 66.7766 -116.586)
		(width 0.12065)
		(layer "B.Cu")
		(net "LAN_SMB_CLK")
	)
	(segment
		(start 65.56375 -107.472226)
		(end 61.55055 -103.459026)
		(width 0.12065)
		(layer "B.Cu")
		(net "LAN_SMB_CLK")
	)
	(segment
		(start 67.6529 -121.580148)
		(end 67.886834 -121.580148)
		(width 0.12065)
		(layer "B.Cu")
		(net "LAN_SMB_CLK")
	)
	(segment
		(start 61.55055 -103.459026)
		(end 61.55055 -101.401626)
		(width 0.12065)
		(layer "B.Cu")
		(net "LAN_SMB_CLK")
	)
	(segment
		(start 67.886834 -121.580148)
		(end 68.351908 -121.115074)
		(width 0.12065)
		(layer "B.Cu")
		(net "LAN_SMB_CLK")
	)
	(segment
		(start 68.351908 -120.542812)
		(end 66.7766 -118.967504)
		(width 0.12065)
		(layer "B.Cu")
		(net "LAN_SMB_CLK")
	)
	(segment
		(start 58.618374 -98.46945)
		(end 54.855872 -98.46945)
		(width 0.12065)
		(layer "B.Cu")
		(net "LAN_SMB_CLK")
	)
	(segment
		(start 54.855872 -98.46945)
		(end 54.855872 -98.810572)
		(width 0.12065)
		(layer "B.Cu")
		(net "LAN_SMB_CLK")
	)
	(segment
		(start 43.46702 -81.93913)
		(end 43.64355 -82.11566)
		(width 0.12065)
		(layer "B.Cu")
		(net "LAN_SMB_CLK")
	)
	(segment
		(start 43.64355 -94.416626)
		(end 47.696374 -98.46945)
		(width 0.12065)
		(layer "B.Cu")
		(net "LAN_SMB_CLK")
	)
	(segment
		(start 42.44975 -77.568552)
		(end 42.44975 -80.319626)
		(width 0.12065)
		(layer "B.Cu")
		(net "LAN_SMB_CLK")
	)
	(segment
		(start 61.55055 -101.401626)
		(end 58.618374 -98.46945)
		(width 0.12065)
		(layer "B.Cu")
		(net "LAN_SMB_CLK")
	)
	(segment
		(start 42.44975 -80.319626)
		(end 43.46702 -81.336896)
		(width 0.12065)
		(layer "B.Cu")
		(net "LAN_SMB_CLK")
	)
	(segment
		(start 66.7766 -116.586)
		(end 65.56375 -115.37315)
		(width 0.12065)
		(layer "B.Cu")
		(net "LAN_SMB_CLK")
	)
	(segment
		(start 68.351908 -121.115074)
		(end 68.351908 -120.542812)
		(width 0.12065)
		(layer "B.Cu")
		(net "LAN_SMB_CLK")
	)
	(segment
		(start 65.56375 -115.37315)
		(end 65.56375 -107.472226)
		(width 0.12065)
		(layer "B.Cu")
		(net "LAN_SMB_CLK")
	)
	(segment
		(start 47.696374 -98.46945)
		(end 54.855872 -98.46945)
		(width 0.12065)
		(layer "B.Cu")
		(net "LAN_SMB_CLK")
	)
	(segment
		(start 67.383152 -121.3104)
		(end 67.6529 -121.580148)
		(width 0.12065)
		(layer "B.Cu")
		(net "LAN_SMB_CLK")
	)
	(segment
		(start 12.125452 -79.5655)
		(end 12.125706 -79.565754)
		(width 0.127)
		(layer "In2.Cu")
		(net "LAN_SMB_CLK")
	)
	(segment
		(start 9.1948 -78.7908)
		(end 10.07618 -78.7908)
		(width 0.127)
		(layer "In2.Cu")
		(net "LAN_SMB_CLK")
	)
	(segment
		(start 42.3164 -76.842112)
		(end 42.3164 -77.174598)
		(width 0.127)
		(layer "In2.Cu")
		(net "LAN_SMB_CLK")
	)
	(segment
		(start 10.85088 -79.5655)
		(end 12.125452 -79.5655)
		(width 0.127)
		(layer "In2.Cu")
		(net "LAN_SMB_CLK")
	)
	(segment
		(start 16.145002 -79.884778)
		(end 16.145256 -79.884524)
		(width 0.127)
		(layer "In2.Cu")
		(net "LAN_SMB_CLK")
	)
	(segment
		(start 12.546584 -79.5655)
		(end 15.4051 -79.5655)
		(width 0.127)
		(layer "In2.Cu")
		(net "LAN_SMB_CLK")
	)
	(segment
		(start 42.3164 -77.174598)
		(end 42.186098 -77.3049)
		(width 0.127)
		(layer "In2.Cu")
		(net "LAN_SMB_CLK")
	)
	(segment
		(start 12.54633 -79.565754)
		(end 12.546584 -79.5655)
		(width 0.127)
		(layer "In2.Cu")
		(net "LAN_SMB_CLK")
	)
	(segment
		(start 26.565098 -76.032868)
		(end 27.612848 -76.032868)
		(width 0.127)
		(layer "In2.Cu")
		(net "LAN_SMB_CLK")
	)
	(segment
		(start 8.0518 -79.9338)
		(end 9.1948 -78.7908)
		(width 0.127)
		(layer "In2.Cu")
		(net "LAN_SMB_CLK")
	)
	(segment
		(start 27.612848 -76.032868)
		(end 28.05938 -76.4794)
		(width 0.127)
		(layer "In2.Cu")
		(net "LAN_SMB_CLK")
	)
	(segment
		(start 15.4051 -79.5655)
		(end 15.724378 -79.884778)
		(width 0.127)
		(layer "In2.Cu")
		(net "LAN_SMB_CLK")
	)
	(segment
		(start 15.724378 -79.884778)
		(end 16.145002 -79.884778)
		(width 0.127)
		(layer "In2.Cu")
		(net "LAN_SMB_CLK")
	)
	(segment
		(start 22.713442 -79.884524)
		(end 26.565098 -76.032868)
		(width 0.127)
		(layer "In2.Cu")
		(net "LAN_SMB_CLK")
	)
	(segment
		(start 41.953688 -76.4794)
		(end 42.3164 -76.842112)
		(width 0.127)
		(layer "In2.Cu")
		(net "LAN_SMB_CLK")
	)
	(segment
		(start 12.125706 -79.565754)
		(end 12.54633 -79.565754)
		(width 0.127)
		(layer "In2.Cu")
		(net "LAN_SMB_CLK")
	)
	(segment
		(start 28.05938 -76.4794)
		(end 41.953688 -76.4794)
		(width 0.127)
		(layer "In2.Cu")
		(net "LAN_SMB_CLK")
	)
	(segment
		(start 16.145256 -79.884524)
		(end 22.713442 -79.884524)
		(width 0.127)
		(layer "In2.Cu")
		(net "LAN_SMB_CLK")
	)
	(segment
		(start 10.07618 -78.7908)
		(end 10.85088 -79.5655)
		(width 0.127)
		(layer "In2.Cu")
		(net "LAN_SMB_CLK")
	)
	(segment
		(start 12.1412 -78.5876)
		(end 12.742672 -78.5876)
		(width 0.12065)
		(layer "F.Cu")
		(net "LAN_SMB_ALERT_N")
	)
	(segment
		(start 30.544008 -111.836708)
		(end 30.544008 -110.858808)
		(width 0.12065)
		(layer "F.Cu")
		(net "LAN_SMB_ALERT_N")
	)
	(segment
		(start 29.5402 -110.8456)
		(end 30.5308 -110.8456)
		(width 0.12065)
		(layer "F.Cu")
		(net "LAN_SMB_ALERT_N")
	)
	(segment
		(start 30.544008 -110.858808)
		(end 30.5308 -110.8456)
		(width 0.12065)
		(layer "F.Cu")
		(net "LAN_SMB_ALERT_N")
	)
	(segment
		(start 28.494736 -112.0521)
		(end 28.494736 -111.047276)
		(width 0.12065)
		(layer "F.Cu")
		(net "LAN_SMB_ALERT_N")
	)
	(segment
		(start 12.913614 -78.416658)
		(end 13.737082 -78.416658)
		(width 0.12065)
		(layer "F.Cu")
		(net "LAN_SMB_ALERT_N")
	)
	(segment
		(start 28.696412 -110.8456)
		(end 29.5402 -110.8456)
		(width 0.12065)
		(layer "F.Cu")
		(net "LAN_SMB_ALERT_N")
	)
	(segment
		(start 28.494736 -111.047276)
		(end 28.696412 -110.8456)
		(width 0.12065)
		(layer "F.Cu")
		(net "LAN_SMB_ALERT_N")
	)
	(segment
		(start 12.742672 -78.5876)
		(end 12.913614 -78.416658)
		(width 0.12065)
		(layer "F.Cu")
		(net "LAN_SMB_ALERT_N")
	)
	(via
		(at 12.1412 -78.5876)
		(size 0.508)
		(drill 0.254)
		(layers "F.Cu" "B.Cu")
		(net "LAN_SMB_ALERT_N")
	)
	(via
		(at 29.5402 -110.8456)
		(size 0.7112)
		(drill 0.3556)
		(layers "F.Cu" "B.Cu")
		(net "LAN_SMB_ALERT_N")
	)
	(via
		(at 30.5308 -110.8456)
		(size 0.508)
		(drill 0.254)
		(layers "F.Cu" "B.Cu")
		(net "LAN_SMB_ALERT_N")
	)
	(segment
		(start 27.785568 -107.475528)
		(end 27.785568 -106.926126)
		(width 0.127)
		(layer "In5.Cu")
		(net "LAN_SMB_ALERT_N")
	)
	(segment
		(start 11.9888 -78.74)
		(end 12.1412 -78.5876)
		(width 0.127)
		(layer "In5.Cu")
		(net "LAN_SMB_ALERT_N")
	)
	(segment
		(start 15.136622 -88.617806)
		(end 13.2461 -86.727284)
		(width 0.127)
		(layer "In5.Cu")
		(net "LAN_SMB_ALERT_N")
	)
	(segment
		(start 14.423898 -98.857308)
		(end 14.423898 -90.94089)
		(width 0.127)
		(layer "In5.Cu")
		(net "LAN_SMB_ALERT_N")
	)
	(segment
		(start 22.77364 -102.4636)
		(end 18.03019 -102.4636)
		(width 0.127)
		(layer "In5.Cu")
		(net "LAN_SMB_ALERT_N")
	)
	(segment
		(start 27.785568 -106.926126)
		(end 26.608024 -105.748582)
		(width 0.127)
		(layer "In5.Cu")
		(net "LAN_SMB_ALERT_N")
	)
	(segment
		(start 26.608024 -105.748582)
		(end 26.058622 -105.748582)
		(width 0.127)
		(layer "In5.Cu")
		(net "LAN_SMB_ALERT_N")
	)
	(segment
		(start 18.03019 -102.4636)
		(end 14.423898 -98.857308)
		(width 0.127)
		(layer "In5.Cu")
		(net "LAN_SMB_ALERT_N")
	)
	(segment
		(start 14.423898 -90.94089)
		(end 15.136622 -90.228166)
		(width 0.127)
		(layer "In5.Cu")
		(net "LAN_SMB_ALERT_N")
	)
	(segment
		(start 11.9888 -81.5086)
		(end 11.9888 -78.74)
		(width 0.127)
		(layer "In5.Cu")
		(net "LAN_SMB_ALERT_N")
	)
	(segment
		(start 13.2461 -82.7659)
		(end 11.9888 -81.5086)
		(width 0.127)
		(layer "In5.Cu")
		(net "LAN_SMB_ALERT_N")
	)
	(segment
		(start 13.2461 -86.727284)
		(end 13.2461 -82.7659)
		(width 0.127)
		(layer "In5.Cu")
		(net "LAN_SMB_ALERT_N")
	)
	(segment
		(start 15.136622 -90.228166)
		(end 15.136622 -88.617806)
		(width 0.127)
		(layer "In5.Cu")
		(net "LAN_SMB_ALERT_N")
	)
	(segment
		(start 30.5308 -110.8456)
		(end 30.5308 -110.22076)
		(width 0.127)
		(layer "In5.Cu")
		(net "LAN_SMB_ALERT_N")
	)
	(segment
		(start 30.5308 -110.22076)
		(end 27.785568 -107.475528)
		(width 0.127)
		(layer "In5.Cu")
		(net "LAN_SMB_ALERT_N")
	)
	(segment
		(start 26.058622 -105.748582)
		(end 22.77364 -102.4636)
		(width 0.127)
		(layer "In5.Cu")
		(net "LAN_SMB_ALERT_N")
	)
	(segment
		(start 13.3604 -71.12)
		(end 13.3604 -71.539862)
		(width 0.12065)
		(layer "F.Cu")
		(net "LAN_SE_RSET")
	)
	(segment
		(start 13.4874 -70.993)
		(end 13.3604 -71.12)
		(width 0.12065)
		(layer "F.Cu")
		(net "LAN_SE_RSET")
	)
	(segment
		(start 17.041622 -90.103198)
		(end 16.326358 -90.103198)
		(width 0.12065)
		(layer "F.Cu")
		(net "LAN_SE_RSET")
	)
	(segment
		(start 16.326358 -90.103198)
		(end 16.129 -89.90584)
		(width 0.12065)
		(layer "F.Cu")
		(net "LAN_SE_RSET")
	)
	(segment
		(start 13.3604 -71.539862)
		(end 13.737082 -71.916544)
		(width 0.12065)
		(layer "F.Cu")
		(net "LAN_SE_RSET")
	)
	(via
		(at 13.4874 -70.993)
		(size 0.508)
		(drill 0.254)
		(layers "F.Cu" "B.Cu")
		(net "LAN_SE_RSET")
	)
	(via
		(at 16.129 -89.90584)
		(size 0.7112)
		(drill 0.254)
		(layers "F.Cu" "B.Cu")
		(net "LAN_SE_RSET")
	)
	(segment
		(start 13.208 -71.2724)
		(end 13.208 -79.18704)
		(width 0.127)
		(layer "In5.Cu")
		(net "LAN_SE_RSET")
	)
	(segment
		(start 13.114782 -80.8482)
		(end 14.1732 -80.8482)
		(width 0.127)
		(layer "In5.Cu")
		(net "LAN_SE_RSET")
	)
	(segment
		(start 12.7508 -80.484218)
		(end 13.114782 -80.8482)
		(width 0.127)
		(layer "In5.Cu")
		(net "LAN_SE_RSET")
	)
	(segment
		(start 13.208 -79.18704)
		(end 12.7508 -79.64424)
		(width 0.127)
		(layer "In5.Cu")
		(net "LAN_SE_RSET")
	)
	(segment
		(start 18.453354 -85.128354)
		(end 18.453354 -87.581486)
		(width 0.127)
		(layer "In5.Cu")
		(net "LAN_SE_RSET")
	)
	(segment
		(start 12.7508 -79.64424)
		(end 12.7508 -80.484218)
		(width 0.127)
		(layer "In5.Cu")
		(net "LAN_SE_RSET")
	)
	(segment
		(start 13.4874 -70.993)
		(end 13.208 -71.2724)
		(width 0.127)
		(layer "In5.Cu")
		(net "LAN_SE_RSET")
	)
	(segment
		(start 14.1732 -80.8482)
		(end 18.453354 -85.128354)
		(width 0.127)
		(layer "In5.Cu")
		(net "LAN_SE_RSET")
	)
	(segment
		(start 18.453354 -87.581486)
		(end 16.129 -89.90584)
		(width 0.127)
		(layer "In5.Cu")
		(net "LAN_SE_RSET")
	)
	(segment
		(start 23.605998 -70.895464)
		(end 24.691848 -70.895464)
		(width 0.12065)
		(layer "F.Cu")
		(net "LAN_MAIN_PWR_OK")
	)
	(segment
		(start 22.584918 -71.916544)
		(end 23.605998 -70.895464)
		(width 0.12065)
		(layer "F.Cu")
		(net "LAN_MAIN_PWR_OK")
	)
	(segment
		(start 24.8285 -70.758812)
		(end 24.8285 -70.1802)
		(width 0.12065)
		(layer "F.Cu")
		(net "LAN_MAIN_PWR_OK")
	)
	(segment
		(start 24.691848 -70.895464)
		(end 24.8285 -70.758812)
		(width 0.12065)
		(layer "F.Cu")
		(net "LAN_MAIN_PWR_OK")
	)
	(segment
		(start 29.142182 -60.704984)
		(end 29.142182 -59.456066)
		(width 0.12065)
		(layer "F.Cu")
		(net "I2C_TPM_SDA")
	)
	(segment
		(start 29.142182 -59.456066)
		(end 28.750768 -59.064652)
		(width 0.12065)
		(layer "F.Cu")
		(net "I2C_TPM_SDA")
	)
	(segment
		(start 26.9367 -58.389266)
		(end 25.574752 -57.027318)
		(width 0.12065)
		(layer "F.Cu")
		(net "I2C_TPM_SDA")
	)
	(segment
		(start 28.750768 -59.064652)
		(end 27.555952 -59.064652)
		(width 0.12065)
		(layer "F.Cu")
		(net "I2C_TPM_SDA")
	)
	(segment
		(start 27.555952 -59.064652)
		(end 26.9367 -58.4454)
		(width 0.12065)
		(layer "F.Cu")
		(net "I2C_TPM_SDA")
	)
	(segment
		(start 26.9367 -58.4454)
		(end 26.9367 -58.389266)
		(width 0.12065)
		(layer "F.Cu")
		(net "I2C_TPM_SDA")
	)
	(via
		(at 25.574752 -57.027318)
		(size 0.7112)
		(drill 0.3556)
		(layers "F.Cu" "B.Cu")
		(net "I2C_TPM_SDA")
	)
	(segment
		(start 26.0477 -69.3928)
		(end 27.1272 -69.3928)
		(width 0.12065)
		(layer "F.Cu")
		(net "I2C_TPM_SCL")
	)
	(segment
		(start 27.800808 -68.719192)
		(end 27.2542 -69.2658)
		(width 0.12065)
		(layer "F.Cu")
		(net "I2C_TPM_SCL")
	)
	(segment
		(start 27.642058 -67.064128)
		(end 27.800808 -67.222878)
		(width 0.12065)
		(layer "F.Cu")
		(net "I2C_TPM_SCL")
	)
	(segment
		(start 27.1272 -69.3928)
		(end 27.2542 -69.2658)
		(width 0.12065)
		(layer "F.Cu")
		(net "I2C_TPM_SCL")
	)
	(segment
		(start 25.7429 -69.088)
		(end 26.0477 -69.3928)
		(width 0.12065)
		(layer "F.Cu")
		(net "I2C_TPM_SCL")
	)
	(segment
		(start 27.800808 -67.222878)
		(end 27.800808 -68.719192)
		(width 0.12065)
		(layer "F.Cu")
		(net "I2C_TPM_SCL")
	)
	(segment
		(start 27.642058 -65.294764)
		(end 27.642058 -67.064128)
		(width 0.12065)
		(layer "F.Cu")
		(net "I2C_TPM_SCL")
	)
	(via
		(at 27.2542 -69.2658)
		(size 0.7112)
		(drill 0.3556)
		(layers "F.Cu" "B.Cu")
		(net "I2C_TPM_SCL")
	)
	(segment
		(start 12.857226 -75.916536)
		(end 12.56792 -75.62723)
		(width 0.3048)
		(layer "F.Cu")
		(net "I210_CTOP")
	)
	(segment
		(start 11.71067 -75.62723)
		(end 11.1506 -76.1873)
		(width 0.3048)
		(layer "F.Cu")
		(net "I210_CTOP")
	)
	(segment
		(start 13.737082 -75.916536)
		(end 12.857226 -75.916536)
		(width 0.3048)
		(layer "F.Cu")
		(net "I210_CTOP")
	)
	(segment
		(start 12.56792 -75.62723)
		(end 11.71067 -75.62723)
		(width 0.3048)
		(layer "F.Cu")
		(net "I210_CTOP")
	)
	(segment
		(start 12.259818 -77.616304)
		(end 12.459462 -77.41666)
		(width 0.3048)
		(layer "F.Cu")
		(net "I210_CBOT")
	)
	(segment
		(start 10.95248 -77.0763)
		(end 11.1506 -77.0763)
		(width 0.3048)
		(layer "F.Cu")
		(net "I210_CBOT")
	)
	(segment
		(start 10.4902 -77.53858)
		(end 10.95248 -77.0763)
		(width 0.3048)
		(layer "F.Cu")
		(net "I210_CBOT")
	)
	(segment
		(start 11.1506 -77.0763)
		(end 11.690604 -77.616304)
		(width 0.3048)
		(layer "F.Cu")
		(net "I210_CBOT")
	)
	(segment
		(start 10.4902 -78.0288)
		(end 10.4902 -77.53858)
		(width 0.3048)
		(layer "F.Cu")
		(net "I210_CBOT")
	)
	(segment
		(start 12.459462 -77.41666)
		(end 13.737082 -77.41666)
		(width 0.3048)
		(layer "F.Cu")
		(net "I210_CBOT")
	)
	(segment
		(start 11.690604 -77.616304)
		(end 12.259818 -77.616304)
		(width 0.3048)
		(layer "F.Cu")
		(net "I210_CBOT")
	)
	(via
		(at 10.4902 -78.0288)
		(size 0.7112)
		(drill 0.3556)
		(layers "F.Cu" "B.Cu")
		(net "I210_CBOT")
	)
	(segment
		(start 30.084268 -132.1054)
		(end 26.0604 -132.1054)
		(width 0.12065)
		(layer "F.Cu")
		(net "GPIOS5_R")
	)
	(segment
		(start 21.738844 -131.79044)
		(end 21.250656 -132.278628)
		(width 0.12065)
		(layer "F.Cu")
		(net "GPIOS5_R")
	)
	(segment
		(start 24.732234 -130.781298)
		(end 22.327108 -130.781298)
		(width 0.12065)
		(layer "F.Cu")
		(net "GPIOS5_R")
	)
	(segment
		(start 17.87906 -133.80974)
		(end 17.87906 -133.92658)
		(width 0.12065)
		(layer "F.Cu")
		(net "GPIOS5_R")
	)
	(segment
		(start 18.326862 -133.361938)
		(end 17.87906 -133.80974)
		(width 0.12065)
		(layer "F.Cu")
		(net "GPIOS5_R")
	)
	(segment
		(start 26.0604 -132.1054)
		(end 25.73655 -131.78155)
		(width 0.12065)
		(layer "F.Cu")
		(net "GPIOS5_R")
	)
	(segment
		(start 20.2057 -133.361938)
		(end 18.326862 -133.361938)
		(width 0.12065)
		(layer "F.Cu")
		(net "GPIOS5_R")
	)
	(segment
		(start 21.738844 -131.369562)
		(end 21.738844 -131.79044)
		(width 0.12065)
		(layer "F.Cu")
		(net "GPIOS5_R")
	)
	(segment
		(start 25.73655 -131.78155)
		(end 25.732486 -131.78155)
		(width 0.12065)
		(layer "F.Cu")
		(net "GPIOS5_R")
	)
	(segment
		(start 21.250656 -132.278628)
		(end 20.800568 -132.278628)
		(width 0.12065)
		(layer "F.Cu")
		(net "GPIOS5_R")
	)
	(segment
		(start 20.706842 -132.372354)
		(end 20.700238 -132.378958)
		(width 0.12065)
		(layer "F.Cu")
		(net "GPIOS5_R")
	)
	(segment
		(start 20.700238 -132.8674)
		(end 20.2057 -133.361938)
		(width 0.12065)
		(layer "F.Cu")
		(net "GPIOS5_R")
	)
	(segment
		(start 20.700238 -132.378958)
		(end 20.700238 -132.8674)
		(width 0.12065)
		(layer "F.Cu")
		(net "GPIOS5_R")
	)
	(segment
		(start 25.732486 -131.78155)
		(end 24.732234 -130.781298)
		(width 0.12065)
		(layer "F.Cu")
		(net "GPIOS5_R")
	)
	(segment
		(start 22.327108 -130.781298)
		(end 21.738844 -131.369562)
		(width 0.12065)
		(layer "F.Cu")
		(net "GPIOS5_R")
	)
	(segment
		(start 20.800568 -132.278628)
		(end 20.706842 -132.372354)
		(width 0.12065)
		(layer "F.Cu")
		(net "GPIOS5_R")
	)
	(segment
		(start 30.504892 -131.684776)
		(end 30.084268 -132.1054)
		(width 0.12065)
		(layer "F.Cu")
		(net "GPIOS5_R")
	)
	(via
		(at 20.706842 -132.372354)
		(size 0.7112)
		(drill 0.3556)
		(layers "F.Cu" "B.Cu")
		(net "GPIOS5_R")
	)
	(segment
		(start 22.883622 -91.679522)
		(end 22.883622 -92.7608)
		(width 0.12065)
		(layer "F.Cu")
		(net "FM_TPM_PRES_RST_N_R")
	)
	(segment
		(start 22.6441 -91.44)
		(end 22.883622 -91.679522)
		(width 0.12065)
		(layer "F.Cu")
		(net "FM_TPM_PRES_RST_N_R")
	)
	(segment
		(start 22.883622 -92.7608)
		(end 22.883622 -94.286578)
		(width 0.12065)
		(layer "F.Cu")
		(net "FM_TPM_PRES_RST_N_R")
	)
	(via
		(at 22.883622 -92.7608)
		(size 0.7112)
		(drill 0.3556)
		(layers "F.Cu" "B.Cu")
		(net "FM_TPM_PRES_RST_N_R")
	)
	(segment
		(start 26.202132 -101.356668)
		(end 25.970992 -101.356668)
		(width 0.12065)
		(layer "F.Cu")
		(net "FM_TPM_PRES_RST_N_C")
	)
	(segment
		(start 26.67 -100.8888)
		(end 26.202132 -101.356668)
		(width 0.12065)
		(layer "F.Cu")
		(net "FM_TPM_PRES_RST_N_C")
	)
	(segment
		(start 25.4508 -99.1362)
		(end 25.4 -99.187)
		(width 0.12065)
		(layer "F.Cu")
		(net "FM_TPM_PRES_RST_N_C")
	)
	(segment
		(start 25.4 -99.187)
		(end 25.4 -99.513136)
		(width 0.12065)
		(layer "F.Cu")
		(net "FM_TPM_PRES_RST_N_C")
	)
	(segment
		(start 25.5016 -99.614736)
		(end 26.544778 -99.614736)
		(width 0.12065)
		(layer "F.Cu")
		(net "FM_TPM_PRES_RST_N_C")
	)
	(segment
		(start 26.67 -99.739958)
		(end 26.67 -100.8888)
		(width 0.12065)
		(layer "F.Cu")
		(net "FM_TPM_PRES_RST_N_C")
	)
	(segment
		(start 25.4 -99.513136)
		(end 25.5016 -99.614736)
		(width 0.12065)
		(layer "F.Cu")
		(net "FM_TPM_PRES_RST_N_C")
	)
	(segment
		(start 26.544778 -99.614736)
		(end 26.67 -99.739958)
		(width 0.12065)
		(layer "F.Cu")
		(net "FM_TPM_PRES_RST_N_C")
	)
	(segment
		(start 25.4508 -98.6409)
		(end 25.4508 -99.1362)
		(width 0.12065)
		(layer "F.Cu")
		(net "FM_TPM_PRES_RST_N_C")
	)
	(via
		(at 25.5016 -99.614736)
		(size 0.7112)
		(drill 0.3556)
		(layers "F.Cu" "B.Cu")
		(net "FM_TPM_PRES_RST_N_C")
	)
	(segment
		(start 26.459688 -67.59956)
		(end 27.26436 -67.59956)
		(width 0.12065)
		(layer "F.Cu")
		(net "FM_TPM_PRES_RST_N")
	)
	(segment
		(start 20.1168 -91.714828)
		(end 20.20697 -91.624658)
		(width 0.12065)
		(layer "F.Cu")
		(net "FM_TPM_PRES_RST_N")
	)
	(segment
		(start 21.10994 -92.17406)
		(end 21.7551 -91.5289)
		(width 0.12065)
		(layer "F.Cu")
		(net "FM_TPM_PRES_RST_N")
	)
	(segment
		(start 25.4508 -97.7519)
		(end 24.652478 -96.953578)
		(width 0.12065)
		(layer "F.Cu")
		(net "FM_TPM_PRES_RST_N")
	)
	(segment
		(start 21.7678 -90.763852)
		(end 21.7678 -91.4273)
		(width 0.12065)
		(layer "F.Cu")
		(net "FM_TPM_PRES_RST_N")
	)
	(segment
		(start 24.9428 -98.2599)
		(end 24.9428 -99.369626)
		(width 0.12065)
		(layer "F.Cu")
		(net "FM_TPM_PRES_RST_N")
	)
	(segment
		(start 21.7932 -90.17)
		(end 21.7932 -90.738452)
		(width 0.12065)
		(layer "F.Cu")
		(net "FM_TPM_PRES_RST_N")
	)
	(segment
		(start 23.407878 -96.953578)
		(end 21.2979 -94.8436)
		(width 0.12065)
		(layer "F.Cu")
		(net "FM_TPM_PRES_RST_N")
	)
	(segment
		(start 21.2979 -94.8436)
		(end 20.82927 -94.8436)
		(width 0.12065)
		(layer "F.Cu")
		(net "FM_TPM_PRES_RST_N")
	)
	(segment
		(start 25.4508 -97.7519)
		(end 24.9428 -98.2599)
		(width 0.12065)
		(layer "F.Cu")
		(net "FM_TPM_PRES_RST_N")
	)
	(segment
		(start 20.756372 -92.17406)
		(end 20.955 -92.17406)
		(width 0.12065)
		(layer "F.Cu")
		(net "FM_TPM_PRES_RST_N")
	)
	(segment
		(start 20.955 -92.17406)
		(end 21.10994 -92.17406)
		(width 0.12065)
		(layer "F.Cu")
		(net "FM_TPM_PRES_RST_N")
	)
	(segment
		(start 21.7678 -91.4273)
		(end 21.7551 -91.44)
		(width 0.12065)
		(layer "F.Cu")
		(net "FM_TPM_PRES_RST_N")
	)
	(segment
		(start 20.267168 -92.742004)
		(end 20.254214 -92.72905)
		(width 0.12065)
		(layer "F.Cu")
		(net "FM_TPM_PRES_RST_N")
	)
	(segment
		(start 24.933148 -99.850194)
		(end 24.9428 -99.859846)
		(width 0.12065)
		(layer "F.Cu")
		(net "FM_TPM_PRES_RST_N")
	)
	(segment
		(start 20.1168 -92.591636)
		(end 20.1168 -91.714828)
		(width 0.12065)
		(layer "F.Cu")
		(net "FM_TPM_PRES_RST_N")
	)
	(segment
		(start 24.652478 -96.953578)
		(end 23.407878 -96.953578)
		(width 0.12065)
		(layer "F.Cu")
		(net "FM_TPM_PRES_RST_N")
	)
	(segment
		(start 24.9428 -99.859846)
		(end 24.9428 -102.251002)
		(width 0.12065)
		(layer "F.Cu")
		(net "FM_TPM_PRES_RST_N")
	)
	(segment
		(start 25.642062 -65.294764)
		(end 25.642062 -66.781934)
		(width 0.12065)
		(layer "F.Cu")
		(net "FM_TPM_PRES_RST_N")
	)
	(segment
		(start 24.9428 -99.369626)
		(end 24.933148 -99.379278)
		(width 0.12065)
		(layer "F.Cu")
		(net "FM_TPM_PRES_RST_N")
	)
	(segment
		(start 21.7551 -91.5289)
		(end 21.7551 -91.44)
		(width 0.12065)
		(layer "F.Cu")
		(net "FM_TPM_PRES_RST_N")
	)
	(segment
		(start 24.9428 -102.251002)
		(end 24.167592 -103.02621)
		(width 0.12065)
		(layer "F.Cu")
		(net "FM_TPM_PRES_RST_N")
	)
	(segment
		(start 20.20697 -91.624658)
		(end 20.756372 -92.17406)
		(width 0.12065)
		(layer "F.Cu")
		(net "FM_TPM_PRES_RST_N")
	)
	(segment
		(start 20.254214 -92.72905)
		(end 20.1168 -92.591636)
		(width 0.12065)
		(layer "F.Cu")
		(net "FM_TPM_PRES_RST_N")
	)
	(segment
		(start 20.82927 -94.8436)
		(end 20.267168 -94.281498)
		(width 0.12065)
		(layer "F.Cu")
		(net "FM_TPM_PRES_RST_N")
	)
	(segment
		(start 24.933148 -99.379278)
		(end 24.933148 -99.850194)
		(width 0.12065)
		(layer "F.Cu")
		(net "FM_TPM_PRES_RST_N")
	)
	(segment
		(start 20.267168 -94.281498)
		(end 20.267168 -92.742004)
		(width 0.12065)
		(layer "F.Cu")
		(net "FM_TPM_PRES_RST_N")
	)
	(segment
		(start 21.7932 -90.738452)
		(end 21.7678 -90.763852)
		(width 0.12065)
		(layer "F.Cu")
		(net "FM_TPM_PRES_RST_N")
	)
	(segment
		(start 25.642062 -66.781934)
		(end 26.459688 -67.59956)
		(width 0.12065)
		(layer "F.Cu")
		(net "FM_TPM_PRES_RST_N")
	)
	(via
		(at 21.7932 -90.17)
		(size 0.7112)
		(drill 0.3556)
		(layers "F.Cu" "B.Cu")
		(net "FM_TPM_PRES_RST_N")
	)
	(via
		(at 20.955 -92.17406)
		(size 0.508)
		(drill 0.254)
		(layers "F.Cu" "B.Cu")
		(net "FM_TPM_PRES_RST_N")
	)
	(via
		(at 27.26436 -67.59956)
		(size 0.508)
		(drill 0.254)
		(layers "F.Cu" "B.Cu")
		(net "FM_TPM_PRES_RST_N")
	)
	(segment
		(start 27.26436 -69.573902)
		(end 27.26436 -67.59956)
		(width 0.127)
		(layer "In5.Cu")
		(net "FM_TPM_PRES_RST_N")
	)
	(segment
		(start 26.548588 -70.289674)
		(end 27.26436 -69.573902)
		(width 0.127)
		(layer "In5.Cu")
		(net "FM_TPM_PRES_RST_N")
	)
	(segment
		(start 26.548588 -85.084412)
		(end 26.548588 -70.289674)
		(width 0.127)
		(layer "In5.Cu")
		(net "FM_TPM_PRES_RST_N")
	)
	(segment
		(start 20.955 -92.17406)
		(end 20.955 -90.678)
		(width 0.127)
		(layer "In5.Cu")
		(net "FM_TPM_PRES_RST_N")
	)
	(segment
		(start 20.955 -90.678)
		(end 26.548588 -85.084412)
		(width 0.127)
		(layer "In5.Cu")
		(net "FM_TPM_PRES_RST_N")
	)
	(segment
		(start 26.980642 -95.489014)
		(end 27.789378 -95.489014)
		(width 0.12065)
		(layer "F.Cu")
		(net "FM_TPM_PRES_RST")
	)
	(segment
		(start 25.33904 -95.33636)
		(end 26.827988 -95.33636)
		(width 0.12065)
		(layer "F.Cu")
		(net "FM_TPM_PRES_RST")
	)
	(segment
		(start 28.5115 -97.79)
		(end 28.5115 -96.211136)
		(width 0.12065)
		(layer "F.Cu")
		(net "FM_TPM_PRES_RST")
	)
	(segment
		(start 28.5115 -98.7044)
		(end 28.5115 -97.79)
		(width 0.12065)
		(layer "F.Cu")
		(net "FM_TPM_PRES_RST")
	)
	(segment
		(start 27.789378 -95.489014)
		(end 28.478988 -96.178624)
		(width 0.12065)
		(layer "F.Cu")
		(net "FM_TPM_PRES_RST")
	)
	(segment
		(start 24.483822 -96.191578)
		(end 25.33904 -95.33636)
		(width 0.12065)
		(layer "F.Cu")
		(net "FM_TPM_PRES_RST")
	)
	(segment
		(start 26.827988 -95.33636)
		(end 26.980642 -95.489014)
		(width 0.12065)
		(layer "F.Cu")
		(net "FM_TPM_PRES_RST")
	)
	(segment
		(start 23.867872 -96.191578)
		(end 24.483822 -96.191578)
		(width 0.12065)
		(layer "F.Cu")
		(net "FM_TPM_PRES_RST")
	)
	(segment
		(start 28.5115 -96.211136)
		(end 28.478988 -96.178624)
		(width 0.12065)
		(layer "F.Cu")
		(net "FM_TPM_PRES_RST")
	)
	(via
		(at 28.5115 -97.79)
		(size 0.7112)
		(drill 0.3556)
		(layers "F.Cu" "B.Cu")
		(net "FM_TPM_PRES_RST")
	)
	(segment
		(start 22.867112 -100.243386)
		(end 22.360636 -99.73691)
		(width 0.12065)
		(layer "F.Cu")
		(net "FM_TPM_PRES_N")
	)
	(segment
		(start 21.44776 -99.73691)
		(end 21.44776 -100.51796)
		(width 0.12065)
		(layer "F.Cu")
		(net "FM_TPM_PRES_N")
	)
	(segment
		(start 21.44776 -100.51796)
		(end 21.5138 -100.584)
		(width 0.12065)
		(layer "F.Cu")
		(net "FM_TPM_PRES_N")
	)
	(segment
		(start 33.180782 -112.969802)
		(end 34.20618 -113.9952)
		(width 0.12065)
		(layer "F.Cu")
		(net "FM_TPM_PRES_N")
	)
	(segment
		(start 34.925 -113.9952)
		(end 36.0553 -115.1255)
		(width 0.12065)
		(layer "F.Cu")
		(net "FM_TPM_PRES_N")
	)
	(segment
		(start 22.360636 -99.73691)
		(end 21.44776 -99.73691)
		(width 0.12065)
		(layer "F.Cu")
		(net "FM_TPM_PRES_N")
	)
	(segment
		(start 36.0553 -115.1255)
		(end 36.068 -115.1255)
		(width 0.12065)
		(layer "F.Cu")
		(net "FM_TPM_PRES_N")
	)
	(segment
		(start 22.867112 -101.37521)
		(end 22.867112 -100.243386)
		(width 0.12065)
		(layer "F.Cu")
		(net "FM_TPM_PRES_N")
	)
	(segment
		(start 34.20618 -113.9952)
		(end 34.925 -113.9952)
		(width 0.12065)
		(layer "F.Cu")
		(net "FM_TPM_PRES_N")
	)
	(via
		(at 21.5138 -100.584)
		(size 0.508)
		(drill 0.254)
		(layers "F.Cu" "B.Cu")
		(net "FM_TPM_PRES_N")
	)
	(via
		(at 33.180782 -112.969802)
		(size 0.508)
		(drill 0.254)
		(layers "F.Cu" "B.Cu")
		(net "FM_TPM_PRES_N")
	)
	(via
		(at 29.163772 -110.116112)
		(size 0.7112)
		(drill 0.3556)
		(layers "F.Cu" "B.Cu")
		(net "FM_TPM_PRES_N")
	)
	(segment
		(start 31.842202 -112.969802)
		(end 33.180782 -112.969802)
		(width 0.12065)
		(layer "B.Cu")
		(net "FM_TPM_PRES_N")
	)
	(segment
		(start 21.5138 -100.584)
		(end 21.6154 -100.584)
		(width 0.12065)
		(layer "B.Cu")
		(net "FM_TPM_PRES_N")
	)
	(segment
		(start 26.867104 -107.333542)
		(end 26.867104 -107.819444)
		(width 0.12065)
		(layer "B.Cu")
		(net "FM_TPM_PRES_N")
	)
	(segment
		(start 25.167844 -105.634282)
		(end 26.867104 -107.333542)
		(width 0.12065)
		(layer "B.Cu")
		(net "FM_TPM_PRES_N")
	)
	(segment
		(start 26.867104 -107.819444)
		(end 29.163772 -110.116112)
		(width 0.12065)
		(layer "B.Cu")
		(net "FM_TPM_PRES_N")
	)
	(segment
		(start 25.167844 -104.136444)
		(end 25.167844 -105.634282)
		(width 0.12065)
		(layer "B.Cu")
		(net "FM_TPM_PRES_N")
	)
	(segment
		(start 29.163772 -110.116112)
		(end 29.163772 -110.291372)
		(width 0.12065)
		(layer "B.Cu")
		(net "FM_TPM_PRES_N")
	)
	(segment
		(start 21.6154 -100.584)
		(end 25.167844 -104.136444)
		(width 0.12065)
		(layer "B.Cu")
		(net "FM_TPM_PRES_N")
	)
	(segment
		(start 29.163772 -110.291372)
		(end 31.842202 -112.969802)
		(width 0.12065)
		(layer "B.Cu")
		(net "FM_TPM_PRES_N")
	)
	(segment
		(start 13.7668 -88.2396)
		(end 13.7668 -86.98357)
		(width 0.12065)
		(layer "F.Cu")
		(net "FM_PCH_LAN1_DISABLE_N")
	)
	(segment
		(start 16.41094 -80.86217)
		(end 16.5608 -81.01203)
		(width 0.12065)
		(layer "F.Cu")
		(net "FM_PCH_LAN1_DISABLE_N")
	)
	(segment
		(start 15.9512 -83.1088)
		(end 15.9512 -83.0961)
		(width 0.12065)
		(layer "F.Cu")
		(net "FM_PCH_LAN1_DISABLE_N")
	)
	(segment
		(start 15.9639 -83.0961)
		(end 15.9512 -83.0961)
		(width 0.12065)
		(layer "F.Cu")
		(net "FM_PCH_LAN1_DISABLE_N")
	)
	(segment
		(start 16.5608 -82.4992)
		(end 15.9639 -83.0961)
		(width 0.12065)
		(layer "F.Cu")
		(net "FM_PCH_LAN1_DISABLE_N")
	)
	(segment
		(start 13.7668 -86.98357)
		(end 15.313152 -85.437218)
		(width 0.12065)
		(layer "F.Cu")
		(net "FM_PCH_LAN1_DISABLE_N")
	)
	(segment
		(start 16.41094 -80.090518)
		(end 16.41094 -80.86217)
		(width 0.12065)
		(layer "F.Cu")
		(net "FM_PCH_LAN1_DISABLE_N")
	)
	(segment
		(start 16.5608 -81.01203)
		(end 16.5608 -82.4992)
		(width 0.12065)
		(layer "F.Cu")
		(net "FM_PCH_LAN1_DISABLE_N")
	)
	(segment
		(start 15.313152 -83.746848)
		(end 15.9512 -83.1088)
		(width 0.12065)
		(layer "F.Cu")
		(net "FM_PCH_LAN1_DISABLE_N")
	)
	(segment
		(start 15.313152 -85.437218)
		(end 15.313152 -83.746848)
		(width 0.12065)
		(layer "F.Cu")
		(net "FM_PCH_LAN1_DISABLE_N")
	)
	(via
		(at 17.220184 -119.390668)
		(size 0.7112)
		(drill 0.3556)
		(layers "F.Cu" "B.Cu")
		(net "FM_PCH_LAN1_DISABLE_N")
	)
	(via
		(at 11.811 -116.9162)
		(size 0.508)
		(drill 0.254)
		(layers "F.Cu" "B.Cu")
		(net "FM_PCH_LAN1_DISABLE_N")
	)
	(via
		(at 13.7668 -88.2396)
		(size 0.508)
		(drill 0.254)
		(layers "F.Cu" "B.Cu")
		(net "FM_PCH_LAN1_DISABLE_N")
	)
	(segment
		(start 22.7457 -120.0912)
		(end 17.920716 -120.0912)
		(width 0.12065)
		(layer "B.Cu")
		(net "FM_PCH_LAN1_DISABLE_N")
	)
	(segment
		(start 14.745716 -116.9162)
		(end 17.220184 -119.390668)
		(width 0.12065)
		(layer "B.Cu")
		(net "FM_PCH_LAN1_DISABLE_N")
	)
	(segment
		(start 11.811 -116.9162)
		(end 14.745716 -116.9162)
		(width 0.12065)
		(layer "B.Cu")
		(net "FM_PCH_LAN1_DISABLE_N")
	)
	(segment
		(start 23.6855 -121.0056)
		(end 22.7457 -120.0912)
		(width 0.12065)
		(layer "B.Cu")
		(net "FM_PCH_LAN1_DISABLE_N")
	)
	(segment
		(start 17.920716 -120.0912)
		(end 17.220184 -119.390668)
		(width 0.12065)
		(layer "B.Cu")
		(net "FM_PCH_LAN1_DISABLE_N")
	)
	(segment
		(start 14.755622 -90.070178)
		(end 12.6746 -92.1512)
		(width 0.127)
		(layer "In5.Cu")
		(net "FM_PCH_LAN1_DISABLE_N")
	)
	(segment
		(start 12.6746 -116.0018)
		(end 11.811 -116.8654)
		(width 0.127)
		(layer "In5.Cu")
		(net "FM_PCH_LAN1_DISABLE_N")
	)
	(segment
		(start 13.7668 -88.2396)
		(end 14.219428 -88.2396)
		(width 0.127)
		(layer "In5.Cu")
		(net "FM_PCH_LAN1_DISABLE_N")
	)
	(segment
		(start 11.811 -116.8654)
		(end 11.811 -116.9162)
		(width 0.127)
		(layer "In5.Cu")
		(net "FM_PCH_LAN1_DISABLE_N")
	)
	(segment
		(start 14.219428 -88.2396)
		(end 14.755622 -88.775794)
		(width 0.127)
		(layer "In5.Cu")
		(net "FM_PCH_LAN1_DISABLE_N")
	)
	(segment
		(start 12.6746 -92.1512)
		(end 12.6746 -116.0018)
		(width 0.127)
		(layer "In5.Cu")
		(net "FM_PCH_LAN1_DISABLE_N")
	)
	(segment
		(start 14.755622 -88.775794)
		(end 14.755622 -90.070178)
		(width 0.127)
		(layer "In5.Cu")
		(net "FM_PCH_LAN1_DISABLE_N")
	)
	(segment
		(start 76.8096 -63.7032)
		(end 76.8096 -63.881)
		(width 0.12065)
		(layer "F.Cu")
		(net "FLA1_WPN")
	)
	(segment
		(start 76.919836 -62.391544)
		(end 76.919836 -63.592964)
		(width 0.12065)
		(layer "F.Cu")
		(net "FLA1_WPN")
	)
	(segment
		(start 76.8096 -63.881)
		(end 76.835 -63.9064)
		(width 0.12065)
		(layer "F.Cu")
		(net "FLA1_WPN")
	)
	(segment
		(start 76.919836 -63.592964)
		(end 76.8096 -63.7032)
		(width 0.12065)
		(layer "F.Cu")
		(net "FLA1_WPN")
	)
	(via
		(at 32.46628 -114.87912)
		(size 0.508)
		(drill 0.254)
		(layers "F.Cu" "B.Cu")
		(net "FLA1_WPN")
	)
	(via
		(at 118.142258 -14.662658)
		(size 0.508)
		(drill 0.254)
		(layers "F.Cu" "B.Cu")
		(net "FLA1_WPN")
	)
	(via
		(at 42.5704 -62.8904)
		(size 0.508)
		(drill 0.254)
		(layers "F.Cu" "B.Cu")
		(net "FLA1_WPN")
	)
	(via
		(at 76.835 -63.9064)
		(size 0.508)
		(drill 0.254)
		(layers "F.Cu" "B.Cu")
		(net "FLA1_WPN")
	)
	(via
		(at 32.294068 -116.688616)
		(size 0.7112)
		(drill 0.3556)
		(layers "F.Cu" "B.Cu")
		(net "FLA1_WPN")
	)
	(segment
		(start 32.294068 -119.55272)
		(end 32.294068 -116.688616)
		(width 0.12065)
		(layer "B.Cu")
		(net "FLA1_WPN")
	)
	(segment
		(start 32.294068 -115.051332)
		(end 32.46628 -114.87912)
		(width 0.12065)
		(layer "B.Cu")
		(net "FLA1_WPN")
	)
	(segment
		(start 32.294068 -116.688616)
		(end 32.294068 -115.051332)
		(width 0.12065)
		(layer "B.Cu")
		(net "FLA1_WPN")
	)
	(segment
		(start 179.965096 -2.622296)
		(end 178.251104 -2.622296)
		(width 0.127)
		(layer "In2.Cu")
		(net "FLA1_WPN")
	)
	(segment
		(start 45.555662 -59.905138)
		(end 68.528692 -59.905138)
		(width 0.127)
		(layer "In2.Cu")
		(net "FLA1_WPN")
	)
	(segment
		(start 193.0781 -4.1148)
		(end 191.795146 -2.831846)
		(width 0.127)
		(layer "In2.Cu")
		(net "FLA1_WPN")
	)
	(segment
		(start 181.874922 -2.831846)
		(end 181.874668 -2.831592)
		(width 0.127)
		(layer "In2.Cu")
		(net "FLA1_WPN")
	)
	(segment
		(start 181.33822 -2.947416)
		(end 180.290216 -2.947416)
		(width 0.127)
		(layer "In2.Cu")
		(net "FLA1_WPN")
	)
	(segment
		(start 178.251104 -2.622296)
		(end 177.720244 -3.153156)
		(width 0.127)
		(layer "In2.Cu")
		(net "FLA1_WPN")
	)
	(segment
		(start 184.941464 -2.831846)
		(end 181.874922 -2.831846)
		(width 0.127)
		(layer "In2.Cu")
		(net "FLA1_WPN")
	)
	(segment
		(start 68.697856 -59.735974)
		(end 69.087492 -59.735974)
		(width 0.127)
		(layer "In2.Cu")
		(net "FLA1_WPN")
	)
	(segment
		(start 184.941718 -2.831592)
		(end 184.941464 -2.831846)
		(width 0.127)
		(layer "In2.Cu")
		(net "FLA1_WPN")
	)
	(segment
		(start 188.833252 -2.831846)
		(end 188.832998 -2.831592)
		(width 0.127)
		(layer "In2.Cu")
		(net "FLA1_WPN")
	)
	(segment
		(start 132.624576 -3.153156)
		(end 132.624068 -3.15341)
		(width 0.127)
		(layer "In2.Cu")
		(net "FLA1_WPN")
	)
	(segment
		(start 125.321568 -10.451846)
		(end 122.35307 -10.451846)
		(width 0.127)
		(layer "In2.Cu")
		(net "FLA1_WPN")
	)
	(segment
		(start 181.874668 -2.831592)
		(end 181.454044 -2.831592)
		(width 0.127)
		(layer "In2.Cu")
		(net "FLA1_WPN")
	)
	(segment
		(start 193.6242 -4.1148)
		(end 193.0781 -4.1148)
		(width 0.127)
		(layer "In2.Cu")
		(net "FLA1_WPN")
	)
	(segment
		(start 72.833738 -59.905138)
		(end 76.835 -63.9064)
		(width 0.127)
		(layer "In2.Cu")
		(net "FLA1_WPN")
	)
	(segment
		(start 181.454044 -2.831592)
		(end 181.33822 -2.947416)
		(width 0.127)
		(layer "In2.Cu")
		(net "FLA1_WPN")
	)
	(segment
		(start 132.624068 -3.15341)
		(end 132.620004 -3.157474)
		(width 0.127)
		(layer "In2.Cu")
		(net "FLA1_WPN")
	)
	(segment
		(start 188.832998 -2.831592)
		(end 184.941718 -2.831592)
		(width 0.127)
		(layer "In2.Cu")
		(net "FLA1_WPN")
	)
	(segment
		(start 191.795146 -2.831846)
		(end 188.833252 -2.831846)
		(width 0.127)
		(layer "In2.Cu")
		(net "FLA1_WPN")
	)
	(segment
		(start 69.256656 -59.905138)
		(end 72.833738 -59.905138)
		(width 0.127)
		(layer "In2.Cu")
		(net "FLA1_WPN")
	)
	(segment
		(start 42.5704 -62.8904)
		(end 45.555662 -59.905138)
		(width 0.127)
		(layer "In2.Cu")
		(net "FLA1_WPN")
	)
	(segment
		(start 177.720244 -3.153156)
		(end 132.624576 -3.153156)
		(width 0.127)
		(layer "In2.Cu")
		(net "FLA1_WPN")
	)
	(segment
		(start 180.290216 -2.947416)
		(end 179.965096 -2.622296)
		(width 0.127)
		(layer "In2.Cu")
		(net "FLA1_WPN")
	)
	(segment
		(start 68.528692 -59.905138)
		(end 68.697856 -59.735974)
		(width 0.127)
		(layer "In2.Cu")
		(net "FLA1_WPN")
	)
	(segment
		(start 132.620004 -3.157474)
		(end 125.321568 -10.451846)
		(width 0.127)
		(layer "In2.Cu")
		(net "FLA1_WPN")
	)
	(segment
		(start 122.35307 -10.451846)
		(end 118.142258 -14.662658)
		(width 0.127)
		(layer "In2.Cu")
		(net "FLA1_WPN")
	)
	(segment
		(start 69.087492 -59.735974)
		(end 69.256656 -59.905138)
		(width 0.127)
		(layer "In2.Cu")
		(net "FLA1_WPN")
	)
	(segment
		(start 111.252 -39.901622)
		(end 111.251746 -27.919934)
		(width 0.127)
		(layer "In5.Cu")
		(net "FLA1_WPN")
	)
	(segment
		(start 41.416732 -76.639928)
		(end 36.54806 -81.5086)
		(width 0.127)
		(layer "In5.Cu")
		(net "FLA1_WPN")
	)
	(segment
		(start 117.127782 -15.3543)
		(end 117.450616 -15.3543)
		(width 0.127)
		(layer "In5.Cu")
		(net "FLA1_WPN")
	)
	(segment
		(start 43.8277 -65.702434)
		(end 43.8277 -75.918314)
		(width 0.127)
		(layer "In5.Cu")
		(net "FLA1_WPN")
	)
	(segment
		(start 33.821116 -103.239316)
		(end 33.821116 -110.166404)
		(width 0.127)
		(layer "In5.Cu")
		(net "FLA1_WPN")
	)
	(segment
		(start 24.708612 -94.126812)
		(end 33.821116 -103.239316)
		(width 0.127)
		(layer "In5.Cu")
		(net "FLA1_WPN")
	)
	(segment
		(start 28.75153 -86.614)
		(end 27.529028 -86.614)
		(width 0.127)
		(layer "In5.Cu")
		(net "FLA1_WPN")
	)
	(segment
		(start 33.8582 -81.5086)
		(end 28.75153 -86.614)
		(width 0.127)
		(layer "In5.Cu")
		(net "FLA1_WPN")
	)
	(segment
		(start 43.106086 -76.639928)
		(end 41.416732 -76.639928)
		(width 0.127)
		(layer "In5.Cu")
		(net "FLA1_WPN")
	)
	(segment
		(start 77.67574 -63.06566)
		(end 97.31502 -63.06566)
		(width 0.127)
		(layer "In5.Cu")
		(net "FLA1_WPN")
	)
	(segment
		(start 109.480858 -50.899822)
		(end 109.480858 -43.326558)
		(width 0.127)
		(layer "In5.Cu")
		(net "FLA1_WPN")
	)
	(segment
		(start 42.5704 -62.8904)
		(end 42.5704 -64.445134)
		(width 0.127)
		(layer "In5.Cu")
		(net "FLA1_WPN")
	)
	(segment
		(start 117.450616 -15.3543)
		(end 118.142258 -14.662658)
		(width 0.127)
		(layer "In5.Cu")
		(net "FLA1_WPN")
	)
	(segment
		(start 24.708612 -89.434416)
		(end 24.708612 -94.126812)
		(width 0.127)
		(layer "In5.Cu")
		(net "FLA1_WPN")
	)
	(segment
		(start 97.31502 -63.06566)
		(end 109.480858 -50.899822)
		(width 0.127)
		(layer "In5.Cu")
		(net "FLA1_WPN")
	)
	(segment
		(start 32.42818 -114.154458)
		(end 32.46628 -114.192558)
		(width 0.127)
		(layer "In5.Cu")
		(net "FLA1_WPN")
	)
	(segment
		(start 36.54806 -81.5086)
		(end 33.8582 -81.5086)
		(width 0.127)
		(layer "In5.Cu")
		(net "FLA1_WPN")
	)
	(segment
		(start 111.251746 -21.55317)
		(end 116.8527 -15.952216)
		(width 0.127)
		(layer "In5.Cu")
		(net "FLA1_WPN")
	)
	(segment
		(start 27.529028 -86.614)
		(end 24.708612 -89.434416)
		(width 0.127)
		(layer "In5.Cu")
		(net "FLA1_WPN")
	)
	(segment
		(start 76.835 -63.9064)
		(end 77.67574 -63.06566)
		(width 0.127)
		(layer "In5.Cu")
		(net "FLA1_WPN")
	)
	(segment
		(start 109.481112 -43.326304)
		(end 109.481112 -41.67251)
		(width 0.127)
		(layer "In5.Cu")
		(net "FLA1_WPN")
	)
	(segment
		(start 116.8527 -15.629382)
		(end 117.127782 -15.3543)
		(width 0.127)
		(layer "In5.Cu")
		(net "FLA1_WPN")
	)
	(segment
		(start 32.42818 -111.55934)
		(end 32.42818 -114.154458)
		(width 0.127)
		(layer "In5.Cu")
		(net "FLA1_WPN")
	)
	(segment
		(start 32.46628 -114.192558)
		(end 32.46628 -114.87912)
		(width 0.127)
		(layer "In5.Cu")
		(net "FLA1_WPN")
	)
	(segment
		(start 43.8277 -75.918314)
		(end 43.106086 -76.639928)
		(width 0.127)
		(layer "In5.Cu")
		(net "FLA1_WPN")
	)
	(segment
		(start 111.251746 -27.919934)
		(end 111.251746 -21.55317)
		(width 0.127)
		(layer "In5.Cu")
		(net "FLA1_WPN")
	)
	(segment
		(start 109.481112 -41.67251)
		(end 111.252 -39.901622)
		(width 0.127)
		(layer "In5.Cu")
		(net "FLA1_WPN")
	)
	(segment
		(start 42.5704 -64.445134)
		(end 43.8277 -65.702434)
		(width 0.127)
		(layer "In5.Cu")
		(net "FLA1_WPN")
	)
	(segment
		(start 109.480858 -43.326558)
		(end 109.481112 -43.326304)
		(width 0.127)
		(layer "In5.Cu")
		(net "FLA1_WPN")
	)
	(segment
		(start 116.8527 -15.952216)
		(end 116.8527 -15.629382)
		(width 0.127)
		(layer "In5.Cu")
		(net "FLA1_WPN")
	)
	(segment
		(start 33.821116 -110.166404)
		(end 32.42818 -111.55934)
		(width 0.127)
		(layer "In5.Cu")
		(net "FLA1_WPN")
	)
	(segment
		(start 59.1058 -73.66)
		(end 61.1378 -73.66)
		(width 0.12065)
		(layer "F.Cu")
		(net "FLA_CS1_R")
	)
	(segment
		(start 56.4388 -76.327)
		(end 59.1058 -73.66)
		(width 0.12065)
		(layer "F.Cu")
		(net "FLA_CS1_R")
	)
	(segment
		(start 61.272674 -73.525126)
		(end 61.272674 -72.023986)
		(width 0.12065)
		(layer "F.Cu")
		(net "FLA_CS1_R")
	)
	(segment
		(start 61.1378 -73.66)
		(end 61.272674 -73.525126)
		(width 0.12065)
		(layer "F.Cu")
		(net "FLA_CS1_R")
	)
	(via
		(at 18.7706 -133.8707)
		(size 0.508)
		(drill 0.254)
		(layers "F.Cu" "B.Cu")
		(net "FLA_CS1_R")
	)
	(via
		(at 18.5674 -140.4874)
		(size 0.7112)
		(drill 0.3556)
		(layers "F.Cu" "B.Cu")
		(net "FLA_CS1_R")
	)
	(via
		(at 16.606774 -139.374626)
		(size 0.508)
		(drill 0.254)
		(layers "F.Cu" "B.Cu")
		(net "FLA_CS1_R")
	)
	(via
		(at 53.984144 -88.85047)
		(size 0.508)
		(drill 0.254)
		(layers "F.Cu" "B.Cu")
		(net "FLA_CS1_R")
	)
	(via
		(at 56.4388 -76.327)
		(size 0.508)
		(drill 0.254)
		(layers "F.Cu" "B.Cu")
		(net "FLA_CS1_R")
	)
	(segment
		(start 19.431 -140.2969)
		(end 20.1295 -140.2969)
		(width 0.12065)
		(layer "B.Cu")
		(net "FLA_CS1_R")
	)
	(segment
		(start 17.719548 -140.4874)
		(end 18.5674 -140.4874)
		(width 0.12065)
		(layer "B.Cu")
		(net "FLA_CS1_R")
	)
	(segment
		(start 20.5105 -139.9159)
		(end 20.5105 -139.827)
		(width 0.12065)
		(layer "B.Cu")
		(net "FLA_CS1_R")
	)
	(segment
		(start 18.7706 -133.8707)
		(end 18.8595 -133.7818)
		(width 0.12065)
		(layer "B.Cu")
		(net "FLA_CS1_R")
	)
	(segment
		(start 18.8595 -133.7818)
		(end 18.8595 -132.715)
		(width 0.12065)
		(layer "B.Cu")
		(net "FLA_CS1_R")
	)
	(segment
		(start 16.606774 -139.374626)
		(end 17.719548 -140.4874)
		(width 0.12065)
		(layer "B.Cu")
		(net "FLA_CS1_R")
	)
	(segment
		(start 19.2405 -140.4874)
		(end 19.431 -140.2969)
		(width 0.12065)
		(layer "B.Cu")
		(net "FLA_CS1_R")
	)
	(segment
		(start 20.1295 -140.2969)
		(end 20.5105 -139.9159)
		(width 0.12065)
		(layer "B.Cu")
		(net "FLA_CS1_R")
	)
	(segment
		(start 18.5674 -140.4874)
		(end 19.2405 -140.4874)
		(width 0.12065)
		(layer "B.Cu")
		(net "FLA_CS1_R")
	)
	(segment
		(start 15.361412 -139.374626)
		(end 13.65504 -137.668254)
		(width 0.127)
		(layer "In2.Cu")
		(net "FLA_CS1_R")
	)
	(segment
		(start 17.42186 -99.63912)
		(end 17.42186 -99.280726)
		(width 0.127)
		(layer "In2.Cu")
		(net "FLA_CS1_R")
	)
	(segment
		(start 16.606774 -139.374626)
		(end 15.361412 -139.374626)
		(width 0.127)
		(layer "In2.Cu")
		(net "FLA_CS1_R")
	)
	(segment
		(start 8.9916 -113.4618)
		(end 8.9916 -110.430564)
		(width 0.127)
		(layer "In2.Cu")
		(net "FLA_CS1_R")
	)
	(segment
		(start 6.8834 -121.82983)
		(end 7.63778 -121.07545)
		(width 0.127)
		(layer "In2.Cu")
		(net "FLA_CS1_R")
	)
	(segment
		(start 29.442156 -88.88222)
		(end 44.997116 -88.88222)
		(width 0.127)
		(layer "In2.Cu")
		(net "FLA_CS1_R")
	)
	(segment
		(start 44.997116 -88.88222)
		(end 45.7962 -88.083136)
		(width 0.127)
		(layer "In2.Cu")
		(net "FLA_CS1_R")
	)
	(segment
		(start 14.902434 -102.1588)
		(end 15.5956 -101.46538)
		(width 0.127)
		(layer "In2.Cu")
		(net "FLA_CS1_R")
	)
	(segment
		(start 15.5956 -101.46538)
		(end 17.42186 -99.63912)
		(width 0.127)
		(layer "In2.Cu")
		(net "FLA_CS1_R")
	)
	(segment
		(start 13.174472 -137.668254)
		(end 6.8834 -131.377182)
		(width 0.127)
		(layer "In2.Cu")
		(net "FLA_CS1_R")
	)
	(segment
		(start 23.7871 -92.915486)
		(end 23.787354 -92.915486)
		(width 0.127)
		(layer "In2.Cu")
		(net "FLA_CS1_R")
	)
	(segment
		(start 6.8834 -131.377182)
		(end 6.8834 -121.82983)
		(width 0.127)
		(layer "In2.Cu")
		(net "FLA_CS1_R")
	)
	(segment
		(start 11.999468 -105.06202)
		(end 12.067794 -104.99344)
		(width 0.127)
		(layer "In2.Cu")
		(net "FLA_CS1_R")
	)
	(segment
		(start 13.65504 -137.668254)
		(end 13.174472 -137.668254)
		(width 0.127)
		(layer "In2.Cu")
		(net "FLA_CS1_R")
	)
	(segment
		(start 28.128976 -90.1954)
		(end 29.442156 -88.88222)
		(width 0.127)
		(layer "In2.Cu")
		(net "FLA_CS1_R")
	)
	(segment
		(start 11.57986 -105.122726)
		(end 11.938762 -105.122726)
		(width 0.127)
		(layer "In2.Cu")
		(net "FLA_CS1_R")
	)
	(segment
		(start 12.067794 -104.99344)
		(end 12.214098 -104.846882)
		(width 0.127)
		(layer "In2.Cu")
		(net "FLA_CS1_R")
	)
	(segment
		(start 12.553696 -104.507538)
		(end 14.902434 -102.1588)
		(width 0.127)
		(layer "In2.Cu")
		(net "FLA_CS1_R")
	)
	(segment
		(start 24.5237 -92.6592)
		(end 26.9875 -90.1954)
		(width 0.127)
		(layer "In2.Cu")
		(net "FLA_CS1_R")
	)
	(segment
		(start 8.9916 -110.430564)
		(end 10.30224 -109.119924)
		(width 0.127)
		(layer "In2.Cu")
		(net "FLA_CS1_R")
	)
	(segment
		(start 52.287932 -88.083136)
		(end 53.055266 -88.85047)
		(width 0.127)
		(layer "In2.Cu")
		(net "FLA_CS1_R")
	)
	(segment
		(start 24.04364 -92.6592)
		(end 24.5237 -92.6592)
		(width 0.127)
		(layer "In2.Cu")
		(net "FLA_CS1_R")
	)
	(segment
		(start 12.214098 -104.846882)
		(end 12.553696 -104.507538)
		(width 0.127)
		(layer "In2.Cu")
		(net "FLA_CS1_R")
	)
	(segment
		(start 11.938762 -105.122726)
		(end 11.999468 -105.06202)
		(width 0.127)
		(layer "In2.Cu")
		(net "FLA_CS1_R")
	)
	(segment
		(start 45.7962 -88.083136)
		(end 52.287932 -88.083136)
		(width 0.127)
		(layer "In2.Cu")
		(net "FLA_CS1_R")
	)
	(segment
		(start 53.055266 -88.85047)
		(end 53.984144 -88.85047)
		(width 0.127)
		(layer "In2.Cu")
		(net "FLA_CS1_R")
	)
	(segment
		(start 10.30224 -106.400346)
		(end 11.57986 -105.122726)
		(width 0.127)
		(layer "In2.Cu")
		(net "FLA_CS1_R")
	)
	(segment
		(start 7.63778 -121.07545)
		(end 7.63778 -114.81562)
		(width 0.127)
		(layer "In2.Cu")
		(net "FLA_CS1_R")
	)
	(segment
		(start 7.63778 -114.81562)
		(end 8.9916 -113.4618)
		(width 0.127)
		(layer "In2.Cu")
		(net "FLA_CS1_R")
	)
	(segment
		(start 10.30224 -109.119924)
		(end 10.30224 -106.400346)
		(width 0.127)
		(layer "In2.Cu")
		(net "FLA_CS1_R")
	)
	(segment
		(start 23.787354 -92.915486)
		(end 24.04364 -92.6592)
		(width 0.127)
		(layer "In2.Cu")
		(net "FLA_CS1_R")
	)
	(segment
		(start 26.9875 -90.1954)
		(end 28.128976 -90.1954)
		(width 0.127)
		(layer "In2.Cu")
		(net "FLA_CS1_R")
	)
	(segment
		(start 17.42186 -99.280726)
		(end 23.7871 -92.915486)
		(width 0.127)
		(layer "In2.Cu")
		(net "FLA_CS1_R")
	)
	(segment
		(start 54.7116 -81.885028)
		(end 56.42356 -80.173322)
		(width 0.127)
		(layer "In5.Cu")
		(net "FLA_CS1_R")
	)
	(segment
		(start 18.7706 -133.8707)
		(end 18.1102 -134.5311)
		(width 0.127)
		(layer "In5.Cu")
		(net "FLA_CS1_R")
	)
	(segment
		(start 17.5768 -138.4046)
		(end 16.606774 -139.374626)
		(width 0.127)
		(layer "In5.Cu")
		(net "FLA_CS1_R")
	)
	(segment
		(start 18.14068 -137.01395)
		(end 18.1102 -137.04443)
		(width 0.127)
		(layer "In5.Cu")
		(net "FLA_CS1_R")
	)
	(segment
		(start 18.14068 -136.624314)
		(end 18.14068 -137.01395)
		(width 0.127)
		(layer "In5.Cu")
		(net "FLA_CS1_R")
	)
	(segment
		(start 18.1102 -136.593834)
		(end 18.14068 -136.624314)
		(width 0.127)
		(layer "In5.Cu")
		(net "FLA_CS1_R")
	)
	(segment
		(start 56.42356 -80.173322)
		(end 56.42356 -76.34224)
		(width 0.127)
		(layer "In5.Cu")
		(net "FLA_CS1_R")
	)
	(segment
		(start 18.1102 -137.04443)
		(end 18.1102 -137.460482)
		(width 0.127)
		(layer "In5.Cu")
		(net "FLA_CS1_R")
	)
	(segment
		(start 56.42356 -76.34224)
		(end 56.4388 -76.327)
		(width 0.127)
		(layer "In5.Cu")
		(net "FLA_CS1_R")
	)
	(segment
		(start 18.2499 -137.600182)
		(end 18.2499 -137.989818)
		(width 0.127)
		(layer "In5.Cu")
		(net "FLA_CS1_R")
	)
	(segment
		(start 18.1102 -134.5311)
		(end 18.1102 -136.593834)
		(width 0.127)
		(layer "In5.Cu")
		(net "FLA_CS1_R")
	)
	(segment
		(start 53.984144 -88.85047)
		(end 54.7116 -88.123014)
		(width 0.127)
		(layer "In5.Cu")
		(net "FLA_CS1_R")
	)
	(segment
		(start 17.835118 -138.4046)
		(end 17.5768 -138.4046)
		(width 0.127)
		(layer "In5.Cu")
		(net "FLA_CS1_R")
	)
	(segment
		(start 18.1102 -137.460482)
		(end 18.2499 -137.600182)
		(width 0.127)
		(layer "In5.Cu")
		(net "FLA_CS1_R")
	)
	(segment
		(start 18.2499 -137.989818)
		(end 17.835118 -138.4046)
		(width 0.127)
		(layer "In5.Cu")
		(net "FLA_CS1_R")
	)
	(segment
		(start 54.7116 -88.123014)
		(end 54.7116 -81.885028)
		(width 0.127)
		(layer "In5.Cu")
		(net "FLA_CS1_R")
	)
	(segment
		(start 31.304738 -135.684768)
		(end 30.904942 -136.084564)
		(width 0.12065)
		(layer "F.Cu")
		(net "FLA_CS1")
	)
	(via
		(at 30.904942 -136.084564)
		(size 0.4572)
		(drill 0.2032)
		(layers "F.Cu" "B.Cu")
		(net "FLA_CS1")
	)
	(via
		(at 29.2354 -137.5918)
		(size 0.7112)
		(drill 0.3556)
		(layers "F.Cu" "B.Cu")
		(net "FLA_CS1")
	)
	(segment
		(start 30.864556 -136.084564)
		(end 30.904942 -136.084564)
		(width 0.12065)
		(layer "B.Cu")
		(net "FLA_CS1")
	)
	(segment
		(start 22.67331 -140.136118)
		(end 23.006304 -140.469112)
		(width 0.12065)
		(layer "B.Cu")
		(net "FLA_CS1")
	)
	(segment
		(start 26.049986 -140.777214)
		(end 29.2354 -137.5918)
		(width 0.12065)
		(layer "B.Cu")
		(net "FLA_CS1")
	)
	(segment
		(start 21.549614 -139.977114)
		(end 22.479 -139.977114)
		(width 0.12065)
		(layer "B.Cu")
		(net "FLA_CS1")
	)
	(segment
		(start 22.479 -139.977114)
		(end 22.638004 -140.136118)
		(width 0.12065)
		(layer "B.Cu")
		(net "FLA_CS1")
	)
	(segment
		(start 23.006304 -140.504418)
		(end 23.2791 -140.777214)
		(width 0.12065)
		(layer "B.Cu")
		(net "FLA_CS1")
	)
	(segment
		(start 23.2791 -140.777214)
		(end 26.049986 -140.777214)
		(width 0.12065)
		(layer "B.Cu")
		(net "FLA_CS1")
	)
	(segment
		(start 29.714952 -137.112248)
		(end 29.836872 -137.112248)
		(width 0.12065)
		(layer "B.Cu")
		(net "FLA_CS1")
	)
	(segment
		(start 23.006304 -140.469112)
		(end 23.006304 -140.504418)
		(width 0.12065)
		(layer "B.Cu")
		(net "FLA_CS1")
	)
	(segment
		(start 21.3995 -139.827)
		(end 21.549614 -139.977114)
		(width 0.12065)
		(layer "B.Cu")
		(net "FLA_CS1")
	)
	(segment
		(start 29.836872 -137.112248)
		(end 30.864556 -136.084564)
		(width 0.12065)
		(layer "B.Cu")
		(net "FLA_CS1")
	)
	(segment
		(start 29.2354 -137.5918)
		(end 29.714952 -137.112248)
		(width 0.12065)
		(layer "B.Cu")
		(net "FLA_CS1")
	)
	(segment
		(start 22.638004 -140.136118)
		(end 22.67331 -140.136118)
		(width 0.12065)
		(layer "B.Cu")
		(net "FLA_CS1")
	)
	(segment
		(start 16.950944 -96.891856)
		(end 17.36471 -96.891856)
		(width 0.12065)
		(layer "F.Cu")
		(net "BMC_SELF_HW_RST")
	)
	(segment
		(start 15.076678 -93.275404)
		(end 15.076678 -94.906846)
		(width 0.12065)
		(layer "F.Cu")
		(net "BMC_SELF_HW_RST")
	)
	(segment
		(start 20.4851 -139.8016)
		(end 19.6596 -139.8016)
		(width 0.12065)
		(layer "F.Cu")
		(net "BMC_SELF_HW_RST")
	)
	(segment
		(start 16.4592 -97.3836)
		(end 16.950944 -96.891856)
		(width 0.12065)
		(layer "F.Cu")
		(net "BMC_SELF_HW_RST")
	)
	(segment
		(start 15.1257 -93.226382)
		(end 15.076678 -93.275404)
		(width 0.12065)
		(layer "F.Cu")
		(net "BMC_SELF_HW_RST")
	)
	(segment
		(start 16.29537 -97.54743)
		(end 16.4592 -97.3836)
		(width 0.12065)
		(layer "F.Cu")
		(net "BMC_SELF_HW_RST")
	)
	(segment
		(start 15.087346 -97.54743)
		(end 16.29537 -97.54743)
		(width 0.12065)
		(layer "F.Cu")
		(net "BMC_SELF_HW_RST")
	)
	(segment
		(start 15.076678 -94.906846)
		(end 14.7066 -95.276924)
		(width 0.12065)
		(layer "F.Cu")
		(net "BMC_SELF_HW_RST")
	)
	(segment
		(start 14.7066 -95.276924)
		(end 14.7066 -97.166684)
		(width 0.12065)
		(layer "F.Cu")
		(net "BMC_SELF_HW_RST")
	)
	(segment
		(start 14.7066 -97.166684)
		(end 15.087346 -97.54743)
		(width 0.12065)
		(layer "F.Cu")
		(net "BMC_SELF_HW_RST")
	)
	(via
		(at 16.4592 -97.3836)
		(size 0.7112)
		(drill 0.3556)
		(layers "F.Cu" "B.Cu")
		(net "BMC_SELF_HW_RST")
	)
	(via
		(at 19.6596 -139.8016)
		(size 0.508)
		(drill 0.254)
		(layers "F.Cu" "B.Cu")
		(net "BMC_SELF_HW_RST")
	)
	(via
		(at 17.36471 -96.891856)
		(size 0.508)
		(drill 0.254)
		(layers "F.Cu" "B.Cu")
		(net "BMC_SELF_HW_RST")
	)
	(segment
		(start 12.858496 -138.430254)
		(end 6.09346 -131.665218)
		(width 0.127)
		(layer "In2.Cu")
		(net "BMC_SELF_HW_RST")
	)
	(segment
		(start 6.09346 -121.541794)
		(end 6.87578 -120.759474)
		(width 0.127)
		(layer "In2.Cu")
		(net "BMC_SELF_HW_RST")
	)
	(segment
		(start 9.539986 -106.652822)
		(end 9.539732 -106.652568)
		(width 0.127)
		(layer "In2.Cu")
		(net "BMC_SELF_HW_RST")
	)
	(segment
		(start 6.87578 -120.759474)
		(end 6.87578 -111.468408)
		(width 0.127)
		(layer "In2.Cu")
		(net "BMC_SELF_HW_RST")
	)
	(segment
		(start 9.539986 -108.804202)
		(end 9.539986 -106.652822)
		(width 0.127)
		(layer "In2.Cu")
		(net "BMC_SELF_HW_RST")
	)
	(segment
		(start 10.977118 -104.583738)
		(end 10.977118 -103.986584)
		(width 0.127)
		(layer "In2.Cu")
		(net "BMC_SELF_HW_RST")
	)
	(segment
		(start 10.977118 -103.986584)
		(end 17.072356 -97.891346)
		(width 0.127)
		(layer "In2.Cu")
		(net "BMC_SELF_HW_RST")
	)
	(segment
		(start 15.134082 -140.225526)
		(end 13.33881 -138.430254)
		(width 0.127)
		(layer "In2.Cu")
		(net "BMC_SELF_HW_RST")
	)
	(segment
		(start 19.235674 -140.225526)
		(end 15.134082 -140.225526)
		(width 0.127)
		(layer "In2.Cu")
		(net "BMC_SELF_HW_RST")
	)
	(segment
		(start 9.539478 -106.336846)
		(end 9.539478 -106.021378)
		(width 0.127)
		(layer "In2.Cu")
		(net "BMC_SELF_HW_RST")
	)
	(segment
		(start 9.539478 -106.021378)
		(end 10.977118 -104.583738)
		(width 0.127)
		(layer "In2.Cu")
		(net "BMC_SELF_HW_RST")
	)
	(segment
		(start 9.539732 -106.3371)
		(end 9.539478 -106.336846)
		(width 0.127)
		(layer "In2.Cu")
		(net "BMC_SELF_HW_RST")
	)
	(segment
		(start 6.09346 -131.665218)
		(end 6.09346 -121.541794)
		(width 0.127)
		(layer "In2.Cu")
		(net "BMC_SELF_HW_RST")
	)
	(segment
		(start 13.33881 -138.430254)
		(end 12.858496 -138.430254)
		(width 0.127)
		(layer "In2.Cu")
		(net "BMC_SELF_HW_RST")
	)
	(segment
		(start 19.6596 -139.8016)
		(end 19.235674 -140.225526)
		(width 0.127)
		(layer "In2.Cu")
		(net "BMC_SELF_HW_RST")
	)
	(segment
		(start 17.072356 -97.18421)
		(end 17.36471 -96.891856)
		(width 0.127)
		(layer "In2.Cu")
		(net "BMC_SELF_HW_RST")
	)
	(segment
		(start 17.072356 -97.891346)
		(end 17.072356 -97.18421)
		(width 0.127)
		(layer "In2.Cu")
		(net "BMC_SELF_HW_RST")
	)
	(segment
		(start 6.87578 -111.468408)
		(end 9.539986 -108.804202)
		(width 0.127)
		(layer "In2.Cu")
		(net "BMC_SELF_HW_RST")
	)
	(segment
		(start 9.539732 -106.652568)
		(end 9.539732 -106.3371)
		(width 0.127)
		(layer "In2.Cu")
		(net "BMC_SELF_HW_RST")
	)
	(segment
		(start 75.470512 -84.74456)
		(end 76.108306 -85.382354)
		(width 0.12065)
		(layer "F.Cu")
		(net "DIVIDER_2_IN")
	)
	(segment
		(start 74.480166 -84.74456)
		(end 75.470512 -84.74456)
		(width 0.12065)
		(layer "F.Cu")
		(net "DIVIDER_2_IN")
	)
	(segment
		(start 78.232 -85.4329)
		(end 77.2414 -85.4329)
		(width 0.12065)
		(layer "F.Cu")
		(net "DIVIDER_2_IN")
	)
	(segment
		(start 77.2414 -85.4329)
		(end 76.158852 -85.4329)
		(width 0.12065)
		(layer "F.Cu")
		(net "DIVIDER_2_IN")
	)
	(segment
		(start 76.158852 -85.4329)
		(end 76.108306 -85.382354)
		(width 0.12065)
		(layer "F.Cu")
		(net "DIVIDER_2_IN")
	)
	(segment
		(start 78.3082 -85.3567)
		(end 78.232 -85.4329)
		(width 0.12065)
		(layer "F.Cu")
		(net "DIVIDER_2_IN")
	)
	(segment
		(start 77.2414 -85.4329)
		(end 77.2414 -85.420454)
		(width 0.12065)
		(layer "F.Cu")
		(net "DIVIDER_2_IN")
	)
	(via
		(at 77.2414 -85.420454)
		(size 0.7112)
		(drill 0.3556)
		(layers "F.Cu" "B.Cu")
		(net "DIVIDER_2_IN")
	)
	(segment
		(start 77.330554 -83.937602)
		(end 75.574398 -83.937602)
		(width 0.12065)
		(layer "F.Cu")
		(net "DIVIDER_1_IN")
	)
	(segment
		(start 75.574398 -83.937602)
		(end 75.3618 -84.1502)
		(width 0.12065)
		(layer "F.Cu")
		(net "DIVIDER_1_IN")
	)
	(segment
		(start 80.0862 -85.6615)
		(end 80.0862 -85.44814)
		(width 0.12065)
		(layer "F.Cu")
		(net "DIVIDER_1_IN")
	)
	(segment
		(start 73.3552 -84.1502)
		(end 72.76084 -84.74456)
		(width 0.12065)
		(layer "F.Cu")
		(net "DIVIDER_1_IN")
	)
	(segment
		(start 79.10576 -84.4677)
		(end 78.3082 -84.4677)
		(width 0.12065)
		(layer "F.Cu")
		(net "DIVIDER_1_IN")
	)
	(segment
		(start 75.3618 -84.1502)
		(end 73.3552 -84.1502)
		(width 0.12065)
		(layer "F.Cu")
		(net "DIVIDER_1_IN")
	)
	(segment
		(start 78.3082 -84.4677)
		(end 77.860652 -84.4677)
		(width 0.12065)
		(layer "F.Cu")
		(net "DIVIDER_1_IN")
	)
	(segment
		(start 80.0862 -85.44814)
		(end 79.35722 -84.71916)
		(width 0.12065)
		(layer "F.Cu")
		(net "DIVIDER_1_IN")
	)
	(segment
		(start 79.35722 -84.71916)
		(end 79.10576 -84.4677)
		(width 0.12065)
		(layer "F.Cu")
		(net "DIVIDER_1_IN")
	)
	(segment
		(start 77.860652 -84.4677)
		(end 77.330554 -83.937602)
		(width 0.12065)
		(layer "F.Cu")
		(net "DIVIDER_1_IN")
	)
	(segment
		(start 72.76084 -84.74456)
		(end 69.400166 -84.74456)
		(width 0.12065)
		(layer "F.Cu")
		(net "DIVIDER_1_IN")
	)
	(via
		(at 79.35722 -84.71916)
		(size 0.7112)
		(drill 0.3556)
		(layers "F.Cu" "B.Cu")
		(net "DIVIDER_1_IN")
	)
	(segment
		(start 225.9838 -5.842)
		(end 224.8535 -5.842)
		(width 0.12065)
		(layer "F.Cu")
		(net "DEBUG_CONSOLE_LED_0")
	)
	(segment
		(start 224.8535 -5.842)
		(end 223.7105 -4.699)
		(width 0.12065)
		(layer "F.Cu")
		(net "DEBUG_CONSOLE_LED_0")
	)
	(segment
		(start 262.382 -16.8275)
		(end 262.382 -12.560554)
		(width 0.12065)
		(layer "F.Cu")
		(net "Q40_D")
	)
	(segment
		(start 262.382 -12.560554)
		(end 262.513318 -12.429236)
		(width 0.12065)
		(layer "F.Cu")
		(net "Q40_D")
	)
	(via
		(at 262.513318 -12.429236)
		(size 0.508)
		(drill 0.254)
		(layers "F.Cu" "B.Cu")
		(net "Q40_D")
	)
	(via
		(at 259.251704 -13.605002)
		(size 0.7112)
		(drill 0.3556)
		(layers "F.Cu" "B.Cu")
		(net "Q40_D")
	)
	(segment
		(start 260.95579 -13.884148)
		(end 259.53085 -13.884148)
		(width 0.12065)
		(layer "B.Cu")
		(net "Q40_D")
	)
	(segment
		(start 261.62 -12.7381)
		(end 261.62 -13.219938)
		(width 0.12065)
		(layer "B.Cu")
		(net "Q40_D")
	)
	(segment
		(start 259.53085 -13.884148)
		(end 259.251704 -13.605002)
		(width 0.12065)
		(layer "B.Cu")
		(net "Q40_D")
	)
	(segment
		(start 262.442452 -12.35837)
		(end 262.513318 -12.429236)
		(width 0.12065)
		(layer "B.Cu")
		(net "Q40_D")
	)
	(segment
		(start 261.62 -13.219938)
		(end 260.95579 -13.884148)
		(width 0.12065)
		(layer "B.Cu")
		(net "Q40_D")
	)
	(segment
		(start 259.231384 -13.625322)
		(end 259.251704 -13.605002)
		(width 0.12065)
		(layer "B.Cu")
		(net "Q40_D")
	)
	(segment
		(start 261.99973 -12.35837)
		(end 262.442452 -12.35837)
		(width 0.12065)
		(layer "B.Cu")
		(net "Q40_D")
	)
	(segment
		(start 259.231384 -14.629638)
		(end 259.231384 -13.625322)
		(width 0.12065)
		(layer "B.Cu")
		(net "Q40_D")
	)
	(segment
		(start 261.62 -12.7381)
		(end 261.99973 -12.35837)
		(width 0.12065)
		(layer "B.Cu")
		(net "Q40_D")
	)
	(via
		(at 260.731 -19.177)
		(size 0.7112)
		(drill 0.3556)
		(layers "F.Cu" "B.Cu")
		(net "Q3203_G")
	)
	(segment
		(start 269.494 -28.194)
		(end 267.843 -28.194)
		(width 0.508)
		(layer "F.Cu")
		(net "P3V3_GPIO")
	)
	(segment
		(start 267.2715 -25.8445)
		(end 267.63091 -26.20391)
		(width 0.508)
		(layer "F.Cu")
		(net "P3V3_GPIO")
	)
	(segment
		(start 267.843 -28.194)
		(end 267.462 -27.813)
		(width 0.508)
		(layer "F.Cu")
		(net "P3V3_GPIO")
	)
	(segment
		(start 266.827 -25.8445)
		(end 267.2715 -25.8445)
		(width 0.508)
		(layer "F.Cu")
		(net "P3V3_GPIO")
	)
	(segment
		(start 267.63091 -26.20391)
		(end 267.63091 -27.64409)
		(width 0.508)
		(layer "F.Cu")
		(net "P3V3_GPIO")
	)
	(segment
		(start 267.63091 -27.64409)
		(end 267.462 -27.813)
		(width 0.508)
		(layer "F.Cu")
		(net "P3V3_GPIO")
	)
	(via
		(at 267.462 -27.813)
		(size 0.508)
		(drill 0.254)
		(layers "F.Cu" "B.Cu")
		(net "P3V3_GPIO")
	)
	(via
		(at 258.191 -25.6667)
		(size 0.7112)
		(drill 0.3556)
		(layers "F.Cu" "B.Cu")
		(net "P3V3_GPIO")
	)
	(via
		(at 269.494 -28.194)
		(size 0.508)
		(drill 0.254)
		(layers "F.Cu" "B.Cu")
		(net "P3V3_GPIO")
	)
	(segment
		(start 267.462 -26.162)
		(end 267.462 -27.813)
		(width 0.508)
		(layer "B.Cu")
		(net "P3V3_GPIO")
	)
	(segment
		(start 269.494 -28.194)
		(end 269.494 -24.257)
		(width 0.508)
		(layer "B.Cu")
		(net "P3V3_GPIO")
	)
	(segment
		(start 267.589 -22.352)
		(end 252.73 -22.352)
		(width 0.508)
		(layer "B.Cu")
		(net "P3V3_GPIO")
	)
	(segment
		(start 253.746 -25.6667)
		(end 254.7874 -25.6667)
		(width 0.508)
		(layer "B.Cu")
		(net "P3V3_GPIO")
	)
	(segment
		(start 269.494 -24.257)
		(end 267.589 -22.352)
		(width 0.508)
		(layer "B.Cu")
		(net "P3V3_GPIO")
	)
	(segment
		(start 251.600208 -25.6667)
		(end 250.584208 -25.6667)
		(width 0.508)
		(layer "B.Cu")
		(net "P3V3_GPIO")
	)
	(segment
		(start 266.9667 -25.6667)
		(end 267.462 -26.162)
		(width 0.508)
		(layer "B.Cu")
		(net "P3V3_GPIO")
	)
	(segment
		(start 252.73 -22.352)
		(end 251.600208 -23.481792)
		(width 0.508)
		(layer "B.Cu")
		(net "P3V3_GPIO")
	)
	(segment
		(start 254.7874 -25.6667)
		(end 258.191 -25.6667)
		(width 0.508)
		(layer "B.Cu")
		(net "P3V3_GPIO")
	)
	(segment
		(start 258.191 -25.6667)
		(end 266.9667 -25.6667)
		(width 0.508)
		(layer "B.Cu")
		(net "P3V3_GPIO")
	)
	(segment
		(start 251.600208 -23.481792)
		(end 251.600208 -25.6667)
		(width 0.508)
		(layer "B.Cu")
		(net "P3V3_GPIO")
	)
	(segment
		(start 22.450552 -149.945852)
		(end 22.450552 -151.52243)
		(width 0.12065)
		(layer "F.Cu")
		(net "U80_B")
	)
	(segment
		(start 22.450552 -152.26157)
		(end 22.080982 -151.892)
		(width 0.12065)
		(layer "F.Cu")
		(net "U80_B")
	)
	(segment
		(start 22.450552 -152.879552)
		(end 22.450552 -152.26157)
		(width 0.12065)
		(layer "F.Cu")
		(net "U80_B")
	)
	(segment
		(start 23.368 -153.797)
		(end 22.450552 -152.879552)
		(width 0.12065)
		(layer "F.Cu")
		(net "U80_B")
	)
	(segment
		(start 22.080982 -151.892)
		(end 21.6535 -151.892)
		(width 0.12065)
		(layer "F.Cu")
		(net "U80_B")
	)
	(segment
		(start 22.4409 -149.6568)
		(end 22.4409 -149.9362)
		(width 0.12065)
		(layer "F.Cu")
		(net "U80_B")
	)
	(segment
		(start 21.5646 -148.7805)
		(end 22.4409 -149.6568)
		(width 0.12065)
		(layer "F.Cu")
		(net "U80_B")
	)
	(segment
		(start 22.450552 -151.52243)
		(end 22.080982 -151.892)
		(width 0.12065)
		(layer "F.Cu")
		(net "U80_B")
	)
	(segment
		(start 22.4409 -149.9362)
		(end 22.450552 -149.945852)
		(width 0.12065)
		(layer "F.Cu")
		(net "U80_B")
	)
	(via
		(at 23.368 -153.797)
		(size 0.7112)
		(drill 0.3556)
		(layers "F.Cu" "B.Cu")
		(net "U80_B")
	)
	(segment
		(start 227.5586 -15.6591)
		(end 228.3968 -15.6591)
		(width 0.12065)
		(layer "F.Cu")
		(net "U82_RST#")
	)
	(segment
		(start 226.7966 -16.4211)
		(end 227.5586 -15.6591)
		(width 0.12065)
		(layer "F.Cu")
		(net "U82_RST#")
	)
	(segment
		(start 228.3968 -15.6591)
		(end 229.3239 -15.6591)
		(width 0.12065)
		(layer "F.Cu")
		(net "U82_RST#")
	)
	(segment
		(start 229.3239 -15.6591)
		(end 229.362 -15.621)
		(width 0.12065)
		(layer "F.Cu")
		(net "U82_RST#")
	)
	(via
		(at 229.362 -15.621)
		(size 0.7112)
		(drill 0.3556)
		(layers "F.Cu" "B.Cu")
		(net "U82_RST#")
	)
	(segment
		(start 224.062036 -16.4211)
		(end 223.263968 -15.623032)
		(width 0.12065)
		(layer "F.Cu")
		(net "U82_MR#")
	)
	(segment
		(start 223.2152 -15.574264)
		(end 223.2152 -14.3129)
		(width 0.12065)
		(layer "F.Cu")
		(net "U82_MR#")
	)
	(segment
		(start 222.3135 -13.4112)
		(end 222.1865 -13.4112)
		(width 0.12065)
		(layer "F.Cu")
		(net "U82_MR#")
	)
	(segment
		(start 223.263968 -15.623032)
		(end 223.2152 -15.574264)
		(width 0.12065)
		(layer "F.Cu")
		(net "U82_MR#")
	)
	(segment
		(start 224.8662 -16.4211)
		(end 224.062036 -16.4211)
		(width 0.12065)
		(layer "F.Cu")
		(net "U82_MR#")
	)
	(segment
		(start 223.2152 -14.3129)
		(end 222.3135 -13.4112)
		(width 0.12065)
		(layer "F.Cu")
		(net "U82_MR#")
	)
	(via
		(at 223.263968 -15.623032)
		(size 0.7112)
		(drill 0.3556)
		(layers "F.Cu" "B.Cu")
		(net "U82_MR#")
	)
	(segment
		(start 187.0837 -3.37185)
		(end 186.140598 -2.428748)
		(width 0.12065)
		(layer "F.Cu")
		(net "Q21_G")
	)
	(segment
		(start 187.0837 -3.556)
		(end 187.0837 -3.37185)
		(width 0.12065)
		(layer "F.Cu")
		(net "Q21_G")
	)
	(segment
		(start 186.279028 -0.985774)
		(end 186.140598 -1.124204)
		(width 0.12065)
		(layer "F.Cu")
		(net "Q21_G")
	)
	(segment
		(start 186.140598 -1.124204)
		(end 186.140598 -2.428748)
		(width 0.12065)
		(layer "F.Cu")
		(net "Q21_G")
	)
	(via
		(at 186.140598 -2.428748)
		(size 0.7112)
		(drill 0.3556)
		(layers "F.Cu" "B.Cu")
		(net "Q21_G")
	)
	(segment
		(start 221.2975 -13.4112)
		(end 221.2975 -13.1191)
		(width 0.12065)
		(layer "F.Cu")
		(net "U81_Y")
	)
	(segment
		(start 219.9005 -13.4112)
		(end 219.9005 -13.2715)
		(width 0.12065)
		(layer "F.Cu")
		(net "U81_Y")
	)
	(segment
		(start 221.2975 -13.1191)
		(end 220.6752 -12.4968)
		(width 0.12065)
		(layer "F.Cu")
		(net "U81_Y")
	)
	(segment
		(start 219.9005 -13.2715)
		(end 220.6752 -12.4968)
		(width 0.12065)
		(layer "F.Cu")
		(net "U81_Y")
	)
	(via
		(at 219.711016 -12.542266)
		(size 0.7112)
		(drill 0.3556)
		(layers "F.Cu" "B.Cu")
		(net "U81_Y")
	)
	(via
		(at 220.6752 -12.4968)
		(size 0.508)
		(drill 0.254)
		(layers "F.Cu" "B.Cu")
		(net "U81_Y")
	)
	(segment
		(start 220.3704 -12.8016)
		(end 219.97035 -12.8016)
		(width 0.12065)
		(layer "B.Cu")
		(net "U81_Y")
	)
	(segment
		(start 220.45676 -11.1379)
		(end 220.0021 -11.1379)
		(width 0.12065)
		(layer "B.Cu")
		(net "U81_Y")
	)
	(segment
		(start 219.6846 -12.51585)
		(end 219.711016 -12.542266)
		(width 0.12065)
		(layer "B.Cu")
		(net "U81_Y")
	)
	(segment
		(start 219.6846 -11.4554)
		(end 219.6846 -12.51585)
		(width 0.12065)
		(layer "B.Cu")
		(net "U81_Y")
	)
	(segment
		(start 220.0021 -11.1379)
		(end 219.6846 -11.4554)
		(width 0.12065)
		(layer "B.Cu")
		(net "U81_Y")
	)
	(segment
		(start 219.97035 -12.8016)
		(end 219.711016 -12.542266)
		(width 0.12065)
		(layer "B.Cu")
		(net "U81_Y")
	)
	(segment
		(start 220.6752 -12.4968)
		(end 220.3704 -12.8016)
		(width 0.12065)
		(layer "B.Cu")
		(net "U81_Y")
	)
	(via
		(at 225.6028 -7.747)
		(size 0.7112)
		(drill 0.3556)
		(layers "F.Cu" "B.Cu")
		(net "U81_B")
	)
	(segment
		(start 221.364048 -10.340848)
		(end 223.237552 -10.340848)
		(width 0.12065)
		(layer "B.Cu")
		(net "U81_B")
	)
	(segment
		(start 224.79 -7.747)
		(end 225.6028 -7.747)
		(width 0.12065)
		(layer "B.Cu")
		(net "U81_B")
	)
	(segment
		(start 224.409 -9.1694)
		(end 224.409 -8.128)
		(width 0.12065)
		(layer "B.Cu")
		(net "U81_B")
	)
	(segment
		(start 226.695 -7.747)
		(end 226.8474 -7.8994)
		(width 0.12065)
		(layer "B.Cu")
		(net "U81_B")
	)
	(segment
		(start 224.409 -8.128)
		(end 224.79 -7.747)
		(width 0.12065)
		(layer "B.Cu")
		(net "U81_B")
	)
	(segment
		(start 221.107 -10.0838)
		(end 221.364048 -10.340848)
		(width 0.12065)
		(layer "B.Cu")
		(net "U81_B")
	)
	(segment
		(start 226.8474 -7.8994)
		(end 226.8474 -8.8011)
		(width 0.12065)
		(layer "B.Cu")
		(net "U81_B")
	)
	(segment
		(start 225.6028 -7.747)
		(end 226.695 -7.747)
		(width 0.12065)
		(layer "B.Cu")
		(net "U81_B")
	)
	(segment
		(start 221.107 -9.4869)
		(end 221.107 -10.0838)
		(width 0.12065)
		(layer "B.Cu")
		(net "U81_B")
	)
	(segment
		(start 223.237552 -10.340848)
		(end 224.409 -9.1694)
		(width 0.12065)
		(layer "B.Cu")
		(net "U81_B")
	)
	(segment
		(start 42.504868 -136.484868)
		(end 42.904664 -136.884664)
		(width 0.12065)
		(layer "F.Cu")
		(net "TP_GPIOO4")
	)
	(via
		(at 42.904664 -136.884664)
		(size 0.4572)
		(drill 0.2032)
		(layers "F.Cu" "B.Cu")
		(net "TP_GPIOO4")
	)
	(segment
		(start 43.307 -138.43)
		(end 43.307 -137.53465)
		(width 0.12065)
		(layer "B.Cu")
		(net "TP_GPIOO4")
	)
	(segment
		(start 42.904664 -137.132314)
		(end 42.904664 -136.884664)
		(width 0.12065)
		(layer "B.Cu")
		(net "TP_GPIOO4")
	)
	(segment
		(start 43.942 -139.065)
		(end 43.307 -138.43)
		(width 0.12065)
		(layer "B.Cu")
		(net "TP_GPIOO4")
	)
	(segment
		(start 43.307 -137.53465)
		(end 42.904664 -137.132314)
		(width 0.12065)
		(layer "B.Cu")
		(net "TP_GPIOO4")
	)
	(segment
		(start 235.0262 -19.439382)
		(end 235.0262 -19.939)
		(width 0.12065)
		(layer "F.Cu")
		(net "SLED29_A")
	)
	(segment
		(start 216.391236 1.415288)
		(end 216.391236 0.46101)
		(width 0.12065)
		(layer "F.Cu")
		(net "SLED29_A")
	)
	(segment
		(start 245.11 -5.1816)
		(end 245.11 -1.898142)
		(width 0.12065)
		(layer "F.Cu")
		(net "SLED29_A")
	)
	(segment
		(start 235.9279 -19.9644)
		(end 235.0516 -19.9644)
		(width 0.12065)
		(layer "F.Cu")
		(net "SLED29_A")
	)
	(segment
		(start 241.600228 1.61163)
		(end 216.587578 1.61163)
		(width 0.12065)
		(layer "F.Cu")
		(net "SLED29_A")
	)
	(segment
		(start 235.035852 -19.42973)
		(end 235.0262 -19.439382)
		(width 0.12065)
		(layer "F.Cu")
		(net "SLED29_A")
	)
	(segment
		(start 235.697522 -16.322802)
		(end 235.035852 -16.984472)
		(width 0.12065)
		(layer "F.Cu")
		(net "SLED29_A")
	)
	(segment
		(start 237.459774 -14.559788)
		(end 237.459774 -15.308834)
		(width 0.12065)
		(layer "F.Cu")
		(net "SLED29_A")
	)
	(segment
		(start 245.11 -1.898142)
		(end 241.600228 1.61163)
		(width 0.12065)
		(layer "F.Cu")
		(net "SLED29_A")
	)
	(segment
		(start 237.459774 -15.308834)
		(end 236.445806 -16.322802)
		(width 0.12065)
		(layer "F.Cu")
		(net "SLED29_A")
	)
	(segment
		(start 236.445806 -16.322802)
		(end 235.697522 -16.322802)
		(width 0.12065)
		(layer "F.Cu")
		(net "SLED29_A")
	)
	(segment
		(start 216.587578 1.61163)
		(end 216.391236 1.415288)
		(width 0.12065)
		(layer "F.Cu")
		(net "SLED29_A")
	)
	(segment
		(start 235.0516 -19.9644)
		(end 235.0262 -19.939)
		(width 0.12065)
		(layer "F.Cu")
		(net "SLED29_A")
	)
	(segment
		(start 244.7798 -5.5118)
		(end 245.11 -5.1816)
		(width 0.12065)
		(layer "F.Cu")
		(net "SLED29_A")
	)
	(segment
		(start 235.035852 -16.984472)
		(end 235.035852 -19.42973)
		(width 0.12065)
		(layer "F.Cu")
		(net "SLED29_A")
	)
	(via
		(at 235.0262 -19.939)
		(size 0.7112)
		(drill 0.3556)
		(layers "F.Cu" "B.Cu")
		(net "SLED29_A")
	)
	(via
		(at 237.459774 -14.559788)
		(size 0.508)
		(drill 0.254)
		(layers "F.Cu" "B.Cu")
		(net "SLED29_A")
	)
	(via
		(at 244.7798 -5.5118)
		(size 0.508)
		(drill 0.254)
		(layers "F.Cu" "B.Cu")
		(net "SLED29_A")
	)
	(segment
		(start 237.459774 -11.626342)
		(end 237.459774 -14.559788)
		(width 0.127)
		(layer "In2.Cu")
		(net "SLED29_A")
	)
	(segment
		(start 244.7798 -5.5118)
		(end 243.574316 -5.5118)
		(width 0.127)
		(layer "In2.Cu")
		(net "SLED29_A")
	)
	(segment
		(start 243.574316 -5.5118)
		(end 237.459774 -11.626342)
		(width 0.127)
		(layer "In2.Cu")
		(net "SLED29_A")
	)
	(segment
		(start 237.5789 -17.20215)
		(end 236.756702 -18.024348)
		(width 0.12065)
		(layer "F.Cu")
		(net "Q22_D")
	)
	(segment
		(start 245.514876 -1.790954)
		(end 245.514876 -3.884676)
		(width 0.12065)
		(layer "F.Cu")
		(net "Q22_D")
	)
	(segment
		(start 245.514876 -3.884676)
		(end 246.396256 -4.766056)
		(width 0.12065)
		(layer "F.Cu")
		(net "Q22_D")
	)
	(segment
		(start 236.393228 -16.887444)
		(end 236.122464 -16.887444)
		(width 0.12065)
		(layer "F.Cu")
		(net "Q22_D")
	)
	(segment
		(start 214.867236 1.155192)
		(end 215.685624 1.97358)
		(width 0.12065)
		(layer "F.Cu")
		(net "Q22_D")
	)
	(segment
		(start 215.685624 1.97358)
		(end 241.750342 1.97358)
		(width 0.12065)
		(layer "F.Cu")
		(net "Q22_D")
	)
	(segment
		(start 238.522256 -14.758416)
		(end 236.393228 -16.887444)
		(width 0.12065)
		(layer "F.Cu")
		(net "Q22_D")
	)
	(segment
		(start 236.756702 -18.024348)
		(end 235.813092 -18.024348)
		(width 0.12065)
		(layer "F.Cu")
		(net "Q22_D")
	)
	(segment
		(start 235.813092 -17.196816)
		(end 235.813092 -18.024348)
		(width 0.12065)
		(layer "F.Cu")
		(net "Q22_D")
	)
	(segment
		(start 236.122464 -16.887444)
		(end 235.813092 -17.196816)
		(width 0.12065)
		(layer "F.Cu")
		(net "Q22_D")
	)
	(segment
		(start 214.867236 0.46101)
		(end 214.867236 1.155192)
		(width 0.12065)
		(layer "F.Cu")
		(net "Q22_D")
	)
	(segment
		(start 237.5789 -17.1196)
		(end 237.5789 -17.20215)
		(width 0.12065)
		(layer "F.Cu")
		(net "Q22_D")
	)
	(segment
		(start 241.750342 1.97358)
		(end 245.514876 -1.790954)
		(width 0.12065)
		(layer "F.Cu")
		(net "Q22_D")
	)
	(via
		(at 235.813092 -18.024348)
		(size 0.7112)
		(drill 0.3556)
		(layers "F.Cu" "B.Cu")
		(net "Q22_D")
	)
	(via
		(at 238.522256 -14.758416)
		(size 0.508)
		(drill 0.254)
		(layers "F.Cu" "B.Cu")
		(net "Q22_D")
	)
	(via
		(at 246.396256 -4.766056)
		(size 0.508)
		(drill 0.254)
		(layers "F.Cu" "B.Cu")
		(net "Q22_D")
	)
	(segment
		(start 246.396256 -4.766056)
		(end 244.964712 -6.1976)
		(width 0.127)
		(layer "In2.Cu")
		(net "Q22_D")
	)
	(segment
		(start 244.964712 -6.1976)
		(end 243.798852 -6.1976)
		(width 0.127)
		(layer "In2.Cu")
		(net "Q22_D")
	)
	(segment
		(start 243.798852 -6.1976)
		(end 238.522256 -11.474196)
		(width 0.127)
		(layer "In2.Cu")
		(net "Q22_D")
	)
	(segment
		(start 238.522256 -11.474196)
		(end 238.522256 -14.758416)
		(width 0.127)
		(layer "In2.Cu")
		(net "Q22_D")
	)
	(segment
		(start 262.204454 -7.123938)
		(end 262.24103 -7.123938)
		(width 0.12065)
		(layer "F.Cu")
		(net "PQ22_G")
	)
	(segment
		(start 262.352028 -6.662928)
		(end 262.527034 -6.837934)
		(width 0.12065)
		(layer "F.Cu")
		(net "PQ22_G")
	)
	(segment
		(start 261.655306 -7.673086)
		(end 262.204454 -7.123938)
		(width 0.12065)
		(layer "F.Cu")
		(net "PQ22_G")
	)
	(segment
		(start 262.24103 -7.123938)
		(end 262.527034 -6.837934)
		(width 0.12065)
		(layer "F.Cu")
		(net "PQ22_G")
	)
	(segment
		(start 260.17982 -6.662928)
		(end 262.352028 -6.662928)
		(width 0.12065)
		(layer "F.Cu")
		(net "PQ22_G")
	)
	(via
		(at 224.136966 -13.855954)
		(size 0.7112)
		(drill 0.3556)
		(layers "F.Cu" "B.Cu")
		(net "PQ22_G")
	)
	(via
		(at 224.4852 -10.5156)
		(size 0.508)
		(drill 0.254)
		(layers "F.Cu" "B.Cu")
		(net "PQ22_G")
	)
	(via
		(at 261.655306 -7.673086)
		(size 0.508)
		(drill 0.254)
		(layers "F.Cu" "B.Cu")
		(net "PQ22_G")
	)
	(segment
		(start 222.748348 -12.791694)
		(end 223.812608 -13.855954)
		(width 0.12065)
		(layer "B.Cu")
		(net "PQ22_G")
	)
	(segment
		(start 224.926652 -12.287504)
		(end 224.926652 -13.198348)
		(width 0.12065)
		(layer "B.Cu")
		(net "PQ22_G")
	)
	(segment
		(start 224.269046 -13.855954)
		(end 224.136966 -13.855954)
		(width 0.12065)
		(layer "B.Cu")
		(net "PQ22_G")
	)
	(segment
		(start 223.812608 -13.855954)
		(end 224.136966 -13.855954)
		(width 0.12065)
		(layer "B.Cu")
		(net "PQ22_G")
	)
	(segment
		(start 223.393 -11.4046)
		(end 222.748348 -12.049252)
		(width 0.12065)
		(layer "B.Cu")
		(net "PQ22_G")
	)
	(segment
		(start 222.748348 -12.049252)
		(end 222.748348 -12.791694)
		(width 0.12065)
		(layer "B.Cu")
		(net "PQ22_G")
	)
	(segment
		(start 224.4852 -10.5156)
		(end 224.4852 -11.846052)
		(width 0.12065)
		(layer "B.Cu")
		(net "PQ22_G")
	)
	(segment
		(start 224.4852 -11.846052)
		(end 224.926652 -12.287504)
		(width 0.12065)
		(layer "B.Cu")
		(net "PQ22_G")
	)
	(segment
		(start 224.926652 -13.198348)
		(end 224.269046 -13.855954)
		(width 0.12065)
		(layer "B.Cu")
		(net "PQ22_G")
	)
	(segment
		(start 246.9515 -15.743682)
		(end 246.616982 -16.0782)
		(width 0.127)
		(layer "In2.Cu")
		(net "PQ22_G")
	)
	(segment
		(start 244.183662 -16.764)
		(end 237.697518 -16.764)
		(width 0.127)
		(layer "In2.Cu")
		(net "PQ22_G")
	)
	(segment
		(start 245.077488 -16.296132)
		(end 244.687852 -16.296132)
		(width 0.127)
		(layer "In2.Cu")
		(net "PQ22_G")
	)
	(segment
		(start 248.285 -13.936218)
		(end 246.9515 -15.269718)
		(width 0.127)
		(layer "In2.Cu")
		(net "PQ22_G")
	)
	(segment
		(start 230.4796 -11.8618)
		(end 225.8314 -11.8618)
		(width 0.127)
		(layer "In2.Cu")
		(net "PQ22_G")
	)
	(segment
		(start 244.669564 -16.277844)
		(end 244.183662 -16.764)
		(width 0.127)
		(layer "In2.Cu")
		(net "PQ22_G")
	)
	(segment
		(start 235.7755 -14.7955)
		(end 234.9246 -13.9446)
		(width 0.127)
		(layer "In2.Cu")
		(net "PQ22_G")
	)
	(segment
		(start 257.626104 -9.426194)
		(end 250.590812 -9.426194)
		(width 0.127)
		(layer "In2.Cu")
		(net "PQ22_G")
	)
	(segment
		(start 225.8314 -11.8618)
		(end 224.4852 -10.5156)
		(width 0.127)
		(layer "In2.Cu")
		(net "PQ22_G")
	)
	(segment
		(start 234.9246 -13.9446)
		(end 232.5624 -13.9446)
		(width 0.127)
		(layer "In2.Cu")
		(net "PQ22_G")
	)
	(segment
		(start 246.143018 -16.0782)
		(end 246.116094 -16.051276)
		(width 0.127)
		(layer "In2.Cu")
		(net "PQ22_G")
	)
	(segment
		(start 246.9515 -15.269718)
		(end 246.9515 -15.743682)
		(width 0.127)
		(layer "In2.Cu")
		(net "PQ22_G")
	)
	(segment
		(start 248.285 -11.732006)
		(end 248.285 -13.936218)
		(width 0.127)
		(layer "In2.Cu")
		(net "PQ22_G")
	)
	(segment
		(start 245.322344 -16.051276)
		(end 245.077488 -16.296132)
		(width 0.127)
		(layer "In2.Cu")
		(net "PQ22_G")
	)
	(segment
		(start 237.697518 -16.764)
		(end 235.7755 -14.841982)
		(width 0.127)
		(layer "In2.Cu")
		(net "PQ22_G")
	)
	(segment
		(start 261.655306 -7.673086)
		(end 261.073392 -8.255)
		(width 0.127)
		(layer "In2.Cu")
		(net "PQ22_G")
	)
	(segment
		(start 246.616982 -16.0782)
		(end 246.143018 -16.0782)
		(width 0.127)
		(layer "In2.Cu")
		(net "PQ22_G")
	)
	(segment
		(start 250.590812 -9.426194)
		(end 248.285 -11.732006)
		(width 0.127)
		(layer "In2.Cu")
		(net "PQ22_G")
	)
	(segment
		(start 232.5624 -13.9446)
		(end 230.4796 -11.8618)
		(width 0.127)
		(layer "In2.Cu")
		(net "PQ22_G")
	)
	(segment
		(start 246.116094 -16.051276)
		(end 245.322344 -16.051276)
		(width 0.127)
		(layer "In2.Cu")
		(net "PQ22_G")
	)
	(segment
		(start 244.687852 -16.296132)
		(end 244.669564 -16.277844)
		(width 0.127)
		(layer "In2.Cu")
		(net "PQ22_G")
	)
	(segment
		(start 258.797298 -8.255)
		(end 257.626104 -9.426194)
		(width 0.127)
		(layer "In2.Cu")
		(net "PQ22_G")
	)
	(segment
		(start 261.073392 -8.255)
		(end 258.797298 -8.255)
		(width 0.127)
		(layer "In2.Cu")
		(net "PQ22_G")
	)
	(segment
		(start 235.7755 -14.841982)
		(end 235.7755 -14.7955)
		(width 0.127)
		(layer "In2.Cu")
		(net "PQ22_G")
	)
	(segment
		(start 261.19582 -10.472166)
		(end 261.31901 -10.595356)
		(width 0.12065)
		(layer "F.Cu")
		(net "PQ21_G")
	)
	(segment
		(start 261.19582 -8.898128)
		(end 262.101838 -8.898128)
		(width 0.12065)
		(layer "F.Cu")
		(net "PQ21_G")
	)
	(segment
		(start 262.101838 -8.898128)
		(end 262.474964 -8.525002)
		(width 0.12065)
		(layer "F.Cu")
		(net "PQ21_G")
	)
	(segment
		(start 261.19582 -8.898128)
		(end 261.19582 -10.472166)
		(width 0.12065)
		(layer "F.Cu")
		(net "PQ21_G")
	)
	(via
		(at 261.31901 -10.595356)
		(size 0.7112)
		(drill 0.3556)
		(layers "F.Cu" "B.Cu")
		(net "PQ21_G")
	)
	(segment
		(start 215.6714 -1.985772)
		(end 215.793574 -1.863598)
		(width 0.12065)
		(layer "F.Cu")
		(net "HOST1_RST_N_R")
	)
	(segment
		(start 215.793574 -1.863598)
		(end 215.793574 -1.409446)
		(width 0.12065)
		(layer "F.Cu")
		(net "HOST1_RST_N_R")
	)
	(segment
		(start 215.793574 -1.409446)
		(end 215.806274 -1.396746)
		(width 0.12065)
		(layer "F.Cu")
		(net "HOST1_RST_N_R")
	)
	(segment
		(start 215.4428 -4.1402)
		(end 215.4428 -4.86664)
		(width 0.12065)
		(layer "F.Cu")
		(net "HOST1_RST_N_R")
	)
	(segment
		(start 216.83472 -0.998474)
		(end 216.834974 -0.998728)
		(width 0.12065)
		(layer "F.Cu")
		(net "HOST1_RST_N_R")
	)
	(segment
		(start 215.9762 -3.6195)
		(end 215.6714 -3.3147)
		(width 0.12065)
		(layer "F.Cu")
		(net "HOST1_RST_N_R")
	)
	(segment
		(start 214.423498 -6.251702)
		(end 214.423498 -7.4676)
		(width 0.12065)
		(layer "F.Cu")
		(net "HOST1_RST_N_R")
	)
	(segment
		(start 216.834974 -0.998728)
		(end 217.031062 -0.998728)
		(width 0.12065)
		(layer "F.Cu")
		(net "HOST1_RST_N_R")
	)
	(segment
		(start 215.192102 -5.117338)
		(end 215.192102 -5.483098)
		(width 0.12065)
		(layer "F.Cu")
		(net "HOST1_RST_N_R")
	)
	(segment
		(start 215.4428 -4.86664)
		(end 215.192102 -5.117338)
		(width 0.12065)
		(layer "F.Cu")
		(net "HOST1_RST_N_R")
	)
	(segment
		(start 215.806274 -1.396746)
		(end 216.204546 -0.998474)
		(width 0.12065)
		(layer "F.Cu")
		(net "HOST1_RST_N_R")
	)
	(segment
		(start 215.5571 -4.0259)
		(end 215.4428 -4.1402)
		(width 0.12065)
		(layer "F.Cu")
		(net "HOST1_RST_N_R")
	)
	(segment
		(start 216.204546 -0.998474)
		(end 216.83472 -0.998474)
		(width 0.12065)
		(layer "F.Cu")
		(net "HOST1_RST_N_R")
	)
	(segment
		(start 215.9762 -3.6195)
		(end 215.5698 -4.0259)
		(width 0.12065)
		(layer "F.Cu")
		(net "HOST1_RST_N_R")
	)
	(segment
		(start 215.6714 -3.3147)
		(end 215.6714 -1.985772)
		(width 0.12065)
		(layer "F.Cu")
		(net "HOST1_RST_N_R")
	)
	(segment
		(start 215.5698 -4.0259)
		(end 215.5571 -4.0259)
		(width 0.12065)
		(layer "F.Cu")
		(net "HOST1_RST_N_R")
	)
	(segment
		(start 215.192102 -5.483098)
		(end 214.423498 -6.251702)
		(width 0.12065)
		(layer "F.Cu")
		(net "HOST1_RST_N_R")
	)
	(via
		(at 217.031062 -0.998728)
		(size 0.7112)
		(drill 0.3556)
		(layers "F.Cu" "B.Cu")
		(net "HOST1_RST_N_R")
	)
	(segment
		(start 324.51548 -97.82048)
		(end 324.51548 -95.885)
		(width 0.12065)
		(layer "F.Cu")
		(net "MAX7311_TP301")
	)
	(segment
		(start 324.612 -97.917)
		(end 324.51548 -97.82048)
		(width 0.12065)
		(layer "F.Cu")
		(net "MAX7311_TP301")
	)
	(segment
		(start 28.91409 -128.246632)
		(end 29.517594 -128.850136)
		(width 0.12065)
		(layer "F.Cu")
		(net "TP_GPIOY3")
	)
	(segment
		(start 25.908 -126.4158)
		(end 26.094436 -126.602236)
		(width 0.12065)
		(layer "F.Cu")
		(net "TP_GPIOY3")
	)
	(segment
		(start 27.59456 -126.602236)
		(end 28.914598 -127.922274)
		(width 0.12065)
		(layer "F.Cu")
		(net "TP_GPIOY3")
	)
	(segment
		(start 30.586426 -128.850136)
		(end 31.021274 -129.284984)
		(width 0.12065)
		(layer "F.Cu")
		(net "TP_GPIOY3")
	)
	(segment
		(start 29.517594 -128.850136)
		(end 30.586426 -128.850136)
		(width 0.12065)
		(layer "F.Cu")
		(net "TP_GPIOY3")
	)
	(segment
		(start 31.021274 -129.284984)
		(end 31.304738 -129.284984)
		(width 0.12065)
		(layer "F.Cu")
		(net "TP_GPIOY3")
	)
	(segment
		(start 26.094436 -126.602236)
		(end 27.59456 -126.602236)
		(width 0.12065)
		(layer "F.Cu")
		(net "TP_GPIOY3")
	)
	(segment
		(start 28.914598 -127.922274)
		(end 28.91409 -127.923036)
		(width 0.12065)
		(layer "F.Cu")
		(net "TP_GPIOY3")
	)
	(segment
		(start 28.91409 -127.923036)
		(end 28.91409 -128.246632)
		(width 0.12065)
		(layer "F.Cu")
		(net "TP_GPIOY3")
	)
	(segment
		(start 40.904922 -123.684792)
		(end 40.505126 -123.284996)
		(width 0.12065)
		(layer "F.Cu")
		(net "TP_GPIOV7")
	)
	(via
		(at 40.505126 -123.284996)
		(size 0.4572)
		(drill 0.2032)
		(layers "F.Cu" "B.Cu")
		(net "TP_GPIOV7")
	)
	(segment
		(start 42.453052 -119.300244)
		(end 41.3258 -120.427496)
		(width 0.12065)
		(layer "B.Cu")
		(net "TP_GPIOV7")
	)
	(segment
		(start 40.505126 -122.461274)
		(end 40.505126 -123.284996)
		(width 0.12065)
		(layer "B.Cu")
		(net "TP_GPIOV7")
	)
	(segment
		(start 42.382948 -116.875052)
		(end 42.382948 -118.068852)
		(width 0.12065)
		(layer "B.Cu")
		(net "TP_GPIOV7")
	)
	(segment
		(start 42.926 -116.332)
		(end 42.382948 -116.875052)
		(width 0.12065)
		(layer "B.Cu")
		(net "TP_GPIOV7")
	)
	(segment
		(start 42.453052 -118.138956)
		(end 42.453052 -119.300244)
		(width 0.12065)
		(layer "B.Cu")
		(net "TP_GPIOV7")
	)
	(segment
		(start 41.3258 -121.6406)
		(end 40.505126 -122.461274)
		(width 0.12065)
		(layer "B.Cu")
		(net "TP_GPIOV7")
	)
	(segment
		(start 41.3258 -120.427496)
		(end 41.3258 -121.6406)
		(width 0.12065)
		(layer "B.Cu")
		(net "TP_GPIOV7")
	)
	(segment
		(start 42.382948 -118.068852)
		(end 42.453052 -118.138956)
		(width 0.12065)
		(layer "B.Cu")
		(net "TP_GPIOV7")
	)
	(segment
		(start 40.904922 -124.484892)
		(end 40.505126 -124.085096)
		(width 0.12065)
		(layer "F.Cu")
		(net "TP_GPIOV6")
	)
	(via
		(at 40.505126 -124.085096)
		(size 0.4572)
		(drill 0.2032)
		(layers "F.Cu" "B.Cu")
		(net "TP_GPIOV6")
	)
	(segment
		(start 41.0464 -121.3358)
		(end 41.0464 -120.094502)
		(width 0.12065)
		(layer "B.Cu")
		(net "TP_GPIOV6")
	)
	(segment
		(start 40.505126 -124.085096)
		(end 40.114474 -123.694444)
		(width 0.12065)
		(layer "B.Cu")
		(net "TP_GPIOV6")
	)
	(segment
		(start 41.0464 -120.094502)
		(end 41.91 -119.230902)
		(width 0.12065)
		(layer "B.Cu")
		(net "TP_GPIOV6")
	)
	(segment
		(start 41.91 -119.230902)
		(end 41.91 -118.872)
		(width 0.12065)
		(layer "B.Cu")
		(net "TP_GPIOV6")
	)
	(segment
		(start 40.114474 -122.267726)
		(end 41.0464 -121.3358)
		(width 0.12065)
		(layer "B.Cu")
		(net "TP_GPIOV6")
	)
	(segment
		(start 40.114474 -123.694444)
		(end 40.114474 -122.267726)
		(width 0.12065)
		(layer "B.Cu")
		(net "TP_GPIOV6")
	)
	(segment
		(start 40.924226 -116.082826)
		(end 40.59428 -115.75288)
		(width 0.12065)
		(layer "F.Cu")
		(net "TP_GPIOV5")
	)
	(segment
		(start 40.59428 -115.124738)
		(end 40.406828 -114.937286)
		(width 0.12065)
		(layer "F.Cu")
		(net "TP_GPIOV5")
	)
	(segment
		(start 40.924226 -116.797836)
		(end 40.924226 -116.082826)
		(width 0.12065)
		(layer "F.Cu")
		(net "TP_GPIOV5")
	)
	(segment
		(start 40.904922 -125.284992)
		(end 40.505126 -124.885196)
		(width 0.12065)
		(layer "F.Cu")
		(net "TP_GPIOV5")
	)
	(segment
		(start 40.59428 -115.75288)
		(end 40.59428 -115.124738)
		(width 0.12065)
		(layer "F.Cu")
		(net "TP_GPIOV5")
	)
	(segment
		(start 41.724072 -117.597682)
		(end 40.924226 -116.797836)
		(width 0.12065)
		(layer "F.Cu")
		(net "TP_GPIOV5")
	)
	(via
		(at 40.505126 -124.885196)
		(size 0.4572)
		(drill 0.2032)
		(layers "F.Cu" "B.Cu")
		(net "TP_GPIOV5")
	)
	(via
		(at 40.406828 -114.937286)
		(size 0.508)
		(drill 0.254)
		(layers "F.Cu" "B.Cu")
		(net "TP_GPIOV5")
	)
	(segment
		(start 40.898826 -115.429284)
		(end 40.898826 -124.491496)
		(width 0.127)
		(layer "In2.Cu")
		(net "TP_GPIOV5")
	)
	(segment
		(start 40.406828 -114.937286)
		(end 40.898826 -115.429284)
		(width 0.127)
		(layer "In2.Cu")
		(net "TP_GPIOV5")
	)
	(segment
		(start 40.898826 -124.491496)
		(end 40.505126 -124.885196)
		(width 0.127)
		(layer "In2.Cu")
		(net "TP_GPIOV5")
	)
	(segment
		(start 40.104822 -120.092978)
		(end 40.104822 -122.084846)
		(width 0.12065)
		(layer "F.Cu")
		(net "TP_GPIOV4")
	)
	(segment
		(start 40.7162 -119.4816)
		(end 40.104822 -120.092978)
		(width 0.12065)
		(layer "F.Cu")
		(net "TP_GPIOV4")
	)
	(segment
		(start 40.7162 -118.3386)
		(end 40.7162 -119.4816)
		(width 0.12065)
		(layer "F.Cu")
		(net "TP_GPIOV4")
	)
	(segment
		(start 40.33266 -116.4463)
		(end 40.148002 -116.630958)
		(width 0.12065)
		(layer "F.Cu")
		(net "TP_GPIOV3")
	)
	(segment
		(start 39.73957 -119.92483)
		(end 39.73957 -122.519694)
		(width 0.12065)
		(layer "F.Cu")
		(net "TP_GPIOV3")
	)
	(segment
		(start 40.148002 -119.516398)
		(end 39.73957 -119.92483)
		(width 0.12065)
		(layer "F.Cu")
		(net "TP_GPIOV3")
	)
	(segment
		(start 40.148002 -116.630958)
		(end 40.148002 -119.516398)
		(width 0.12065)
		(layer "F.Cu")
		(net "TP_GPIOV3")
	)
	(segment
		(start 39.73957 -122.519694)
		(end 40.104822 -122.884946)
		(width 0.12065)
		(layer "F.Cu")
		(net "TP_GPIOV3")
	)
	(segment
		(start 39.304722 -124.484892)
		(end 38.904926 -124.085096)
		(width 0.12065)
		(layer "F.Cu")
		(net "TP_GPIOU3")
	)
	(via
		(at 38.904926 -124.085096)
		(size 0.4572)
		(drill 0.2032)
		(layers "F.Cu" "B.Cu")
		(net "TP_GPIOU3")
	)
	(segment
		(start 39.085012 -120.561862)
		(end 38.514274 -121.1326)
		(width 0.12065)
		(layer "B.Cu")
		(net "TP_GPIOU3")
	)
	(segment
		(start 38.514274 -121.1326)
		(end 38.514274 -123.694444)
		(width 0.12065)
		(layer "B.Cu")
		(net "TP_GPIOU3")
	)
	(segment
		(start 38.514274 -123.694444)
		(end 38.904926 -124.085096)
		(width 0.12065)
		(layer "B.Cu")
		(net "TP_GPIOU3")
	)
	(segment
		(start 40.005 -118.872)
		(end 39.085012 -119.791988)
		(width 0.12065)
		(layer "B.Cu")
		(net "TP_GPIOU3")
	)
	(segment
		(start 39.085012 -119.791988)
		(end 39.085012 -120.561862)
		(width 0.12065)
		(layer "B.Cu")
		(net "TP_GPIOU3")
	)
	(segment
		(start 39.304722 -123.684792)
		(end 38.904926 -123.284996)
		(width 0.12065)
		(layer "F.Cu")
		(net "TP_GPIOU2")
	)
	(via
		(at 38.904926 -123.284996)
		(size 0.4572)
		(drill 0.2032)
		(layers "F.Cu" "B.Cu")
		(net "TP_GPIOU2")
	)
	(segment
		(start 38.904926 -121.2088)
		(end 38.904926 -123.284996)
		(width 0.12065)
		(layer "B.Cu")
		(net "TP_GPIOU2")
	)
	(segment
		(start 40.005 -117.602)
		(end 40.548052 -118.145052)
		(width 0.12065)
		(layer "B.Cu")
		(net "TP_GPIOU2")
	)
	(segment
		(start 40.548052 -119.15521)
		(end 39.466266 -120.236996)
		(width 0.12065)
		(layer "B.Cu")
		(net "TP_GPIOU2")
	)
	(segment
		(start 40.548052 -118.145052)
		(end 40.548052 -119.15521)
		(width 0.12065)
		(layer "B.Cu")
		(net "TP_GPIOU2")
	)
	(segment
		(start 39.466266 -120.64746)
		(end 38.904926 -121.2088)
		(width 0.12065)
		(layer "B.Cu")
		(net "TP_GPIOU2")
	)
	(segment
		(start 39.466266 -120.236996)
		(end 39.466266 -120.64746)
		(width 0.12065)
		(layer "B.Cu")
		(net "TP_GPIOU2")
	)
	(segment
		(start 39.243 -118.364)
		(end 39.243 -119.2276)
		(width 0.12065)
		(layer "F.Cu")
		(net "TP_GPIOU1")
	)
	(segment
		(start 39.243 -119.2276)
		(end 38.93947 -119.53113)
		(width 0.12065)
		(layer "F.Cu")
		(net "TP_GPIOU1")
	)
	(segment
		(start 38.93947 -122.519694)
		(end 39.304722 -122.884946)
		(width 0.12065)
		(layer "F.Cu")
		(net "TP_GPIOU1")
	)
	(segment
		(start 38.93947 -119.53113)
		(end 38.93947 -122.519694)
		(width 0.12065)
		(layer "F.Cu")
		(net "TP_GPIOU1")
	)
	(segment
		(start 39.786052 -117.611652)
		(end 39.2938 -117.1194)
		(width 0.12065)
		(layer "F.Cu")
		(net "TP_GPIOU0")
	)
	(segment
		(start 39.786052 -119.294148)
		(end 39.786052 -117.611652)
		(width 0.12065)
		(layer "F.Cu")
		(net "TP_GPIOU0")
	)
	(segment
		(start 39.304722 -119.775478)
		(end 39.786052 -119.294148)
		(width 0.12065)
		(layer "F.Cu")
		(net "TP_GPIOU0")
	)
	(segment
		(start 39.304722 -122.084846)
		(end 39.304722 -119.775478)
		(width 0.12065)
		(layer "F.Cu")
		(net "TP_GPIOU0")
	)
	(segment
		(start 40.98544 -114.45494)
		(end 40.596566 -114.066066)
		(width 0.12065)
		(layer "F.Cu")
		(net "TP_GPIOT7")
	)
	(segment
		(start 41.712388 -116.311426)
		(end 40.98544 -115.584478)
		(width 0.12065)
		(layer "F.Cu")
		(net "TP_GPIOT7")
	)
	(segment
		(start 40.98544 -115.584478)
		(end 40.98544 -114.45494)
		(width 0.12065)
		(layer "F.Cu")
		(net "TP_GPIOT7")
	)
	(segment
		(start 40.596566 -114.066066)
		(end 40.446706 -114.066066)
		(width 0.12065)
		(layer "F.Cu")
		(net "TP_GPIOT7")
	)
	(segment
		(start 40.104822 -125.284992)
		(end 39.705026 -124.885196)
		(width 0.12065)
		(layer "F.Cu")
		(net "TP_GPIOT7")
	)
	(via
		(at 39.705026 -124.885196)
		(size 0.4572)
		(drill 0.2032)
		(layers "F.Cu" "B.Cu")
		(net "TP_GPIOT7")
	)
	(via
		(at 40.446706 -114.066066)
		(size 0.508)
		(drill 0.254)
		(layers "F.Cu" "B.Cu")
		(net "TP_GPIOT7")
	)
	(segment
		(start 40.098726 -124.491496)
		(end 40.098726 -122.811286)
		(width 0.127)
		(layer "In2.Cu")
		(net "TP_GPIOT7")
	)
	(segment
		(start 39.936928 -114.575844)
		(end 40.446706 -114.066066)
		(width 0.127)
		(layer "In2.Cu")
		(net "TP_GPIOT7")
	)
	(segment
		(start 40.098726 -122.811286)
		(end 39.936928 -122.649488)
		(width 0.127)
		(layer "In2.Cu")
		(net "TP_GPIOT7")
	)
	(segment
		(start 39.936928 -122.649488)
		(end 39.936928 -114.575844)
		(width 0.127)
		(layer "In2.Cu")
		(net "TP_GPIOT7")
	)
	(segment
		(start 39.705026 -124.885196)
		(end 40.098726 -124.491496)
		(width 0.127)
		(layer "In2.Cu")
		(net "TP_GPIOT7")
	)
	(segment
		(start 40.104822 -124.484892)
		(end 39.704772 -124.084842)
		(width 0.12065)
		(layer "F.Cu")
		(net "TP_GPIOT6")
	)
	(via
		(at 39.704772 -124.084842)
		(size 0.4572)
		(drill 0.2032)
		(layers "F.Cu" "B.Cu")
		(net "TP_GPIOT6")
	)
	(segment
		(start 40.005 -116.332)
		(end 40.910002 -117.237002)
		(width 0.12065)
		(layer "B.Cu")
		(net "TP_GPIOT6")
	)
	(segment
		(start 39.314374 -121.285)
		(end 39.314374 -123.694444)
		(width 0.12065)
		(layer "B.Cu")
		(net "TP_GPIOT6")
	)
	(segment
		(start 39.72306 -120.486932)
		(end 39.72306 -120.876314)
		(width 0.12065)
		(layer "B.Cu")
		(net "TP_GPIOT6")
	)
	(segment
		(start 40.910002 -117.237002)
		(end 40.910002 -119.29999)
		(width 0.12065)
		(layer "B.Cu")
		(net "TP_GPIOT6")
	)
	(segment
		(start 39.72306 -120.876314)
		(end 39.314374 -121.285)
		(width 0.12065)
		(layer "B.Cu")
		(net "TP_GPIOT6")
	)
	(segment
		(start 39.314374 -123.694444)
		(end 39.704772 -124.084842)
		(width 0.12065)
		(layer "B.Cu")
		(net "TP_GPIOT6")
	)
	(segment
		(start 40.910002 -119.29999)
		(end 39.72306 -120.486932)
		(width 0.12065)
		(layer "B.Cu")
		(net "TP_GPIOT6")
	)
	(segment
		(start 44.323 -142.621)
		(end 44.323 -140.562838)
		(width 0.12065)
		(layer "F.Cu")
		(net "TP_GPIOP6")
	)
	(segment
		(start 42.139616 -138.519662)
		(end 41.704768 -138.084814)
		(width 0.12065)
		(layer "F.Cu")
		(net "TP_GPIOP6")
	)
	(segment
		(start 44.323 -140.562838)
		(end 43.454828 -139.694666)
		(width 0.12065)
		(layer "F.Cu")
		(net "TP_GPIOP6")
	)
	(segment
		(start 42.798238 -139.694666)
		(end 42.139616 -139.036044)
		(width 0.12065)
		(layer "F.Cu")
		(net "TP_GPIOP6")
	)
	(segment
		(start 43.454828 -139.694666)
		(end 42.798238 -139.694666)
		(width 0.12065)
		(layer "F.Cu")
		(net "TP_GPIOP6")
	)
	(segment
		(start 42.139616 -139.036044)
		(end 42.139616 -138.519662)
		(width 0.12065)
		(layer "F.Cu")
		(net "TP_GPIOP6")
	)
	(segment
		(start 42.64787 -139.058904)
		(end 42.64787 -139.027916)
		(width 0.12065)
		(layer "F.Cu")
		(net "TP_GPIOP4")
	)
	(segment
		(start 44.958 -143.256)
		(end 44.958 -140.883386)
		(width 0.12065)
		(layer "F.Cu")
		(net "TP_GPIOP4")
	)
	(segment
		(start 43.54703 -139.472416)
		(end 43.061382 -139.472416)
		(width 0.12065)
		(layer "F.Cu")
		(net "TP_GPIOP4")
	)
	(segment
		(start 43.061382 -139.472416)
		(end 42.64787 -139.058904)
		(width 0.12065)
		(layer "F.Cu")
		(net "TP_GPIOP4")
	)
	(segment
		(start 44.958 -140.883386)
		(end 43.54703 -139.472416)
		(width 0.12065)
		(layer "F.Cu")
		(net "TP_GPIOP4")
	)
	(segment
		(start 42.64787 -139.027916)
		(end 42.504868 -138.884914)
		(width 0.12065)
		(layer "F.Cu")
		(net "TP_GPIOP4")
	)
	(segment
		(start 44.323 -143.891)
		(end 44.958 -143.256)
		(width 0.12065)
		(layer "F.Cu")
		(net "TP_GPIOP4")
	)
	(segment
		(start 41.704768 -136.484868)
		(end 42.104564 -136.884664)
		(width 0.12065)
		(layer "F.Cu")
		(net "TP_GPIOP2")
	)
	(via
		(at 42.104564 -136.884664)
		(size 0.4572)
		(drill 0.2032)
		(layers "F.Cu" "B.Cu")
		(net "TP_GPIOP2")
	)
	(segment
		(start 42.495216 -137.275316)
		(end 42.104564 -136.884664)
		(width 0.12065)
		(layer "B.Cu")
		(net "TP_GPIOP2")
	)
	(segment
		(start 42.495216 -138.059922)
		(end 42.495216 -137.275316)
		(width 0.12065)
		(layer "B.Cu")
		(net "TP_GPIOP2")
	)
	(segment
		(start 42.418 -138.137138)
		(end 42.495216 -138.059922)
		(width 0.12065)
		(layer "B.Cu")
		(net "TP_GPIOP2")
	)
	(segment
		(start 42.418 -138.557)
		(end 42.418 -138.137138)
		(width 0.12065)
		(layer "B.Cu")
		(net "TP_GPIOP2")
	)
	(segment
		(start 44.831 -145.161)
		(end 45.6819 -144.3101)
		(width 0.12065)
		(layer "F.Cu")
		(net "TP_GPIOP1")
	)
	(segment
		(start 43.588432 -138.884914)
		(end 43.304714 -138.884914)
		(width 0.12065)
		(layer "F.Cu")
		(net "TP_GPIOP1")
	)
	(segment
		(start 45.6819 -144.3101)
		(end 45.6819 -140.978382)
		(width 0.12065)
		(layer "F.Cu")
		(net "TP_GPIOP1")
	)
	(segment
		(start 45.6819 -140.978382)
		(end 43.588432 -138.884914)
		(width 0.12065)
		(layer "F.Cu")
		(net "TP_GPIOP1")
	)
	(segment
		(start 42.504868 -137.284968)
		(end 42.904664 -137.684764)
		(width 0.12065)
		(layer "F.Cu")
		(net "TP_GPIOP0")
	)
	(via
		(at 42.904664 -137.684764)
		(size 0.4572)
		(drill 0.2032)
		(layers "F.Cu" "B.Cu")
		(net "TP_GPIOP0")
	)
	(segment
		(start 43.942 -139.833096)
		(end 43.053 -138.944096)
		(width 0.12065)
		(layer "B.Cu")
		(net "TP_GPIOP0")
	)
	(segment
		(start 43.053 -137.8331)
		(end 42.904664 -137.684764)
		(width 0.12065)
		(layer "B.Cu")
		(net "TP_GPIOP0")
	)
	(segment
		(start 43.942 -140.335)
		(end 43.942 -139.833096)
		(width 0.12065)
		(layer "B.Cu")
		(net "TP_GPIOP0")
	)
	(segment
		(start 43.053 -138.944096)
		(end 43.053 -137.8331)
		(width 0.12065)
		(layer "B.Cu")
		(net "TP_GPIOP0")
	)
	(segment
		(start 41.704768 -135.684768)
		(end 41.304972 -135.284972)
		(width 0.12065)
		(layer "F.Cu")
		(net "TP_GPIOO7")
	)
	(via
		(at 41.304972 -135.284972)
		(size 0.4572)
		(drill 0.2032)
		(layers "F.Cu" "B.Cu")
		(net "TP_GPIOO7")
	)
	(segment
		(start 41.795446 -135.284972)
		(end 41.304972 -135.284972)
		(width 0.12065)
		(layer "B.Cu")
		(net "TP_GPIOO7")
	)
	(segment
		(start 42.129456 -135.618982)
		(end 41.795446 -135.284972)
		(width 0.12065)
		(layer "B.Cu")
		(net "TP_GPIOO7")
	)
	(segment
		(start 46.04385 -145.694654)
		(end 46.04385 -141.004036)
		(width 0.12065)
		(layer "F.Cu")
		(net "TP_GPIOO6")
	)
	(segment
		(start 44.104814 -139.065)
		(end 44.104814 -138.884914)
		(width 0.12065)
		(layer "F.Cu")
		(net "TP_GPIOO6")
	)
	(segment
		(start 45.339 -146.399504)
		(end 46.04385 -145.694654)
		(width 0.12065)
		(layer "F.Cu")
		(net "TP_GPIOO6")
	)
	(segment
		(start 46.04385 -141.004036)
		(end 44.104814 -139.065)
		(width 0.12065)
		(layer "F.Cu")
		(net "TP_GPIOO6")
	)
	(segment
		(start 44.352464 -138.084814)
		(end 44.761912 -138.494262)
		(width 0.12065)
		(layer "F.Cu")
		(net "TP_GPIOO2")
	)
	(segment
		(start 45.066712 -138.494262)
		(end 45.314108 -138.741658)
		(width 0.12065)
		(layer "F.Cu")
		(net "TP_GPIOO2")
	)
	(segment
		(start 45.314108 -139.051284)
		(end 48.748188 -142.485364)
		(width 0.12065)
		(layer "F.Cu")
		(net "TP_GPIOO2")
	)
	(segment
		(start 44.104814 -138.084814)
		(end 44.352464 -138.084814)
		(width 0.12065)
		(layer "F.Cu")
		(net "TP_GPIOO2")
	)
	(segment
		(start 45.314108 -138.741658)
		(end 45.314108 -139.051284)
		(width 0.12065)
		(layer "F.Cu")
		(net "TP_GPIOO2")
	)
	(segment
		(start 49.489106 -146.723354)
		(end 49.17694 -147.03552)
		(width 0.12065)
		(layer "F.Cu")
		(net "TP_GPIOO2")
	)
	(segment
		(start 48.748188 -142.485364)
		(end 48.748188 -143.291052)
		(width 0.12065)
		(layer "F.Cu")
		(net "TP_GPIOO2")
	)
	(segment
		(start 49.489106 -144.03197)
		(end 49.489106 -146.723354)
		(width 0.12065)
		(layer "F.Cu")
		(net "TP_GPIOO2")
	)
	(segment
		(start 44.761912 -138.494262)
		(end 45.066712 -138.494262)
		(width 0.12065)
		(layer "F.Cu")
		(net "TP_GPIOO2")
	)
	(segment
		(start 48.748188 -143.291052)
		(end 49.489106 -144.03197)
		(width 0.12065)
		(layer "F.Cu")
		(net "TP_GPIOO2")
	)
	(segment
		(start 43.304714 -137.284968)
		(end 43.70451 -136.885172)
		(width 0.12065)
		(layer "F.Cu")
		(net "TP_GPIOO1")
	)
	(via
		(at 43.70451 -136.885172)
		(size 0.4572)
		(drill 0.2032)
		(layers "F.Cu" "B.Cu")
		(net "TP_GPIOO1")
	)
	(segment
		(start 44.311824 -137.275824)
		(end 43.921172 -136.885172)
		(width 0.12065)
		(layer "B.Cu")
		(net "TP_GPIOO1")
	)
	(segment
		(start 43.921172 -136.885172)
		(end 43.70451 -136.885172)
		(width 0.12065)
		(layer "B.Cu")
		(net "TP_GPIOO1")
	)
	(segment
		(start 45.212 -137.668)
		(end 44.819824 -137.275824)
		(width 0.12065)
		(layer "B.Cu")
		(net "TP_GPIOO1")
	)
	(segment
		(start 44.819824 -137.275824)
		(end 44.311824 -137.275824)
		(width 0.12065)
		(layer "B.Cu")
		(net "TP_GPIOO1")
	)
	(segment
		(start 42.504868 -135.684768)
		(end 42.904664 -136.084564)
		(width 0.12065)
		(layer "F.Cu")
		(net "TP_GPIOO0")
	)
	(via
		(at 42.904664 -136.084564)
		(size 0.4572)
		(drill 0.2032)
		(layers "F.Cu" "B.Cu")
		(net "TP_GPIOO0")
	)
	(segment
		(start 43.313858 -137.166858)
		(end 43.313858 -136.493758)
		(width 0.12065)
		(layer "B.Cu")
		(net "TP_GPIOO0")
	)
	(segment
		(start 43.942 -137.795)
		(end 43.313858 -137.166858)
		(width 0.12065)
		(layer "B.Cu")
		(net "TP_GPIOO0")
	)
	(segment
		(start 43.313858 -136.493758)
		(end 42.904664 -136.084564)
		(width 0.12065)
		(layer "B.Cu")
		(net "TP_GPIOO0")
	)
	(segment
		(start 44.104814 -137.284968)
		(end 44.50461 -136.885172)
		(width 0.12065)
		(layer "F.Cu")
		(net "TP_GPION5")
	)
	(via
		(at 44.50461 -136.885172)
		(size 0.4572)
		(drill 0.2032)
		(layers "F.Cu" "B.Cu")
		(net "TP_GPION5")
	)
	(segment
		(start 45.882052 -137.322052)
		(end 45.593 -137.033)
		(width 0.12065)
		(layer "B.Cu")
		(net "TP_GPION5")
	)
	(segment
		(start 45.593 -137.033)
		(end 44.652438 -137.033)
		(width 0.12065)
		(layer "B.Cu")
		(net "TP_GPION5")
	)
	(segment
		(start 45.882052 -138.267948)
		(end 45.882052 -137.322052)
		(width 0.12065)
		(layer "B.Cu")
		(net "TP_GPION5")
	)
	(segment
		(start 44.652438 -137.033)
		(end 44.50461 -136.885172)
		(width 0.12065)
		(layer "B.Cu")
		(net "TP_GPION5")
	)
	(segment
		(start 45.212 -138.938)
		(end 45.882052 -138.267948)
		(width 0.12065)
		(layer "B.Cu")
		(net "TP_GPION5")
	)
	(segment
		(start 32.104838 -124.484892)
		(end 31.704788 -124.084842)
		(width 0.12065)
		(layer "F.Cu")
		(net "TP_GPIOI2")
	)
	(via
		(at 31.704788 -124.084842)
		(size 0.4572)
		(drill 0.2032)
		(layers "F.Cu" "B.Cu")
		(net "TP_GPIOI2")
	)
	(segment
		(start 31.704788 -124.084842)
		(end 31.704788 -124.038868)
		(width 0.12065)
		(layer "B.Cu")
		(net "TP_GPIOI2")
	)
	(segment
		(start 31.704788 -124.038868)
		(end 27.457908 -119.793512)
		(width 0.12065)
		(layer "B.Cu")
		(net "TP_GPIOI2")
	)
	(segment
		(start 27.457908 -119.793512)
		(end 26.854912 -119.793512)
		(width 0.12065)
		(layer "B.Cu")
		(net "TP_GPIOI2")
	)
	(segment
		(start 32.904938 -126.884938)
		(end 32.505142 -126.485142)
		(width 0.12065)
		(layer "F.Cu")
		(net "TP_GPIOI1")
	)
	(via
		(at 32.505142 -126.485142)
		(size 0.4572)
		(drill 0.2032)
		(layers "F.Cu" "B.Cu")
		(net "TP_GPIOI1")
	)
	(segment
		(start 32.685228 -126.665228)
		(end 32.505142 -126.485142)
		(width 0.12065)
		(layer "B.Cu")
		(net "TP_GPIOI1")
	)
	(segment
		(start 33.456372 -126.665228)
		(end 32.685228 -126.665228)
		(width 0.12065)
		(layer "B.Cu")
		(net "TP_GPIOI1")
	)
	(segment
		(start 29.374592 -123.684792)
		(end 29.704792 -123.684792)
		(width 0.12065)
		(layer "F.Cu")
		(net "TP_GPIOI0")
	)
	(segment
		(start 26.409396 -120.719596)
		(end 29.374592 -123.684792)
		(width 0.12065)
		(layer "F.Cu")
		(net "TP_GPIOI0")
	)
	(segment
		(start 25.916128 -120.719596)
		(end 26.409396 -120.719596)
		(width 0.12065)
		(layer "F.Cu")
		(net "TP_GPIOI0")
	)
	(segment
		(start 35.739578 -121.830846)
		(end 35.739578 -122.519694)
		(width 0.12065)
		(layer "F.Cu")
		(net "TP_GPIOE7")
	)
	(segment
		(start 35.941 -118.751096)
		(end 35.739578 -118.952518)
		(width 0.12065)
		(layer "F.Cu")
		(net "TP_GPIOE7")
	)
	(segment
		(start 35.739578 -121.043954)
		(end 35.676078 -121.107454)
		(width 0.12065)
		(layer "F.Cu")
		(net "TP_GPIOE7")
	)
	(segment
		(start 35.739578 -122.519694)
		(end 36.10483 -122.884946)
		(width 0.12065)
		(layer "F.Cu")
		(net "TP_GPIOE7")
	)
	(segment
		(start 35.676078 -121.107454)
		(end 35.676078 -121.767346)
		(width 0.12065)
		(layer "F.Cu")
		(net "TP_GPIOE7")
	)
	(segment
		(start 35.739578 -118.952518)
		(end 35.739578 -121.043954)
		(width 0.12065)
		(layer "F.Cu")
		(net "TP_GPIOE7")
	)
	(segment
		(start 35.676078 -121.767346)
		(end 35.739578 -121.830846)
		(width 0.12065)
		(layer "F.Cu")
		(net "TP_GPIOE7")
	)
	(segment
		(start 35.941 -117.1956)
		(end 35.941 -118.751096)
		(width 0.12065)
		(layer "F.Cu")
		(net "TP_GPIOE7")
	)
	(segment
		(start 36.10483 -123.684792)
		(end 35.705034 -123.284996)
		(width 0.12065)
		(layer "F.Cu")
		(net "TP_GPIOE6")
	)
	(via
		(at 35.705034 -123.284996)
		(size 0.4572)
		(drill 0.2032)
		(layers "F.Cu" "B.Cu")
		(net "TP_GPIOE6")
	)
	(segment
		(start 35.181032 -118.742968)
		(end 35.181032 -122.694192)
		(width 0.12065)
		(layer "B.Cu")
		(net "TP_GPIOE6")
	)
	(segment
		(start 35.433 -118.491)
		(end 35.181032 -118.742968)
		(width 0.12065)
		(layer "B.Cu")
		(net "TP_GPIOE6")
	)
	(segment
		(start 35.181032 -122.694192)
		(end 35.705034 -123.218194)
		(width 0.12065)
		(layer "B.Cu")
		(net "TP_GPIOE6")
	)
	(segment
		(start 35.705034 -123.218194)
		(end 35.705034 -123.284996)
		(width 0.12065)
		(layer "B.Cu")
		(net "TP_GPIOE6")
	)
	(segment
		(start 35.28822 -118.27764)
		(end 35.30473 -118.29415)
		(width 0.12065)
		(layer "F.Cu")
		(net "TP_GPIOE3")
	)
	(segment
		(start 35.30473 -118.29415)
		(end 35.30473 -122.084846)
		(width 0.12065)
		(layer "F.Cu")
		(net "TP_GPIOE3")
	)
	(segment
		(start 35.30473 -122.601228)
		(end 35.30473 -122.884946)
		(width 0.12065)
		(layer "F.Cu")
		(net "TP_GPIOE2")
	)
	(segment
		(start 34.05886 -118.30812)
		(end 34.05886 -118.364)
		(width 0.12065)
		(layer "F.Cu")
		(net "TP_GPIOE2")
	)
	(segment
		(start 34.939478 -119.244618)
		(end 34.939478 -122.235976)
		(width 0.12065)
		(layer "F.Cu")
		(net "TP_GPIOE2")
	)
	(segment
		(start 34.939478 -122.235976)
		(end 35.30473 -122.601228)
		(width 0.12065)
		(layer "F.Cu")
		(net "TP_GPIOE2")
	)
	(segment
		(start 34.05886 -118.364)
		(end 34.939478 -119.244618)
		(width 0.12065)
		(layer "F.Cu")
		(net "TP_GPIOE2")
	)
	(segment
		(start 35.30473 -123.684792)
		(end 34.904934 -123.284996)
		(width 0.12065)
		(layer "F.Cu")
		(net "TP_GPIOE1")
	)
	(via
		(at 34.904934 -123.284996)
		(size 0.4572)
		(drill 0.2032)
		(layers "F.Cu" "B.Cu")
		(net "TP_GPIOE1")
	)
	(segment
		(start 34.163 -120.777)
		(end 34.474658 -121.088658)
		(width 0.12065)
		(layer "B.Cu")
		(net "TP_GPIOE1")
	)
	(segment
		(start 34.474658 -121.088658)
		(end 34.474658 -121.538746)
		(width 0.12065)
		(layer "B.Cu")
		(net "TP_GPIOE1")
	)
	(segment
		(start 34.736532 -123.116594)
		(end 34.904934 -123.284996)
		(width 0.12065)
		(layer "B.Cu")
		(net "TP_GPIOE1")
	)
	(segment
		(start 34.474658 -121.538746)
		(end 34.47288 -121.540524)
		(width 0.12065)
		(layer "B.Cu")
		(net "TP_GPIOE1")
	)
	(segment
		(start 34.47288 -121.540524)
		(end 34.736532 -121.804176)
		(width 0.12065)
		(layer "B.Cu")
		(net "TP_GPIOE1")
	)
	(segment
		(start 34.163 -118.364)
		(end 34.163 -120.777)
		(width 0.12065)
		(layer "B.Cu")
		(net "TP_GPIOE1")
	)
	(segment
		(start 34.736532 -121.804176)
		(end 34.736532 -123.116594)
		(width 0.12065)
		(layer "B.Cu")
		(net "TP_GPIOE1")
	)
	(segment
		(start 35.30473 -125.284992)
		(end 34.904934 -124.885196)
		(width 0.12065)
		(layer "F.Cu")
		(net "TP_GPIOD7")
	)
	(segment
		(start 32.418782 -112.19307)
		(end 32.418782 -113.452402)
		(width 0.12065)
		(layer "F.Cu")
		(net "TP_GPIOD7")
	)
	(segment
		(start 32.418782 -113.452402)
		(end 32.89808 -113.9317)
		(width 0.12065)
		(layer "F.Cu")
		(net "TP_GPIOD7")
	)
	(segment
		(start 32.89808 -113.9317)
		(end 32.89808 -113.95964)
		(width 0.12065)
		(layer "F.Cu")
		(net "TP_GPIOD7")
	)
	(via
		(at 34.904934 -124.885196)
		(size 0.4572)
		(drill 0.2032)
		(layers "F.Cu" "B.Cu")
		(net "TP_GPIOD7")
	)
	(via
		(at 32.89808 -113.95964)
		(size 0.508)
		(drill 0.254)
		(layers "F.Cu" "B.Cu")
		(net "TP_GPIOD7")
	)
	(segment
		(start 34.511234 -116.604034)
		(end 34.511234 -124.491496)
		(width 0.127)
		(layer "In2.Cu")
		(net "TP_GPIOD7")
	)
	(segment
		(start 34.3281 -115.297966)
		(end 34.3281 -116.4209)
		(width 0.127)
		(layer "In2.Cu")
		(net "TP_GPIOD7")
	)
	(segment
		(start 34.3281 -116.4209)
		(end 34.511234 -116.604034)
		(width 0.127)
		(layer "In2.Cu")
		(net "TP_GPIOD7")
	)
	(segment
		(start 34.511234 -124.491496)
		(end 34.904934 -124.885196)
		(width 0.127)
		(layer "In2.Cu")
		(net "TP_GPIOD7")
	)
	(segment
		(start 33.408366 -114.441986)
		(end 33.47212 -114.441986)
		(width 0.127)
		(layer "In2.Cu")
		(net "TP_GPIOD7")
	)
	(segment
		(start 32.92602 -113.95964)
		(end 33.408366 -114.441986)
		(width 0.127)
		(layer "In2.Cu")
		(net "TP_GPIOD7")
	)
	(segment
		(start 33.47212 -114.441986)
		(end 34.3281 -115.297966)
		(width 0.127)
		(layer "In2.Cu")
		(net "TP_GPIOD7")
	)
	(segment
		(start 32.89808 -113.95964)
		(end 32.92602 -113.95964)
		(width 0.127)
		(layer "In2.Cu")
		(net "TP_GPIOD7")
	)
	(segment
		(start 34.139632 -122.235976)
		(end 34.139632 -120.114568)
		(width 0.12065)
		(layer "F.Cu")
		(net "TP_GPIOD5")
	)
	(segment
		(start 34.139632 -120.114568)
		(end 32.420052 -118.394988)
		(width 0.12065)
		(layer "F.Cu")
		(net "TP_GPIOD5")
	)
	(segment
		(start 34.504884 -122.884946)
		(end 34.504884 -122.601228)
		(width 0.12065)
		(layer "F.Cu")
		(net "TP_GPIOD5")
	)
	(segment
		(start 34.504884 -122.601228)
		(end 34.139632 -122.235976)
		(width 0.12065)
		(layer "F.Cu")
		(net "TP_GPIOD5")
	)
	(segment
		(start 32.216852 -117.710458)
		(end 32.216852 -116.246148)
		(width 0.12065)
		(layer "F.Cu")
		(net "TP_GPIOD5")
	)
	(segment
		(start 32.420052 -117.913658)
		(end 32.216852 -117.710458)
		(width 0.12065)
		(layer "F.Cu")
		(net "TP_GPIOD5")
	)
	(segment
		(start 32.420052 -118.394988)
		(end 32.420052 -117.913658)
		(width 0.12065)
		(layer "F.Cu")
		(net "TP_GPIOD5")
	)
	(segment
		(start 32.216852 -116.246148)
		(end 32.639 -115.824)
		(width 0.12065)
		(layer "F.Cu")
		(net "TP_GPIOD5")
	)
	(segment
		(start 34.504884 -123.684792)
		(end 34.105088 -123.284996)
		(width 0.12065)
		(layer "F.Cu")
		(net "TP_GPIOD4")
	)
	(via
		(at 34.105088 -123.284996)
		(size 0.4572)
		(drill 0.2032)
		(layers "F.Cu" "B.Cu")
		(net "TP_GPIOD4")
	)
	(segment
		(start 32.58312 -120.93448)
		(end 34.105088 -122.456448)
		(width 0.12065)
		(layer "B.Cu")
		(net "TP_GPIOD4")
	)
	(segment
		(start 34.105088 -122.456448)
		(end 34.105088 -123.284996)
		(width 0.12065)
		(layer "B.Cu")
		(net "TP_GPIOD4")
	)
	(segment
		(start 33.704784 -120.191784)
		(end 33.704784 -122.084846)
		(width 0.12065)
		(layer "F.Cu")
		(net "TP_GPIOD3")
	)
	(segment
		(start 31.877 -118.364)
		(end 33.704784 -120.191784)
		(width 0.12065)
		(layer "F.Cu")
		(net "TP_GPIOD3")
	)
	(segment
		(start 31.333948 -118.589044)
		(end 33.339532 -120.594628)
		(width 0.12065)
		(layer "F.Cu")
		(net "TP_GPIOD2")
	)
	(segment
		(start 33.704784 -122.601228)
		(end 33.704784 -122.884946)
		(width 0.12065)
		(layer "F.Cu")
		(net "TP_GPIOD2")
	)
	(segment
		(start 30.607 -117.094)
		(end 31.333948 -117.820948)
		(width 0.12065)
		(layer "F.Cu")
		(net "TP_GPIOD2")
	)
	(segment
		(start 33.339532 -122.235976)
		(end 33.704784 -122.601228)
		(width 0.12065)
		(layer "F.Cu")
		(net "TP_GPIOD2")
	)
	(segment
		(start 33.339532 -120.594628)
		(end 33.339532 -122.235976)
		(width 0.12065)
		(layer "F.Cu")
		(net "TP_GPIOD2")
	)
	(segment
		(start 31.333948 -117.820948)
		(end 31.333948 -118.589044)
		(width 0.12065)
		(layer "F.Cu")
		(net "TP_GPIOD2")
	)
	(segment
		(start 34.504884 -124.484892)
		(end 34.105088 -124.085096)
		(width 0.12065)
		(layer "F.Cu")
		(net "TP_GPIOD1")
	)
	(via
		(at 34.105088 -124.085096)
		(size 0.4572)
		(drill 0.2032)
		(layers "F.Cu" "B.Cu")
		(net "TP_GPIOD1")
	)
	(segment
		(start 33.097216 -122.29338)
		(end 33.714436 -122.9106)
		(width 0.12065)
		(layer "B.Cu")
		(net "TP_GPIOD1")
	)
	(segment
		(start 33.714436 -122.9106)
		(end 33.714436 -123.694444)
		(width 0.12065)
		(layer "B.Cu")
		(net "TP_GPIOD1")
	)
	(segment
		(start 32.6263 -122.29338)
		(end 33.097216 -122.29338)
		(width 0.12065)
		(layer "B.Cu")
		(net "TP_GPIOD1")
	)
	(segment
		(start 33.714436 -123.694444)
		(end 34.105088 -124.085096)
		(width 0.12065)
		(layer "B.Cu")
		(net "TP_GPIOD1")
	)
	(segment
		(start 30.971998 -118.688358)
		(end 30.65272 -118.36908)
		(width 0.12065)
		(layer "F.Cu")
		(net "TP_GPIOD0")
	)
	(segment
		(start 30.971998 -118.739158)
		(end 30.971998 -118.688358)
		(width 0.12065)
		(layer "F.Cu")
		(net "TP_GPIOD0")
	)
	(segment
		(start 32.904938 -122.084846)
		(end 32.904938 -120.672098)
		(width 0.12065)
		(layer "F.Cu")
		(net "TP_GPIOD0")
	)
	(segment
		(start 32.904938 -120.672098)
		(end 30.971998 -118.739158)
		(width 0.12065)
		(layer "F.Cu")
		(net "TP_GPIOD0")
	)
	(segment
		(start 31.304738 -127.684784)
		(end 30.904942 -127.284988)
		(width 0.12065)
		(layer "F.Cu")
		(net "TP_GPIOB6")
	)
	(via
		(at 30.904942 -127.284988)
		(size 0.4572)
		(drill 0.2032)
		(layers "F.Cu" "B.Cu")
		(net "TP_GPIOB6")
	)
	(segment
		(start 29.913834 -126.973584)
		(end 30.225238 -127.284988)
		(width 0.12065)
		(layer "B.Cu")
		(net "TP_GPIOB6")
	)
	(segment
		(start 30.225238 -127.284988)
		(end 30.904942 -127.284988)
		(width 0.12065)
		(layer "B.Cu")
		(net "TP_GPIOB6")
	)
	(segment
		(start 32.104838 -127.684784)
		(end 31.705042 -127.284988)
		(width 0.12065)
		(layer "F.Cu")
		(net "TP_GPIOB5")
	)
	(via
		(at 31.705042 -127.284988)
		(size 0.4572)
		(drill 0.2032)
		(layers "F.Cu" "B.Cu")
		(net "TP_GPIOB5")
	)
	(segment
		(start 34.10585 -126.76505)
		(end 33.999424 -126.871476)
		(width 0.12065)
		(layer "B.Cu")
		(net "TP_GPIOB5")
	)
	(segment
		(start 32.095694 -126.894336)
		(end 31.705042 -127.284988)
		(width 0.12065)
		(layer "B.Cu")
		(net "TP_GPIOB5")
	)
	(segment
		(start 33.999424 -126.871476)
		(end 33.999424 -126.890272)
		(width 0.12065)
		(layer "B.Cu")
		(net "TP_GPIOB5")
	)
	(segment
		(start 34.10585 -126.61265)
		(end 34.10585 -126.76505)
		(width 0.12065)
		(layer "B.Cu")
		(net "TP_GPIOB5")
	)
	(segment
		(start 32.66694 -126.894336)
		(end 32.095694 -126.894336)
		(width 0.12065)
		(layer "B.Cu")
		(net "TP_GPIOB5")
	)
	(segment
		(start 33.001204 -127.2286)
		(end 32.66694 -126.894336)
		(width 0.12065)
		(layer "B.Cu")
		(net "TP_GPIOB5")
	)
	(segment
		(start 33.999424 -126.890272)
		(end 33.661096 -127.2286)
		(width 0.12065)
		(layer "B.Cu")
		(net "TP_GPIOB5")
	)
	(segment
		(start 34.613088 -126.105412)
		(end 34.10585 -126.61265)
		(width 0.12065)
		(layer "B.Cu")
		(net "TP_GPIOB5")
	)
	(segment
		(start 33.661096 -127.2286)
		(end 33.001204 -127.2286)
		(width 0.12065)
		(layer "B.Cu")
		(net "TP_GPIOB5")
	)
	(segment
		(start 43.304714 -124.484892)
		(end 43.70451 -124.085096)
		(width 0.12065)
		(layer "F.Cu")
		(net "TP_GPIOA7")
	)
	(via
		(at 43.70451 -124.085096)
		(size 0.4572)
		(drill 0.2032)
		(layers "F.Cu" "B.Cu")
		(net "TP_GPIOA7")
	)
	(segment
		(start 44.946316 -119.551704)
		(end 44.946316 -119.523256)
		(width 0.12065)
		(layer "B.Cu")
		(net "TP_GPIOA7")
	)
	(segment
		(start 42.730674 -123.110244)
		(end 42.730674 -121.767346)
		(width 0.12065)
		(layer "B.Cu")
		(net "TP_GPIOA7")
	)
	(segment
		(start 43.70451 -124.085096)
		(end 42.730674 -123.110244)
		(width 0.12065)
		(layer "B.Cu")
		(net "TP_GPIOA7")
	)
	(segment
		(start 42.730674 -121.767346)
		(end 44.946316 -119.551704)
		(width 0.12065)
		(layer "B.Cu")
		(net "TP_GPIOA7")
	)
	(segment
		(start 46.105572 -118.364)
		(end 46.228 -118.364)
		(width 0.12065)
		(layer "B.Cu")
		(net "TP_GPIOA7")
	)
	(segment
		(start 44.946316 -119.523256)
		(end 46.105572 -118.364)
		(width 0.12065)
		(layer "B.Cu")
		(net "TP_GPIOA7")
	)
	(segment
		(start 48.811942 -118.38305)
		(end 48.811942 -120.072658)
		(width 0.12065)
		(layer "F.Cu")
		(net "TP_GPIOA6")
	)
	(segment
		(start 48.811942 -120.072658)
		(end 47.7012 -121.1834)
		(width 0.12065)
		(layer "F.Cu")
		(net "TP_GPIOA6")
	)
	(segment
		(start 47.7012 -121.1834)
		(end 45.80636 -121.1834)
		(width 0.12065)
		(layer "F.Cu")
		(net "TP_GPIOA6")
	)
	(segment
		(start 45.80636 -121.1834)
		(end 44.904914 -122.084846)
		(width 0.12065)
		(layer "F.Cu")
		(net "TP_GPIOA6")
	)
	(segment
		(start 42.504868 -125.284992)
		(end 42.105072 -124.885196)
		(width 0.12065)
		(layer "F.Cu")
		(net "TP_GPIOA3")
	)
	(via
		(at 42.105072 -124.885196)
		(size 0.4572)
		(drill 0.2032)
		(layers "F.Cu" "B.Cu")
		(net "TP_GPIOA3")
	)
	(segment
		(start 42.6466 -123.723146)
		(end 42.4942 -123.570746)
		(width 0.12065)
		(layer "B.Cu")
		(net "TP_GPIOA3")
	)
	(segment
		(start 44.724066 -119.432578)
		(end 44.724066 -118.597934)
		(width 0.12065)
		(layer "B.Cu")
		(net "TP_GPIOA3")
	)
	(segment
		(start 44.724066 -118.597934)
		(end 44.958 -118.364)
		(width 0.12065)
		(layer "B.Cu")
		(net "TP_GPIOA3")
	)
	(segment
		(start 42.4942 -121.662444)
		(end 44.724066 -119.432578)
		(width 0.12065)
		(layer "B.Cu")
		(net "TP_GPIOA3")
	)
	(segment
		(start 42.4942 -123.570746)
		(end 42.4942 -121.662444)
		(width 0.12065)
		(layer "B.Cu")
		(net "TP_GPIOA3")
	)
	(segment
		(start 42.6466 -124.11583)
		(end 42.6466 -123.723146)
		(width 0.12065)
		(layer "B.Cu")
		(net "TP_GPIOA3")
	)
	(segment
		(start 42.105072 -124.657358)
		(end 42.6466 -124.11583)
		(width 0.12065)
		(layer "B.Cu")
		(net "TP_GPIOA3")
	)
	(segment
		(start 42.105072 -124.885196)
		(end 42.105072 -124.657358)
		(width 0.12065)
		(layer "B.Cu")
		(net "TP_GPIOA3")
	)
	(segment
		(start 21.6535 -152.54224)
		(end 21.6535 -153.67)
		(width 0.12065)
		(layer "F.Cu")
		(net "FM_BMC_RESET_Q36_R")
	)
	(segment
		(start 21.224748 -154.098752)
		(end 21.224748 -155.071826)
		(width 0.12065)
		(layer "F.Cu")
		(net "FM_BMC_RESET_Q36_R")
	)
	(segment
		(start 21.420074 -155.071826)
		(end 22.352 -154.1399)
		(width 0.12065)
		(layer "F.Cu")
		(net "FM_BMC_RESET_Q36_R")
	)
	(segment
		(start 21.224748 -155.071826)
		(end 21.420074 -155.071826)
		(width 0.12065)
		(layer "F.Cu")
		(net "FM_BMC_RESET_Q36_R")
	)
	(segment
		(start 21.2725 -154.051)
		(end 21.224748 -154.098752)
		(width 0.12065)
		(layer "F.Cu")
		(net "FM_BMC_RESET_Q36_R")
	)
	(segment
		(start 21.6535 -153.67)
		(end 21.2725 -154.051)
		(width 0.12065)
		(layer "F.Cu")
		(net "FM_BMC_RESET_Q36_R")
	)
	(via
		(at 21.224748 -155.071826)
		(size 0.7112)
		(drill 0.3556)
		(layers "F.Cu" "B.Cu")
		(net "FM_BMC_RESET_Q36_R")
	)
	(segment
		(start 7.4422 -137.1219)
		(end 7.4422 -136.3472)
		(width 0.12065)
		(layer "F.Cu")
		(net "FM_BMC_RESET_Q36")
	)
	(segment
		(start 7.7597 -136.0297)
		(end 7.7597 -135.509)
		(width 0.12065)
		(layer "F.Cu")
		(net "FM_BMC_RESET_Q36")
	)
	(segment
		(start 7.4422 -136.3472)
		(end 7.7597 -136.0297)
		(width 0.12065)
		(layer "F.Cu")
		(net "FM_BMC_RESET_Q36")
	)
	(segment
		(start 17.664938 -153.9875)
		(end 17.147032 -154.505406)
		(width 0.12065)
		(layer "F.Cu")
		(net "FM_BMC_RESET_Q36")
	)
	(segment
		(start 18.288 -153.9875)
		(end 17.664938 -153.9875)
		(width 0.12065)
		(layer "F.Cu")
		(net "FM_BMC_RESET_Q36")
	)
	(segment
		(start 19.3675 -154.051)
		(end 20.3835 -154.051)
		(width 0.12065)
		(layer "F.Cu")
		(net "FM_BMC_RESET_Q36")
	)
	(segment
		(start 17.147032 -154.505406)
		(end 15.903194 -154.505406)
		(width 0.12065)
		(layer "F.Cu")
		(net "FM_BMC_RESET_Q36")
	)
	(segment
		(start 18.288 -153.9875)
		(end 19.304 -153.9875)
		(width 0.12065)
		(layer "F.Cu")
		(net "FM_BMC_RESET_Q36")
	)
	(segment
		(start 19.304 -153.9875)
		(end 19.3675 -154.051)
		(width 0.12065)
		(layer "F.Cu")
		(net "FM_BMC_RESET_Q36")
	)
	(via
		(at 15.903194 -154.505406)
		(size 0.508)
		(drill 0.254)
		(layers "F.Cu" "B.Cu")
		(net "FM_BMC_RESET_Q36")
	)
	(via
		(at 7.4422 -137.1219)
		(size 0.508)
		(drill 0.254)
		(layers "F.Cu" "B.Cu")
		(net "FM_BMC_RESET_Q36")
	)
	(via
		(at 17.147032 -154.505406)
		(size 0.7112)
		(drill 0.3556)
		(layers "F.Cu" "B.Cu")
		(net "FM_BMC_RESET_Q36")
	)
	(segment
		(start 7.4422 -146.044412)
		(end 15.903194 -154.505406)
		(width 0.127)
		(layer "In2.Cu")
		(net "FM_BMC_RESET_Q36")
	)
	(segment
		(start 7.4422 -137.1219)
		(end 7.4422 -146.044412)
		(width 0.127)
		(layer "In2.Cu")
		(net "FM_BMC_RESET_Q36")
	)
	(segment
		(start 44.904914 -130.88493)
		(end 45.30471 -130.485134)
		(width 0.12065)
		(layer "F.Cu")
		(net "ADC_P1V26_BMC")
	)
	(via
		(at 52.3748 -134.747)
		(size 0.7112)
		(drill 0.3556)
		(layers "F.Cu" "B.Cu")
		(net "ADC_P1V26_BMC")
	)
	(via
		(at 45.30471 -130.485134)
		(size 0.4572)
		(drill 0.2032)
		(layers "F.Cu" "B.Cu")
		(net "ADC_P1V26_BMC")
	)
	(segment
		(start 47.354998 -130.485134)
		(end 51.616864 -134.747)
		(width 0.12065)
		(layer "B.Cu")
		(net "ADC_P1V26_BMC")
	)
	(segment
		(start 51.616864 -134.747)
		(end 52.3748 -134.747)
		(width 0.12065)
		(layer "B.Cu")
		(net "ADC_P1V26_BMC")
	)
	(segment
		(start 45.30471 -130.485134)
		(end 47.354998 -130.485134)
		(width 0.12065)
		(layer "B.Cu")
		(net "ADC_P1V26_BMC")
	)
	(segment
		(start 52.3748 -134.747)
		(end 53.2765 -134.747)
		(width 0.12065)
		(layer "B.Cu")
		(net "ADC_P1V26_BMC")
	)
	(segment
		(start 80.2005 -135.763)
		(end 80.2005 -136.7028)
		(width 0.12065)
		(layer "F.Cu")
		(net "ADC_P1V26")
	)
	(segment
		(start 80.2005 -135.763)
		(end 79.6163 -135.1788)
		(width 0.12065)
		(layer "F.Cu")
		(net "ADC_P1V26")
	)
	(segment
		(start 80.1751 -137.795)
		(end 80.1751 -136.7282)
		(width 0.12065)
		(layer "F.Cu")
		(net "ADC_P1V26")
	)
	(segment
		(start 79.6163 -135.1788)
		(end 78.74 -135.1788)
		(width 0.12065)
		(layer "F.Cu")
		(net "ADC_P1V26")
	)
	(segment
		(start 80.2005 -136.7028)
		(end 80.1751 -136.7282)
		(width 0.12065)
		(layer "F.Cu")
		(net "ADC_P1V26")
	)
	(segment
		(start 78.74 -135.1788)
		(end 77.9526 -134.3914)
		(width 0.12065)
		(layer "F.Cu")
		(net "ADC_P1V26")
	)
	(via
		(at 66.675 -135.131048)
		(size 0.7112)
		(drill 0.3556)
		(layers "F.Cu" "B.Cu")
		(net "ADC_P1V26")
	)
	(via
		(at 77.9526 -134.3914)
		(size 0.508)
		(drill 0.254)
		(layers "F.Cu" "B.Cu")
		(net "ADC_P1V26")
	)
	(segment
		(start 54.1655 -134.747)
		(end 54.549548 -135.131048)
		(width 0.12065)
		(layer "B.Cu")
		(net "ADC_P1V26")
	)
	(segment
		(start 54.549548 -135.131048)
		(end 66.675 -135.131048)
		(width 0.12065)
		(layer "B.Cu")
		(net "ADC_P1V26")
	)
	(segment
		(start 73.618852 -135.131048)
		(end 66.675 -135.131048)
		(width 0.12065)
		(layer "B.Cu")
		(net "ADC_P1V26")
	)
	(segment
		(start 74.3585 -134.3914)
		(end 73.618852 -135.131048)
		(width 0.12065)
		(layer "B.Cu")
		(net "ADC_P1V26")
	)
	(segment
		(start 77.9526 -134.3914)
		(end 74.3585 -134.3914)
		(width 0.12065)
		(layer "B.Cu")
		(net "ADC_P1V26")
	)
	(segment
		(start 43.588432 -138.084814)
		(end 43.304714 -138.084814)
		(width 0.12065)
		(layer "F.Cu")
		(net "PEER_BMC_HB")
	)
	(segment
		(start 44.682664 -139.284202)
		(end 44.682664 -139.277598)
		(width 0.12065)
		(layer "F.Cu")
		(net "PEER_BMC_HB")
	)
	(segment
		(start 47.117 -144.1958)
		(end 47.33036 -143.98244)
		(width 0.12065)
		(layer "F.Cu")
		(net "PEER_BMC_HB")
	)
	(segment
		(start 47.33036 -143.270224)
		(end 47.117 -143.056864)
		(width 0.12065)
		(layer "F.Cu")
		(net "PEER_BMC_HB")
	)
	(segment
		(start 47.117 -144.1958)
		(end 47.117 -144.9705)
		(width 0.12065)
		(layer "F.Cu")
		(net "PEER_BMC_HB")
	)
	(segment
		(start 43.953684 -138.450066)
		(end 43.588432 -138.084814)
		(width 0.12065)
		(layer "F.Cu")
		(net "PEER_BMC_HB")
	)
	(segment
		(start 47.117 -143.056864)
		(end 47.117 -141.718538)
		(width 0.12065)
		(layer "F.Cu")
		(net "PEER_BMC_HB")
	)
	(segment
		(start 44.470066 -139.065)
		(end 44.470066 -138.733784)
		(width 0.12065)
		(layer "F.Cu")
		(net "PEER_BMC_HB")
	)
	(segment
		(start 47.117 -141.718538)
		(end 44.682664 -139.284202)
		(width 0.12065)
		(layer "F.Cu")
		(net "PEER_BMC_HB")
	)
	(segment
		(start 44.682664 -139.277598)
		(end 44.470066 -139.065)
		(width 0.12065)
		(layer "F.Cu")
		(net "PEER_BMC_HB")
	)
	(segment
		(start 44.186348 -138.450066)
		(end 43.953684 -138.450066)
		(width 0.12065)
		(layer "F.Cu")
		(net "PEER_BMC_HB")
	)
	(segment
		(start 47.33036 -143.98244)
		(end 47.33036 -143.270224)
		(width 0.12065)
		(layer "F.Cu")
		(net "PEER_BMC_HB")
	)
	(segment
		(start 44.470066 -138.733784)
		(end 44.186348 -138.450066)
		(width 0.12065)
		(layer "F.Cu")
		(net "PEER_BMC_HB")
	)
	(via
		(at 44.26331 -210.49869)
		(size 0.7112)
		(drill 0.3556)
		(layers "F.Cu" "B.Cu")
		(net "PEER_BMC_HB")
	)
	(via
		(at 42.418 -174.371)
		(size 0.508)
		(drill 0.254)
		(layers "F.Cu" "B.Cu")
		(net "PEER_BMC_HB")
	)
	(via
		(at 47.117 -144.1958)
		(size 0.508)
		(drill 0.254)
		(layers "F.Cu" "B.Cu")
		(net "PEER_BMC_HB")
	)
	(segment
		(start 42.900092 -225.92538)
		(end 42.900092 -224.052892)
		(width 0.12065)
		(layer "B.Cu")
		(net "PEER_BMC_HB")
	)
	(segment
		(start 54.356 -206.629)
		(end 48.133 -206.629)
		(width 0.12065)
		(layer "B.Cu")
		(net "PEER_BMC_HB")
	)
	(segment
		(start 43.100752 -175.053752)
		(end 48.974248 -175.053752)
		(width 0.12065)
		(layer "B.Cu")
		(net "PEER_BMC_HB")
	)
	(segment
		(start 55.536846 -174.13605)
		(end 56.15305 -174.13605)
		(width 0.12065)
		(layer "B.Cu")
		(net "PEER_BMC_HB")
	)
	(segment
		(start 42.418 -174.371)
		(end 43.100752 -175.053752)
		(width 0.12065)
		(layer "B.Cu")
		(net "PEER_BMC_HB")
	)
	(segment
		(start 50.409602 -174.13605)
		(end 50.41011 -174.136558)
		(width 0.12065)
		(layer "B.Cu")
		(net "PEER_BMC_HB")
	)
	(segment
		(start 60.198 -200.787)
		(end 54.356 -206.629)
		(width 0.12065)
		(layer "B.Cu")
		(net "PEER_BMC_HB")
	)
	(segment
		(start 42.164 -212.598)
		(end 44.26331 -210.49869)
		(width 0.12065)
		(layer "B.Cu")
		(net "PEER_BMC_HB")
	)
	(segment
		(start 55.236618 -174.136558)
		(end 55.236872 -174.136304)
		(width 0.12065)
		(layer "B.Cu")
		(net "PEER_BMC_HB")
	)
	(segment
		(start 42.900092 -224.052892)
		(end 42.164 -223.3168)
		(width 0.12065)
		(layer "B.Cu")
		(net "PEER_BMC_HB")
	)
	(segment
		(start 55.536592 -174.136304)
		(end 55.536846 -174.13605)
		(width 0.12065)
		(layer "B.Cu")
		(net "PEER_BMC_HB")
	)
	(segment
		(start 49.89195 -174.13605)
		(end 50.409602 -174.13605)
		(width 0.12065)
		(layer "B.Cu")
		(net "PEER_BMC_HB")
	)
	(segment
		(start 42.164 -223.3168)
		(end 42.164 -212.598)
		(width 0.12065)
		(layer "B.Cu")
		(net "PEER_BMC_HB")
	)
	(segment
		(start 50.41011 -174.136558)
		(end 55.236618 -174.136558)
		(width 0.12065)
		(layer "B.Cu")
		(net "PEER_BMC_HB")
	)
	(segment
		(start 60.198 -178.181)
		(end 60.198 -200.787)
		(width 0.12065)
		(layer "B.Cu")
		(net "PEER_BMC_HB")
	)
	(segment
		(start 55.236872 -174.136304)
		(end 55.536592 -174.136304)
		(width 0.12065)
		(layer "B.Cu")
		(net "PEER_BMC_HB")
	)
	(segment
		(start 48.133 -206.629)
		(end 44.26331 -210.49869)
		(width 0.12065)
		(layer "B.Cu")
		(net "PEER_BMC_HB")
	)
	(segment
		(start 48.974248 -175.053752)
		(end 49.89195 -174.13605)
		(width 0.12065)
		(layer "B.Cu")
		(net "PEER_BMC_HB")
	)
	(segment
		(start 56.15305 -174.13605)
		(end 60.198 -178.181)
		(width 0.12065)
		(layer "B.Cu")
		(net "PEER_BMC_HB")
	)
	(segment
		(start 42.418 -171.958)
		(end 42.418 -174.371)
		(width 0.127)
		(layer "In5.Cu")
		(net "PEER_BMC_HB")
	)
	(segment
		(start 47.719234 -166.656766)
		(end 42.418 -171.958)
		(width 0.127)
		(layer "In5.Cu")
		(net "PEER_BMC_HB")
	)
	(segment
		(start 47.719234 -145.021046)
		(end 47.719234 -166.656766)
		(width 0.127)
		(layer "In5.Cu")
		(net "PEER_BMC_HB")
	)
	(segment
		(start 47.117 -144.418812)
		(end 47.719234 -145.021046)
		(width 0.127)
		(layer "In5.Cu")
		(net "PEER_BMC_HB")
	)
	(segment
		(start 47.117 -144.1958)
		(end 47.117 -144.418812)
		(width 0.127)
		(layer "In5.Cu")
		(net "PEER_BMC_HB")
	)
	(segment
		(start 246.599964 -39.99992)
		(end 247.099836 -39.500048)
		(width 0.12065)
		(layer "F.Cu")
		(net "TWI_SRST#9")
	)
	(via
		(at 247.099836 -39.500048)
		(size 0.4572)
		(drill 0.2032)
		(layers "F.Cu" "B.Cu")
		(net "TWI_SRST#9")
	)
	(segment
		(start 246.599964 -39.000176)
		(end 247.099836 -39.500048)
		(width 0.12065)
		(layer "B.Cu")
		(net "TWI_SRST#9")
	)
	(segment
		(start 246.599964 -38.999922)
		(end 246.599964 -39.000176)
		(width 0.12065)
		(layer "B.Cu")
		(net "TWI_SRST#9")
	)
	(segment
		(start 247.599962 -36.999926)
		(end 248.099834 -36.500054)
		(width 0.12065)
		(layer "F.Cu")
		(net "TWI_SRST#8")
	)
	(via
		(at 248.099834 -36.500054)
		(size 0.4572)
		(drill 0.2032)
		(layers "F.Cu" "B.Cu")
		(net "TWI_SRST#8")
	)
	(segment
		(start 248.69648 -37.0967)
		(end 248.099834 -36.500054)
		(width 0.12065)
		(layer "B.Cu")
		(net "TWI_SRST#8")
	)
	(segment
		(start 249.027696 -37.9984)
		(end 248.69648 -37.667184)
		(width 0.12065)
		(layer "B.Cu")
		(net "TWI_SRST#8")
	)
	(segment
		(start 248.69648 -37.667184)
		(end 248.69648 -37.0967)
		(width 0.12065)
		(layer "B.Cu")
		(net "TWI_SRST#8")
	)
	(segment
		(start 249.6058 -37.9984)
		(end 249.027696 -37.9984)
		(width 0.12065)
		(layer "B.Cu")
		(net "TWI_SRST#8")
	)
	(segment
		(start 246.599964 -36.999926)
		(end 247.099836 -36.500054)
		(width 0.12065)
		(layer "F.Cu")
		(net "TWI_SRST#7")
	)
	(via
		(at 247.099836 -36.500054)
		(size 0.4572)
		(drill 0.2032)
		(layers "F.Cu" "B.Cu")
		(net "TWI_SRST#7")
	)
	(segment
		(start 246.599964 -36.000182)
		(end 247.099836 -36.500054)
		(width 0.12065)
		(layer "B.Cu")
		(net "TWI_SRST#7")
	)
	(segment
		(start 246.599964 -34.99993)
		(end 246.599964 -36.000182)
		(width 0.12065)
		(layer "B.Cu")
		(net "TWI_SRST#7")
	)
	(segment
		(start 247.599962 -34.99993)
		(end 248.099834 -34.500058)
		(width 0.12065)
		(layer "F.Cu")
		(net "TWI_SRST#6")
	)
	(segment
		(start 261.844282 -28.443682)
		(end 261.844282 -27.543252)
		(width 0.12065)
		(layer "F.Cu")
		(net "TWI_SRST#6")
	)
	(segment
		(start 261.9756 -28.575)
		(end 261.844282 -28.443682)
		(width 0.12065)
		(layer "F.Cu")
		(net "TWI_SRST#6")
	)
	(via
		(at 261.844282 -27.543252)
		(size 0.508)
		(drill 0.254)
		(layers "F.Cu" "B.Cu")
		(net "TWI_SRST#6")
	)
	(via
		(at 261.844282 -28.508452)
		(size 0.7112)
		(drill 0.3556)
		(layers "F.Cu" "B.Cu")
		(net "TWI_SRST#6")
	)
	(via
		(at 248.099834 -34.500058)
		(size 0.4572)
		(drill 0.2032)
		(layers "F.Cu" "B.Cu")
		(net "TWI_SRST#6")
	)
	(segment
		(start 261.844282 -28.508452)
		(end 261.844282 -27.543252)
		(width 0.12065)
		(layer "B.Cu")
		(net "TWI_SRST#6")
	)
	(segment
		(start 261.844282 -27.543252)
		(end 261.398004 -27.096974)
		(width 0.127)
		(layer "In2.Cu")
		(net "TWI_SRST#6")
	)
	(segment
		(start 251.696728 -31.34614)
		(end 251.696728 -31.747714)
		(width 0.1016)
		(layer "In2.Cu")
		(net "TWI_SRST#6")
	)
	(segment
		(start 255.843532 -28.636468)
		(end 253.536196 -28.636468)
		(width 0.127)
		(layer "In2.Cu")
		(net "TWI_SRST#6")
	)
	(segment
		(start 249.308112 -33.89376)
		(end 249.149108 -33.89376)
		(width 0.1016)
		(layer "In2.Cu")
		(net "TWI_SRST#6")
	)
	(segment
		(start 252.338078 -31.106364)
		(end 251.936504 -31.106364)
		(width 0.1016)
		(layer "In2.Cu")
		(net "TWI_SRST#6")
	)
	(segment
		(start 257.383026 -27.096974)
		(end 255.843532 -28.636468)
		(width 0.127)
		(layer "In2.Cu")
		(net "TWI_SRST#6")
	)
	(segment
		(start 251.696728 -31.747714)
		(end 251.347478 -32.096964)
		(width 0.1016)
		(layer "In2.Cu")
		(net "TWI_SRST#6")
	)
	(segment
		(start 252.696726 -29.475938)
		(end 252.696726 -30.747716)
		(width 0.1016)
		(layer "In2.Cu")
		(net "TWI_SRST#6")
	)
	(segment
		(start 253.536196 -28.636468)
		(end 253.216664 -28.956)
		(width 0.127)
		(layer "In2.Cu")
		(net "TWI_SRST#6")
	)
	(segment
		(start 250.69673 -32.747712)
		(end 250.338082 -33.10636)
		(width 0.1016)
		(layer "In2.Cu")
		(net "TWI_SRST#6")
	)
	(segment
		(start 249.70613 -33.336738)
		(end 249.70613 -33.495742)
		(width 0.1016)
		(layer "In2.Cu")
		(net "TWI_SRST#6")
	)
	(segment
		(start 249.936508 -33.10636)
		(end 249.70613 -33.336738)
		(width 0.1016)
		(layer "In2.Cu")
		(net "TWI_SRST#6")
	)
	(segment
		(start 253.216664 -28.956)
		(end 252.696726 -29.475938)
		(width 0.1016)
		(layer "In2.Cu")
		(net "TWI_SRST#6")
	)
	(segment
		(start 251.347478 -32.096964)
		(end 250.945904 -32.096964)
		(width 0.1016)
		(layer "In2.Cu")
		(net "TWI_SRST#6")
	)
	(segment
		(start 249.149108 -33.89376)
		(end 248.54281 -34.500058)
		(width 0.1016)
		(layer "In2.Cu")
		(net "TWI_SRST#6")
	)
	(segment
		(start 250.945904 -32.096964)
		(end 250.69673 -32.346138)
		(width 0.1016)
		(layer "In2.Cu")
		(net "TWI_SRST#6")
	)
	(segment
		(start 248.54281 -34.500058)
		(end 248.099834 -34.500058)
		(width 0.1016)
		(layer "In2.Cu")
		(net "TWI_SRST#6")
	)
	(segment
		(start 250.69673 -32.346138)
		(end 250.69673 -32.747712)
		(width 0.1016)
		(layer "In2.Cu")
		(net "TWI_SRST#6")
	)
	(segment
		(start 261.398004 -27.096974)
		(end 257.383026 -27.096974)
		(width 0.127)
		(layer "In2.Cu")
		(net "TWI_SRST#6")
	)
	(segment
		(start 252.696726 -30.747716)
		(end 252.338078 -31.106364)
		(width 0.1016)
		(layer "In2.Cu")
		(net "TWI_SRST#6")
	)
	(segment
		(start 249.70613 -33.495742)
		(end 249.308112 -33.89376)
		(width 0.1016)
		(layer "In2.Cu")
		(net "TWI_SRST#6")
	)
	(segment
		(start 250.338082 -33.10636)
		(end 249.936508 -33.10636)
		(width 0.1016)
		(layer "In2.Cu")
		(net "TWI_SRST#6")
	)
	(segment
		(start 251.936504 -31.106364)
		(end 251.696728 -31.34614)
		(width 0.1016)
		(layer "In2.Cu")
		(net "TWI_SRST#6")
	)
	(segment
		(start 247.599962 -40.999918)
		(end 248.099834 -40.500046)
		(width 0.12065)
		(layer "F.Cu")
		(net "TWI_SRST#5")
	)
	(via
		(at 248.099834 -40.500046)
		(size 0.4572)
		(drill 0.2032)
		(layers "F.Cu" "B.Cu")
		(net "TWI_SRST#5")
	)
	(segment
		(start 247.599962 -40.999918)
		(end 248.099834 -40.500046)
		(width 0.12065)
		(layer "B.Cu")
		(net "TWI_SRST#5")
	)
	(segment
		(start 246.599964 -40.999918)
		(end 247.599962 -40.999918)
		(width 0.12065)
		(layer "B.Cu")
		(net "TWI_SRST#5")
	)
	(segment
		(start 245.599966 -33.999932)
		(end 246.099838 -33.50006)
		(width 0.12065)
		(layer "F.Cu")
		(net "TWI_SRST#4")
	)
	(via
		(at 246.099838 -33.50006)
		(size 0.4572)
		(drill 0.2032)
		(layers "F.Cu" "B.Cu")
		(net "TWI_SRST#4")
	)
	(segment
		(start 245.599966 -33.999932)
		(end 246.099838 -33.50006)
		(width 0.12065)
		(layer "B.Cu")
		(net "TWI_SRST#4")
	)
	(segment
		(start 245.599966 -36.999926)
		(end 246.099838 -36.500054)
		(width 0.12065)
		(layer "F.Cu")
		(net "TWI_SRST#3")
	)
	(via
		(at 246.099838 -36.500054)
		(size 0.4572)
		(drill 0.2032)
		(layers "F.Cu" "B.Cu")
		(net "TWI_SRST#3")
	)
	(segment
		(start 246.59971 -36.999926)
		(end 246.099838 -36.500054)
		(width 0.12065)
		(layer "B.Cu")
		(net "TWI_SRST#3")
	)
	(segment
		(start 246.599964 -36.999926)
		(end 246.59971 -36.999926)
		(width 0.12065)
		(layer "B.Cu")
		(net "TWI_SRST#3")
	)
	(segment
		(start 248.59996 -38.999922)
		(end 249.099832 -38.50005)
		(width 0.12065)
		(layer "F.Cu")
		(net "TWI_SRST#2")
	)
	(via
		(at 249.099832 -38.50005)
		(size 0.4572)
		(drill 0.2032)
		(layers "F.Cu" "B.Cu")
		(net "TWI_SRST#2")
	)
	(segment
		(start 248.59996 -38.999922)
		(end 249.099832 -38.50005)
		(width 0.12065)
		(layer "B.Cu")
		(net "TWI_SRST#2")
	)
	(segment
		(start 249.599958 -35.999928)
		(end 250.09983 -35.500056)
		(width 0.12065)
		(layer "F.Cu")
		(net "TWI_SRST#1")
	)
	(via
		(at 250.09983 -35.500056)
		(size 0.4572)
		(drill 0.2032)
		(layers "F.Cu" "B.Cu")
		(net "TWI_SRST#1")
	)
	(segment
		(start 249.599958 -35.999928)
		(end 250.09983 -35.500056)
		(width 0.12065)
		(layer "B.Cu")
		(net "TWI_SRST#1")
	)
	(segment
		(start 250.599956 -33.999932)
		(end 251.099828 -33.50006)
		(width 0.12065)
		(layer "F.Cu")
		(net "TWI_SRST#0")
	)
	(via
		(at 251.099828 -33.50006)
		(size 0.4572)
		(drill 0.2032)
		(layers "F.Cu" "B.Cu")
		(net "TWI_SRST#0")
	)
	(segment
		(start 251.599954 -33.999932)
		(end 251.5997 -33.999932)
		(width 0.12065)
		(layer "B.Cu")
		(net "TWI_SRST#0")
	)
	(segment
		(start 251.5997 -33.999932)
		(end 251.099828 -33.50006)
		(width 0.12065)
		(layer "B.Cu")
		(net "TWI_SRST#0")
	)
	(segment
		(start 247.599962 -35.999928)
		(end 248.099834 -35.500056)
		(width 0.12065)
		(layer "F.Cu")
		(net "TWI_SDA6")
	)
	(via
		(at 248.099834 -35.500056)
		(size 0.4572)
		(drill 0.2032)
		(layers "F.Cu" "B.Cu")
		(net "TWI_SDA6")
	)
	(segment
		(start 247.599962 -35.999928)
		(end 248.099834 -35.500056)
		(width 0.12065)
		(layer "B.Cu")
		(net "TWI_SDA6")
	)
	(segment
		(start 248.59996 -37.999924)
		(end 249.099832 -37.500052)
		(width 0.12065)
		(layer "F.Cu")
		(net "TWI_SDA5")
	)
	(via
		(at 249.099832 -37.500052)
		(size 0.4572)
		(drill 0.2032)
		(layers "F.Cu" "B.Cu")
		(net "TWI_SDA5")
	)
	(segment
		(start 249.428 -25.663398)
		(end 249.428 -25.4)
		(width 0.12065)
		(layer "B.Cu")
		(net "TWI_SDA5")
	)
	(segment
		(start 248.256806 -28.679648)
		(end 248.256806 -28.654248)
		(width 0.1016)
		(layer "B.Cu")
		(net "TWI_SDA5")
	)
	(segment
		(start 248.405904 -30.249114)
		(end 248.405904 -28.828746)
		(width 0.1016)
		(layer "B.Cu")
		(net "TWI_SDA5")
	)
	(segment
		(start 248.493534 -36.479734)
		(end 248.493534 -30.336744)
		(width 0.1016)
		(layer "B.Cu")
		(net "TWI_SDA5")
	)
	(segment
		(start 248.755154 -25.784048)
		(end 249.30735 -25.784048)
		(width 0.12065)
		(layer "B.Cu")
		(net "TWI_SDA5")
	)
	(segment
		(start 249.099832 -37.086032)
		(end 248.493534 -36.479734)
		(width 0.1016)
		(layer "B.Cu")
		(net "TWI_SDA5")
	)
	(segment
		(start 248.256806 -28.654248)
		(end 248.256806 -26.282396)
		(width 0.12065)
		(layer "B.Cu")
		(net "TWI_SDA5")
	)
	(segment
		(start 249.099832 -37.500052)
		(end 249.099832 -37.086032)
		(width 0.1016)
		(layer "B.Cu")
		(net "TWI_SDA5")
	)
	(segment
		(start 248.256806 -26.282396)
		(end 248.755154 -25.784048)
		(width 0.12065)
		(layer "B.Cu")
		(net "TWI_SDA5")
	)
	(segment
		(start 248.405904 -28.828746)
		(end 248.256806 -28.679648)
		(width 0.1016)
		(layer "B.Cu")
		(net "TWI_SDA5")
	)
	(segment
		(start 249.30735 -25.784048)
		(end 249.428 -25.663398)
		(width 0.12065)
		(layer "B.Cu")
		(net "TWI_SDA5")
	)
	(segment
		(start 248.493534 -30.336744)
		(end 248.405904 -30.249114)
		(width 0.1016)
		(layer "B.Cu")
		(net "TWI_SDA5")
	)
	(segment
		(start 264.505694 -27.207972)
		(end 264.505694 -27.543506)
		(width 0.12065)
		(layer "F.Cu")
		(net "TWI_SDA3")
	)
	(segment
		(start 320.631566 -102.964488)
		(end 320.631566 -100.223066)
		(width 0.12065)
		(layer "F.Cu")
		(net "TWI_SDA3")
	)
	(segment
		(start 264.7569 -29.097224)
		(end 264.7569 -62.09665)
		(width 0.12065)
		(layer "F.Cu")
		(net "TWI_SDA3")
	)
	(segment
		(start 264.4902 -27.559)
		(end 264.334498 -27.714702)
		(width 0.12065)
		(layer "F.Cu")
		(net "TWI_SDA3")
	)
	(segment
		(start 264.334498 -28.674822)
		(end 264.7569 -29.097224)
		(width 0.12065)
		(layer "F.Cu")
		(net "TWI_SDA3")
	)
	(segment
		(start 264.541 -26.7335)
		(end 264.541 -27.172666)
		(width 0.12065)
		(layer "F.Cu")
		(net "TWI_SDA3")
	)
	(segment
		(start 264.505694 -27.543506)
		(end 264.4902 -27.559)
		(width 0.12065)
		(layer "F.Cu")
		(net "TWI_SDA3")
	)
	(segment
		(start 264.541 -27.172666)
		(end 264.505694 -27.207972)
		(width 0.12065)
		(layer "F.Cu")
		(net "TWI_SDA3")
	)
	(segment
		(start 264.7569 -62.09665)
		(end 306.73675 -104.0765)
		(width 0.12065)
		(layer "F.Cu")
		(net "TWI_SDA3")
	)
	(segment
		(start 306.73675 -104.0765)
		(end 319.519554 -104.0765)
		(width 0.12065)
		(layer "F.Cu")
		(net "TWI_SDA3")
	)
	(segment
		(start 320.631566 -100.223066)
		(end 320.421 -100.0125)
		(width 0.12065)
		(layer "F.Cu")
		(net "TWI_SDA3")
	)
	(segment
		(start 264.334498 -27.714702)
		(end 264.334498 -28.674822)
		(width 0.12065)
		(layer "F.Cu")
		(net "TWI_SDA3")
	)
	(segment
		(start 245.599966 -34.99993)
		(end 246.099838 -34.500058)
		(width 0.12065)
		(layer "F.Cu")
		(net "TWI_SDA3")
	)
	(segment
		(start 319.519554 -104.0765)
		(end 320.631566 -102.964488)
		(width 0.12065)
		(layer "F.Cu")
		(net "TWI_SDA3")
	)
	(via
		(at 264.477246 -28.5242)
		(size 0.7112)
		(drill 0.3556)
		(layers "F.Cu" "B.Cu")
		(net "TWI_SDA3")
	)
	(via
		(at 264.4902 -27.559)
		(size 0.508)
		(drill 0.254)
		(layers "F.Cu" "B.Cu")
		(net "TWI_SDA3")
	)
	(via
		(at 246.099838 -34.500058)
		(size 0.4572)
		(drill 0.2032)
		(layers "F.Cu" "B.Cu")
		(net "TWI_SDA3")
	)
	(segment
		(start 264.4902 -27.559)
		(end 264.4902 -28.511246)
		(width 0.12065)
		(layer "B.Cu")
		(net "TWI_SDA3")
	)
	(segment
		(start 264.4902 -28.511246)
		(end 264.477246 -28.5242)
		(width 0.12065)
		(layer "B.Cu")
		(net "TWI_SDA3")
	)
	(segment
		(start 246.834152 -32.898588)
		(end 246.493538 -33.239202)
		(width 0.1016)
		(layer "In2.Cu")
		(net "TWI_SDA3")
	)
	(segment
		(start 250.28271 -31.897574)
		(end 249.75439 -31.897574)
		(width 0.1016)
		(layer "In2.Cu")
		(net "TWI_SDA3")
	)
	(segment
		(start 250.8504 -30.897322)
		(end 250.501658 -31.246064)
		(width 0.1016)
		(layer "In2.Cu")
		(net "TWI_SDA3")
	)
	(segment
		(start 249.281696 -32.898588)
		(end 246.834152 -32.898588)
		(width 0.1016)
		(layer "In2.Cu")
		(net "TWI_SDA3")
	)
	(segment
		(start 249.502168 -32.678116)
		(end 249.281696 -32.898588)
		(width 0.1016)
		(layer "In2.Cu")
		(net "TWI_SDA3")
	)
	(segment
		(start 264.3124 -27.3812)
		(end 264.3124 -26.651712)
		(width 0.127)
		(layer "In2.Cu")
		(net "TWI_SDA3")
	)
	(segment
		(start 253.715266 -27.504136)
		(end 253.689866 -27.504136)
		(width 0.1016)
		(layer "In2.Cu")
		(net "TWI_SDA3")
	)
	(segment
		(start 251.496576 -29.12491)
		(end 251.496576 -30.67939)
		(width 0.1016)
		(layer "In2.Cu")
		(net "TWI_SDA3")
	)
	(segment
		(start 249.75439 -31.897574)
		(end 249.502168 -32.149796)
		(width 0.1016)
		(layer "In2.Cu")
		(net "TWI_SDA3")
	)
	(segment
		(start 264.4902 -27.559)
		(end 264.3124 -27.3812)
		(width 0.127)
		(layer "In2.Cu")
		(net "TWI_SDA3")
	)
	(segment
		(start 251.278644 -30.897322)
		(end 250.8504 -30.897322)
		(width 0.1016)
		(layer "In2.Cu")
		(net "TWI_SDA3")
	)
	(segment
		(start 255.735328 -25.795224)
		(end 254.026416 -27.504136)
		(width 0.127)
		(layer "In2.Cu")
		(net "TWI_SDA3")
	)
	(segment
		(start 253.537466 -27.656536)
		(end 252.96495 -27.656536)
		(width 0.1016)
		(layer "In2.Cu")
		(net "TWI_SDA3")
	)
	(segment
		(start 249.502168 -32.149796)
		(end 249.502168 -32.678116)
		(width 0.1016)
		(layer "In2.Cu")
		(net "TWI_SDA3")
	)
	(segment
		(start 246.493538 -34.106358)
		(end 246.099838 -34.500058)
		(width 0.1016)
		(layer "In2.Cu")
		(net "TWI_SDA3")
	)
	(segment
		(start 250.501658 -31.678626)
		(end 250.28271 -31.897574)
		(width 0.1016)
		(layer "In2.Cu")
		(net "TWI_SDA3")
	)
	(segment
		(start 251.496576 -30.67939)
		(end 251.278644 -30.897322)
		(width 0.1016)
		(layer "In2.Cu")
		(net "TWI_SDA3")
	)
	(segment
		(start 253.689866 -27.504136)
		(end 253.537466 -27.656536)
		(width 0.1016)
		(layer "In2.Cu")
		(net "TWI_SDA3")
	)
	(segment
		(start 264.3124 -26.651712)
		(end 263.455912 -25.795224)
		(width 0.127)
		(layer "In2.Cu")
		(net "TWI_SDA3")
	)
	(segment
		(start 254.026416 -27.504136)
		(end 253.715266 -27.504136)
		(width 0.127)
		(layer "In2.Cu")
		(net "TWI_SDA3")
	)
	(segment
		(start 263.455912 -25.795224)
		(end 255.735328 -25.795224)
		(width 0.127)
		(layer "In2.Cu")
		(net "TWI_SDA3")
	)
	(segment
		(start 252.96495 -27.656536)
		(end 251.496576 -29.12491)
		(width 0.1016)
		(layer "In2.Cu")
		(net "TWI_SDA3")
	)
	(segment
		(start 250.501658 -31.246064)
		(end 250.501658 -31.678626)
		(width 0.1016)
		(layer "In2.Cu")
		(net "TWI_SDA3")
	)
	(segment
		(start 246.493538 -33.239202)
		(end 246.493538 -34.106358)
		(width 0.1016)
		(layer "In2.Cu")
		(net "TWI_SDA3")
	)
	(segment
		(start 247.599962 -39.99992)
		(end 248.099834 -39.500048)
		(width 0.12065)
		(layer "F.Cu")
		(net "TWI_SCL6")
	)
	(via
		(at 248.099834 -39.500048)
		(size 0.4572)
		(drill 0.2032)
		(layers "F.Cu" "B.Cu")
		(net "TWI_SCL6")
	)
	(segment
		(start 247.599962 -39.99992)
		(end 248.099834 -39.500048)
		(width 0.12065)
		(layer "B.Cu")
		(net "TWI_SCL6")
	)
	(segment
		(start 248.59996 -36.999926)
		(end 249.099832 -36.500054)
		(width 0.12065)
		(layer "F.Cu")
		(net "TWI_SCL5")
	)
	(via
		(at 249.099832 -36.500054)
		(size 0.4572)
		(drill 0.2032)
		(layers "F.Cu" "B.Cu")
		(net "TWI_SCL5")
	)
	(segment
		(start 248.609104 -28.829)
		(end 248.758456 -28.679648)
		(width 0.1016)
		(layer "B.Cu")
		(net "TWI_SCL5")
	)
	(segment
		(start 248.758456 -28.654248)
		(end 248.758456 -26.490422)
		(width 0.12065)
		(layer "B.Cu")
		(net "TWI_SCL5")
	)
	(segment
		(start 248.696734 -30.252416)
		(end 248.609104 -30.164786)
		(width 0.1016)
		(layer "B.Cu")
		(net "TWI_SCL5")
	)
	(segment
		(start 248.758456 -28.679648)
		(end 248.758456 -28.654248)
		(width 0.1016)
		(layer "B.Cu")
		(net "TWI_SCL5")
	)
	(segment
		(start 249.428 -26.406348)
		(end 249.428 -26.67)
		(width 0.12065)
		(layer "B.Cu")
		(net "TWI_SCL5")
	)
	(segment
		(start 248.609104 -30.164786)
		(end 248.609104 -28.829)
		(width 0.1016)
		(layer "B.Cu")
		(net "TWI_SCL5")
	)
	(segment
		(start 249.099832 -36.500054)
		(end 248.696734 -36.096956)
		(width 0.1016)
		(layer "B.Cu")
		(net "TWI_SCL5")
	)
	(segment
		(start 249.30735 -26.285698)
		(end 249.428 -26.406348)
		(width 0.12065)
		(layer "B.Cu")
		(net "TWI_SCL5")
	)
	(segment
		(start 248.696734 -36.096956)
		(end 248.696734 -30.252416)
		(width 0.1016)
		(layer "B.Cu")
		(net "TWI_SCL5")
	)
	(segment
		(start 248.96318 -26.285698)
		(end 249.30735 -26.285698)
		(width 0.12065)
		(layer "B.Cu")
		(net "TWI_SCL5")
	)
	(segment
		(start 248.758456 -26.490422)
		(end 248.96318 -26.285698)
		(width 0.12065)
		(layer "B.Cu")
		(net "TWI_SCL5")
	)
	(segment
		(start 264.25525 -62.304676)
		(end 306.528724 -104.57815)
		(width 0.12065)
		(layer "F.Cu")
		(net "TWI_SCL3")
	)
	(segment
		(start 263.603232 -27.535632)
		(end 263.6266 -27.559)
		(width 0.12065)
		(layer "F.Cu")
		(net "TWI_SCL3")
	)
	(segment
		(start 263.398 -27.006042)
		(end 263.603232 -27.211274)
		(width 0.12065)
		(layer "F.Cu")
		(net "TWI_SCL3")
	)
	(segment
		(start 319.72758 -104.57815)
		(end 321.133216 -103.172514)
		(width 0.12065)
		(layer "F.Cu")
		(net "TWI_SCL3")
	)
	(segment
		(start 263.832848 -28.882848)
		(end 264.25525 -29.30525)
		(width 0.12065)
		(layer "F.Cu")
		(net "TWI_SCL3")
	)
	(segment
		(start 263.603232 -27.211274)
		(end 263.603232 -27.535632)
		(width 0.12065)
		(layer "F.Cu")
		(net "TWI_SCL3")
	)
	(segment
		(start 263.6266 -27.559)
		(end 263.832848 -27.765248)
		(width 0.12065)
		(layer "F.Cu")
		(net "TWI_SCL3")
	)
	(segment
		(start 321.133216 -103.172514)
		(end 321.133216 -100.316284)
		(width 0.12065)
		(layer "F.Cu")
		(net "TWI_SCL3")
	)
	(segment
		(start 263.398 -26.7335)
		(end 263.398 -27.006042)
		(width 0.12065)
		(layer "F.Cu")
		(net "TWI_SCL3")
	)
	(segment
		(start 321.133216 -100.316284)
		(end 321.437 -100.0125)
		(width 0.12065)
		(layer "F.Cu")
		(net "TWI_SCL3")
	)
	(segment
		(start 245.599966 -37.999924)
		(end 246.099838 -37.500052)
		(width 0.12065)
		(layer "F.Cu")
		(net "TWI_SCL3")
	)
	(segment
		(start 264.25525 -29.30525)
		(end 264.25525 -62.304676)
		(width 0.12065)
		(layer "F.Cu")
		(net "TWI_SCL3")
	)
	(segment
		(start 306.528724 -104.57815)
		(end 319.72758 -104.57815)
		(width 0.12065)
		(layer "F.Cu")
		(net "TWI_SCL3")
	)
	(segment
		(start 263.832848 -27.765248)
		(end 263.832848 -28.882848)
		(width 0.12065)
		(layer "F.Cu")
		(net "TWI_SCL3")
	)
	(via
		(at 263.6266 -27.559)
		(size 0.508)
		(drill 0.254)
		(layers "F.Cu" "B.Cu")
		(net "TWI_SCL3")
	)
	(via
		(at 246.099838 -37.500052)
		(size 0.4572)
		(drill 0.2032)
		(layers "F.Cu" "B.Cu")
		(net "TWI_SCL3")
	)
	(via
		(at 263.60501 -26.5938)
		(size 0.7112)
		(drill 0.3556)
		(layers "F.Cu" "B.Cu")
		(net "TWI_SCL3")
	)
	(segment
		(start 263.6266 -27.559)
		(end 263.60501 -27.53741)
		(width 0.12065)
		(layer "B.Cu")
		(net "TWI_SCL3")
	)
	(segment
		(start 263.60501 -27.53741)
		(end 263.60501 -26.5938)
		(width 0.12065)
		(layer "B.Cu")
		(net "TWI_SCL3")
	)
	(segment
		(start 251.699776 -29.209238)
		(end 251.699776 -30.763718)
		(width 0.1016)
		(layer "In2.Cu")
		(net "TWI_SCL3")
	)
	(segment
		(start 246.91848 -33.101788)
		(end 246.696738 -33.32353)
		(width 0.1016)
		(layer "In2.Cu")
		(net "TWI_SCL3")
	)
	(segment
		(start 251.362972 -31.100522)
		(end 250.934728 -31.100522)
		(width 0.1016)
		(layer "In2.Cu")
		(net "TWI_SCL3")
	)
	(segment
		(start 250.934728 -31.100522)
		(end 250.704858 -31.330392)
		(width 0.1016)
		(layer "In2.Cu")
		(net "TWI_SCL3")
	)
	(segment
		(start 251.699776 -30.763718)
		(end 251.362972 -31.100522)
		(width 0.1016)
		(layer "In2.Cu")
		(net "TWI_SCL3")
	)
	(segment
		(start 254.236982 -28.012136)
		(end 253.715266 -28.012136)
		(width 0.127)
		(layer "In2.Cu")
		(net "TWI_SCL3")
	)
	(segment
		(start 263.6266 -27.559)
		(end 263.8044 -27.3812)
		(width 0.127)
		(layer "In2.Cu")
		(net "TWI_SCL3")
	)
	(segment
		(start 249.705368 -32.234124)
		(end 249.705368 -32.762444)
		(width 0.1016)
		(layer "In2.Cu")
		(net "TWI_SCL3")
	)
	(segment
		(start 250.367038 -32.100774)
		(end 249.838718 -32.100774)
		(width 0.1016)
		(layer "In2.Cu")
		(net "TWI_SCL3")
	)
	(segment
		(start 253.689866 -28.012136)
		(end 253.537466 -27.859736)
		(width 0.1016)
		(layer "In2.Cu")
		(net "TWI_SCL3")
	)
	(segment
		(start 249.366024 -33.101788)
		(end 246.91848 -33.101788)
		(width 0.1016)
		(layer "In2.Cu")
		(net "TWI_SCL3")
	)
	(segment
		(start 263.8044 -27.3812)
		(end 263.8044 -26.862278)
		(width 0.127)
		(layer "In2.Cu")
		(net "TWI_SCL3")
	)
	(segment
		(start 246.696738 -33.32353)
		(end 246.696738 -36.903152)
		(width 0.1016)
		(layer "In2.Cu")
		(net "TWI_SCL3")
	)
	(segment
		(start 249.838718 -32.100774)
		(end 249.705368 -32.234124)
		(width 0.1016)
		(layer "In2.Cu")
		(net "TWI_SCL3")
	)
	(segment
		(start 253.715266 -28.012136)
		(end 253.689866 -28.012136)
		(width 0.1016)
		(layer "In2.Cu")
		(net "TWI_SCL3")
	)
	(segment
		(start 253.049278 -27.859736)
		(end 251.699776 -29.209238)
		(width 0.1016)
		(layer "In2.Cu")
		(net "TWI_SCL3")
	)
	(segment
		(start 249.705368 -32.762444)
		(end 249.366024 -33.101788)
		(width 0.1016)
		(layer "In2.Cu")
		(net "TWI_SCL3")
	)
	(segment
		(start 255.945894 -26.303224)
		(end 254.236982 -28.012136)
		(width 0.127)
		(layer "In2.Cu")
		(net "TWI_SCL3")
	)
	(segment
		(start 263.245346 -26.303224)
		(end 255.945894 -26.303224)
		(width 0.127)
		(layer "In2.Cu")
		(net "TWI_SCL3")
	)
	(segment
		(start 250.704858 -31.762954)
		(end 250.367038 -32.100774)
		(width 0.1016)
		(layer "In2.Cu")
		(net "TWI_SCL3")
	)
	(segment
		(start 246.696738 -36.903152)
		(end 246.099838 -37.500052)
		(width 0.1016)
		(layer "In2.Cu")
		(net "TWI_SCL3")
	)
	(segment
		(start 263.8044 -26.862278)
		(end 263.245346 -26.303224)
		(width 0.127)
		(layer "In2.Cu")
		(net "TWI_SCL3")
	)
	(segment
		(start 250.704858 -31.330392)
		(end 250.704858 -31.762954)
		(width 0.1016)
		(layer "In2.Cu")
		(net "TWI_SCL3")
	)
	(segment
		(start 253.537466 -27.859736)
		(end 253.049278 -27.859736)
		(width 0.1016)
		(layer "In2.Cu")
		(net "TWI_SCL3")
	)
	(segment
		(start 244.599968 -37.999924)
		(end 245.09984 -37.500052)
		(width 0.12065)
		(layer "F.Cu")
		(net "TPIN")
	)
	(via
		(at 245.09984 -37.500052)
		(size 0.4572)
		(drill 0.2032)
		(layers "F.Cu" "B.Cu")
		(net "TPIN")
	)
	(segment
		(start 245.599966 -37.999924)
		(end 245.100094 -37.500052)
		(width 0.12065)
		(layer "B.Cu")
		(net "TPIN")
	)
	(segment
		(start 245.100094 -37.500052)
		(end 245.09984 -37.500052)
		(width 0.12065)
		(layer "B.Cu")
		(net "TPIN")
	)
	(via
		(at 338.88553 -176.27727)
		(size 0.7112)
		(drill 0.3556)
		(layers "F.Cu" "B.Cu")
		(net "SSD_PERST_Y9")
	)
	(segment
		(start 338.074 -177.038)
		(end 338.566252 -177.038)
		(width 0.12065)
		(layer "B.Cu")
		(net "SSD_PERST_Y9")
	)
	(segment
		(start 338.79536 -176.1871)
		(end 338.88553 -176.27727)
		(width 0.12065)
		(layer "B.Cu")
		(net "SSD_PERST_Y9")
	)
	(segment
		(start 337.891628 -177.220372)
		(end 338.074 -177.038)
		(width 0.12065)
		(layer "B.Cu")
		(net "SSD_PERST_Y9")
	)
	(segment
		(start 337.891628 -177.982626)
		(end 337.891628 -177.220372)
		(width 0.12065)
		(layer "B.Cu")
		(net "SSD_PERST_Y9")
	)
	(segment
		(start 338.88553 -176.718722)
		(end 338.88553 -176.27727)
		(width 0.12065)
		(layer "B.Cu")
		(net "SSD_PERST_Y9")
	)
	(segment
		(start 337.9216 -176.1871)
		(end 338.79536 -176.1871)
		(width 0.12065)
		(layer "B.Cu")
		(net "SSD_PERST_Y9")
	)
	(segment
		(start 338.566252 -177.038)
		(end 338.88553 -176.718722)
		(width 0.12065)
		(layer "B.Cu")
		(net "SSD_PERST_Y9")
	)
	(via
		(at 225.171 -194.31)
		(size 0.7112)
		(drill 0.3556)
		(layers "F.Cu" "B.Cu")
		(net "SSD_PERST_Y8")
	)
	(segment
		(start 224.736152 -194.31)
		(end 225.171 -194.31)
		(width 0.12065)
		(layer "B.Cu")
		(net "SSD_PERST_Y8")
	)
	(segment
		(start 224.04324 -196.1515)
		(end 224.5995 -196.1515)
		(width 0.12065)
		(layer "B.Cu")
		(net "SSD_PERST_Y8")
	)
	(segment
		(start 225.015298 -195.735702)
		(end 225.015298 -194.769994)
		(width 0.12065)
		(layer "B.Cu")
		(net "SSD_PERST_Y8")
	)
	(segment
		(start 225.015298 -194.769994)
		(end 225.171 -194.614292)
		(width 0.12065)
		(layer "B.Cu")
		(net "SSD_PERST_Y8")
	)
	(segment
		(start 224.079562 -194.49923)
		(end 224.546922 -194.49923)
		(width 0.12065)
		(layer "B.Cu")
		(net "SSD_PERST_Y8")
	)
	(segment
		(start 224.546922 -194.49923)
		(end 224.736152 -194.31)
		(width 0.12065)
		(layer "B.Cu")
		(net "SSD_PERST_Y8")
	)
	(segment
		(start 224.5995 -196.1515)
		(end 225.015298 -195.735702)
		(width 0.12065)
		(layer "B.Cu")
		(net "SSD_PERST_Y8")
	)
	(segment
		(start 225.171 -194.614292)
		(end 225.171 -194.31)
		(width 0.12065)
		(layer "B.Cu")
		(net "SSD_PERST_Y8")
	)
	(via
		(at 125.984 -200.152)
		(size 0.7112)
		(drill 0.3556)
		(layers "F.Cu" "B.Cu")
		(net "SSD_PERST_Y7")
	)
	(segment
		(start 124.9426 -200.1901)
		(end 125.9459 -200.1901)
		(width 0.12065)
		(layer "B.Cu")
		(net "SSD_PERST_Y7")
	)
	(segment
		(start 124.912628 -201.985626)
		(end 125.396244 -201.985626)
		(width 0.12065)
		(layer "B.Cu")
		(net "SSD_PERST_Y7")
	)
	(segment
		(start 125.984 -201.39787)
		(end 125.984 -200.152)
		(width 0.12065)
		(layer "B.Cu")
		(net "SSD_PERST_Y7")
	)
	(segment
		(start 125.9459 -200.1901)
		(end 125.984 -200.152)
		(width 0.12065)
		(layer "B.Cu")
		(net "SSD_PERST_Y7")
	)
	(segment
		(start 125.396244 -201.985626)
		(end 125.984 -201.39787)
		(width 0.12065)
		(layer "B.Cu")
		(net "SSD_PERST_Y7")
	)
	(via
		(at 138.684 -201.422)
		(size 0.7112)
		(drill 0.3556)
		(layers "F.Cu" "B.Cu")
		(net "SSD_PERST_Y6")
	)
	(segment
		(start 138.1125 -201.9935)
		(end 138.684 -201.422)
		(width 0.12065)
		(layer "B.Cu")
		(net "SSD_PERST_Y6")
	)
	(segment
		(start 138.684 -200.66)
		(end 138.684 -201.422)
		(width 0.12065)
		(layer "B.Cu")
		(net "SSD_PERST_Y6")
	)
	(segment
		(start 137.30224 -201.9935)
		(end 138.1125 -201.9935)
		(width 0.12065)
		(layer "B.Cu")
		(net "SSD_PERST_Y6")
	)
	(segment
		(start 137.332212 -200.197974)
		(end 138.221974 -200.197974)
		(width 0.12065)
		(layer "B.Cu")
		(net "SSD_PERST_Y6")
	)
	(segment
		(start 138.221974 -200.197974)
		(end 138.684 -200.66)
		(width 0.12065)
		(layer "B.Cu")
		(net "SSD_PERST_Y6")
	)
	(via
		(at 80.144874 -186.640978)
		(size 0.7112)
		(drill 0.3556)
		(layers "F.Cu" "B.Cu")
		(net "SSD_PERST_Y5")
	)
	(segment
		(start 79.166212 -186.989974)
		(end 79.515208 -186.640978)
		(width 0.12065)
		(layer "B.Cu")
		(net "SSD_PERST_Y5")
	)
	(segment
		(start 79.13624 -188.7855)
		(end 79.13624 -187.019946)
		(width 0.12065)
		(layer "B.Cu")
		(net "SSD_PERST_Y5")
	)
	(segment
		(start 79.515208 -186.640978)
		(end 80.144874 -186.640978)
		(width 0.12065)
		(layer "B.Cu")
		(net "SSD_PERST_Y5")
	)
	(segment
		(start 79.13624 -187.019946)
		(end 79.166212 -186.989974)
		(width 0.12065)
		(layer "B.Cu")
		(net "SSD_PERST_Y5")
	)
	(via
		(at 334.645 -176.53)
		(size 0.7112)
		(drill 0.3556)
		(layers "F.Cu" "B.Cu")
		(net "SSD_PERST_Y4")
	)
	(segment
		(start 334.645 -177.18913)
		(end 334.645 -176.53)
		(width 0.12065)
		(layer "B.Cu")
		(net "SSD_PERST_Y4")
	)
	(segment
		(start 333.446628 -177.855626)
		(end 333.978504 -177.855626)
		(width 0.12065)
		(layer "B.Cu")
		(net "SSD_PERST_Y4")
	)
	(segment
		(start 334.3021 -176.1871)
		(end 334.645 -176.53)
		(width 0.12065)
		(layer "B.Cu")
		(net "SSD_PERST_Y4")
	)
	(segment
		(start 333.978504 -177.855626)
		(end 334.645 -177.18913)
		(width 0.12065)
		(layer "B.Cu")
		(net "SSD_PERST_Y4")
	)
	(segment
		(start 333.4766 -176.1871)
		(end 334.3021 -176.1871)
		(width 0.12065)
		(layer "B.Cu")
		(net "SSD_PERST_Y4")
	)
	(via
		(at 220.38056 -193.51752)
		(size 0.7112)
		(drill 0.3556)
		(layers "F.Cu" "B.Cu")
		(net "SSD_PERST_Y3")
	)
	(segment
		(start 220.48724 -195.3768)
		(end 220.1291 -195.01866)
		(width 0.12065)
		(layer "B.Cu")
		(net "SSD_PERST_Y3")
	)
	(segment
		(start 220.1291 -194.5132)
		(end 220.1291 -193.76898)
		(width 0.12065)
		(layer "B.Cu")
		(net "SSD_PERST_Y3")
	)
	(segment
		(start 220.48724 -196.1515)
		(end 220.48724 -195.3768)
		(width 0.12065)
		(layer "B.Cu")
		(net "SSD_PERST_Y3")
	)
	(segment
		(start 220.1291 -195.01866)
		(end 220.1291 -194.5132)
		(width 0.12065)
		(layer "B.Cu")
		(net "SSD_PERST_Y3")
	)
	(segment
		(start 220.1291 -193.76898)
		(end 220.38056 -193.51752)
		(width 0.12065)
		(layer "B.Cu")
		(net "SSD_PERST_Y3")
	)
	(via
		(at 134.239 -200.152)
		(size 0.7112)
		(drill 0.3556)
		(layers "F.Cu" "B.Cu")
		(net "SSD_PERST_Y2")
	)
	(segment
		(start 133.23824 -201.9935)
		(end 133.23824 -200.227946)
		(width 0.12065)
		(layer "B.Cu")
		(net "SSD_PERST_Y2")
	)
	(segment
		(start 133.314186 -200.152)
		(end 134.239 -200.152)
		(width 0.12065)
		(layer "B.Cu")
		(net "SSD_PERST_Y2")
	)
	(segment
		(start 133.23824 -200.227946)
		(end 133.268212 -200.197974)
		(width 0.12065)
		(layer "B.Cu")
		(net "SSD_PERST_Y2")
	)
	(segment
		(start 133.268212 -200.197974)
		(end 133.314186 -200.152)
		(width 0.12065)
		(layer "B.Cu")
		(net "SSD_PERST_Y2")
	)
	(via
		(at 343.408 -177.292)
		(size 0.7112)
		(drill 0.3556)
		(layers "F.Cu" "B.Cu")
		(net "SSD_PERST_Y14")
	)
	(segment
		(start 342.1126 -176.1871)
		(end 342.9381 -176.1871)
		(width 0.12065)
		(layer "B.Cu")
		(net "SSD_PERST_Y14")
	)
	(segment
		(start 343.225374 -177.982626)
		(end 343.408 -177.8)
		(width 0.12065)
		(layer "B.Cu")
		(net "SSD_PERST_Y14")
	)
	(segment
		(start 343.408 -177.8)
		(end 343.408 -177.292)
		(width 0.12065)
		(layer "B.Cu")
		(net "SSD_PERST_Y14")
	)
	(segment
		(start 342.082628 -177.982626)
		(end 343.225374 -177.982626)
		(width 0.12065)
		(layer "B.Cu")
		(net "SSD_PERST_Y14")
	)
	(segment
		(start 342.9381 -176.1871)
		(end 343.408 -176.657)
		(width 0.12065)
		(layer "B.Cu")
		(net "SSD_PERST_Y14")
	)
	(segment
		(start 343.408 -176.657)
		(end 343.408 -177.292)
		(width 0.12065)
		(layer "B.Cu")
		(net "SSD_PERST_Y14")
	)
	(via
		(at 217.570304 -195.013834)
		(size 0.7112)
		(drill 0.3556)
		(layers "F.Cu" "B.Cu")
		(net "SSD_PERST_Y13")
	)
	(segment
		(start 216.577926 -196.045328)
		(end 216.577926 -196.006212)
		(width 0.12065)
		(layer "B.Cu")
		(net "SSD_PERST_Y13")
	)
	(segment
		(start 217.03157 -194.4751)
		(end 217.570304 -195.013834)
		(width 0.12065)
		(layer "B.Cu")
		(net "SSD_PERST_Y13")
	)
	(segment
		(start 216.352628 -196.270626)
		(end 216.577926 -196.045328)
		(width 0.12065)
		(layer "B.Cu")
		(net "SSD_PERST_Y13")
	)
	(segment
		(start 216.577926 -196.006212)
		(end 217.570304 -195.013834)
		(width 0.12065)
		(layer "B.Cu")
		(net "SSD_PERST_Y13")
	)
	(segment
		(start 216.5096 -194.4751)
		(end 217.03157 -194.4751)
		(width 0.12065)
		(layer "B.Cu")
		(net "SSD_PERST_Y13")
	)
	(via
		(at 228.235764 -193.40322)
		(size 0.7112)
		(drill 0.3556)
		(layers "F.Cu" "B.Cu")
		(net "SSD_PERST_Y12")
	)
	(segment
		(start 227.7237 -193.915284)
		(end 227.7237 -194.4116)
		(width 0.12065)
		(layer "B.Cu")
		(net "SSD_PERST_Y12")
	)
	(segment
		(start 228.10724 -194.79514)
		(end 228.10724 -196.1515)
		(width 0.12065)
		(layer "B.Cu")
		(net "SSD_PERST_Y12")
	)
	(segment
		(start 228.235764 -193.40322)
		(end 227.7237 -193.915284)
		(width 0.12065)
		(layer "B.Cu")
		(net "SSD_PERST_Y12")
	)
	(segment
		(start 227.7237 -194.4116)
		(end 228.10724 -194.79514)
		(width 0.12065)
		(layer "B.Cu")
		(net "SSD_PERST_Y12")
	)
	(via
		(at 71.883016 -187.708286)
		(size 0.7112)
		(drill 0.3556)
		(layers "F.Cu" "B.Cu")
		(net "SSD_PERST_Y11")
	)
	(segment
		(start 71.313548 -187.138818)
		(end 71.883016 -187.708286)
		(width 0.12065)
		(layer "B.Cu")
		(net "SSD_PERST_Y11")
	)
	(segment
		(start 71.445374 -188.777626)
		(end 71.931784 -188.291216)
		(width 0.12065)
		(layer "B.Cu")
		(net "SSD_PERST_Y11")
	)
	(segment
		(start 71.931784 -187.708286)
		(end 71.883016 -187.708286)
		(width 0.12065)
		(layer "B.Cu")
		(net "SSD_PERST_Y11")
	)
	(segment
		(start 70.683628 -188.777626)
		(end 71.445374 -188.777626)
		(width 0.12065)
		(layer "B.Cu")
		(net "SSD_PERST_Y11")
	)
	(segment
		(start 71.931784 -188.291216)
		(end 71.931784 -187.708286)
		(width 0.12065)
		(layer "B.Cu")
		(net "SSD_PERST_Y11")
	)
	(segment
		(start 70.6247 -187.138818)
		(end 71.313548 -187.138818)
		(width 0.12065)
		(layer "B.Cu")
		(net "SSD_PERST_Y11")
	)
	(via
		(at 84.455 -187.833)
		(size 0.7112)
		(drill 0.3556)
		(layers "F.Cu" "B.Cu")
		(net "SSD_PERST_Y10")
	)
	(segment
		(start 84.455 -188.214)
		(end 84.455 -187.833)
		(width 0.12065)
		(layer "B.Cu")
		(net "SSD_PERST_Y10")
	)
	(segment
		(start 83.20024 -188.7855)
		(end 83.8835 -188.7855)
		(width 0.12065)
		(layer "B.Cu")
		(net "SSD_PERST_Y10")
	)
	(segment
		(start 83.230212 -186.989974)
		(end 83.611974 -186.989974)
		(width 0.12065)
		(layer "B.Cu")
		(net "SSD_PERST_Y10")
	)
	(segment
		(start 83.611974 -186.989974)
		(end 84.455 -187.833)
		(width 0.12065)
		(layer "B.Cu")
		(net "SSD_PERST_Y10")
	)
	(segment
		(start 83.8835 -188.7855)
		(end 84.455 -188.214)
		(width 0.12065)
		(layer "B.Cu")
		(net "SSD_PERST_Y10")
	)
	(via
		(at 129.2098 -199.3138)
		(size 0.7112)
		(drill 0.3556)
		(layers "F.Cu" "B.Cu")
		(net "SSD_PERST_Y1")
	)
	(segment
		(start 129.6543 -199.7583)
		(end 129.2098 -199.3138)
		(width 0.12065)
		(layer "B.Cu")
		(net "SSD_PERST_Y1")
	)
	(segment
		(start 129.6543 -200.3298)
		(end 129.6543 -199.7583)
		(width 0.12065)
		(layer "B.Cu")
		(net "SSD_PERST_Y1")
	)
	(segment
		(start 129.17424 -201.9935)
		(end 129.17424 -201.1426)
		(width 0.12065)
		(layer "B.Cu")
		(net "SSD_PERST_Y1")
	)
	(segment
		(start 129.6543 -200.66254)
		(end 129.6543 -200.3298)
		(width 0.12065)
		(layer "B.Cu")
		(net "SSD_PERST_Y1")
	)
	(segment
		(start 129.17424 -201.1426)
		(end 129.6543 -200.66254)
		(width 0.12065)
		(layer "B.Cu")
		(net "SSD_PERST_Y1")
	)
	(via
		(at 76.073 -186.944)
		(size 0.7112)
		(drill 0.3556)
		(layers "F.Cu" "B.Cu")
		(net "SSD_PERST_Y0")
	)
	(segment
		(start 75.07224 -187.775088)
		(end 75.102212 -187.745116)
		(width 0.12065)
		(layer "B.Cu")
		(net "SSD_PERST_Y0")
	)
	(segment
		(start 75.532742 -186.944)
		(end 76.073 -186.944)
		(width 0.12065)
		(layer "B.Cu")
		(net "SSD_PERST_Y0")
	)
	(segment
		(start 75.102212 -187.745116)
		(end 75.102212 -186.989974)
		(width 0.12065)
		(layer "B.Cu")
		(net "SSD_PERST_Y0")
	)
	(segment
		(start 75.07224 -188.7855)
		(end 75.07224 -187.775088)
		(width 0.12065)
		(layer "B.Cu")
		(net "SSD_PERST_Y0")
	)
	(segment
		(start 75.102212 -186.989974)
		(end 75.486768 -186.989974)
		(width 0.12065)
		(layer "B.Cu")
		(net "SSD_PERST_Y0")
	)
	(segment
		(start 75.486768 -186.989974)
		(end 75.532742 -186.944)
		(width 0.12065)
		(layer "B.Cu")
		(net "SSD_PERST_Y0")
	)
	(via
		(at 338.744306 -181.882796)
		(size 0.7112)
		(drill 0.3556)
		(layers "F.Cu" "B.Cu")
		(net "SSD_PERST#0_B9")
	)
	(segment
		(start 338.283296 -181.882796)
		(end 338.744306 -181.882796)
		(width 0.12065)
		(layer "B.Cu")
		(net "SSD_PERST#0_B9")
	)
	(segment
		(start 337.566 -180.594)
		(end 338.368386 -180.594)
		(width 0.12065)
		(layer "B.Cu")
		(net "SSD_PERST#0_B9")
	)
	(segment
		(start 337.7946 -181.3941)
		(end 338.283296 -181.882796)
		(width 0.12065)
		(layer "B.Cu")
		(net "SSD_PERST#0_B9")
	)
	(segment
		(start 338.749386 -181.877716)
		(end 338.744306 -181.882796)
		(width 0.12065)
		(layer "B.Cu")
		(net "SSD_PERST#0_B9")
	)
	(segment
		(start 337.241388 -180.269388)
		(end 337.566 -180.594)
		(width 0.12065)
		(layer "B.Cu")
		(net "SSD_PERST#0_B9")
	)
	(segment
		(start 337.241388 -179.633626)
		(end 337.241388 -180.269388)
		(width 0.12065)
		(layer "B.Cu")
		(net "SSD_PERST#0_B9")
	)
	(segment
		(start 338.368386 -180.594)
		(end 338.749386 -180.975)
		(width 0.12065)
		(layer "B.Cu")
		(net "SSD_PERST#0_B9")
	)
	(segment
		(start 338.749386 -180.975)
		(end 338.749386 -181.877716)
		(width 0.12065)
		(layer "B.Cu")
		(net "SSD_PERST#0_B9")
	)
	(via
		(at 224.17786 -199.93102)
		(size 0.7112)
		(drill 0.3556)
		(layers "F.Cu" "B.Cu")
		(net "SSD_PERST#0_B8")
	)
	(segment
		(start 224.17786 -199.93102)
		(end 224.17786 -199.13346)
		(width 0.12065)
		(layer "B.Cu")
		(net "SSD_PERST#0_B8")
	)
	(segment
		(start 224.17786 -200.35012)
		(end 224.17786 -199.93102)
		(width 0.12065)
		(layer "B.Cu")
		(net "SSD_PERST#0_B8")
	)
	(segment
		(start 223.12884 -201.39914)
		(end 224.17786 -200.35012)
		(width 0.12065)
		(layer "B.Cu")
		(net "SSD_PERST#0_B8")
	)
	(segment
		(start 224.17786 -199.13346)
		(end 223.393 -198.3486)
		(width 0.12065)
		(layer "B.Cu")
		(net "SSD_PERST#0_B8")
	)
	(segment
		(start 223.393 -198.3486)
		(end 223.393 -197.8025)
		(width 0.12065)
		(layer "B.Cu")
		(net "SSD_PERST#0_B8")
	)
	(via
		(at 122.3264 -202.3872)
		(size 0.7112)
		(drill 0.3556)
		(layers "F.Cu" "B.Cu")
		(net "SSD_PERST#0_B7")
	)
	(segment
		(start 123.892818 -202.839574)
		(end 122.778774 -202.839574)
		(width 0.12065)
		(layer "B.Cu")
		(net "SSD_PERST#0_B7")
	)
	(segment
		(start 124.262388 -203.636626)
		(end 124.262388 -203.209144)
		(width 0.12065)
		(layer "B.Cu")
		(net "SSD_PERST#0_B7")
	)
	(segment
		(start 124.262388 -204.462888)
		(end 124.262388 -203.636626)
		(width 0.12065)
		(layer "B.Cu")
		(net "SSD_PERST#0_B7")
	)
	(segment
		(start 124.262388 -203.209144)
		(end 123.892818 -202.839574)
		(width 0.12065)
		(layer "B.Cu")
		(net "SSD_PERST#0_B7")
	)
	(segment
		(start 122.778774 -202.839574)
		(end 122.3264 -202.3872)
		(width 0.12065)
		(layer "B.Cu")
		(net "SSD_PERST#0_B7")
	)
	(segment
		(start 125.095 -205.2955)
		(end 124.262388 -204.462888)
		(width 0.12065)
		(layer "B.Cu")
		(net "SSD_PERST#0_B7")
	)
	(via
		(at 138.7348 -203.1492)
		(size 0.7112)
		(drill 0.3556)
		(layers "F.Cu" "B.Cu")
		(net "SSD_PERST#0_B6")
	)
	(segment
		(start 136.652 -203.6445)
		(end 136.652 -203.072746)
		(width 0.12065)
		(layer "B.Cu")
		(net "SSD_PERST#0_B6")
	)
	(segment
		(start 136.934194 -202.790552)
		(end 138.376152 -202.790552)
		(width 0.12065)
		(layer "B.Cu")
		(net "SSD_PERST#0_B6")
	)
	(segment
		(start 138.376152 -202.790552)
		(end 138.7348 -203.1492)
		(width 0.12065)
		(layer "B.Cu")
		(net "SSD_PERST#0_B6")
	)
	(segment
		(start 136.824212 -205.404974)
		(end 136.824212 -204.851)
		(width 0.12065)
		(layer "B.Cu")
		(net "SSD_PERST#0_B6")
	)
	(segment
		(start 136.652 -204.678788)
		(end 136.652 -203.6445)
		(width 0.12065)
		(layer "B.Cu")
		(net "SSD_PERST#0_B6")
	)
	(segment
		(start 136.824212 -204.851)
		(end 136.652 -204.678788)
		(width 0.12065)
		(layer "B.Cu")
		(net "SSD_PERST#0_B6")
	)
	(segment
		(start 136.652 -203.072746)
		(end 136.934194 -202.790552)
		(width 0.12065)
		(layer "B.Cu")
		(net "SSD_PERST#0_B6")
	)
	(via
		(at 80.0354 -192.3796)
		(size 0.7112)
		(drill 0.3556)
		(layers "F.Cu" "B.Cu")
		(net "SSD_PERST#0_B5")
	)
	(segment
		(start 78.486 -190.4365)
		(end 78.486 -191.643762)
		(width 0.12065)
		(layer "B.Cu")
		(net "SSD_PERST#0_B5")
	)
	(segment
		(start 79.039212 -192.196974)
		(end 79.221838 -192.3796)
		(width 0.12065)
		(layer "B.Cu")
		(net "SSD_PERST#0_B5")
	)
	(segment
		(start 79.221838 -192.3796)
		(end 80.0354 -192.3796)
		(width 0.12065)
		(layer "B.Cu")
		(net "SSD_PERST#0_B5")
	)
	(segment
		(start 78.486 -191.643762)
		(end 79.039212 -192.196974)
		(width 0.12065)
		(layer "B.Cu")
		(net "SSD_PERST#0_B5")
	)
	(via
		(at 334.01 -181.356)
		(size 0.7112)
		(drill 0.3556)
		(layers "F.Cu" "B.Cu")
		(net "SSD_PERST#0_B4")
	)
	(segment
		(start 332.796388 -180.213)
		(end 332.923388 -180.34)
		(width 0.12065)
		(layer "B.Cu")
		(net "SSD_PERST#0_B4")
	)
	(segment
		(start 332.923388 -180.34)
		(end 333.502 -180.34)
		(width 0.12065)
		(layer "B.Cu")
		(net "SSD_PERST#0_B4")
	)
	(segment
		(start 334.01 -180.848)
		(end 334.01 -181.356)
		(width 0.12065)
		(layer "B.Cu")
		(net "SSD_PERST#0_B4")
	)
	(segment
		(start 333.0575 -181.356)
		(end 334.01 -181.356)
		(width 0.12065)
		(layer "B.Cu")
		(net "SSD_PERST#0_B4")
	)
	(segment
		(start 333.502 -180.34)
		(end 334.01 -180.848)
		(width 0.12065)
		(layer "B.Cu")
		(net "SSD_PERST#0_B4")
	)
	(segment
		(start 332.9686 -181.2671)
		(end 333.0575 -181.356)
		(width 0.12065)
		(layer "B.Cu")
		(net "SSD_PERST#0_B4")
	)
	(segment
		(start 332.796388 -179.506626)
		(end 332.796388 -180.213)
		(width 0.12065)
		(layer "B.Cu")
		(net "SSD_PERST#0_B4")
	)
	(via
		(at 219.493338 -199.413622)
		(size 0.7112)
		(drill 0.3556)
		(layers "F.Cu" "B.Cu")
		(net "SSD_PERST#0_B3")
	)
	(segment
		(start 219.837 -199.06996)
		(end 219.493338 -199.413622)
		(width 0.12065)
		(layer "B.Cu")
		(net "SSD_PERST#0_B3")
	)
	(segment
		(start 219.15374 -199.75322)
		(end 219.493338 -199.413622)
		(width 0.12065)
		(layer "B.Cu")
		(net "SSD_PERST#0_B3")
	)
	(segment
		(start 219.837 -197.8025)
		(end 219.837 -199.06996)
		(width 0.12065)
		(layer "B.Cu")
		(net "SSD_PERST#0_B3")
	)
	(segment
		(start 219.15374 -200.37552)
		(end 219.15374 -199.75322)
		(width 0.12065)
		(layer "B.Cu")
		(net "SSD_PERST#0_B3")
	)
	(via
		(at 134.098792 -205.64348)
		(size 0.7112)
		(drill 0.3556)
		(layers "F.Cu" "B.Cu")
		(net "SSD_PERST#0_B2")
	)
	(segment
		(start 132.588 -204.851762)
		(end 133.141212 -205.404974)
		(width 0.12065)
		(layer "B.Cu")
		(net "SSD_PERST#0_B2")
	)
	(segment
		(start 133.379718 -205.64348)
		(end 134.098792 -205.64348)
		(width 0.12065)
		(layer "B.Cu")
		(net "SSD_PERST#0_B2")
	)
	(segment
		(start 133.141212 -205.404974)
		(end 133.379718 -205.64348)
		(width 0.12065)
		(layer "B.Cu")
		(net "SSD_PERST#0_B2")
	)
	(segment
		(start 132.588 -203.6445)
		(end 132.588 -204.851762)
		(width 0.12065)
		(layer "B.Cu")
		(net "SSD_PERST#0_B2")
	)
	(via
		(at 343.408 -179.959)
		(size 0.7112)
		(drill 0.3556)
		(layers "F.Cu" "B.Cu")
		(net "SSD_PERST#0_B14")
	)
	(segment
		(start 341.609426 -178.836574)
		(end 343.044018 -178.836574)
		(width 0.12065)
		(layer "B.Cu")
		(net "SSD_PERST#0_B14")
	)
	(segment
		(start 341.6046 -181.3941)
		(end 341.779352 -181.568852)
		(width 0.12065)
		(layer "B.Cu")
		(net "SSD_PERST#0_B14")
	)
	(segment
		(start 341.779352 -181.568852)
		(end 342.941148 -181.568852)
		(width 0.12065)
		(layer "B.Cu")
		(net "SSD_PERST#0_B14")
	)
	(segment
		(start 341.432388 -179.013612)
		(end 341.609426 -178.836574)
		(width 0.12065)
		(layer "B.Cu")
		(net "SSD_PERST#0_B14")
	)
	(segment
		(start 343.408 -181.102)
		(end 343.408 -179.959)
		(width 0.12065)
		(layer "B.Cu")
		(net "SSD_PERST#0_B14")
	)
	(segment
		(start 343.044018 -178.836574)
		(end 343.408 -179.200556)
		(width 0.12065)
		(layer "B.Cu")
		(net "SSD_PERST#0_B14")
	)
	(segment
		(start 341.432388 -179.633626)
		(end 341.432388 -179.013612)
		(width 0.12065)
		(layer "B.Cu")
		(net "SSD_PERST#0_B14")
	)
	(segment
		(start 342.941148 -181.568852)
		(end 343.408 -181.102)
		(width 0.12065)
		(layer "B.Cu")
		(net "SSD_PERST#0_B14")
	)
	(segment
		(start 343.408 -179.200556)
		(end 343.408 -179.959)
		(width 0.12065)
		(layer "B.Cu")
		(net "SSD_PERST#0_B14")
	)
	(via
		(at 213.60384 -199.45604)
		(size 0.7112)
		(drill 0.3556)
		(layers "F.Cu" "B.Cu")
		(net "SSD_PERST#0_B13")
	)
	(segment
		(start 215.702388 -197.921626)
		(end 215.702388 -198.553832)
		(width 0.12065)
		(layer "B.Cu")
		(net "SSD_PERST#0_B13")
	)
	(segment
		(start 214.43442 -199.45604)
		(end 214.58174 -199.60336)
		(width 0.12065)
		(layer "B.Cu")
		(net "SSD_PERST#0_B13")
	)
	(segment
		(start 215.702388 -198.553832)
		(end 214.65286 -199.60336)
		(width 0.12065)
		(layer "B.Cu")
		(net "SSD_PERST#0_B13")
	)
	(segment
		(start 213.60384 -199.45604)
		(end 214.43442 -199.45604)
		(width 0.12065)
		(layer "B.Cu")
		(net "SSD_PERST#0_B13")
	)
	(segment
		(start 214.65286 -199.60336)
		(end 214.58174 -199.60336)
		(width 0.12065)
		(layer "B.Cu")
		(net "SSD_PERST#0_B13")
	)
	(via
		(at 228.6 -199.644)
		(size 0.7112)
		(drill 0.3556)
		(layers "F.Cu" "B.Cu")
		(net "SSD_PERST#0_B12")
	)
	(segment
		(start 227.457 -198.501)
		(end 227.711 -198.755)
		(width 0.12065)
		(layer "B.Cu")
		(net "SSD_PERST#0_B12")
	)
	(segment
		(start 228.6 -199.136)
		(end 228.6 -199.644)
		(width 0.12065)
		(layer "B.Cu")
		(net "SSD_PERST#0_B12")
	)
	(segment
		(start 227.710238 -199.644)
		(end 228.6 -199.644)
		(width 0.12065)
		(layer "B.Cu")
		(net "SSD_PERST#0_B12")
	)
	(segment
		(start 227.629212 -199.562974)
		(end 227.710238 -199.644)
		(width 0.12065)
		(layer "B.Cu")
		(net "SSD_PERST#0_B12")
	)
	(segment
		(start 227.711 -198.755)
		(end 228.219 -198.755)
		(width 0.12065)
		(layer "B.Cu")
		(net "SSD_PERST#0_B12")
	)
	(segment
		(start 227.457 -197.8025)
		(end 227.457 -198.501)
		(width 0.12065)
		(layer "B.Cu")
		(net "SSD_PERST#0_B12")
	)
	(segment
		(start 228.219 -198.755)
		(end 228.6 -199.136)
		(width 0.12065)
		(layer "B.Cu")
		(net "SSD_PERST#0_B12")
	)
	(via
		(at 70.0786 -192.011554)
		(size 0.7112)
		(drill 0.3556)
		(layers "F.Cu" "B.Cu")
		(net "SSD_PERST#0_B11")
	)
	(segment
		(start 70.033388 -191.966342)
		(end 70.0786 -192.011554)
		(width 0.12065)
		(layer "B.Cu")
		(net "SSD_PERST#0_B11")
	)
	(segment
		(start 70.154546 -192.0875)
		(end 70.0786 -192.011554)
		(width 0.12065)
		(layer "B.Cu")
		(net "SSD_PERST#0_B11")
	)
	(segment
		(start 70.033388 -190.428626)
		(end 70.033388 -191.966342)
		(width 0.12065)
		(layer "B.Cu")
		(net "SSD_PERST#0_B11")
	)
	(segment
		(start 70.993 -192.0875)
		(end 70.154546 -192.0875)
		(width 0.12065)
		(layer "B.Cu")
		(net "SSD_PERST#0_B11")
	)
	(via
		(at 83.71205 -192.59042)
		(size 0.7112)
		(drill 0.3556)
		(layers "F.Cu" "B.Cu")
		(net "SSD_PERST#0_B10")
	)
	(segment
		(start 83.115658 -192.59042)
		(end 83.71205 -192.59042)
		(width 0.12065)
		(layer "B.Cu")
		(net "SSD_PERST#0_B10")
	)
	(segment
		(start 82.722212 -192.196974)
		(end 83.115658 -192.59042)
		(width 0.12065)
		(layer "B.Cu")
		(net "SSD_PERST#0_B10")
	)
	(segment
		(start 82.55 -192.024762)
		(end 82.722212 -192.196974)
		(width 0.12065)
		(layer "B.Cu")
		(net "SSD_PERST#0_B10")
	)
	(segment
		(start 82.55 -190.4365)
		(end 82.55 -192.024762)
		(width 0.12065)
		(layer "B.Cu")
		(net "SSD_PERST#0_B10")
	)
	(via
		(at 129.667 -205.359)
		(size 0.7112)
		(drill 0.3556)
		(layers "F.Cu" "B.Cu")
		(net "SSD_PERST#0_B1")
	)
	(segment
		(start 129.413 -205.613)
		(end 129.667 -205.359)
		(width 0.12065)
		(layer "B.Cu")
		(net "SSD_PERST#0_B1")
	)
	(segment
		(start 128.778 -204.597)
		(end 129.286 -204.597)
		(width 0.12065)
		(layer "B.Cu")
		(net "SSD_PERST#0_B1")
	)
	(segment
		(start 128.524 -203.6445)
		(end 128.524 -204.343)
		(width 0.12065)
		(layer "B.Cu")
		(net "SSD_PERST#0_B1")
	)
	(segment
		(start 128.524 -204.343)
		(end 128.778 -204.597)
		(width 0.12065)
		(layer "B.Cu")
		(net "SSD_PERST#0_B1")
	)
	(segment
		(start 129.286 -204.597)
		(end 129.667 -204.978)
		(width 0.12065)
		(layer "B.Cu")
		(net "SSD_PERST#0_B1")
	)
	(segment
		(start 128.696212 -205.404974)
		(end 128.904238 -205.613)
		(width 0.12065)
		(layer "B.Cu")
		(net "SSD_PERST#0_B1")
	)
	(segment
		(start 128.904238 -205.613)
		(end 129.413 -205.613)
		(width 0.12065)
		(layer "B.Cu")
		(net "SSD_PERST#0_B1")
	)
	(segment
		(start 129.667 -204.978)
		(end 129.667 -205.359)
		(width 0.12065)
		(layer "B.Cu")
		(net "SSD_PERST#0_B1")
	)
	(via
		(at 75.565 -192.278)
		(size 0.7112)
		(drill 0.3556)
		(layers "F.Cu" "B.Cu")
		(net "SSD_PERST#0_B0")
	)
	(segment
		(start 74.675238 -192.278)
		(end 75.565 -192.278)
		(width 0.12065)
		(layer "B.Cu")
		(net "SSD_PERST#0_B0")
	)
	(segment
		(start 74.422 -191.135)
		(end 74.676 -191.389)
		(width 0.12065)
		(layer "B.Cu")
		(net "SSD_PERST#0_B0")
	)
	(segment
		(start 74.594212 -192.196974)
		(end 74.675238 -192.278)
		(width 0.12065)
		(layer "B.Cu")
		(net "SSD_PERST#0_B0")
	)
	(segment
		(start 75.565 -191.516)
		(end 75.565 -192.278)
		(width 0.12065)
		(layer "B.Cu")
		(net "SSD_PERST#0_B0")
	)
	(segment
		(start 74.422 -190.4365)
		(end 74.422 -191.135)
		(width 0.12065)
		(layer "B.Cu")
		(net "SSD_PERST#0_B0")
	)
	(segment
		(start 74.676 -191.389)
		(end 75.438 -191.389)
		(width 0.12065)
		(layer "B.Cu")
		(net "SSD_PERST#0_B0")
	)
	(segment
		(start 75.438 -191.389)
		(end 75.565 -191.516)
		(width 0.12065)
		(layer "B.Cu")
		(net "SSD_PERST#0_B0")
	)
	(segment
		(start 320.80835 -98.171)
		(end 320.808096 -98.171254)
		(width 0.12065)
		(layer "F.Cu")
		(net "IOEXP_TWI_SDA3")
	)
	(segment
		(start 320.808096 -98.171254)
		(end 320.808096 -98.736404)
		(width 0.12065)
		(layer "F.Cu")
		(net "IOEXP_TWI_SDA3")
	)
	(segment
		(start 320.808096 -98.736404)
		(end 320.421 -99.1235)
		(width 0.12065)
		(layer "F.Cu")
		(net "IOEXP_TWI_SDA3")
	)
	(segment
		(start 320.808604 -98.170746)
		(end 320.80835 -98.171)
		(width 0.12065)
		(layer "F.Cu")
		(net "IOEXP_TWI_SDA3")
	)
	(segment
		(start 321.91452 -96.670114)
		(end 320.808604 -97.77603)
		(width 0.12065)
		(layer "F.Cu")
		(net "IOEXP_TWI_SDA3")
	)
	(segment
		(start 321.91452 -95.885)
		(end 321.91452 -96.670114)
		(width 0.12065)
		(layer "F.Cu")
		(net "IOEXP_TWI_SDA3")
	)
	(segment
		(start 320.80835 -98.171)
		(end 320.4464 -98.171)
		(width 0.12065)
		(layer "F.Cu")
		(net "IOEXP_TWI_SDA3")
	)
	(segment
		(start 320.808604 -97.77603)
		(end 320.808604 -98.170746)
		(width 0.12065)
		(layer "F.Cu")
		(net "IOEXP_TWI_SDA3")
	)
	(via
		(at 320.4464 -98.171)
		(size 0.7112)
		(drill 0.3556)
		(layers "F.Cu" "B.Cu")
		(net "IOEXP_TWI_SDA3")
	)
	(segment
		(start 321.903852 -99.64293)
		(end 321.903852 -100.35667)
		(width 0.12065)
		(layer "F.Cu")
		(net "IOEXP_TWI_SCL3")
	)
	(segment
		(start 321.437 -99.176078)
		(end 321.903852 -99.64293)
		(width 0.12065)
		(layer "F.Cu")
		(net "IOEXP_TWI_SCL3")
	)
	(segment
		(start 321.31 -98.9965)
		(end 321.310254 -98.996246)
		(width 0.12065)
		(layer "F.Cu")
		(net "IOEXP_TWI_SCL3")
	)
	(segment
		(start 321.437 -99.1235)
		(end 321.31 -98.9965)
		(width 0.12065)
		(layer "F.Cu")
		(net "IOEXP_TWI_SCL3")
	)
	(segment
		(start 321.903852 -100.35667)
		(end 321.897248 -100.363274)
		(width 0.12065)
		(layer "F.Cu")
		(net "IOEXP_TWI_SCL3")
	)
	(segment
		(start 322.56476 -96.72955)
		(end 322.56476 -95.885)
		(width 0.12065)
		(layer "F.Cu")
		(net "IOEXP_TWI_SCL3")
	)
	(segment
		(start 321.310254 -97.984056)
		(end 322.56476 -96.72955)
		(width 0.12065)
		(layer "F.Cu")
		(net "IOEXP_TWI_SCL3")
	)
	(segment
		(start 321.897248 -100.762054)
		(end 321.694302 -100.965)
		(width 0.12065)
		(layer "F.Cu")
		(net "IOEXP_TWI_SCL3")
	)
	(segment
		(start 321.310254 -98.996246)
		(end 321.310254 -97.984056)
		(width 0.12065)
		(layer "F.Cu")
		(net "IOEXP_TWI_SCL3")
	)
	(segment
		(start 321.897248 -100.363274)
		(end 321.897248 -100.762054)
		(width 0.12065)
		(layer "F.Cu")
		(net "IOEXP_TWI_SCL3")
	)
	(segment
		(start 321.437 -99.1235)
		(end 321.437 -99.176078)
		(width 0.12065)
		(layer "F.Cu")
		(net "IOEXP_TWI_SCL3")
	)
	(via
		(at 321.694302 -100.965)
		(size 0.7112)
		(drill 0.3556)
		(layers "F.Cu" "B.Cu")
		(net "IOEXP_TWI_SCL3")
	)
	(segment
		(start 306.959 -106.934)
		(end 319.405 -106.934)
		(width 0.12065)
		(layer "F.Cu")
		(net "IOEXP_PMC1_INT#")
	)
	(segment
		(start 321.26428 -90.2462)
		(end 321.26428 -88.72728)
		(width 0.12065)
		(layer "F.Cu")
		(net "IOEXP_PMC1_INT#")
	)
	(segment
		(start 260.096 -27.559)
		(end 260.096 -28.194)
		(width 0.12065)
		(layer "F.Cu")
		(net "IOEXP_PMC1_INT#")
	)
	(segment
		(start 260.096 -26.7335)
		(end 260.096 -27.559)
		(width 0.12065)
		(layer "F.Cu")
		(net "IOEXP_PMC1_INT#")
	)
	(segment
		(start 260.096 -28.194)
		(end 262.9027 -31.0007)
		(width 0.12065)
		(layer "F.Cu")
		(net "IOEXP_PMC1_INT#")
	)
	(segment
		(start 262.9027 -31.0007)
		(end 262.9027 -62.8777)
		(width 0.12065)
		(layer "F.Cu")
		(net "IOEXP_PMC1_INT#")
	)
	(segment
		(start 319.405 -106.934)
		(end 319.532 -107.061)
		(width 0.12065)
		(layer "F.Cu")
		(net "IOEXP_PMC1_INT#")
	)
	(segment
		(start 247.599962 -37.999924)
		(end 248.099834 -37.500052)
		(width 0.12065)
		(layer "F.Cu")
		(net "IOEXP_PMC1_INT#")
	)
	(segment
		(start 262.9027 -62.8777)
		(end 306.959 -106.934)
		(width 0.12065)
		(layer "F.Cu")
		(net "IOEXP_PMC1_INT#")
	)
	(via
		(at 321.26428 -90.424)
		(size 0.7112)
		(drill 0.3556)
		(layers "F.Cu" "B.Cu")
		(net "IOEXP_PMC1_INT#")
	)
	(via
		(at 248.099834 -37.500052)
		(size 0.4572)
		(drill 0.2032)
		(layers "F.Cu" "B.Cu")
		(net "IOEXP_PMC1_INT#")
	)
	(via
		(at 260.096 -27.559)
		(size 0.508)
		(drill 0.254)
		(layers "F.Cu" "B.Cu")
		(net "IOEXP_PMC1_INT#")
	)
	(via
		(at 321.26428 -88.72728)
		(size 0.508)
		(drill 0.254)
		(layers "F.Cu" "B.Cu")
		(net "IOEXP_PMC1_INT#")
	)
	(via
		(at 319.532 -107.061)
		(size 0.508)
		(drill 0.254)
		(layers "F.Cu" "B.Cu")
		(net "IOEXP_PMC1_INT#")
	)
	(segment
		(start 321.26428 -102.1334)
		(end 321.26428 -90.424)
		(width 0.12065)
		(layer "B.Cu")
		(net "IOEXP_PMC1_INT#")
	)
	(segment
		(start 319.532 -107.061)
		(end 319.532 -103.86568)
		(width 0.12065)
		(layer "B.Cu")
		(net "IOEXP_PMC1_INT#")
	)
	(segment
		(start 319.532 -103.86568)
		(end 321.26428 -102.1334)
		(width 0.12065)
		(layer "B.Cu")
		(net "IOEXP_PMC1_INT#")
	)
	(segment
		(start 321.26428 -90.424)
		(end 321.26428 -88.72728)
		(width 0.12065)
		(layer "B.Cu")
		(net "IOEXP_PMC1_INT#")
	)
	(segment
		(start 249.838464 -34.893758)
		(end 250.263152 -34.893758)
		(width 0.1016)
		(layer "In2.Cu")
		(net "IOEXP_PMC1_INT#")
	)
	(segment
		(start 258.396232 -29.893768)
		(end 258.6228 -29.6672)
		(width 0.1016)
		(layer "In2.Cu")
		(net "IOEXP_PMC1_INT#")
	)
	(segment
		(start 253.504446 -31.25089)
		(end 253.852172 -30.903164)
		(width 0.1016)
		(layer "In2.Cu")
		(net "IOEXP_PMC1_INT#")
	)
	(segment
		(start 258.6228 -29.6672)
		(end 260.096 -28.194)
		(width 0.127)
		(layer "In2.Cu")
		(net "IOEXP_PMC1_INT#")
	)
	(segment
		(start 254.50292 -30.252416)
		(end 254.861568 -29.893768)
		(width 0.1016)
		(layer "In2.Cu")
		(net "IOEXP_PMC1_INT#")
	)
	(segment
		(start 254.861568 -29.893768)
		(end 258.396232 -29.893768)
		(width 0.1016)
		(layer "In2.Cu")
		(net "IOEXP_PMC1_INT#")
	)
	(segment
		(start 253.276608 -31.903162)
		(end 253.502668 -31.677102)
		(width 0.1016)
		(layer "In2.Cu")
		(net "IOEXP_PMC1_INT#")
	)
	(segment
		(start 252.493526 -32.26181)
		(end 252.852174 -31.903162)
		(width 0.1016)
		(layer "In2.Cu")
		(net "IOEXP_PMC1_INT#")
	)
	(segment
		(start 254.253746 -30.903164)
		(end 254.50292 -30.65399)
		(width 0.1016)
		(layer "In2.Cu")
		(net "IOEXP_PMC1_INT#")
	)
	(segment
		(start 250.263152 -34.893758)
		(end 250.49353 -34.66338)
		(width 0.1016)
		(layer "In2.Cu")
		(net "IOEXP_PMC1_INT#")
	)
	(segment
		(start 250.49353 -34.66338)
		(end 250.49353 -34.238438)
		(width 0.1016)
		(layer "In2.Cu")
		(net "IOEXP_PMC1_INT#")
	)
	(segment
		(start 249.263154 -35.893756)
		(end 249.493532 -35.663378)
		(width 0.1016)
		(layer "In2.Cu")
		(net "IOEXP_PMC1_INT#")
	)
	(segment
		(start 251.44984 -33.89376)
		(end 252.493526 -32.850074)
		(width 0.1016)
		(layer "In2.Cu")
		(net "IOEXP_PMC1_INT#")
	)
	(segment
		(start 249.493532 -35.23869)
		(end 249.838464 -34.893758)
		(width 0.1016)
		(layer "In2.Cu")
		(net "IOEXP_PMC1_INT#")
	)
	(segment
		(start 248.099834 -37.057076)
		(end 248.493534 -36.663376)
		(width 0.1016)
		(layer "In2.Cu")
		(net "IOEXP_PMC1_INT#")
	)
	(segment
		(start 250.838462 -33.89376)
		(end 251.44984 -33.89376)
		(width 0.1016)
		(layer "In2.Cu")
		(net "IOEXP_PMC1_INT#")
	)
	(segment
		(start 248.713244 -35.893756)
		(end 249.263154 -35.893756)
		(width 0.1016)
		(layer "In2.Cu")
		(net "IOEXP_PMC1_INT#")
	)
	(segment
		(start 252.852174 -31.903162)
		(end 253.276608 -31.903162)
		(width 0.1016)
		(layer "In2.Cu")
		(net "IOEXP_PMC1_INT#")
	)
	(segment
		(start 248.493534 -36.663376)
		(end 248.493534 -36.113466)
		(width 0.1016)
		(layer "In2.Cu")
		(net "IOEXP_PMC1_INT#")
	)
	(segment
		(start 253.502668 -31.252922)
		(end 253.504446 -31.25089)
		(width 0.1016)
		(layer "In2.Cu")
		(net "IOEXP_PMC1_INT#")
	)
	(segment
		(start 254.50292 -30.65399)
		(end 254.50292 -30.252416)
		(width 0.1016)
		(layer "In2.Cu")
		(net "IOEXP_PMC1_INT#")
	)
	(segment
		(start 249.493532 -35.663378)
		(end 249.493532 -35.23869)
		(width 0.1016)
		(layer "In2.Cu")
		(net "IOEXP_PMC1_INT#")
	)
	(segment
		(start 260.096 -28.194)
		(end 260.096 -27.559)
		(width 0.127)
		(layer "In2.Cu")
		(net "IOEXP_PMC1_INT#")
	)
	(segment
		(start 248.099834 -37.500052)
		(end 248.099834 -37.057076)
		(width 0.1016)
		(layer "In2.Cu")
		(net "IOEXP_PMC1_INT#")
	)
	(segment
		(start 253.502668 -31.677102)
		(end 253.502668 -31.252922)
		(width 0.1016)
		(layer "In2.Cu")
		(net "IOEXP_PMC1_INT#")
	)
	(segment
		(start 252.493526 -32.850074)
		(end 252.493526 -32.26181)
		(width 0.1016)
		(layer "In2.Cu")
		(net "IOEXP_PMC1_INT#")
	)
	(segment
		(start 248.493534 -36.113466)
		(end 248.713244 -35.893756)
		(width 0.1016)
		(layer "In2.Cu")
		(net "IOEXP_PMC1_INT#")
	)
	(segment
		(start 253.852172 -30.903164)
		(end 254.253746 -30.903164)
		(width 0.1016)
		(layer "In2.Cu")
		(net "IOEXP_PMC1_INT#")
	)
	(segment
		(start 250.49353 -34.238438)
		(end 250.838462 -33.89376)
		(width 0.1016)
		(layer "In2.Cu")
		(net "IOEXP_PMC1_INT#")
	)
	(segment
		(start 322.707 -86.9315)
		(end 321.691 -86.9315)
		(width 0.12065)
		(layer "F.Cu")
		(net "IOEXP_PMC1_AD2")
	)
	(segment
		(start 322.56476 -87.07374)
		(end 322.707 -86.9315)
		(width 0.12065)
		(layer "F.Cu")
		(net "IOEXP_PMC1_AD2")
	)
	(segment
		(start 322.56476 -87.884)
		(end 322.56476 -90.2462)
		(width 0.12065)
		(layer "F.Cu")
		(net "IOEXP_PMC1_AD2")
	)
	(segment
		(start 322.56476 -87.884)
		(end 322.56476 -87.07374)
		(width 0.12065)
		(layer "F.Cu")
		(net "IOEXP_PMC1_AD2")
	)
	(via
		(at 322.56476 -87.884)
		(size 0.7112)
		(drill 0.3556)
		(layers "F.Cu" "B.Cu")
		(net "IOEXP_PMC1_AD2")
	)
	(segment
		(start 321.91452 -90.2462)
		(end 321.91452 -88.48852)
		(width 0.12065)
		(layer "F.Cu")
		(net "IOEXP_PMC1_AD1")
	)
	(segment
		(start 321.91452 -88.48852)
		(end 321.31 -87.884)
		(width 0.12065)
		(layer "F.Cu")
		(net "IOEXP_PMC1_AD1")
	)
	(segment
		(start 320.675 -86.9315)
		(end 320.7004 -86.9569)
		(width 0.12065)
		(layer "F.Cu")
		(net "IOEXP_PMC1_AD1")
	)
	(segment
		(start 321.31 -87.884)
		(end 320.7004 -87.884)
		(width 0.12065)
		(layer "F.Cu")
		(net "IOEXP_PMC1_AD1")
	)
	(segment
		(start 319.659 -86.9315)
		(end 320.675 -86.9315)
		(width 0.12065)
		(layer "F.Cu")
		(net "IOEXP_PMC1_AD1")
	)
	(segment
		(start 320.7004 -86.9569)
		(end 320.7004 -87.884)
		(width 0.12065)
		(layer "F.Cu")
		(net "IOEXP_PMC1_AD1")
	)
	(via
		(at 320.7004 -87.884)
		(size 0.7112)
		(drill 0.3556)
		(layers "F.Cu" "B.Cu")
		(net "IOEXP_PMC1_AD1")
	)
	(segment
		(start 322.1736 -98.8441)
		(end 322.453 -99.1235)
		(width 0.12065)
		(layer "F.Cu")
		(net "IOEXP_PMC1_AD0")
	)
	(segment
		(start 322.1736 -97.7138)
		(end 322.1736 -98.0694)
		(width 0.12065)
		(layer "F.Cu")
		(net "IOEXP_PMC1_AD0")
	)
	(segment
		(start 322.453 -99.1235)
		(end 323.469 -99.1235)
		(width 0.12065)
		(layer "F.Cu")
		(net "IOEXP_PMC1_AD0")
	)
	(segment
		(start 323.215 -95.885)
		(end 323.215 -96.6724)
		(width 0.12065)
		(layer "F.Cu")
		(net "IOEXP_PMC1_AD0")
	)
	(segment
		(start 323.215 -96.6724)
		(end 322.1736 -97.7138)
		(width 0.12065)
		(layer "F.Cu")
		(net "IOEXP_PMC1_AD0")
	)
	(segment
		(start 322.1736 -98.0694)
		(end 322.1736 -98.8441)
		(width 0.12065)
		(layer "F.Cu")
		(net "IOEXP_PMC1_AD0")
	)
	(via
		(at 322.1736 -98.0694)
		(size 0.7112)
		(drill 0.3556)
		(layers "F.Cu" "B.Cu")
		(net "IOEXP_PMC1_AD0")
	)
	(segment
		(start 323.4436 -98.0821)
		(end 323.4436 -97.409)
		(width 0.12065)
		(layer "F.Cu")
		(net "IOEXP_PEWAKE#")
	)
	(segment
		(start 323.86524 -96.98736)
		(end 323.4436 -97.409)
		(width 0.12065)
		(layer "F.Cu")
		(net "IOEXP_PEWAKE#")
	)
	(segment
		(start 323.86524 -95.885)
		(end 323.86524 -96.98736)
		(width 0.12065)
		(layer "F.Cu")
		(net "IOEXP_PEWAKE#")
	)
	(segment
		(start 324.485 -99.1235)
		(end 323.4436 -98.0821)
		(width 0.12065)
		(layer "F.Cu")
		(net "IOEXP_PEWAKE#")
	)
	(via
		(at 323.4436 -97.409)
		(size 0.7112)
		(drill 0.3556)
		(layers "F.Cu" "B.Cu")
		(net "IOEXP_PEWAKE#")
	)
	(via
		(at 52.0954 -105.0798)
		(size 0.7112)
		(drill 0.3556)
		(layers "F.Cu" "B.Cu")
		(net "I2C8_LS_G2")
	)
	(segment
		(start 51.6001 -104.5845)
		(end 52.0954 -105.0798)
		(width 0.12065)
		(layer "B.Cu")
		(net "I2C8_LS_G2")
	)
	(segment
		(start 50.927 -104.5845)
		(end 51.6001 -104.5845)
		(width 0.12065)
		(layer "B.Cu")
		(net "I2C8_LS_G2")
	)
	(segment
		(start 49.53 -104.5464)
		(end 50.8889 -104.5464)
		(width 0.12065)
		(layer "B.Cu")
		(net "I2C8_LS_G2")
	)
	(segment
		(start 50.8889 -104.5464)
		(end 50.927 -104.5845)
		(width 0.12065)
		(layer "B.Cu")
		(net "I2C8_LS_G2")
	)
	(via
		(at 46.0756 -105.4862)
		(size 0.7112)
		(drill 0.3556)
		(layers "F.Cu" "B.Cu")
		(net "I2C8_LS_G1")
	)
	(segment
		(start 47.6504 -104.5464)
		(end 46.3677 -104.5464)
		(width 0.12065)
		(layer "B.Cu")
		(net "I2C8_LS_G1")
	)
	(segment
		(start 46.3042 -105.2576)
		(end 46.3042 -104.4829)
		(width 0.12065)
		(layer "B.Cu")
		(net "I2C8_LS_G1")
	)
	(segment
		(start 46.0756 -105.4862)
		(end 46.3042 -105.2576)
		(width 0.12065)
		(layer "B.Cu")
		(net "I2C8_LS_G1")
	)
	(segment
		(start 46.3677 -104.5464)
		(end 46.3042 -104.4829)
		(width 0.12065)
		(layer "B.Cu")
		(net "I2C8_LS_G1")
	)
	(segment
		(start 55.615586 -110.470188)
		(end 56.126126 -110.470188)
		(width 0.12065)
		(layer "F.Cu")
		(net "I2C7_LS_G2")
	)
	(segment
		(start 56.126126 -110.470188)
		(end 56.126126 -109.568488)
		(width 0.12065)
		(layer "F.Cu")
		(net "I2C7_LS_G2")
	)
	(segment
		(start 55.342028 -110.19663)
		(end 55.615586 -110.470188)
		(width 0.12065)
		(layer "F.Cu")
		(net "I2C7_LS_G2")
	)
	(segment
		(start 54.695852 -110.19663)
		(end 55.342028 -110.19663)
		(width 0.12065)
		(layer "F.Cu")
		(net "I2C7_LS_G2")
	)
	(via
		(at 56.126126 -109.568488)
		(size 0.7112)
		(drill 0.3556)
		(layers "F.Cu" "B.Cu")
		(net "I2C7_LS_G2")
	)
	(segment
		(start 51.473608 -109.793786)
		(end 51.876452 -110.19663)
		(width 0.12065)
		(layer "F.Cu")
		(net "I2C7_LS_G1")
	)
	(segment
		(start 51.876452 -110.19663)
		(end 52.816252 -110.19663)
		(width 0.12065)
		(layer "F.Cu")
		(net "I2C7_LS_G1")
	)
	(segment
		(start 50.99939 -109.319568)
		(end 51.473608 -109.793786)
		(width 0.12065)
		(layer "F.Cu")
		(net "I2C7_LS_G1")
	)
	(segment
		(start 50.251614 -109.319568)
		(end 50.99939 -109.319568)
		(width 0.12065)
		(layer "F.Cu")
		(net "I2C7_LS_G1")
	)
	(via
		(at 51.473608 -109.793786)
		(size 0.7112)
		(drill 0.3556)
		(layers "F.Cu" "B.Cu")
		(net "I2C7_LS_G1")
	)
	(via
		(at 51.427126 -109.187742)
		(size 0.7112)
		(drill 0.3556)
		(layers "F.Cu" "B.Cu")
		(net "I2C6_LS_G2")
	)
	(segment
		(start 52.816252 -110.19663)
		(end 52.752752 -110.26013)
		(width 0.12065)
		(layer "B.Cu")
		(net "I2C6_LS_G2")
	)
	(segment
		(start 51.470052 -109.474)
		(end 51.427126 -109.431074)
		(width 0.12065)
		(layer "B.Cu")
		(net "I2C6_LS_G2")
	)
	(segment
		(start 51.427126 -109.431074)
		(end 51.427126 -109.187742)
		(width 0.12065)
		(layer "B.Cu")
		(net "I2C6_LS_G2")
	)
	(segment
		(start 51.470052 -110.26013)
		(end 51.470052 -109.474)
		(width 0.12065)
		(layer "B.Cu")
		(net "I2C6_LS_G2")
	)
	(segment
		(start 52.752752 -110.26013)
		(end 51.470052 -110.26013)
		(width 0.12065)
		(layer "B.Cu")
		(net "I2C6_LS_G2")
	)
	(via
		(at 56.311546 -108.726224)
		(size 0.7112)
		(drill 0.3556)
		(layers "F.Cu" "B.Cu")
		(net "I2C6_LS_G1")
	)
	(segment
		(start 54.695852 -110.19663)
		(end 55.597552 -110.19663)
		(width 0.12065)
		(layer "B.Cu")
		(net "I2C6_LS_G1")
	)
	(segment
		(start 56.092852 -108.944918)
		(end 56.311546 -108.726224)
		(width 0.12065)
		(layer "B.Cu")
		(net "I2C6_LS_G1")
	)
	(segment
		(start 56.092852 -109.70133)
		(end 56.092852 -108.944918)
		(width 0.12065)
		(layer "B.Cu")
		(net "I2C6_LS_G1")
	)
	(segment
		(start 55.597552 -110.19663)
		(end 56.092852 -109.70133)
		(width 0.12065)
		(layer "B.Cu")
		(net "I2C6_LS_G1")
	)
	(segment
		(start 66.7131 -109.3724)
		(end 65.4304 -109.3724)
		(width 0.12065)
		(layer "F.Cu")
		(net "I2C5_LS_G2")
	)
	(segment
		(start 66.7766 -109.3089)
		(end 66.7131 -109.3724)
		(width 0.12065)
		(layer "F.Cu")
		(net "I2C5_LS_G2")
	)
	(segment
		(start 67.451478 -109.3089)
		(end 67.756024 -109.613446)
		(width 0.12065)
		(layer "F.Cu")
		(net "I2C5_LS_G2")
	)
	(segment
		(start 66.7766 -109.3089)
		(end 67.451478 -109.3089)
		(width 0.12065)
		(layer "F.Cu")
		(net "I2C5_LS_G2")
	)
	(via
		(at 67.756024 -109.613446)
		(size 0.7112)
		(drill 0.3556)
		(layers "F.Cu" "B.Cu")
		(net "I2C5_LS_G2")
	)
	(segment
		(start 62.2046 -109.4359)
		(end 62.2046 -109.0676)
		(width 0.12065)
		(layer "F.Cu")
		(net "I2C5_LS_G1")
	)
	(segment
		(start 62.2046 -109.0676)
		(end 61.4172 -108.2802)
		(width 0.12065)
		(layer "F.Cu")
		(net "I2C5_LS_G1")
	)
	(segment
		(start 63.5508 -109.3724)
		(end 62.2681 -109.3724)
		(width 0.12065)
		(layer "F.Cu")
		(net "I2C5_LS_G1")
	)
	(segment
		(start 62.2681 -109.3724)
		(end 62.2046 -109.4359)
		(width 0.12065)
		(layer "F.Cu")
		(net "I2C5_LS_G1")
	)
	(via
		(at 61.4172 -108.2802)
		(size 0.7112)
		(drill 0.3556)
		(layers "F.Cu" "B.Cu")
		(net "I2C5_LS_G1")
	)
	(segment
		(start 67.60464 -118.6942)
		(end 68.4149 -118.6942)
		(width 0.12065)
		(layer "F.Cu")
		(net "I2C4_LS_G2")
	)
	(segment
		(start 68.0212 -119.253)
		(end 67.696842 -119.253)
		(width 0.12065)
		(layer "F.Cu")
		(net "I2C4_LS_G2")
	)
	(segment
		(start 67.696842 -119.253)
		(end 67.5132 -119.069358)
		(width 0.12065)
		(layer "F.Cu")
		(net "I2C4_LS_G2")
	)
	(segment
		(start 67.5132 -118.78564)
		(end 67.60464 -118.6942)
		(width 0.12065)
		(layer "F.Cu")
		(net "I2C4_LS_G2")
	)
	(segment
		(start 67.5132 -119.069358)
		(end 67.5132 -118.78564)
		(width 0.12065)
		(layer "F.Cu")
		(net "I2C4_LS_G2")
	)
	(segment
		(start 68.3514 -120.0404)
		(end 68.3514 -119.5832)
		(width 0.12065)
		(layer "F.Cu")
		(net "I2C4_LS_G2")
	)
	(segment
		(start 68.3514 -119.5832)
		(end 68.0212 -119.253)
		(width 0.12065)
		(layer "F.Cu")
		(net "I2C4_LS_G2")
	)
	(via
		(at 67.5132 -118.78564)
		(size 0.7112)
		(drill 0.3556)
		(layers "F.Cu" "B.Cu")
		(net "I2C4_LS_G2")
	)
	(segment
		(start 67.5132 -123.084082)
		(end 67.5132 -123.19)
		(width 0.12065)
		(layer "F.Cu")
		(net "I2C4_LS_G1")
	)
	(segment
		(start 68.3514 -121.92)
		(end 68.3514 -122.245882)
		(width 0.12065)
		(layer "F.Cu")
		(net "I2C4_LS_G1")
	)
	(segment
		(start 68.3514 -122.245882)
		(end 67.5132 -123.084082)
		(width 0.12065)
		(layer "F.Cu")
		(net "I2C4_LS_G1")
	)
	(segment
		(start 67.5132 -123.19)
		(end 67.7164 -123.3932)
		(width 0.12065)
		(layer "F.Cu")
		(net "I2C4_LS_G1")
	)
	(segment
		(start 67.7164 -123.3932)
		(end 68.4149 -123.3932)
		(width 0.12065)
		(layer "F.Cu")
		(net "I2C4_LS_G1")
	)
	(via
		(at 67.5132 -123.19)
		(size 0.7112)
		(drill 0.3556)
		(layers "F.Cu" "B.Cu")
		(net "I2C4_LS_G1")
	)
	(via
		(at 62.858142 -115.7224)
		(size 0.7112)
		(drill 0.3556)
		(layers "F.Cu" "B.Cu")
		(net "I2C3_LS_G2")
	)
	(segment
		(start 61.8236 -117.0686)
		(end 61.8236 -115.7859)
		(width 0.12065)
		(layer "B.Cu")
		(net "I2C3_LS_G2")
	)
	(segment
		(start 61.8236 -115.7859)
		(end 61.8871 -115.7224)
		(width 0.12065)
		(layer "B.Cu")
		(net "I2C3_LS_G2")
	)
	(segment
		(start 62.858142 -115.7224)
		(end 61.8871 -115.7224)
		(width 0.12065)
		(layer "B.Cu")
		(net "I2C3_LS_G2")
	)
	(via
		(at 62.905894 -120.2944)
		(size 0.7112)
		(drill 0.3556)
		(layers "F.Cu" "B.Cu")
		(net "I2C3_LS_G1")
	)
	(segment
		(start 61.8871 -120.2944)
		(end 62.905894 -120.2944)
		(width 0.12065)
		(layer "B.Cu")
		(net "I2C3_LS_G1")
	)
	(segment
		(start 61.8236 -118.9482)
		(end 61.8236 -120.2309)
		(width 0.12065)
		(layer "B.Cu")
		(net "I2C3_LS_G1")
	)
	(segment
		(start 61.8236 -120.2309)
		(end 61.8871 -120.2944)
		(width 0.12065)
		(layer "B.Cu")
		(net "I2C3_LS_G1")
	)
	(segment
		(start 13.462 -122.682)
		(end 14.1605 -122.682)
		(width 0.12065)
		(layer "F.Cu")
		(net "I2C2_LS_G2")
	)
	(segment
		(start 14.097 -124.1552)
		(end 14.097 -123.825)
		(width 0.12065)
		(layer "F.Cu")
		(net "I2C2_LS_G2")
	)
	(segment
		(start 14.097 -123.825)
		(end 13.208 -122.936)
		(width 0.12065)
		(layer "F.Cu")
		(net "I2C2_LS_G2")
	)
	(segment
		(start 13.208 -122.936)
		(end 13.462 -122.682)
		(width 0.12065)
		(layer "F.Cu")
		(net "I2C2_LS_G2")
	)
	(via
		(at 13.208 -122.936)
		(size 0.7112)
		(drill 0.3556)
		(layers "F.Cu" "B.Cu")
		(net "I2C2_LS_G2")
	)
	(segment
		(start 13.335 -127.508)
		(end 14.1605 -127.508)
		(width 0.12065)
		(layer "F.Cu")
		(net "I2C2_LS_G1")
	)
	(segment
		(start 14.097 -126.619)
		(end 13.985748 -126.730252)
		(width 0.12065)
		(layer "F.Cu")
		(net "I2C2_LS_G1")
	)
	(segment
		(start 14.097 -126.0348)
		(end 14.097 -126.619)
		(width 0.12065)
		(layer "F.Cu")
		(net "I2C2_LS_G1")
	)
	(segment
		(start 13.208 -127.381)
		(end 13.335 -127.508)
		(width 0.12065)
		(layer "F.Cu")
		(net "I2C2_LS_G1")
	)
	(segment
		(start 13.985748 -126.730252)
		(end 13.454126 -126.730252)
		(width 0.12065)
		(layer "F.Cu")
		(net "I2C2_LS_G1")
	)
	(segment
		(start 13.208 -126.976378)
		(end 13.208 -127.381)
		(width 0.12065)
		(layer "F.Cu")
		(net "I2C2_LS_G1")
	)
	(segment
		(start 13.454126 -126.730252)
		(end 13.208 -126.976378)
		(width 0.12065)
		(layer "F.Cu")
		(net "I2C2_LS_G1")
	)
	(via
		(at 13.208 -127.381)
		(size 0.7112)
		(drill 0.3556)
		(layers "F.Cu" "B.Cu")
		(net "I2C2_LS_G1")
	)
	(segment
		(start 11.176 -123.063)
		(end 10.3505 -123.063)
		(width 0.12065)
		(layer "F.Cu")
		(net "I2C1_LS_G2")
	)
	(segment
		(start 10.461752 -122.285252)
		(end 11.029188 -122.285252)
		(width 0.12065)
		(layer "F.Cu")
		(net "I2C1_LS_G2")
	)
	(segment
		(start 10.287 -122.1105)
		(end 10.461752 -122.285252)
		(width 0.12065)
		(layer "F.Cu")
		(net "I2C1_LS_G2")
	)
	(segment
		(start 11.303 -122.559064)
		(end 11.303 -122.936)
		(width 0.12065)
		(layer "F.Cu")
		(net "I2C1_LS_G2")
	)
	(segment
		(start 11.029188 -122.285252)
		(end 11.303 -122.559064)
		(width 0.12065)
		(layer "F.Cu")
		(net "I2C1_LS_G2")
	)
	(segment
		(start 11.303 -122.936)
		(end 11.176 -123.063)
		(width 0.12065)
		(layer "F.Cu")
		(net "I2C1_LS_G2")
	)
	(segment
		(start 10.287 -121.5898)
		(end 10.287 -122.1105)
		(width 0.12065)
		(layer "F.Cu")
		(net "I2C1_LS_G2")
	)
	(via
		(at 11.303 -122.936)
		(size 0.7112)
		(drill 0.3556)
		(layers "F.Cu" "B.Cu")
		(net "I2C1_LS_G2")
	)
	(segment
		(start 10.287 -119.2022)
		(end 10.9982 -118.491)
		(width 0.12065)
		(layer "F.Cu")
		(net "I2C1_LS_G1")
	)
	(segment
		(start 10.3505 -118.237)
		(end 10.2235 -118.364)
		(width 0.12065)
		(layer "F.Cu")
		(net "I2C1_LS_G1")
	)
	(segment
		(start 11.176 -118.491)
		(end 10.922 -118.237)
		(width 0.12065)
		(layer "F.Cu")
		(net "I2C1_LS_G1")
	)
	(segment
		(start 10.9982 -118.491)
		(end 11.176 -118.491)
		(width 0.12065)
		(layer "F.Cu")
		(net "I2C1_LS_G1")
	)
	(segment
		(start 10.287 -119.7102)
		(end 10.287 -119.2022)
		(width 0.12065)
		(layer "F.Cu")
		(net "I2C1_LS_G1")
	)
	(segment
		(start 10.922 -118.237)
		(end 10.3505 -118.237)
		(width 0.12065)
		(layer "F.Cu")
		(net "I2C1_LS_G1")
	)
	(via
		(at 11.176 -118.491)
		(size 0.7112)
		(drill 0.3556)
		(layers "F.Cu" "B.Cu")
		(net "I2C1_LS_G1")
	)
	(segment
		(start 17.78 -156.337)
		(end 17.78 -155.3845)
		(width 0.12065)
		(layer "F.Cu")
		(net "FM_BMC_RESET#_BTN_D")
	)
	(segment
		(start 17.78 -155.3845)
		(end 18.288 -154.8765)
		(width 0.12065)
		(layer "F.Cu")
		(net "FM_BMC_RESET#_BTN_D")
	)
	(segment
		(start 16.383 -156.337)
		(end 17.78 -156.337)
		(width 0.12065)
		(layer "F.Cu")
		(net "FM_BMC_RESET#_BTN_D")
	)
	(via
		(at 16.383 -156.337)
		(size 0.7112)
		(drill 0.3556)
		(layers "F.Cu" "B.Cu")
		(net "FM_BMC_RESET#_BTN_D")
	)
	(via
		(at 335.8642 -181.229)
		(size 0.7112)
		(drill 0.3556)
		(layers "F.Cu" "B.Cu")
		(net "BMC_SSD_RST#0_A9")
	)
	(segment
		(start 336.0293 -181.3941)
		(end 335.8642 -181.229)
		(width 0.12065)
		(layer "B.Cu")
		(net "BMC_SSD_RST#0_A9")
	)
	(segment
		(start 336.591148 -181.206648)
		(end 336.591148 -179.633626)
		(width 0.12065)
		(layer "B.Cu")
		(net "BMC_SSD_RST#0_A9")
	)
	(segment
		(start 336.7786 -181.3941)
		(end 336.591148 -181.206648)
		(width 0.12065)
		(layer "B.Cu")
		(net "BMC_SSD_RST#0_A9")
	)
	(segment
		(start 335.153 -180.1495)
		(end 335.153 -180.5178)
		(width 0.12065)
		(layer "B.Cu")
		(net "BMC_SSD_RST#0_A9")
	)
	(segment
		(start 336.7786 -181.3941)
		(end 336.0293 -181.3941)
		(width 0.12065)
		(layer "B.Cu")
		(net "BMC_SSD_RST#0_A9")
	)
	(segment
		(start 335.153 -180.5178)
		(end 335.8642 -181.229)
		(width 0.12065)
		(layer "B.Cu")
		(net "BMC_SSD_RST#0_A9")
	)
	(via
		(at 222.1992 -199.8472)
		(size 0.7112)
		(drill 0.3556)
		(layers "F.Cu" "B.Cu")
		(net "BMC_SSD_RST#0_A8")
	)
	(segment
		(start 223.1644 -199.03948)
		(end 222.74276 -198.61784)
		(width 0.12065)
		(layer "B.Cu")
		(net "BMC_SSD_RST#0_A8")
	)
	(segment
		(start 223.1644 -199.4535)
		(end 223.1644 -199.03948)
		(width 0.12065)
		(layer "B.Cu")
		(net "BMC_SSD_RST#0_A8")
	)
	(segment
		(start 222.74276 -198.61784)
		(end 222.74276 -197.8025)
		(width 0.12065)
		(layer "B.Cu")
		(net "BMC_SSD_RST#0_A8")
	)
	(segment
		(start 221.0816 -200.4441)
		(end 221.6023 -200.4441)
		(width 0.12065)
		(layer "B.Cu")
		(net "BMC_SSD_RST#0_A8")
	)
	(segment
		(start 221.6023 -200.4441)
		(end 222.1992 -199.8472)
		(width 0.12065)
		(layer "B.Cu")
		(net "BMC_SSD_RST#0_A8")
	)
	(segment
		(start 222.5929 -199.4535)
		(end 223.1644 -199.4535)
		(width 0.12065)
		(layer "B.Cu")
		(net "BMC_SSD_RST#0_A8")
	)
	(segment
		(start 222.1992 -199.8472)
		(end 222.5929 -199.4535)
		(width 0.12065)
		(layer "B.Cu")
		(net "BMC_SSD_RST#0_A8")
	)
	(via
		(at 121.158 -204.216)
		(size 0.7112)
		(drill 0.3556)
		(layers "F.Cu" "B.Cu")
		(net "BMC_SSD_RST#0_A7")
	)
	(segment
		(start 121.158 -204.597)
		(end 121.158 -204.216)
		(width 0.12065)
		(layer "B.Cu")
		(net "BMC_SSD_RST#0_A7")
	)
	(segment
		(start 121.8565 -205.2955)
		(end 121.158 -204.597)
		(width 0.12065)
		(layer "B.Cu")
		(net "BMC_SSD_RST#0_A7")
	)
	(segment
		(start 122.0597 -204.216)
		(end 122.1232 -204.2795)
		(width 0.12065)
		(layer "B.Cu")
		(net "BMC_SSD_RST#0_A7")
	)
	(segment
		(start 121.158 -204.216)
		(end 122.0597 -204.216)
		(width 0.12065)
		(layer "B.Cu")
		(net "BMC_SSD_RST#0_A7")
	)
	(segment
		(start 122.1232 -204.2795)
		(end 122.766074 -203.636626)
		(width 0.12065)
		(layer "B.Cu")
		(net "BMC_SSD_RST#0_A7")
	)
	(segment
		(start 122.428 -205.2955)
		(end 121.8565 -205.2955)
		(width 0.12065)
		(layer "B.Cu")
		(net "BMC_SSD_RST#0_A7")
	)
	(segment
		(start 122.766074 -203.636626)
		(end 123.612148 -203.636626)
		(width 0.12065)
		(layer "B.Cu")
		(net "BMC_SSD_RST#0_A7")
	)
	(via
		(at 134.623048 -203.96835)
		(size 0.7112)
		(drill 0.3556)
		(layers "F.Cu" "B.Cu")
		(net "BMC_SSD_RST#0_A6")
	)
	(segment
		(start 134.623048 -203.012548)
		(end 134.623048 -203.96835)
		(width 0.12065)
		(layer "B.Cu")
		(net "BMC_SSD_RST#0_A6")
	)
	(segment
		(start 135.808212 -205.404974)
		(end 134.623048 -204.21981)
		(width 0.12065)
		(layer "B.Cu")
		(net "BMC_SSD_RST#0_A6")
	)
	(segment
		(start 134.623048 -204.21981)
		(end 134.623048 -203.96835)
		(width 0.12065)
		(layer "B.Cu")
		(net "BMC_SSD_RST#0_A6")
	)
	(segment
		(start 135.808212 -204.851)
		(end 135.808212 -205.404974)
		(width 0.12065)
		(layer "B.Cu")
		(net "BMC_SSD_RST#0_A6")
	)
	(segment
		(start 136.00176 -204.657452)
		(end 135.808212 -204.851)
		(width 0.12065)
		(layer "B.Cu")
		(net "BMC_SSD_RST#0_A6")
	)
	(segment
		(start 134.62 -203.0095)
		(end 134.623048 -203.012548)
		(width 0.12065)
		(layer "B.Cu")
		(net "BMC_SSD_RST#0_A6")
	)
	(segment
		(start 136.00176 -203.6445)
		(end 136.00176 -204.657452)
		(width 0.12065)
		(layer "B.Cu")
		(net "BMC_SSD_RST#0_A6")
	)
	(via
		(at 76.962 -192.151)
		(size 0.7112)
		(drill 0.3556)
		(layers "F.Cu" "B.Cu")
		(net "BMC_SSD_RST#0_A5")
	)
	(segment
		(start 77.32776 -189.9285)
		(end 77.83576 -190.4365)
		(width 0.12065)
		(layer "B.Cu")
		(net "BMC_SSD_RST#0_A5")
	)
	(segment
		(start 76.962 -192.151)
		(end 76.962 -192.00876)
		(width 0.12065)
		(layer "B.Cu")
		(net "BMC_SSD_RST#0_A5")
	)
	(segment
		(start 77.83576 -191.135)
		(end 77.83576 -190.4365)
		(width 0.12065)
		(layer "B.Cu")
		(net "BMC_SSD_RST#0_A5")
	)
	(segment
		(start 78.023212 -192.196974)
		(end 77.007974 -192.196974)
		(width 0.12065)
		(layer "B.Cu")
		(net "BMC_SSD_RST#0_A5")
	)
	(segment
		(start 77.007974 -192.196974)
		(end 76.962 -192.151)
		(width 0.12065)
		(layer "B.Cu")
		(net "BMC_SSD_RST#0_A5")
	)
	(segment
		(start 76.962 -192.00876)
		(end 77.83576 -191.135)
		(width 0.12065)
		(layer "B.Cu")
		(net "BMC_SSD_RST#0_A5")
	)
	(segment
		(start 76.454 -189.9285)
		(end 77.32776 -189.9285)
		(width 0.12065)
		(layer "B.Cu")
		(net "BMC_SSD_RST#0_A5")
	)
	(via
		(at 329.692 -178.689)
		(size 0.7112)
		(drill 0.3556)
		(layers "F.Cu" "B.Cu")
		(net "BMC_SSD_RST#0_A4")
	)
	(segment
		(start 330.708 -179.5145)
		(end 332.138274 -179.5145)
		(width 0.12065)
		(layer "B.Cu")
		(net "BMC_SSD_RST#0_A4")
	)
	(segment
		(start 332.138274 -179.5145)
		(end 332.146148 -179.506626)
		(width 0.12065)
		(layer "B.Cu")
		(net "BMC_SSD_RST#0_A4")
	)
	(segment
		(start 329.692 -178.689)
		(end 329.8825 -178.689)
		(width 0.12065)
		(layer "B.Cu")
		(net "BMC_SSD_RST#0_A4")
	)
	(segment
		(start 329.692 -179.6415)
		(end 329.692 -178.689)
		(width 0.12065)
		(layer "B.Cu")
		(net "BMC_SSD_RST#0_A4")
	)
	(segment
		(start 329.8825 -178.689)
		(end 330.708 -179.5145)
		(width 0.12065)
		(layer "B.Cu")
		(net "BMC_SSD_RST#0_A4")
	)
	(via
		(at 217.93708 -199.68972)
		(size 0.7112)
		(drill 0.3556)
		(layers "F.Cu" "B.Cu")
		(net "BMC_SSD_RST#0_A3")
	)
	(segment
		(start 217.96248 -198.40702)
		(end 218.30792 -198.40702)
		(width 0.12065)
		(layer "B.Cu")
		(net "BMC_SSD_RST#0_A3")
	)
	(segment
		(start 218.10726 -199.8599)
		(end 218.10726 -200.71588)
		(width 0.12065)
		(layer "B.Cu")
		(net "BMC_SSD_RST#0_A3")
	)
	(segment
		(start 217.805 -198.5645)
		(end 217.96248 -198.40702)
		(width 0.12065)
		(layer "B.Cu")
		(net "BMC_SSD_RST#0_A3")
	)
	(segment
		(start 217.805 -199.55764)
		(end 217.93708 -199.68972)
		(width 0.12065)
		(layer "B.Cu")
		(net "BMC_SSD_RST#0_A3")
	)
	(segment
		(start 217.805 -198.5645)
		(end 217.805 -199.55764)
		(width 0.12065)
		(layer "B.Cu")
		(net "BMC_SSD_RST#0_A3")
	)
	(segment
		(start 218.91244 -197.8025)
		(end 219.18676 -197.8025)
		(width 0.12065)
		(layer "B.Cu")
		(net "BMC_SSD_RST#0_A3")
	)
	(segment
		(start 218.30792 -198.40702)
		(end 218.91244 -197.8025)
		(width 0.12065)
		(layer "B.Cu")
		(net "BMC_SSD_RST#0_A3")
	)
	(segment
		(start 217.93708 -199.68972)
		(end 218.10726 -199.8599)
		(width 0.12065)
		(layer "B.Cu")
		(net "BMC_SSD_RST#0_A3")
	)
	(via
		(at 131.191 -205.232)
		(size 0.7112)
		(drill 0.3556)
		(layers "F.Cu" "B.Cu")
		(net "BMC_SSD_RST#0_A2")
	)
	(segment
		(start 131.191 -205.08976)
		(end 131.93776 -204.343)
		(width 0.12065)
		(layer "B.Cu")
		(net "BMC_SSD_RST#0_A2")
	)
	(segment
		(start 131.191 -205.232)
		(end 131.191 -205.08976)
		(width 0.12065)
		(layer "B.Cu")
		(net "BMC_SSD_RST#0_A2")
	)
	(segment
		(start 130.556 -203.0095)
		(end 130.8735 -203.0095)
		(width 0.12065)
		(layer "B.Cu")
		(net "BMC_SSD_RST#0_A2")
	)
	(segment
		(start 131.93776 -204.343)
		(end 131.93776 -203.6445)
		(width 0.12065)
		(layer "B.Cu")
		(net "BMC_SSD_RST#0_A2")
	)
	(segment
		(start 132.125212 -205.404974)
		(end 131.363974 -205.404974)
		(width 0.12065)
		(layer "B.Cu")
		(net "BMC_SSD_RST#0_A2")
	)
	(segment
		(start 131.5085 -203.6445)
		(end 131.93776 -203.6445)
		(width 0.12065)
		(layer "B.Cu")
		(net "BMC_SSD_RST#0_A2")
	)
	(segment
		(start 131.363974 -205.404974)
		(end 131.191 -205.232)
		(width 0.12065)
		(layer "B.Cu")
		(net "BMC_SSD_RST#0_A2")
	)
	(segment
		(start 130.8735 -203.0095)
		(end 131.5085 -203.6445)
		(width 0.12065)
		(layer "B.Cu")
		(net "BMC_SSD_RST#0_A2")
	)
	(via
		(at 339.683852 -181.028086)
		(size 0.7112)
		(drill 0.3556)
		(layers "F.Cu" "B.Cu")
		(net "BMC_SSD_RST#0_A14")
	)
	(segment
		(start 339.344 -179.615084)
		(end 339.537802 -179.808886)
		(width 0.12065)
		(layer "B.Cu")
		(net "BMC_SSD_RST#0_A14")
	)
	(segment
		(start 340.782148 -179.633626)
		(end 340.782148 -181.200552)
		(width 0.12065)
		(layer "B.Cu")
		(net "BMC_SSD_RST#0_A14")
	)
	(segment
		(start 339.537802 -179.808886)
		(end 339.537802 -180.882036)
		(width 0.12065)
		(layer "B.Cu")
		(net "BMC_SSD_RST#0_A14")
	)
	(segment
		(start 340.782148 -181.200552)
		(end 340.5886 -181.3941)
		(width 0.12065)
		(layer "B.Cu")
		(net "BMC_SSD_RST#0_A14")
	)
	(segment
		(start 340.049866 -181.3941)
		(end 339.683852 -181.028086)
		(width 0.12065)
		(layer "B.Cu")
		(net "BMC_SSD_RST#0_A14")
	)
	(segment
		(start 339.344 -179.1335)
		(end 339.344 -179.615084)
		(width 0.12065)
		(layer "B.Cu")
		(net "BMC_SSD_RST#0_A14")
	)
	(segment
		(start 339.537802 -180.882036)
		(end 339.683852 -181.028086)
		(width 0.12065)
		(layer "B.Cu")
		(net "BMC_SSD_RST#0_A14")
	)
	(segment
		(start 340.5886 -181.3941)
		(end 340.049866 -181.3941)
		(width 0.12065)
		(layer "B.Cu")
		(net "BMC_SSD_RST#0_A14")
	)
	(via
		(at 212.4202 -198.9582)
		(size 0.7112)
		(drill 0.3556)
		(layers "F.Cu" "B.Cu")
		(net "BMC_SSD_RST#0_A13")
	)
	(segment
		(start 213.614 -197.6755)
		(end 214.2109 -197.6755)
		(width 0.12065)
		(layer "B.Cu")
		(net "BMC_SSD_RST#0_A13")
	)
	(segment
		(start 214.2109 -197.6755)
		(end 214.457026 -197.921626)
		(width 0.12065)
		(layer "B.Cu")
		(net "BMC_SSD_RST#0_A13")
	)
	(segment
		(start 214.457026 -197.921626)
		(end 215.052148 -197.921626)
		(width 0.12065)
		(layer "B.Cu")
		(net "BMC_SSD_RST#0_A13")
	)
	(segment
		(start 212.4202 -197.8533)
		(end 212.598 -197.6755)
		(width 0.12065)
		(layer "B.Cu")
		(net "BMC_SSD_RST#0_A13")
	)
	(segment
		(start 212.8774 -198.9836)
		(end 213.614 -198.247)
		(width 0.12065)
		(layer "B.Cu")
		(net "BMC_SSD_RST#0_A13")
	)
	(segment
		(start 212.4202 -198.9582)
		(end 212.4456 -198.9836)
		(width 0.12065)
		(layer "B.Cu")
		(net "BMC_SSD_RST#0_A13")
	)
	(segment
		(start 212.4456 -198.9836)
		(end 212.8774 -198.9836)
		(width 0.12065)
		(layer "B.Cu")
		(net "BMC_SSD_RST#0_A13")
	)
	(segment
		(start 212.4202 -198.9582)
		(end 212.4202 -197.8533)
		(width 0.12065)
		(layer "B.Cu")
		(net "BMC_SSD_RST#0_A13")
	)
	(segment
		(start 213.614 -198.247)
		(end 213.614 -197.6755)
		(width 0.12065)
		(layer "B.Cu")
		(net "BMC_SSD_RST#0_A13")
	)
	(via
		(at 225.552 -200.406)
		(size 0.7112)
		(drill 0.3556)
		(layers "F.Cu" "B.Cu")
		(net "BMC_SSD_RST#0_A12")
	)
	(segment
		(start 225.425 -199.3265)
		(end 225.425 -200.279)
		(width 0.12065)
		(layer "B.Cu")
		(net "BMC_SSD_RST#0_A12")
	)
	(segment
		(start 225.770186 -200.406)
		(end 225.552 -200.406)
		(width 0.12065)
		(layer "B.Cu")
		(net "BMC_SSD_RST#0_A12")
	)
	(segment
		(start 225.425 -200.279)
		(end 225.552 -200.406)
		(width 0.12065)
		(layer "B.Cu")
		(net "BMC_SSD_RST#0_A12")
	)
	(segment
		(start 226.80676 -199.369426)
		(end 226.80676 -197.8025)
		(width 0.12065)
		(layer "B.Cu")
		(net "BMC_SSD_RST#0_A12")
	)
	(segment
		(start 226.613212 -199.562974)
		(end 226.80676 -199.369426)
		(width 0.12065)
		(layer "B.Cu")
		(net "BMC_SSD_RST#0_A12")
	)
	(segment
		(start 226.613212 -199.562974)
		(end 225.770186 -200.406)
		(width 0.12065)
		(layer "B.Cu")
		(net "BMC_SSD_RST#0_A12")
	)
	(via
		(at 66.929 -190.1698)
		(size 0.7112)
		(drill 0.3556)
		(layers "F.Cu" "B.Cu")
		(net "BMC_SSD_RST#0_A11")
	)
	(segment
		(start 66.802 -191.0715)
		(end 66.802 -190.2968)
		(width 0.12065)
		(layer "B.Cu")
		(net "BMC_SSD_RST#0_A11")
	)
	(segment
		(start 66.929 -190.1698)
		(end 67.0433 -190.1698)
		(width 0.12065)
		(layer "B.Cu")
		(net "BMC_SSD_RST#0_A11")
	)
	(segment
		(start 68.3895 -191.0715)
		(end 69.032374 -190.428626)
		(width 0.12065)
		(layer "B.Cu")
		(net "BMC_SSD_RST#0_A11")
	)
	(segment
		(start 66.802 -190.2968)
		(end 66.929 -190.1698)
		(width 0.12065)
		(layer "B.Cu")
		(net "BMC_SSD_RST#0_A11")
	)
	(segment
		(start 67.0433 -190.1698)
		(end 67.945 -191.0715)
		(width 0.12065)
		(layer "B.Cu")
		(net "BMC_SSD_RST#0_A11")
	)
	(segment
		(start 67.945 -191.0715)
		(end 68.3895 -191.0715)
		(width 0.12065)
		(layer "B.Cu")
		(net "BMC_SSD_RST#0_A11")
	)
	(segment
		(start 69.032374 -190.428626)
		(end 69.383148 -190.428626)
		(width 0.12065)
		(layer "B.Cu")
		(net "BMC_SSD_RST#0_A11")
	)
	(via
		(at 80.633062 -191.056768)
		(size 0.7112)
		(drill 0.3556)
		(layers "F.Cu" "B.Cu")
		(net "BMC_SSD_RST#0_A10")
	)
	(segment
		(start 80.633062 -190.625984)
		(end 80.633062 -191.056768)
		(width 0.12065)
		(layer "B.Cu")
		(net "BMC_SSD_RST#0_A10")
	)
	(segment
		(start 80.518 -190.510922)
		(end 80.633062 -190.625984)
		(width 0.12065)
		(layer "B.Cu")
		(net "BMC_SSD_RST#0_A10")
	)
	(segment
		(start 81.706212 -192.196974)
		(end 81.54416 -192.196974)
		(width 0.12065)
		(layer "B.Cu")
		(net "BMC_SSD_RST#0_A10")
	)
	(segment
		(start 81.54416 -192.196974)
		(end 80.633062 -191.285876)
		(width 0.12065)
		(layer "B.Cu")
		(net "BMC_SSD_RST#0_A10")
	)
	(segment
		(start 80.633062 -191.285876)
		(end 80.633062 -191.056768)
		(width 0.12065)
		(layer "B.Cu")
		(net "BMC_SSD_RST#0_A10")
	)
	(segment
		(start 80.518 -190.0555)
		(end 80.518 -190.510922)
		(width 0.12065)
		(layer "B.Cu")
		(net "BMC_SSD_RST#0_A10")
	)
	(segment
		(start 81.89976 -192.003426)
		(end 81.706212 -192.196974)
		(width 0.12065)
		(layer "B.Cu")
		(net "BMC_SSD_RST#0_A10")
	)
	(segment
		(start 81.89976 -190.4365)
		(end 81.89976 -192.003426)
		(width 0.12065)
		(layer "B.Cu")
		(net "BMC_SSD_RST#0_A10")
	)
	(via
		(at 126.619 -205.486)
		(size 0.7112)
		(drill 0.3556)
		(layers "F.Cu" "B.Cu")
		(net "BMC_SSD_RST#0_A1")
	)
	(segment
		(start 126.492 -204.2795)
		(end 126.492 -205.359)
		(width 0.12065)
		(layer "B.Cu")
		(net "BMC_SSD_RST#0_A1")
	)
	(segment
		(start 127.680212 -204.678788)
		(end 127.680212 -205.404974)
		(width 0.12065)
		(layer "B.Cu")
		(net "BMC_SSD_RST#0_A1")
	)
	(segment
		(start 127.680212 -205.404974)
		(end 127.599186 -205.486)
		(width 0.12065)
		(layer "B.Cu")
		(net "BMC_SSD_RST#0_A1")
	)
	(segment
		(start 127.599186 -205.486)
		(end 126.619 -205.486)
		(width 0.12065)
		(layer "B.Cu")
		(net "BMC_SSD_RST#0_A1")
	)
	(segment
		(start 127.87376 -204.48524)
		(end 127.680212 -204.678788)
		(width 0.12065)
		(layer "B.Cu")
		(net "BMC_SSD_RST#0_A1")
	)
	(segment
		(start 126.492 -205.359)
		(end 126.619 -205.486)
		(width 0.12065)
		(layer "B.Cu")
		(net "BMC_SSD_RST#0_A1")
	)
	(segment
		(start 127.87376 -203.6445)
		(end 127.87376 -204.48524)
		(width 0.12065)
		(layer "B.Cu")
		(net "BMC_SSD_RST#0_A1")
	)
	(via
		(at 72.39 -192.278)
		(size 0.7112)
		(drill 0.3556)
		(layers "F.Cu" "B.Cu")
		(net "BMC_SSD_RST#0_A0")
	)
	(segment
		(start 73.77176 -190.4365)
		(end 73.77176 -191.576452)
		(width 0.12065)
		(layer "B.Cu")
		(net "BMC_SSD_RST#0_A0")
	)
	(segment
		(start 73.497186 -192.278)
		(end 72.39 -192.278)
		(width 0.12065)
		(layer "B.Cu")
		(net "BMC_SSD_RST#0_A0")
	)
	(segment
		(start 73.77176 -191.576452)
		(end 73.578212 -191.77)
		(width 0.12065)
		(layer "B.Cu")
		(net "BMC_SSD_RST#0_A0")
	)
	(segment
		(start 72.39 -191.0715)
		(end 72.39 -192.278)
		(width 0.12065)
		(layer "B.Cu")
		(net "BMC_SSD_RST#0_A0")
	)
	(segment
		(start 73.578212 -192.196974)
		(end 73.497186 -192.278)
		(width 0.12065)
		(layer "B.Cu")
		(net "BMC_SSD_RST#0_A0")
	)
	(segment
		(start 73.578212 -191.77)
		(end 73.578212 -192.196974)
		(width 0.12065)
		(layer "B.Cu")
		(net "BMC_SSD_RST#0_A0")
	)
	(segment
		(start 25.91308 -160.96488)
		(end 25.52446 -161.3535)
		(width 0.12065)
		(layer "F.Cu")
		(net "BMC_RESET#_DDR3_BUF")
	)
	(segment
		(start 23.38324 -161.3535)
		(end 24.765 -161.3535)
		(width 0.12065)
		(layer "F.Cu")
		(net "BMC_RESET#_DDR3_BUF")
	)
	(segment
		(start 25.52446 -161.3535)
		(end 24.765 -161.3535)
		(width 0.12065)
		(layer "F.Cu")
		(net "BMC_RESET#_DDR3_BUF")
	)
	(via
		(at 25.91308 -160.96488)
		(size 0.7112)
		(drill 0.3556)
		(layers "F.Cu" "B.Cu")
		(net "BMC_RESET#_DDR3_BUF")
	)
	(segment
		(start 34.504884 -135.684768)
		(end 34.105088 -135.284972)
		(width 0.12065)
		(layer "F.Cu")
		(net "BMC_MIOZ")
	)
	(via
		(at 17.416018 -134.97687)
		(size 0.7112)
		(drill 0.3556)
		(layers "F.Cu" "B.Cu")
		(net "BMC_MIOZ")
	)
	(via
		(at 34.105088 -135.284972)
		(size 0.4572)
		(drill 0.2032)
		(layers "F.Cu" "B.Cu")
		(net "BMC_MIOZ")
	)
	(via
		(at 18.8722 -135.5344)
		(size 0.508)
		(drill 0.254)
		(layers "F.Cu" "B.Cu")
		(net "BMC_MIOZ")
	)
	(segment
		(start 17.416018 -134.97687)
		(end 17.70507 -135.265922)
		(width 0.12065)
		(layer "B.Cu")
		(net "BMC_MIOZ")
	)
	(segment
		(start 17.9705 -135.518398)
		(end 17.9705 -135.89)
		(width 0.12065)
		(layer "B.Cu")
		(net "BMC_MIOZ")
	)
	(segment
		(start 18.5166 -135.89)
		(end 17.9705 -135.89)
		(width 0.12065)
		(layer "B.Cu")
		(net "BMC_MIOZ")
	)
	(segment
		(start 18.8722 -135.5344)
		(end 18.5166 -135.89)
		(width 0.12065)
		(layer "B.Cu")
		(net "BMC_MIOZ")
	)
	(segment
		(start 17.718024 -135.265922)
		(end 17.9705 -135.518398)
		(width 0.12065)
		(layer "B.Cu")
		(net "BMC_MIOZ")
	)
	(segment
		(start 17.70507 -135.265922)
		(end 17.718024 -135.265922)
		(width 0.12065)
		(layer "B.Cu")
		(net "BMC_MIOZ")
	)
	(segment
		(start 33.86201 -135.284972)
		(end 34.105088 -135.284972)
		(width 0.127)
		(layer "In2.Cu")
		(net "BMC_MIOZ")
	)
	(segment
		(start 21.080222 -135.2931)
		(end 30.257242 -135.2931)
		(width 0.127)
		(layer "In2.Cu")
		(net "BMC_MIOZ")
	)
	(segment
		(start 33.468056 -134.891018)
		(end 33.86201 -135.284972)
		(width 0.127)
		(layer "In2.Cu")
		(net "BMC_MIOZ")
	)
	(segment
		(start 18.910554 -135.572754)
		(end 20.800568 -135.572754)
		(width 0.127)
		(layer "In2.Cu")
		(net "BMC_MIOZ")
	)
	(segment
		(start 30.659324 -134.891018)
		(end 33.468056 -134.891018)
		(width 0.127)
		(layer "In2.Cu")
		(net "BMC_MIOZ")
	)
	(segment
		(start 20.800568 -135.572754)
		(end 21.080222 -135.2931)
		(width 0.127)
		(layer "In2.Cu")
		(net "BMC_MIOZ")
	)
	(segment
		(start 30.257242 -135.2931)
		(end 30.659324 -134.891018)
		(width 0.127)
		(layer "In2.Cu")
		(net "BMC_MIOZ")
	)
	(segment
		(start 18.8722 -135.5344)
		(end 18.910554 -135.572754)
		(width 0.127)
		(layer "In2.Cu")
		(net "BMC_MIOZ")
	)
	(segment
		(start 68.08216 -124.72416)
		(end 69.699378 -124.72416)
		(width 0.12065)
		(layer "F.Cu")
		(net "BMC_I2C4_MINI4_SDA_S")
	)
	(segment
		(start 63.27394 -122.24766)
		(end 64.24295 -121.27865)
		(width 0.12065)
		(layer "F.Cu")
		(net "BMC_I2C4_MINI4_SDA_S")
	)
	(segment
		(start 70.634352 -123.789186)
		(end 70.634352 -122.431048)
		(width 0.12065)
		(layer "F.Cu")
		(net "BMC_I2C4_MINI4_SDA_S")
	)
	(segment
		(start 62.74054 -122.24766)
		(end 63.27394 -122.24766)
		(width 0.12065)
		(layer "F.Cu")
		(net "BMC_I2C4_MINI4_SDA_S")
	)
	(segment
		(start 66.8782 -122.529854)
		(end 66.8782 -123.5202)
		(width 0.12065)
		(layer "F.Cu")
		(net "BMC_I2C4_MINI4_SDA_S")
	)
	(segment
		(start 69.699378 -124.72416)
		(end 70.634352 -123.789186)
		(width 0.12065)
		(layer "F.Cu")
		(net "BMC_I2C4_MINI4_SDA_S")
	)
	(segment
		(start 65.148968 -121.708926)
		(end 66.057272 -121.708926)
		(width 0.12065)
		(layer "F.Cu")
		(net "BMC_I2C4_MINI4_SDA_S")
	)
	(segment
		(start 64.718692 -121.27865)
		(end 65.148968 -121.708926)
		(width 0.12065)
		(layer "F.Cu")
		(net "BMC_I2C4_MINI4_SDA_S")
	)
	(segment
		(start 70.6374 -122.428)
		(end 70.6374 -121.4247)
		(width 0.12065)
		(layer "F.Cu")
		(net "BMC_I2C4_MINI4_SDA_S")
	)
	(segment
		(start 69.49694 -121.4247)
		(end 69.00164 -121.92)
		(width 0.12065)
		(layer "F.Cu")
		(net "BMC_I2C4_MINI4_SDA_S")
	)
	(segment
		(start 62.5602 -122.428)
		(end 62.74054 -122.24766)
		(width 0.12065)
		(layer "F.Cu")
		(net "BMC_I2C4_MINI4_SDA_S")
	)
	(segment
		(start 70.6374 -121.4247)
		(end 69.49694 -121.4247)
		(width 0.12065)
		(layer "F.Cu")
		(net "BMC_I2C4_MINI4_SDA_S")
	)
	(segment
		(start 64.24295 -121.27865)
		(end 64.718692 -121.27865)
		(width 0.12065)
		(layer "F.Cu")
		(net "BMC_I2C4_MINI4_SDA_S")
	)
	(segment
		(start 70.634352 -122.431048)
		(end 70.6374 -122.428)
		(width 0.12065)
		(layer "F.Cu")
		(net "BMC_I2C4_MINI4_SDA_S")
	)
	(segment
		(start 66.8782 -123.5202)
		(end 68.08216 -124.72416)
		(width 0.12065)
		(layer "F.Cu")
		(net "BMC_I2C4_MINI4_SDA_S")
	)
	(segment
		(start 66.057272 -121.708926)
		(end 66.8782 -122.529854)
		(width 0.12065)
		(layer "F.Cu")
		(net "BMC_I2C4_MINI4_SDA_S")
	)
	(via
		(at 62.5602 -122.428)
		(size 0.508)
		(drill 0.254)
		(layers "F.Cu" "B.Cu")
		(net "BMC_I2C4_MINI4_SDA_S")
	)
	(via
		(at 70.6374 -122.428)
		(size 0.7112)
		(drill 0.3556)
		(layers "F.Cu" "B.Cu")
		(net "BMC_I2C4_MINI4_SDA_S")
	)
	(segment
		(start 63.6905 -122.301)
		(end 62.6872 -122.301)
		(width 0.12065)
		(layer "B.Cu")
		(net "BMC_I2C4_MINI4_SDA_S")
	)
	(segment
		(start 62.6872 -122.301)
		(end 62.5602 -122.428)
		(width 0.12065)
		(layer "B.Cu")
		(net "BMC_I2C4_MINI4_SDA_S")
	)
	(segment
		(start 62.5602 -122.428)
		(end 61.7855 -122.428)
		(width 0.12065)
		(layer "B.Cu")
		(net "BMC_I2C4_MINI4_SDA_S")
	)
	(segment
		(start 66.3067 -120.0404)
		(end 66.1924 -120.1547)
		(width 0.12065)
		(layer "F.Cu")
		(net "BMC_I2C4_MINI4_SCL_S")
	)
	(segment
		(start 66.1924 -120.1547)
		(end 66.1035 -120.2436)
		(width 0.12065)
		(layer "F.Cu")
		(net "BMC_I2C4_MINI4_SCL_S")
	)
	(segment
		(start 64.034924 -120.777)
		(end 64.510666 -120.777)
		(width 0.12065)
		(layer "F.Cu")
		(net "BMC_I2C4_MINI4_SCL_S")
	)
	(segment
		(start 64.510666 -120.777)
		(end 65.044066 -120.2436)
		(width 0.12065)
		(layer "F.Cu")
		(net "BMC_I2C4_MINI4_SCL_S")
	)
	(segment
		(start 63.065914 -121.74601)
		(end 64.034924 -120.777)
		(width 0.12065)
		(layer "F.Cu")
		(net "BMC_I2C4_MINI4_SCL_S")
	)
	(segment
		(start 62.5602 -121.5644)
		(end 62.74181 -121.74601)
		(width 0.12065)
		(layer "F.Cu")
		(net "BMC_I2C4_MINI4_SCL_S")
	)
	(segment
		(start 67.70116 -120.0404)
		(end 66.3067 -120.0404)
		(width 0.12065)
		(layer "F.Cu")
		(net "BMC_I2C4_MINI4_SCL_S")
	)
	(segment
		(start 62.74181 -121.74601)
		(end 63.065914 -121.74601)
		(width 0.12065)
		(layer "F.Cu")
		(net "BMC_I2C4_MINI4_SCL_S")
	)
	(segment
		(start 65.044066 -120.2436)
		(end 65.278 -120.2436)
		(width 0.12065)
		(layer "F.Cu")
		(net "BMC_I2C4_MINI4_SCL_S")
	)
	(segment
		(start 66.1035 -120.2436)
		(end 65.278 -120.2436)
		(width 0.12065)
		(layer "F.Cu")
		(net "BMC_I2C4_MINI4_SCL_S")
	)
	(via
		(at 62.5602 -121.5644)
		(size 0.508)
		(drill 0.254)
		(layers "F.Cu" "B.Cu")
		(net "BMC_I2C4_MINI4_SCL_S")
	)
	(via
		(at 65.278 -120.2436)
		(size 0.7112)
		(drill 0.3556)
		(layers "F.Cu" "B.Cu")
		(net "BMC_I2C4_MINI4_SCL_S")
	)
	(segment
		(start 61.9379 -121.5644)
		(end 61.7855 -121.412)
		(width 0.12065)
		(layer "B.Cu")
		(net "BMC_I2C4_MINI4_SCL_S")
	)
	(segment
		(start 62.5602 -121.5644)
		(end 61.9379 -121.5644)
		(width 0.12065)
		(layer "B.Cu")
		(net "BMC_I2C4_MINI4_SCL_S")
	)
	(segment
		(start 63.2587 -121.7168)
		(end 63.6905 -121.285)
		(width 0.12065)
		(layer "B.Cu")
		(net "BMC_I2C4_MINI4_SCL_S")
	)
	(segment
		(start 62.7126 -121.7168)
		(end 63.2587 -121.7168)
		(width 0.12065)
		(layer "B.Cu")
		(net "BMC_I2C4_MINI4_SCL_S")
	)
	(segment
		(start 62.5602 -121.5644)
		(end 62.7126 -121.7168)
		(width 0.12065)
		(layer "B.Cu")
		(net "BMC_I2C4_MINI4_SCL_S")
	)
	(via
		(at 57.035192 -119.399558)
		(size 0.7112)
		(drill 0.3556)
		(layers "F.Cu" "B.Cu")
		(net "BMC_I2C3_MINI3_SDA_S")
	)
	(segment
		(start 58.569352 -118.4275)
		(end 58.565034 -118.431818)
		(width 0.12065)
		(layer "B.Cu")
		(net "BMC_I2C3_MINI3_SDA_S")
	)
	(segment
		(start 57.035192 -118.88216)
		(end 57.477152 -118.4402)
		(width 0.12065)
		(layer "B.Cu")
		(net "BMC_I2C3_MINI3_SDA_S")
	)
	(segment
		(start 60.052966 -118.765066)
		(end 59.7154 -118.4275)
		(width 0.12065)
		(layer "B.Cu")
		(net "BMC_I2C3_MINI3_SDA_S")
	)
	(segment
		(start 59.7154 -118.4275)
		(end 58.569352 -118.4275)
		(width 0.12065)
		(layer "B.Cu")
		(net "BMC_I2C3_MINI3_SDA_S")
	)
	(segment
		(start 57.035192 -119.399558)
		(end 57.035192 -118.88216)
		(width 0.12065)
		(layer "B.Cu")
		(net "BMC_I2C3_MINI3_SDA_S")
	)
	(segment
		(start 60.43803 -118.9482)
		(end 60.254896 -118.765066)
		(width 0.12065)
		(layer "B.Cu")
		(net "BMC_I2C3_MINI3_SDA_S")
	)
	(segment
		(start 61.17336 -118.9482)
		(end 60.43803 -118.9482)
		(width 0.12065)
		(layer "B.Cu")
		(net "BMC_I2C3_MINI3_SDA_S")
	)
	(segment
		(start 60.254896 -118.765066)
		(end 60.052966 -118.765066)
		(width 0.12065)
		(layer "B.Cu")
		(net "BMC_I2C3_MINI3_SDA_S")
	)
	(segment
		(start 57.477152 -118.4402)
		(end 58.556652 -118.4402)
		(width 0.12065)
		(layer "B.Cu")
		(net "BMC_I2C3_MINI3_SDA_S")
	)
	(segment
		(start 58.556652 -118.4402)
		(end 58.565034 -118.431818)
		(width 0.12065)
		(layer "B.Cu")
		(net "BMC_I2C3_MINI3_SDA_S")
	)
	(via
		(at 61.327284 -114.809016)
		(size 0.7112)
		(drill 0.3556)
		(layers "F.Cu" "B.Cu")
		(net "BMC_I2C3_MINI3_SCL_S")
	)
	(segment
		(start 61.327284 -114.809016)
		(end 59.968384 -114.809016)
		(width 0.12065)
		(layer "B.Cu")
		(net "BMC_I2C3_MINI3_SCL_S")
	)
	(segment
		(start 59.2582 -116.74729)
		(end 58.565288 -117.440202)
		(width 0.12065)
		(layer "B.Cu")
		(net "BMC_I2C3_MINI3_SCL_S")
	)
	(segment
		(start 61.327284 -114.809016)
		(end 62.804548 -114.809016)
		(width 0.12065)
		(layer "B.Cu")
		(net "BMC_I2C3_MINI3_SCL_S")
	)
	(segment
		(start 57.493154 -117.440202)
		(end 58.565288 -117.440202)
		(width 0.12065)
		(layer "B.Cu")
		(net "BMC_I2C3_MINI3_SCL_S")
	)
	(segment
		(start 59.2582 -115.5192)
		(end 59.2582 -116.74729)
		(width 0.12065)
		(layer "B.Cu")
		(net "BMC_I2C3_MINI3_SCL_S")
	)
	(segment
		(start 62.804548 -114.809016)
		(end 63.871856 -115.876324)
		(width 0.12065)
		(layer "B.Cu")
		(net "BMC_I2C3_MINI3_SCL_S")
	)
	(segment
		(start 63.9572 -117.5893)
		(end 63.7921 -117.5893)
		(width 0.12065)
		(layer "B.Cu")
		(net "BMC_I2C3_MINI3_SCL_S")
	)
	(segment
		(start 63.2714 -117.0686)
		(end 62.47384 -117.0686)
		(width 0.12065)
		(layer "B.Cu")
		(net "BMC_I2C3_MINI3_SCL_S")
	)
	(segment
		(start 63.9572 -116.275104)
		(end 63.9572 -117.5893)
		(width 0.12065)
		(layer "B.Cu")
		(net "BMC_I2C3_MINI3_SCL_S")
	)
	(segment
		(start 57.477152 -117.4242)
		(end 57.493154 -117.440202)
		(width 0.12065)
		(layer "B.Cu")
		(net "BMC_I2C3_MINI3_SCL_S")
	)
	(segment
		(start 63.7921 -117.5893)
		(end 63.2714 -117.0686)
		(width 0.12065)
		(layer "B.Cu")
		(net "BMC_I2C3_MINI3_SCL_S")
	)
	(segment
		(start 63.871856 -116.18976)
		(end 63.9572 -116.275104)
		(width 0.12065)
		(layer "B.Cu")
		(net "BMC_I2C3_MINI3_SCL_S")
	)
	(segment
		(start 63.871856 -115.876324)
		(end 63.871856 -116.18976)
		(width 0.12065)
		(layer "B.Cu")
		(net "BMC_I2C3_MINI3_SCL_S")
	)
	(segment
		(start 59.968384 -114.809016)
		(end 59.2582 -115.5192)
		(width 0.12065)
		(layer "B.Cu")
		(net "BMC_I2C3_MINI3_SCL_S")
	)
	(segment
		(start 15.4686 -125.760988)
		(end 15.4686 -125.9586)
		(width 0.12065)
		(layer "F.Cu")
		(net "BMC_I2C2_MINI2_SDA_S")
	)
	(segment
		(start 14.74724 -126.0348)
		(end 15.194788 -126.0348)
		(width 0.12065)
		(layer "F.Cu")
		(net "BMC_I2C2_MINI2_SDA_S")
	)
	(segment
		(start 16.256 -126.386336)
		(end 16.256 -125.5395)
		(width 0.12065)
		(layer "F.Cu")
		(net "BMC_I2C2_MINI2_SDA_S")
	)
	(segment
		(start 15.194788 -126.0348)
		(end 15.4686 -125.760988)
		(width 0.12065)
		(layer "F.Cu")
		(net "BMC_I2C2_MINI2_SDA_S")
	)
	(segment
		(start 16.09598 -126.546356)
		(end 16.256 -126.386336)
		(width 0.12065)
		(layer "F.Cu")
		(net "BMC_I2C2_MINI2_SDA_S")
	)
	(segment
		(start 16.09598 -126.58598)
		(end 16.09598 -126.546356)
		(width 0.12065)
		(layer "F.Cu")
		(net "BMC_I2C2_MINI2_SDA_S")
	)
	(segment
		(start 15.4686 -125.9586)
		(end 16.09598 -126.58598)
		(width 0.12065)
		(layer "F.Cu")
		(net "BMC_I2C2_MINI2_SDA_S")
	)
	(via
		(at 15.4686 -125.760988)
		(size 0.508)
		(drill 0.254)
		(layers "F.Cu" "B.Cu")
		(net "BMC_I2C2_MINI2_SDA_S")
	)
	(via
		(at 16.09598 -126.546356)
		(size 0.7112)
		(drill 0.3556)
		(layers "F.Cu" "B.Cu")
		(net "BMC_I2C2_MINI2_SDA_S")
	)
	(segment
		(start 19.750024 -125.29185)
		(end 19.956018 -125.497844)
		(width 0.12065)
		(layer "B.Cu")
		(net "BMC_I2C2_MINI2_SDA_S")
	)
	(segment
		(start 18.104104 -125.29185)
		(end 19.750024 -125.29185)
		(width 0.12065)
		(layer "B.Cu")
		(net "BMC_I2C2_MINI2_SDA_S")
	)
	(segment
		(start 15.309088 -125.9205)
		(end 15.4686 -125.760988)
		(width 0.12065)
		(layer "B.Cu")
		(net "BMC_I2C2_MINI2_SDA_S")
	)
	(segment
		(start 17.500854 -124.6886)
		(end 18.104104 -125.29185)
		(width 0.12065)
		(layer "B.Cu")
		(net "BMC_I2C2_MINI2_SDA_S")
	)
	(segment
		(start 15.4686 -125.760988)
		(end 16.540988 -124.6886)
		(width 0.12065)
		(layer "B.Cu")
		(net "BMC_I2C2_MINI2_SDA_S")
	)
	(segment
		(start 14.6558 -125.9205)
		(end 15.309088 -125.9205)
		(width 0.12065)
		(layer "B.Cu")
		(net "BMC_I2C2_MINI2_SDA_S")
	)
	(segment
		(start 16.540988 -124.6886)
		(end 17.500854 -124.6886)
		(width 0.12065)
		(layer "B.Cu")
		(net "BMC_I2C2_MINI2_SDA_S")
	)
	(segment
		(start 10.822686 -124.5743)
		(end 11.9126 -124.5743)
		(width 0.12065)
		(layer "F.Cu")
		(net "BMC_I2C2_MINI2_SCL_S")
	)
	(segment
		(start 10.803636 -124.59335)
		(end 10.822686 -124.5743)
		(width 0.12065)
		(layer "F.Cu")
		(net "BMC_I2C2_MINI2_SCL_S")
	)
	(segment
		(start 13.44676 -124.41174)
		(end 13.208 -124.6505)
		(width 0.12065)
		(layer "F.Cu")
		(net "BMC_I2C2_MINI2_SCL_S")
	)
	(segment
		(start 12.73556 -124.6505)
		(end 11.9888 -124.6505)
		(width 0.12065)
		(layer "F.Cu")
		(net "BMC_I2C2_MINI2_SCL_S")
	)
	(segment
		(start 13.208 -124.6505)
		(end 12.73556 -124.6505)
		(width 0.12065)
		(layer "F.Cu")
		(net "BMC_I2C2_MINI2_SCL_S")
	)
	(segment
		(start 11.9888 -124.6505)
		(end 11.9126 -124.5743)
		(width 0.12065)
		(layer "F.Cu")
		(net "BMC_I2C2_MINI2_SCL_S")
	)
	(segment
		(start 13.44676 -124.1552)
		(end 13.44676 -124.41174)
		(width 0.12065)
		(layer "F.Cu")
		(net "BMC_I2C2_MINI2_SCL_S")
	)
	(via
		(at 12.73556 -124.6505)
		(size 0.508)
		(drill 0.254)
		(layers "F.Cu" "B.Cu")
		(net "BMC_I2C2_MINI2_SCL_S")
	)
	(via
		(at 10.803636 -124.59335)
		(size 0.7112)
		(drill 0.3556)
		(layers "F.Cu" "B.Cu")
		(net "BMC_I2C2_MINI2_SCL_S")
	)
	(segment
		(start 12.74826 -124.6378)
		(end 13.6398 -124.6378)
		(width 0.12065)
		(layer "B.Cu")
		(net "BMC_I2C2_MINI2_SCL_S")
	)
	(segment
		(start 12.73556 -124.6505)
		(end 13.202412 -125.117352)
		(width 0.12065)
		(layer "B.Cu")
		(net "BMC_I2C2_MINI2_SCL_S")
	)
	(segment
		(start 17.70888 -124.18695)
		(end 18.31213 -124.7902)
		(width 0.12065)
		(layer "B.Cu")
		(net "BMC_I2C2_MINI2_SCL_S")
	)
	(segment
		(start 13.202412 -125.117352)
		(end 13.202412 -125.508512)
		(width 0.12065)
		(layer "B.Cu")
		(net "BMC_I2C2_MINI2_SCL_S")
	)
	(segment
		(start 13.202412 -125.508512)
		(end 13.6144 -125.9205)
		(width 0.12065)
		(layer "B.Cu")
		(net "BMC_I2C2_MINI2_SCL_S")
	)
	(segment
		(start 19.647662 -124.7902)
		(end 19.956018 -124.481844)
		(width 0.12065)
		(layer "B.Cu")
		(net "BMC_I2C2_MINI2_SCL_S")
	)
	(segment
		(start 18.31213 -124.7902)
		(end 19.647662 -124.7902)
		(width 0.12065)
		(layer "B.Cu")
		(net "BMC_I2C2_MINI2_SCL_S")
	)
	(segment
		(start 15.637256 -124.882656)
		(end 16.332962 -124.18695)
		(width 0.12065)
		(layer "B.Cu")
		(net "BMC_I2C2_MINI2_SCL_S")
	)
	(segment
		(start 13.6398 -124.6378)
		(end 13.884656 -124.882656)
		(width 0.12065)
		(layer "B.Cu")
		(net "BMC_I2C2_MINI2_SCL_S")
	)
	(segment
		(start 13.884656 -124.882656)
		(end 15.637256 -124.882656)
		(width 0.12065)
		(layer "B.Cu")
		(net "BMC_I2C2_MINI2_SCL_S")
	)
	(segment
		(start 12.73556 -124.6505)
		(end 12.74826 -124.6378)
		(width 0.12065)
		(layer "B.Cu")
		(net "BMC_I2C2_MINI2_SCL_S")
	)
	(segment
		(start 16.332962 -124.18695)
		(end 17.70888 -124.18695)
		(width 0.12065)
		(layer "B.Cu")
		(net "BMC_I2C2_MINI2_SCL_S")
	)
	(segment
		(start 57.3786 -26.7589)
		(end 57.073292 -26.7589)
		(width 0.12065)
		(layer "F.Cu")
		(net "BMC_I2C14_MINI8_SDA_S")
	)
	(segment
		(start 57.073292 -26.7589)
		(end 56.477916 -26.163524)
		(width 0.12065)
		(layer "F.Cu")
		(net "BMC_I2C14_MINI8_SDA_S")
	)
	(via
		(at 44.530518 -105.837482)
		(size 0.7112)
		(drill 0.3556)
		(layers "F.Cu" "B.Cu")
		(net "BMC_I2C14_MINI8_SDA_S")
	)
	(via
		(at 56.477916 -26.163524)
		(size 0.508)
		(drill 0.254)
		(layers "F.Cu" "B.Cu")
		(net "BMC_I2C14_MINI8_SDA_S")
	)
	(via
		(at 46.99 -106.6546)
		(size 0.508)
		(drill 0.254)
		(layers "F.Cu" "B.Cu")
		(net "BMC_I2C14_MINI8_SDA_S")
	)
	(via
		(at 70.931278 -57.49036)
		(size 0.508)
		(drill 0.254)
		(layers "F.Cu" "B.Cu")
		(net "BMC_I2C14_MINI8_SDA_S")
	)
	(via
		(at 57.53862 -127.585978)
		(size 0.508)
		(drill 0.254)
		(layers "F.Cu" "B.Cu")
		(net "BMC_I2C14_MINI8_SDA_S")
	)
	(segment
		(start 44.530518 -105.837482)
		(end 45.347636 -106.6546)
		(width 0.12065)
		(layer "B.Cu")
		(net "BMC_I2C14_MINI8_SDA_S")
	)
	(segment
		(start 44.4754 -105.782364)
		(end 44.530518 -105.837482)
		(width 0.12065)
		(layer "B.Cu")
		(net "BMC_I2C14_MINI8_SDA_S")
	)
	(segment
		(start 45.347636 -106.6546)
		(end 46.99 -106.6546)
		(width 0.12065)
		(layer "B.Cu")
		(net "BMC_I2C14_MINI8_SDA_S")
	)
	(segment
		(start 52.828952 -127.968248)
		(end 52.238148 -127.968248)
		(width 0.12065)
		(layer "B.Cu")
		(net "BMC_I2C14_MINI8_SDA_S")
	)
	(segment
		(start 56.54675 -126.961646)
		(end 56.505348 -126.920244)
		(width 0.12065)
		(layer "B.Cu")
		(net "BMC_I2C14_MINI8_SDA_S")
	)
	(segment
		(start 52.238148 -127.968248)
		(end 51.9811 -127.7112)
		(width 0.12065)
		(layer "B.Cu")
		(net "BMC_I2C14_MINI8_SDA_S")
	)
	(segment
		(start 58.2422 -127.74295)
		(end 58.47715 -127.508)
		(width 0.12065)
		(layer "B.Cu")
		(net "BMC_I2C14_MINI8_SDA_S")
	)
	(segment
		(start 47.6504 -103.89616)
		(end 47.6504 -102.9081)
		(width 0.12065)
		(layer "B.Cu")
		(net "BMC_I2C14_MINI8_SDA_S")
	)
	(segment
		(start 56.634126 -126.961646)
		(end 56.54675 -126.961646)
		(width 0.12065)
		(layer "B.Cu")
		(net "BMC_I2C14_MINI8_SDA_S")
	)
	(segment
		(start 56.505348 -126.920244)
		(end 53.876956 -126.920244)
		(width 0.12065)
		(layer "B.Cu")
		(net "BMC_I2C14_MINI8_SDA_S")
	)
	(segment
		(start 53.876956 -126.920244)
		(end 52.828952 -127.968248)
		(width 0.12065)
		(layer "B.Cu")
		(net "BMC_I2C14_MINI8_SDA_S")
	)
	(segment
		(start 48.1203 -102.4382)
		(end 45.3136 -102.4382)
		(width 0.12065)
		(layer "B.Cu")
		(net "BMC_I2C14_MINI8_SDA_S")
	)
	(segment
		(start 47.6504 -102.9081)
		(end 48.1203 -102.4382)
		(width 0.12065)
		(layer "B.Cu")
		(net "BMC_I2C14_MINI8_SDA_S")
	)
	(segment
		(start 58.47715 -127.508)
		(end 58.7629 -127.508)
		(width 0.12065)
		(layer "B.Cu")
		(net "BMC_I2C14_MINI8_SDA_S")
	)
	(segment
		(start 45.3136 -102.4382)
		(end 44.4754 -103.2764)
		(width 0.12065)
		(layer "B.Cu")
		(net "BMC_I2C14_MINI8_SDA_S")
	)
	(segment
		(start 57.53862 -127.585978)
		(end 57.695592 -127.74295)
		(width 0.12065)
		(layer "B.Cu")
		(net "BMC_I2C14_MINI8_SDA_S")
	)
	(segment
		(start 57.695592 -127.74295)
		(end 58.2422 -127.74295)
		(width 0.12065)
		(layer "B.Cu")
		(net "BMC_I2C14_MINI8_SDA_S")
	)
	(segment
		(start 57.53862 -127.585978)
		(end 57.258458 -127.585978)
		(width 0.12065)
		(layer "B.Cu")
		(net "BMC_I2C14_MINI8_SDA_S")
	)
	(segment
		(start 57.258458 -127.585978)
		(end 56.634126 -126.961646)
		(width 0.12065)
		(layer "B.Cu")
		(net "BMC_I2C14_MINI8_SDA_S")
	)
	(segment
		(start 44.4754 -103.2764)
		(end 44.4754 -105.782364)
		(width 0.12065)
		(layer "B.Cu")
		(net "BMC_I2C14_MINI8_SDA_S")
	)
	(segment
		(start 80.5688 -43.0276)
		(end 80.5688 -34.1884)
		(width 0.127)
		(layer "In2.Cu")
		(net "BMC_I2C14_MINI8_SDA_S")
	)
	(segment
		(start 57.830466 -127.585978)
		(end 58.165746 -127.921258)
		(width 0.127)
		(layer "In2.Cu")
		(net "BMC_I2C14_MINI8_SDA_S")
	)
	(segment
		(start 72.662034 -122.174)
		(end 75.379834 -119.4562)
		(width 0.127)
		(layer "In2.Cu")
		(net "BMC_I2C14_MINI8_SDA_S")
	)
	(segment
		(start 78.9432 -116.908834)
		(end 80.6958 -115.156234)
		(width 0.127)
		(layer "In2.Cu")
		(net "BMC_I2C14_MINI8_SDA_S")
	)
	(segment
		(start 48.718978 -106.289348)
		(end 48.718978 -106.287824)
		(width 0.127)
		(layer "In2.Cu")
		(net "BMC_I2C14_MINI8_SDA_S")
	)
	(segment
		(start 75.379834 -119.4562)
		(end 78.173834 -119.4562)
		(width 0.127)
		(layer "In2.Cu")
		(net "BMC_I2C14_MINI8_SDA_S")
	)
	(segment
		(start 49.167034 -106.99877)
		(end 48.7426 -106.574336)
		(width 0.127)
		(layer "In2.Cu")
		(net "BMC_I2C14_MINI8_SDA_S")
	)
	(segment
		(start 48.703738 -106.243628)
		(end 48.28413 -106.243628)
		(width 0.127)
		(layer "In2.Cu")
		(net "BMC_I2C14_MINI8_SDA_S")
	)
	(segment
		(start 61.766196 -29.558996)
		(end 61.766196 -27.926284)
		(width 0.127)
		(layer "In2.Cu")
		(net "BMC_I2C14_MINI8_SDA_S")
	)
	(segment
		(start 58.429398 -127.9398)
		(end 62.149482 -127.9398)
		(width 0.127)
		(layer "In2.Cu")
		(net "BMC_I2C14_MINI8_SDA_S")
	)
	(segment
		(start 64.3509 -32.1437)
		(end 61.766196 -29.558996)
		(width 0.127)
		(layer "In2.Cu")
		(net "BMC_I2C14_MINI8_SDA_S")
	)
	(segment
		(start 80.6958 -115.156234)
		(end 80.6958 -108.414566)
		(width 0.127)
		(layer "In2.Cu")
		(net "BMC_I2C14_MINI8_SDA_S")
	)
	(segment
		(start 51.934618 -106.99877)
		(end 49.167034 -106.99877)
		(width 0.127)
		(layer "In2.Cu")
		(net "BMC_I2C14_MINI8_SDA_S")
	)
	(segment
		(start 57.252616 -109.075728)
		(end 54.807104 -106.630216)
		(width 0.127)
		(layer "In2.Cu")
		(net "BMC_I2C14_MINI8_SDA_S")
	)
	(segment
		(start 78.5241 -32.1437)
		(end 64.3509 -32.1437)
		(width 0.127)
		(layer "In2.Cu")
		(net "BMC_I2C14_MINI8_SDA_S")
	)
	(segment
		(start 66.491866 -129.185416)
		(end 66.949828 -128.727454)
		(width 0.127)
		(layer "In2.Cu")
		(net "BMC_I2C14_MINI8_SDA_S")
	)
	(segment
		(start 68.981066 -107.9881)
		(end 67.893438 -109.075728)
		(width 0.127)
		(layer "In2.Cu")
		(net "BMC_I2C14_MINI8_SDA_S")
	)
	(segment
		(start 48.7426 -106.574336)
		(end 48.7426 -106.364278)
		(width 0.127)
		(layer "In2.Cu")
		(net "BMC_I2C14_MINI8_SDA_S")
	)
	(segment
		(start 48.7426 -106.364278)
		(end 48.718978 -106.289348)
		(width 0.127)
		(layer "In2.Cu")
		(net "BMC_I2C14_MINI8_SDA_S")
	)
	(segment
		(start 69.602858 -122.174)
		(end 72.662034 -122.174)
		(width 0.127)
		(layer "In2.Cu")
		(net "BMC_I2C14_MINI8_SDA_S")
	)
	(segment
		(start 66.949828 -128.727454)
		(end 66.949828 -127.6985)
		(width 0.127)
		(layer "In2.Cu")
		(net "BMC_I2C14_MINI8_SDA_S")
	)
	(segment
		(start 63.395098 -129.185416)
		(end 66.491866 -129.185416)
		(width 0.127)
		(layer "In2.Cu")
		(net "BMC_I2C14_MINI8_SDA_S")
	)
	(segment
		(start 71.23176 -52.36464)
		(end 80.5688 -43.0276)
		(width 0.127)
		(layer "In2.Cu")
		(net "BMC_I2C14_MINI8_SDA_S")
	)
	(segment
		(start 68.11645 -126.531878)
		(end 68.11645 -123.660408)
		(width 0.127)
		(layer "In2.Cu")
		(net "BMC_I2C14_MINI8_SDA_S")
	)
	(segment
		(start 52.303172 -106.630216)
		(end 51.934618 -106.99877)
		(width 0.127)
		(layer "In2.Cu")
		(net "BMC_I2C14_MINI8_SDA_S")
	)
	(segment
		(start 71.23176 -57.189878)
		(end 71.23176 -52.36464)
		(width 0.127)
		(layer "In2.Cu")
		(net "BMC_I2C14_MINI8_SDA_S")
	)
	(segment
		(start 54.807104 -106.630216)
		(end 52.303172 -106.630216)
		(width 0.127)
		(layer "In2.Cu")
		(net "BMC_I2C14_MINI8_SDA_S")
	)
	(segment
		(start 48.28413 -106.243628)
		(end 46.99 -106.6546)
		(width 0.127)
		(layer "In2.Cu")
		(net "BMC_I2C14_MINI8_SDA_S")
	)
	(segment
		(start 61.766196 -27.926284)
		(end 60.003436 -26.163524)
		(width 0.127)
		(layer "In2.Cu")
		(net "BMC_I2C14_MINI8_SDA_S")
	)
	(segment
		(start 60.003436 -26.163524)
		(end 56.477916 -26.163524)
		(width 0.127)
		(layer "In2.Cu")
		(net "BMC_I2C14_MINI8_SDA_S")
	)
	(segment
		(start 70.931278 -57.49036)
		(end 71.23176 -57.189878)
		(width 0.127)
		(layer "In2.Cu")
		(net "BMC_I2C14_MINI8_SDA_S")
	)
	(segment
		(start 66.949828 -127.6985)
		(end 68.11645 -126.531878)
		(width 0.127)
		(layer "In2.Cu")
		(net "BMC_I2C14_MINI8_SDA_S")
	)
	(segment
		(start 62.149482 -127.9398)
		(end 63.395098 -129.185416)
		(width 0.127)
		(layer "In2.Cu")
		(net "BMC_I2C14_MINI8_SDA_S")
	)
	(segment
		(start 48.7045 -106.24439)
		(end 48.703738 -106.243628)
		(width 0.127)
		(layer "In2.Cu")
		(net "BMC_I2C14_MINI8_SDA_S")
	)
	(segment
		(start 58.165746 -127.921258)
		(end 58.410856 -127.921258)
		(width 0.127)
		(layer "In2.Cu")
		(net "BMC_I2C14_MINI8_SDA_S")
	)
	(segment
		(start 57.53862 -127.585978)
		(end 57.830466 -127.585978)
		(width 0.127)
		(layer "In2.Cu")
		(net "BMC_I2C14_MINI8_SDA_S")
	)
	(segment
		(start 78.173834 -119.4562)
		(end 78.9432 -118.686834)
		(width 0.127)
		(layer "In2.Cu")
		(net "BMC_I2C14_MINI8_SDA_S")
	)
	(segment
		(start 78.9432 -118.686834)
		(end 78.9432 -116.908834)
		(width 0.127)
		(layer "In2.Cu")
		(net "BMC_I2C14_MINI8_SDA_S")
	)
	(segment
		(start 48.718978 -106.287824)
		(end 48.7045 -106.24439)
		(width 0.127)
		(layer "In2.Cu")
		(net "BMC_I2C14_MINI8_SDA_S")
	)
	(segment
		(start 58.410856 -127.921258)
		(end 58.429398 -127.9398)
		(width 0.127)
		(layer "In2.Cu")
		(net "BMC_I2C14_MINI8_SDA_S")
	)
	(segment
		(start 68.11645 -123.660408)
		(end 69.602858 -122.174)
		(width 0.127)
		(layer "In2.Cu")
		(net "BMC_I2C14_MINI8_SDA_S")
	)
	(segment
		(start 80.269334 -107.9881)
		(end 68.981066 -107.9881)
		(width 0.127)
		(layer "In2.Cu")
		(net "BMC_I2C14_MINI8_SDA_S")
	)
	(segment
		(start 80.6958 -108.414566)
		(end 80.269334 -107.9881)
		(width 0.127)
		(layer "In2.Cu")
		(net "BMC_I2C14_MINI8_SDA_S")
	)
	(segment
		(start 67.893438 -109.075728)
		(end 57.252616 -109.075728)
		(width 0.127)
		(layer "In2.Cu")
		(net "BMC_I2C14_MINI8_SDA_S")
	)
	(segment
		(start 80.5688 -34.1884)
		(end 78.5241 -32.1437)
		(width 0.127)
		(layer "In2.Cu")
		(net "BMC_I2C14_MINI8_SDA_S")
	)
	(segment
		(start 53.2384 -77.481938)
		(end 53.2384 -80.010508)
		(width 0.127)
		(layer "In5.Cu")
		(net "BMC_I2C14_MINI8_SDA_S")
	)
	(segment
		(start 51.1556 -89.019634)
		(end 47.3456 -92.829634)
		(width 0.127)
		(layer "In5.Cu")
		(net "BMC_I2C14_MINI8_SDA_S")
	)
	(segment
		(start 47.879254 -105.765346)
		(end 46.99 -106.6546)
		(width 0.127)
		(layer "In5.Cu")
		(net "BMC_I2C14_MINI8_SDA_S")
	)
	(segment
		(start 53.2384 -80.010508)
		(end 51.1556 -82.093308)
		(width 0.127)
		(layer "In5.Cu")
		(net "BMC_I2C14_MINI8_SDA_S")
	)
	(segment
		(start 70.29196 -58.9788)
		(end 66.820034 -58.9788)
		(width 0.127)
		(layer "In5.Cu")
		(net "BMC_I2C14_MINI8_SDA_S")
	)
	(segment
		(start 66.820034 -58.9788)
		(end 55.753 -70.045834)
		(width 0.127)
		(layer "In5.Cu")
		(net "BMC_I2C14_MINI8_SDA_S")
	)
	(segment
		(start 71.15556 -57.714642)
		(end 71.15556 -58.1152)
		(width 0.127)
		(layer "In5.Cu")
		(net "BMC_I2C14_MINI8_SDA_S")
	)
	(segment
		(start 71.15556 -58.1152)
		(end 70.29196 -58.9788)
		(width 0.127)
		(layer "In5.Cu")
		(net "BMC_I2C14_MINI8_SDA_S")
	)
	(segment
		(start 47.879254 -105.46842)
		(end 47.879254 -105.765346)
		(width 0.127)
		(layer "In5.Cu")
		(net "BMC_I2C14_MINI8_SDA_S")
	)
	(segment
		(start 70.931278 -57.49036)
		(end 71.15556 -57.714642)
		(width 0.127)
		(layer "In5.Cu")
		(net "BMC_I2C14_MINI8_SDA_S")
	)
	(segment
		(start 47.3456 -92.829634)
		(end 47.3456 -104.934766)
		(width 0.127)
		(layer "In5.Cu")
		(net "BMC_I2C14_MINI8_SDA_S")
	)
	(segment
		(start 51.1556 -82.093308)
		(end 51.1556 -89.019634)
		(width 0.127)
		(layer "In5.Cu")
		(net "BMC_I2C14_MINI8_SDA_S")
	)
	(segment
		(start 55.753 -74.967338)
		(end 53.2384 -77.481938)
		(width 0.127)
		(layer "In5.Cu")
		(net "BMC_I2C14_MINI8_SDA_S")
	)
	(segment
		(start 47.3456 -104.934766)
		(end 47.879254 -105.46842)
		(width 0.127)
		(layer "In5.Cu")
		(net "BMC_I2C14_MINI8_SDA_S")
	)
	(segment
		(start 55.753 -70.045834)
		(end 55.753 -74.967338)
		(width 0.127)
		(layer "In5.Cu")
		(net "BMC_I2C14_MINI8_SDA_S")
	)
	(segment
		(start 66.3448 -26.7589)
		(end 67.263518 -26.7589)
		(width 0.12065)
		(layer "F.Cu")
		(net "BMC_I2C14_MINI8_SCL_S")
	)
	(via
		(at 67.263518 -26.7589)
		(size 0.508)
		(drill 0.254)
		(layers "F.Cu" "B.Cu")
		(net "BMC_I2C14_MINI8_SCL_S")
	)
	(via
		(at 50.7746 -106.7054)
		(size 0.7112)
		(drill 0.3556)
		(layers "F.Cu" "B.Cu")
		(net "BMC_I2C14_MINI8_SCL_S")
	)
	(via
		(at 50.8254 -105.4354)
		(size 0.508)
		(drill 0.254)
		(layers "F.Cu" "B.Cu")
		(net "BMC_I2C14_MINI8_SCL_S")
	)
	(via
		(at 57.4802 -128.4478)
		(size 0.508)
		(drill 0.254)
		(layers "F.Cu" "B.Cu")
		(net "BMC_I2C14_MINI8_SCL_S")
	)
	(via
		(at 72.039988 -57.49036)
		(size 0.508)
		(drill 0.254)
		(layers "F.Cu" "B.Cu")
		(net "BMC_I2C14_MINI8_SCL_S")
	)
	(segment
		(start 58.2422 -128.2446)
		(end 58.5216 -128.524)
		(width 0.12065)
		(layer "B.Cu")
		(net "BMC_I2C14_MINI8_SCL_S")
	)
	(segment
		(start 57.6834 -128.2446)
		(end 58.2422 -128.2446)
		(width 0.12065)
		(layer "B.Cu")
		(net "BMC_I2C14_MINI8_SCL_S")
	)
	(segment
		(start 56.338724 -127.463296)
		(end 56.4261 -127.463296)
		(width 0.12065)
		(layer "B.Cu")
		(net "BMC_I2C14_MINI8_SCL_S")
	)
	(segment
		(start 50.7746 -105.4862)
		(end 50.8254 -105.4354)
		(width 0.12065)
		(layer "B.Cu")
		(net "BMC_I2C14_MINI8_SCL_S")
	)
	(segment
		(start 57.175654 -128.21285)
		(end 57.24525 -128.21285)
		(width 0.12065)
		(layer "B.Cu")
		(net "BMC_I2C14_MINI8_SCL_S")
	)
	(segment
		(start 49.5554 -107.1626)
		(end 49.0601 -106.6673)
		(width 0.12065)
		(layer "B.Cu")
		(net "BMC_I2C14_MINI8_SCL_S")
	)
	(segment
		(start 58.5216 -128.524)
		(end 58.7629 -128.524)
		(width 0.12065)
		(layer "B.Cu")
		(net "BMC_I2C14_MINI8_SCL_S")
	)
	(segment
		(start 51.9811 -128.7272)
		(end 52.238402 -128.469898)
		(width 0.12065)
		(layer "B.Cu")
		(net "BMC_I2C14_MINI8_SCL_S")
	)
	(segment
		(start 49.0601 -105.66654)
		(end 49.0601 -106.6292)
		(width 0.12065)
		(layer "B.Cu")
		(net "BMC_I2C14_MINI8_SCL_S")
	)
	(segment
		(start 49.53 -105.19664)
		(end 49.0601 -105.66654)
		(width 0.12065)
		(layer "B.Cu")
		(net "BMC_I2C14_MINI8_SCL_S")
	)
	(segment
		(start 54.084982 -127.421894)
		(end 56.297322 -127.421894)
		(width 0.12065)
		(layer "B.Cu")
		(net "BMC_I2C14_MINI8_SCL_S")
	)
	(segment
		(start 50.3174 -107.1626)
		(end 49.5554 -107.1626)
		(width 0.12065)
		(layer "B.Cu")
		(net "BMC_I2C14_MINI8_SCL_S")
	)
	(segment
		(start 49.0601 -106.6673)
		(end 49.0601 -106.6292)
		(width 0.12065)
		(layer "B.Cu")
		(net "BMC_I2C14_MINI8_SCL_S")
	)
	(segment
		(start 56.297322 -127.421894)
		(end 56.338724 -127.463296)
		(width 0.12065)
		(layer "B.Cu")
		(net "BMC_I2C14_MINI8_SCL_S")
	)
	(segment
		(start 52.238402 -128.469898)
		(end 53.036978 -128.469898)
		(width 0.12065)
		(layer "B.Cu")
		(net "BMC_I2C14_MINI8_SCL_S")
	)
	(segment
		(start 50.7746 -106.7054)
		(end 50.3174 -107.1626)
		(width 0.12065)
		(layer "B.Cu")
		(net "BMC_I2C14_MINI8_SCL_S")
	)
	(segment
		(start 57.4802 -128.4478)
		(end 57.6834 -128.2446)
		(width 0.12065)
		(layer "B.Cu")
		(net "BMC_I2C14_MINI8_SCL_S")
	)
	(segment
		(start 57.24525 -128.21285)
		(end 57.4802 -128.4478)
		(width 0.12065)
		(layer "B.Cu")
		(net "BMC_I2C14_MINI8_SCL_S")
	)
	(segment
		(start 50.7746 -106.7054)
		(end 50.7746 -105.4862)
		(width 0.12065)
		(layer "B.Cu")
		(net "BMC_I2C14_MINI8_SCL_S")
	)
	(segment
		(start 56.4261 -127.463296)
		(end 57.175654 -128.21285)
		(width 0.12065)
		(layer "B.Cu")
		(net "BMC_I2C14_MINI8_SCL_S")
	)
	(segment
		(start 53.036978 -128.469898)
		(end 54.084982 -127.421894)
		(width 0.12065)
		(layer "B.Cu")
		(net "BMC_I2C14_MINI8_SCL_S")
	)
	(segment
		(start 52.092606 -106.122216)
		(end 51.724052 -106.49077)
		(width 0.127)
		(layer "In2.Cu")
		(net "BMC_I2C14_MINI8_SCL_S")
	)
	(segment
		(start 75.5904 -119.9642)
		(end 78.3844 -119.9642)
		(width 0.127)
		(layer "In2.Cu")
		(net "BMC_I2C14_MINI8_SCL_S")
	)
	(segment
		(start 68.62445 -126.742444)
		(end 68.62445 -123.870974)
		(width 0.127)
		(layer "In2.Cu")
		(net "BMC_I2C14_MINI8_SCL_S")
	)
	(segment
		(start 79.4512 -118.8974)
		(end 79.4512 -117.1194)
		(width 0.127)
		(layer "In2.Cu")
		(net "BMC_I2C14_MINI8_SCL_S")
	)
	(segment
		(start 71.73976 -57.190132)
		(end 71.73976 -52.575206)
		(width 0.127)
		(layer "In2.Cu")
		(net "BMC_I2C14_MINI8_SCL_S")
	)
	(segment
		(start 80.4799 -107.4801)
		(end 68.7705 -107.4801)
		(width 0.127)
		(layer "In2.Cu")
		(net "BMC_I2C14_MINI8_SCL_S")
	)
	(segment
		(start 68.62445 -123.870974)
		(end 69.813424 -122.682)
		(width 0.127)
		(layer "In2.Cu")
		(net "BMC_I2C14_MINI8_SCL_S")
	)
	(segment
		(start 57.4802 -128.4478)
		(end 61.938916 -128.4478)
		(width 0.127)
		(layer "In2.Cu")
		(net "BMC_I2C14_MINI8_SCL_S")
	)
	(segment
		(start 81.2038 -115.3668)
		(end 81.2038 -108.204)
		(width 0.127)
		(layer "In2.Cu")
		(net "BMC_I2C14_MINI8_SCL_S")
	)
	(segment
		(start 72.039988 -57.49036)
		(end 71.73976 -57.190132)
		(width 0.127)
		(layer "In2.Cu")
		(net "BMC_I2C14_MINI8_SCL_S")
	)
	(segment
		(start 57.463182 -108.567728)
		(end 55.01767 -106.122216)
		(width 0.127)
		(layer "In2.Cu")
		(net "BMC_I2C14_MINI8_SCL_S")
	)
	(segment
		(start 79.4512 -117.1194)
		(end 81.2038 -115.3668)
		(width 0.127)
		(layer "In2.Cu")
		(net "BMC_I2C14_MINI8_SCL_S")
	)
	(segment
		(start 55.01767 -106.122216)
		(end 52.092606 -106.122216)
		(width 0.127)
		(layer "In2.Cu")
		(net "BMC_I2C14_MINI8_SCL_S")
	)
	(segment
		(start 78.3844 -119.9642)
		(end 79.4512 -118.8974)
		(width 0.127)
		(layer "In2.Cu")
		(net "BMC_I2C14_MINI8_SCL_S")
	)
	(segment
		(start 67.682872 -108.567728)
		(end 57.463182 -108.567728)
		(width 0.127)
		(layer "In2.Cu")
		(net "BMC_I2C14_MINI8_SCL_S")
	)
	(segment
		(start 49.28743 -106.149902)
		(end 49.618646 -105.818686)
		(width 0.127)
		(layer "In2.Cu")
		(net "BMC_I2C14_MINI8_SCL_S")
	)
	(segment
		(start 49.3776 -106.49077)
		(end 49.28743 -106.4006)
		(width 0.127)
		(layer "In2.Cu")
		(net "BMC_I2C14_MINI8_SCL_S")
	)
	(segment
		(start 67.457828 -127.909066)
		(end 68.62445 -126.742444)
		(width 0.127)
		(layer "In2.Cu")
		(net "BMC_I2C14_MINI8_SCL_S")
	)
	(segment
		(start 81.0768 -43.238166)
		(end 81.0768 -33.977834)
		(width 0.127)
		(layer "In2.Cu")
		(net "BMC_I2C14_MINI8_SCL_S")
	)
	(segment
		(start 49.28743 -106.4006)
		(end 49.28743 -106.149902)
		(width 0.127)
		(layer "In2.Cu")
		(net "BMC_I2C14_MINI8_SCL_S")
	)
	(segment
		(start 66.702432 -129.693416)
		(end 67.457828 -128.93802)
		(width 0.127)
		(layer "In2.Cu")
		(net "BMC_I2C14_MINI8_SCL_S")
	)
	(segment
		(start 51.724052 -106.49077)
		(end 49.3776 -106.49077)
		(width 0.127)
		(layer "In2.Cu")
		(net "BMC_I2C14_MINI8_SCL_S")
	)
	(segment
		(start 78.734666 -31.6357)
		(end 64.561466 -31.6357)
		(width 0.127)
		(layer "In2.Cu")
		(net "BMC_I2C14_MINI8_SCL_S")
	)
	(segment
		(start 62.3316 -29.405834)
		(end 62.3316 -28.410662)
		(width 0.127)
		(layer "In2.Cu")
		(net "BMC_I2C14_MINI8_SCL_S")
	)
	(segment
		(start 81.0768 -33.977834)
		(end 78.734666 -31.6357)
		(width 0.127)
		(layer "In2.Cu")
		(net "BMC_I2C14_MINI8_SCL_S")
	)
	(segment
		(start 69.813424 -122.682)
		(end 72.8726 -122.682)
		(width 0.127)
		(layer "In2.Cu")
		(net "BMC_I2C14_MINI8_SCL_S")
	)
	(segment
		(start 81.2038 -108.204)
		(end 80.4799 -107.4801)
		(width 0.127)
		(layer "In2.Cu")
		(net "BMC_I2C14_MINI8_SCL_S")
	)
	(segment
		(start 67.457828 -128.93802)
		(end 67.457828 -127.909066)
		(width 0.127)
		(layer "In2.Cu")
		(net "BMC_I2C14_MINI8_SCL_S")
	)
	(segment
		(start 49.618646 -105.818686)
		(end 50.8254 -105.4354)
		(width 0.127)
		(layer "In2.Cu")
		(net "BMC_I2C14_MINI8_SCL_S")
	)
	(segment
		(start 72.8726 -122.682)
		(end 75.5904 -119.9642)
		(width 0.127)
		(layer "In2.Cu")
		(net "BMC_I2C14_MINI8_SCL_S")
	)
	(segment
		(start 61.938916 -128.4478)
		(end 63.184532 -129.693416)
		(width 0.127)
		(layer "In2.Cu")
		(net "BMC_I2C14_MINI8_SCL_S")
	)
	(segment
		(start 63.983362 -26.7589)
		(end 67.263518 -26.7589)
		(width 0.127)
		(layer "In2.Cu")
		(net "BMC_I2C14_MINI8_SCL_S")
	)
	(segment
		(start 68.7705 -107.4801)
		(end 67.682872 -108.567728)
		(width 0.127)
		(layer "In2.Cu")
		(net "BMC_I2C14_MINI8_SCL_S")
	)
	(segment
		(start 71.73976 -52.575206)
		(end 81.0768 -43.238166)
		(width 0.127)
		(layer "In2.Cu")
		(net "BMC_I2C14_MINI8_SCL_S")
	)
	(segment
		(start 63.184532 -129.693416)
		(end 66.702432 -129.693416)
		(width 0.127)
		(layer "In2.Cu")
		(net "BMC_I2C14_MINI8_SCL_S")
	)
	(segment
		(start 62.3316 -28.410662)
		(end 63.983362 -26.7589)
		(width 0.127)
		(layer "In2.Cu")
		(net "BMC_I2C14_MINI8_SCL_S")
	)
	(segment
		(start 64.561466 -31.6357)
		(end 62.3316 -29.405834)
		(width 0.127)
		(layer "In2.Cu")
		(net "BMC_I2C14_MINI8_SCL_S")
	)
	(segment
		(start 53.7464 -77.692504)
		(end 53.7464 -80.221074)
		(width 0.127)
		(layer "In5.Cu")
		(net "BMC_I2C14_MINI8_SCL_S")
	)
	(segment
		(start 56.261 -70.2564)
		(end 56.261 -75.177904)
		(width 0.127)
		(layer "In5.Cu")
		(net "BMC_I2C14_MINI8_SCL_S")
	)
	(segment
		(start 72.039988 -57.49036)
		(end 71.66356 -57.866788)
		(width 0.127)
		(layer "In5.Cu")
		(net "BMC_I2C14_MINI8_SCL_S")
	)
	(segment
		(start 67.0306 -59.4868)
		(end 56.261 -70.2564)
		(width 0.127)
		(layer "In5.Cu")
		(net "BMC_I2C14_MINI8_SCL_S")
	)
	(segment
		(start 70.502526 -59.4868)
		(end 67.0306 -59.4868)
		(width 0.127)
		(layer "In5.Cu")
		(net "BMC_I2C14_MINI8_SCL_S")
	)
	(segment
		(start 71.66356 -57.866788)
		(end 71.66356 -58.325766)
		(width 0.127)
		(layer "In5.Cu")
		(net "BMC_I2C14_MINI8_SCL_S")
	)
	(segment
		(start 47.8536 -104.7242)
		(end 48.5648 -105.4354)
		(width 0.127)
		(layer "In5.Cu")
		(net "BMC_I2C14_MINI8_SCL_S")
	)
	(segment
		(start 51.6636 -89.2302)
		(end 47.8536 -93.0402)
		(width 0.127)
		(layer "In5.Cu")
		(net "BMC_I2C14_MINI8_SCL_S")
	)
	(segment
		(start 47.8536 -93.0402)
		(end 47.8536 -104.7242)
		(width 0.127)
		(layer "In5.Cu")
		(net "BMC_I2C14_MINI8_SCL_S")
	)
	(segment
		(start 51.6636 -82.303874)
		(end 51.6636 -89.2302)
		(width 0.127)
		(layer "In5.Cu")
		(net "BMC_I2C14_MINI8_SCL_S")
	)
	(segment
		(start 71.66356 -58.325766)
		(end 70.502526 -59.4868)
		(width 0.127)
		(layer "In5.Cu")
		(net "BMC_I2C14_MINI8_SCL_S")
	)
	(segment
		(start 53.7464 -80.221074)
		(end 51.6636 -82.303874)
		(width 0.127)
		(layer "In5.Cu")
		(net "BMC_I2C14_MINI8_SCL_S")
	)
	(segment
		(start 48.5648 -105.4354)
		(end 50.8254 -105.4354)
		(width 0.127)
		(layer "In5.Cu")
		(net "BMC_I2C14_MINI8_SCL_S")
	)
	(segment
		(start 56.261 -75.177904)
		(end 53.7464 -77.692504)
		(width 0.127)
		(layer "In5.Cu")
		(net "BMC_I2C14_MINI8_SCL_S")
	)
	(segment
		(start 52.816252 -110.84687)
		(end 52.816252 -111.668052)
		(width 0.12065)
		(layer "F.Cu")
		(net "BMC_I2C13_MINI7_SDA_S")
	)
	(segment
		(start 53.2003 -114.3)
		(end 53.2003 -113.284)
		(width 0.12065)
		(layer "F.Cu")
		(net "BMC_I2C13_MINI7_SDA_S")
	)
	(segment
		(start 53.1876 -114.3127)
		(end 53.2003 -114.3)
		(width 0.12065)
		(layer "F.Cu")
		(net "BMC_I2C13_MINI7_SDA_S")
	)
	(segment
		(start 53.286152 -112.137952)
		(end 53.286152 -112.25403)
		(width 0.12065)
		(layer "F.Cu")
		(net "BMC_I2C13_MINI7_SDA_S")
	)
	(segment
		(start 53.2003 -113.284)
		(end 53.2003 -112.339882)
		(width 0.12065)
		(layer "F.Cu")
		(net "BMC_I2C13_MINI7_SDA_S")
	)
	(segment
		(start 53.2003 -112.339882)
		(end 53.286152 -112.25403)
		(width 0.12065)
		(layer "F.Cu")
		(net "BMC_I2C13_MINI7_SDA_S")
	)
	(segment
		(start 51.895502 -110.84687)
		(end 51.37658 -111.365792)
		(width 0.12065)
		(layer "F.Cu")
		(net "BMC_I2C13_MINI7_SDA_S")
	)
	(segment
		(start 52.816252 -110.84687)
		(end 51.895502 -110.84687)
		(width 0.12065)
		(layer "F.Cu")
		(net "BMC_I2C13_MINI7_SDA_S")
	)
	(segment
		(start 52.816252 -111.668052)
		(end 53.286152 -112.137952)
		(width 0.12065)
		(layer "F.Cu")
		(net "BMC_I2C13_MINI7_SDA_S")
	)
	(via
		(at 51.37658 -111.365792)
		(size 0.7112)
		(drill 0.3556)
		(layers "F.Cu" "B.Cu")
		(net "BMC_I2C13_MINI7_SDA_S")
	)
	(segment
		(start 54.225952 -108.561886)
		(end 54.695852 -109.031786)
		(width 0.12065)
		(layer "F.Cu")
		(net "BMC_I2C13_MINI7_SCL_S")
	)
	(segment
		(start 54.2163 -113.1951)
		(end 54.2163 -113.284)
		(width 0.12065)
		(layer "F.Cu")
		(net "BMC_I2C13_MINI7_SCL_S")
	)
	(segment
		(start 56.6547 -112.597692)
		(end 56.384444 -112.867948)
		(width 0.12065)
		(layer "F.Cu")
		(net "BMC_I2C13_MINI7_SCL_S")
	)
	(segment
		(start 55.371492 -107.891834)
		(end 57.037986 -109.558328)
		(width 0.12065)
		(layer "F.Cu")
		(net "BMC_I2C13_MINI7_SCL_S")
	)
	(segment
		(start 54.447948 -107.891834)
		(end 54.225952 -108.11383)
		(width 0.12065)
		(layer "F.Cu")
		(net "BMC_I2C13_MINI7_SCL_S")
	)
	(segment
		(start 54.229 -113.2967)
		(end 54.2163 -113.284)
		(width 0.12065)
		(layer "F.Cu")
		(net "BMC_I2C13_MINI7_SCL_S")
	)
	(segment
		(start 56.384444 -112.867948)
		(end 55.954676 -112.867948)
		(width 0.12065)
		(layer "F.Cu")
		(net "BMC_I2C13_MINI7_SCL_S")
	)
	(segment
		(start 55.442866 -112.728248)
		(end 55.438294 -112.73282)
		(width 0.12065)
		(layer "F.Cu")
		(net "BMC_I2C13_MINI7_SCL_S")
	)
	(segment
		(start 54.695852 -109.031786)
		(end 54.695852 -109.54639)
		(width 0.12065)
		(layer "F.Cu")
		(net "BMC_I2C13_MINI7_SCL_S")
	)
	(segment
		(start 55.051706 -112.73282)
		(end 55.047134 -112.728248)
		(width 0.12065)
		(layer "F.Cu")
		(net "BMC_I2C13_MINI7_SCL_S")
	)
	(segment
		(start 55.438294 -112.73282)
		(end 55.051706 -112.73282)
		(width 0.12065)
		(layer "F.Cu")
		(net "BMC_I2C13_MINI7_SCL_S")
	)
	(segment
		(start 55.371492 -107.891834)
		(end 54.447948 -107.891834)
		(width 0.12065)
		(layer "F.Cu")
		(net "BMC_I2C13_MINI7_SCL_S")
	)
	(segment
		(start 55.047134 -112.728248)
		(end 54.683152 -112.728248)
		(width 0.12065)
		(layer "F.Cu")
		(net "BMC_I2C13_MINI7_SCL_S")
	)
	(segment
		(start 57.037986 -109.558328)
		(end 57.037986 -112.197388)
		(width 0.12065)
		(layer "F.Cu")
		(net "BMC_I2C13_MINI7_SCL_S")
	)
	(segment
		(start 55.814976 -112.728248)
		(end 55.442866 -112.728248)
		(width 0.12065)
		(layer "F.Cu")
		(net "BMC_I2C13_MINI7_SCL_S")
	)
	(segment
		(start 54.229 -114.3127)
		(end 54.229 -113.2967)
		(width 0.12065)
		(layer "F.Cu")
		(net "BMC_I2C13_MINI7_SCL_S")
	)
	(segment
		(start 54.683152 -112.728248)
		(end 54.2163 -113.1951)
		(width 0.12065)
		(layer "F.Cu")
		(net "BMC_I2C13_MINI7_SCL_S")
	)
	(segment
		(start 56.6547 -112.580674)
		(end 56.6547 -112.597692)
		(width 0.12065)
		(layer "F.Cu")
		(net "BMC_I2C13_MINI7_SCL_S")
	)
	(segment
		(start 55.954676 -112.867948)
		(end 55.814976 -112.728248)
		(width 0.12065)
		(layer "F.Cu")
		(net "BMC_I2C13_MINI7_SCL_S")
	)
	(segment
		(start 54.225952 -108.11383)
		(end 54.225952 -108.561886)
		(width 0.12065)
		(layer "F.Cu")
		(net "BMC_I2C13_MINI7_SCL_S")
	)
	(segment
		(start 57.037986 -112.197388)
		(end 56.6547 -112.580674)
		(width 0.12065)
		(layer "F.Cu")
		(net "BMC_I2C13_MINI7_SCL_S")
	)
	(via
		(at 55.371492 -107.891834)
		(size 0.7112)
		(drill 0.3556)
		(layers "F.Cu" "B.Cu")
		(net "BMC_I2C13_MINI7_SCL_S")
	)
	(via
		(at 55.568596 -114.87023)
		(size 0.7112)
		(drill 0.3556)
		(layers "F.Cu" "B.Cu")
		(net "BMC_I2C12_MINI6_SDA_S")
	)
	(segment
		(start 54.454552 -112.22863)
		(end 54.7497 -112.523778)
		(width 0.12065)
		(layer "B.Cu")
		(net "BMC_I2C12_MINI6_SDA_S")
	)
	(segment
		(start 54.695852 -110.84687)
		(end 54.695852 -111.98733)
		(width 0.12065)
		(layer "B.Cu")
		(net "BMC_I2C12_MINI6_SDA_S")
	)
	(segment
		(start 54.4322 -115.3287)
		(end 55.110126 -115.3287)
		(width 0.12065)
		(layer "B.Cu")
		(net "BMC_I2C12_MINI6_SDA_S")
	)
	(segment
		(start 54.174898 -115.071398)
		(end 54.4322 -115.3287)
		(width 0.12065)
		(layer "B.Cu")
		(net "BMC_I2C12_MINI6_SDA_S")
	)
	(segment
		(start 54.7497 -112.523778)
		(end 54.7497 -113.538)
		(width 0.12065)
		(layer "B.Cu")
		(net "BMC_I2C12_MINI6_SDA_S")
	)
	(segment
		(start 54.695852 -111.98733)
		(end 54.454552 -112.22863)
		(width 0.12065)
		(layer "B.Cu")
		(net "BMC_I2C12_MINI6_SDA_S")
	)
	(segment
		(start 55.110126 -115.3287)
		(end 55.568596 -114.87023)
		(width 0.12065)
		(layer "B.Cu")
		(net "BMC_I2C12_MINI6_SDA_S")
	)
	(segment
		(start 54.4449 -113.8428)
		(end 54.174898 -114.112802)
		(width 0.12065)
		(layer "B.Cu")
		(net "BMC_I2C12_MINI6_SDA_S")
	)
	(segment
		(start 54.7497 -113.538)
		(end 54.4449 -113.8428)
		(width 0.12065)
		(layer "B.Cu")
		(net "BMC_I2C12_MINI6_SDA_S")
	)
	(segment
		(start 54.174898 -114.112802)
		(end 54.174898 -115.071398)
		(width 0.12065)
		(layer "B.Cu")
		(net "BMC_I2C12_MINI6_SDA_S")
	)
	(via
		(at 50.219102 -109.580172)
		(size 0.7112)
		(drill 0.3556)
		(layers "F.Cu" "B.Cu")
		(net "BMC_I2C12_MINI6_SCL_S")
	)
	(segment
		(start 53.4162 -115.3287)
		(end 53.673248 -115.071652)
		(width 0.12065)
		(layer "B.Cu")
		(net "BMC_I2C12_MINI6_SCL_S")
	)
	(segment
		(start 53.673248 -115.071652)
		(end 53.673248 -114.097054)
		(width 0.12065)
		(layer "B.Cu")
		(net "BMC_I2C12_MINI6_SCL_S")
	)
	(segment
		(start 51.736244 -108.06303)
		(end 52.778152 -108.06303)
		(width 0.12065)
		(layer "B.Cu")
		(net "BMC_I2C12_MINI6_SCL_S")
	)
	(segment
		(start 50.219102 -109.580172)
		(end 51.736244 -108.06303)
		(width 0.12065)
		(layer "B.Cu")
		(net "BMC_I2C12_MINI6_SCL_S")
	)
	(segment
		(start 52.816252 -109.54639)
		(end 52.816252 -108.10113)
		(width 0.12065)
		(layer "B.Cu")
		(net "BMC_I2C12_MINI6_SCL_S")
	)
	(segment
		(start 50.060352 -111.704882)
		(end 52.192682 -111.704882)
		(width 0.12065)
		(layer "B.Cu")
		(net "BMC_I2C12_MINI6_SCL_S")
	)
	(segment
		(start 53.673248 -114.097054)
		(end 53.410104 -113.83391)
		(width 0.12065)
		(layer "B.Cu")
		(net "BMC_I2C12_MINI6_SCL_S")
	)
	(segment
		(start 49.697894 -110.10138)
		(end 49.697894 -111.342424)
		(width 0.12065)
		(layer "B.Cu")
		(net "BMC_I2C12_MINI6_SCL_S")
	)
	(segment
		(start 53.410104 -112.922304)
		(end 53.410104 -113.83391)
		(width 0.12065)
		(layer "B.Cu")
		(net "BMC_I2C12_MINI6_SCL_S")
	)
	(segment
		(start 52.816252 -108.10113)
		(end 52.778152 -108.06303)
		(width 0.12065)
		(layer "B.Cu")
		(net "BMC_I2C12_MINI6_SCL_S")
	)
	(segment
		(start 50.219102 -109.580172)
		(end 49.697894 -110.10138)
		(width 0.12065)
		(layer "B.Cu")
		(net "BMC_I2C12_MINI6_SCL_S")
	)
	(segment
		(start 49.697894 -111.342424)
		(end 50.060352 -111.704882)
		(width 0.12065)
		(layer "B.Cu")
		(net "BMC_I2C12_MINI6_SCL_S")
	)
	(segment
		(start 52.192682 -111.704882)
		(end 53.410104 -112.922304)
		(width 0.12065)
		(layer "B.Cu")
		(net "BMC_I2C12_MINI6_SCL_S")
	)
	(segment
		(start 177.46345 -46.5074)
		(end 177.163476 -46.207426)
		(width 0.12065)
		(layer "F.Cu")
		(net "BMC_I2C11_MINI5_SDA_S")
	)
	(segment
		(start 207.954626 -32.503872)
		(end 207.625188 -32.174434)
		(width 0.12065)
		(layer "F.Cu")
		(net "BMC_I2C11_MINI5_SDA_S")
	)
	(segment
		(start 207.29829 -32.174434)
		(end 207.05445 -32.418274)
		(width 0.12065)
		(layer "F.Cu")
		(net "BMC_I2C11_MINI5_SDA_S")
	)
	(segment
		(start 64.3763 -113.6396)
		(end 64.3763 -112.5982)
		(width 0.12065)
		(layer "F.Cu")
		(net "BMC_I2C11_MINI5_SDA_S")
	)
	(segment
		(start 206.270606 -35.613594)
		(end 207.954626 -33.929574)
		(width 0.12065)
		(layer "F.Cu")
		(net "BMC_I2C11_MINI5_SDA_S")
	)
	(segment
		(start 206.045308 -35.388296)
		(end 206.270606 -35.613594)
		(width 0.12065)
		(layer "F.Cu")
		(net "BMC_I2C11_MINI5_SDA_S")
	)
	(segment
		(start 64.3001 -111.4044)
		(end 64.3001 -112.522)
		(width 0.12065)
		(layer "F.Cu")
		(net "BMC_I2C11_MINI5_SDA_S")
	)
	(segment
		(start 63.5508 -110.02264)
		(end 64.17564 -110.02264)
		(width 0.12065)
		(layer "F.Cu")
		(net "BMC_I2C11_MINI5_SDA_S")
	)
	(segment
		(start 64.3636 -113.6523)
		(end 64.3763 -113.6396)
		(width 0.12065)
		(layer "F.Cu")
		(net "BMC_I2C11_MINI5_SDA_S")
	)
	(segment
		(start 63.332868 -111.522256)
		(end 63.332868 -110.240572)
		(width 0.12065)
		(layer "F.Cu")
		(net "BMC_I2C11_MINI5_SDA_S")
	)
	(segment
		(start 64.3001 -112.522)
		(end 64.3763 -112.5982)
		(width 0.12065)
		(layer "F.Cu")
		(net "BMC_I2C11_MINI5_SDA_S")
	)
	(segment
		(start 64.3001 -110.1471)
		(end 64.3001 -111.4044)
		(width 0.12065)
		(layer "F.Cu")
		(net "BMC_I2C11_MINI5_SDA_S")
	)
	(segment
		(start 207.954626 -33.929574)
		(end 207.954626 -32.503872)
		(width 0.12065)
		(layer "F.Cu")
		(net "BMC_I2C11_MINI5_SDA_S")
	)
	(segment
		(start 64.17564 -110.02264)
		(end 64.3001 -110.1471)
		(width 0.12065)
		(layer "F.Cu")
		(net "BMC_I2C11_MINI5_SDA_S")
	)
	(segment
		(start 63.332868 -110.240572)
		(end 63.5508 -110.02264)
		(width 0.12065)
		(layer "F.Cu")
		(net "BMC_I2C11_MINI5_SDA_S")
	)
	(segment
		(start 207.625188 -32.174434)
		(end 207.29829 -32.174434)
		(width 0.12065)
		(layer "F.Cu")
		(net "BMC_I2C11_MINI5_SDA_S")
	)
	(segment
		(start 186.563 -37.973)
		(end 178.0286 -46.5074)
		(width 0.12065)
		(layer "F.Cu")
		(net "BMC_I2C11_MINI5_SDA_S")
	)
	(segment
		(start 203.9112 -37.973)
		(end 186.563 -37.973)
		(width 0.12065)
		(layer "F.Cu")
		(net "BMC_I2C11_MINI5_SDA_S")
	)
	(segment
		(start 206.270606 -35.613594)
		(end 203.9112 -37.973)
		(width 0.12065)
		(layer "F.Cu")
		(net "BMC_I2C11_MINI5_SDA_S")
	)
	(segment
		(start 178.0286 -46.5074)
		(end 177.46345 -46.5074)
		(width 0.12065)
		(layer "F.Cu")
		(net "BMC_I2C11_MINI5_SDA_S")
	)
	(via
		(at 115.951 -42.016172)
		(size 0.508)
		(drill 0.254)
		(layers "F.Cu" "B.Cu")
		(net "BMC_I2C11_MINI5_SDA_S")
	)
	(via
		(at 63.332868 -111.522256)
		(size 0.508)
		(drill 0.254)
		(layers "F.Cu" "B.Cu")
		(net "BMC_I2C11_MINI5_SDA_S")
	)
	(via
		(at 206.045308 -35.388296)
		(size 0.7112)
		(drill 0.3556)
		(layers "F.Cu" "B.Cu")
		(net "BMC_I2C11_MINI5_SDA_S")
	)
	(via
		(at 177.163476 -46.207426)
		(size 0.508)
		(drill 0.254)
		(layers "F.Cu" "B.Cu")
		(net "BMC_I2C11_MINI5_SDA_S")
	)
	(segment
		(start 157.16504 -47.703994)
		(end 153.808938 -47.703994)
		(width 0.127)
		(layer "In2.Cu")
		(net "BMC_I2C11_MINI5_SDA_S")
	)
	(segment
		(start 173.235874 -49.18456)
		(end 158.645606 -49.18456)
		(width 0.127)
		(layer "In2.Cu")
		(net "BMC_I2C11_MINI5_SDA_S")
	)
	(segment
		(start 139.464542 -44.564554)
		(end 130.336036 -44.564554)
		(width 0.127)
		(layer "In2.Cu")
		(net "BMC_I2C11_MINI5_SDA_S")
	)
	(segment
		(start 142.603982 -47.703994)
		(end 139.464542 -44.564554)
		(width 0.127)
		(layer "In2.Cu")
		(net "BMC_I2C11_MINI5_SDA_S")
	)
	(segment
		(start 176.866804 -46.504098)
		(end 175.916336 -46.504098)
		(width 0.127)
		(layer "In2.Cu")
		(net "BMC_I2C11_MINI5_SDA_S")
	)
	(segment
		(start 118.137432 -42.2402)
		(end 116.175028 -42.2402)
		(width 0.127)
		(layer "In2.Cu")
		(net "BMC_I2C11_MINI5_SDA_S")
	)
	(segment
		(start 119.291354 -43.394122)
		(end 118.137432 -42.2402)
		(width 0.127)
		(layer "In2.Cu")
		(net "BMC_I2C11_MINI5_SDA_S")
	)
	(segment
		(start 152.515062 -47.703994)
		(end 142.603982 -47.703994)
		(width 0.127)
		(layer "In2.Cu")
		(net "BMC_I2C11_MINI5_SDA_S")
	)
	(segment
		(start 158.645606 -49.18456)
		(end 157.16504 -47.703994)
		(width 0.127)
		(layer "In2.Cu")
		(net "BMC_I2C11_MINI5_SDA_S")
	)
	(segment
		(start 128.011682 -42.2402)
		(end 123.027186 -42.2402)
		(width 0.127)
		(layer "In2.Cu")
		(net "BMC_I2C11_MINI5_SDA_S")
	)
	(segment
		(start 153.567384 -47.46244)
		(end 152.756616 -47.46244)
		(width 0.127)
		(layer "In2.Cu")
		(net "BMC_I2C11_MINI5_SDA_S")
	)
	(segment
		(start 116.175028 -42.2402)
		(end 115.951 -42.016172)
		(width 0.127)
		(layer "In2.Cu")
		(net "BMC_I2C11_MINI5_SDA_S")
	)
	(segment
		(start 153.808938 -47.703994)
		(end 153.567384 -47.46244)
		(width 0.127)
		(layer "In2.Cu")
		(net "BMC_I2C11_MINI5_SDA_S")
	)
	(segment
		(start 177.163476 -46.207426)
		(end 176.866804 -46.504098)
		(width 0.127)
		(layer "In2.Cu")
		(net "BMC_I2C11_MINI5_SDA_S")
	)
	(segment
		(start 121.873264 -43.394122)
		(end 119.291354 -43.394122)
		(width 0.127)
		(layer "In2.Cu")
		(net "BMC_I2C11_MINI5_SDA_S")
	)
	(segment
		(start 123.027186 -42.2402)
		(end 121.873264 -43.394122)
		(width 0.127)
		(layer "In2.Cu")
		(net "BMC_I2C11_MINI5_SDA_S")
	)
	(segment
		(start 175.916336 -46.504098)
		(end 173.235874 -49.18456)
		(width 0.127)
		(layer "In2.Cu")
		(net "BMC_I2C11_MINI5_SDA_S")
	)
	(segment
		(start 152.756616 -47.46244)
		(end 152.515062 -47.703994)
		(width 0.127)
		(layer "In2.Cu")
		(net "BMC_I2C11_MINI5_SDA_S")
	)
	(segment
		(start 130.336036 -44.564554)
		(end 128.011682 -42.2402)
		(width 0.127)
		(layer "In2.Cu")
		(net "BMC_I2C11_MINI5_SDA_S")
	)
	(segment
		(start 64.712596 -109.62767)
		(end 64.933576 -109.865922)
		(width 0.127)
		(layer "In5.Cu")
		(net "BMC_I2C11_MINI5_SDA_S")
	)
	(segment
		(start 75.664314 -66.97472)
		(end 65.278 -77.361034)
		(width 0.127)
		(layer "In5.Cu")
		(net "BMC_I2C11_MINI5_SDA_S")
	)
	(segment
		(start 65.405 -101.414834)
		(end 65.405 -108.044234)
		(width 0.127)
		(layer "In5.Cu")
		(net "BMC_I2C11_MINI5_SDA_S")
	)
	(segment
		(start 64.8462 -87.317834)
		(end 64.8462 -93.250766)
		(width 0.127)
		(layer "In5.Cu")
		(net "BMC_I2C11_MINI5_SDA_S")
	)
	(segment
		(start 64.712596 -108.736638)
		(end 64.712596 -109.62767)
		(width 0.127)
		(layer "In5.Cu")
		(net "BMC_I2C11_MINI5_SDA_S")
	)
	(segment
		(start 66.3702 -94.774766)
		(end 66.3702 -100.449634)
		(width 0.127)
		(layer "In5.Cu")
		(net "BMC_I2C11_MINI5_SDA_S")
	)
	(segment
		(start 95.785432 -66.97472)
		(end 75.664314 -66.97472)
		(width 0.127)
		(layer "In5.Cu")
		(net "BMC_I2C11_MINI5_SDA_S")
	)
	(segment
		(start 65.83426 -82.224626)
		(end 65.83426 -86.329774)
		(width 0.127)
		(layer "In5.Cu")
		(net "BMC_I2C11_MINI5_SDA_S")
	)
	(segment
		(start 64.933576 -109.865922)
		(end 64.926972 -110.045246)
		(width 0.127)
		(layer "In5.Cu")
		(net "BMC_I2C11_MINI5_SDA_S")
	)
	(segment
		(start 66.3702 -100.449634)
		(end 65.405 -101.414834)
		(width 0.127)
		(layer "In5.Cu")
		(net "BMC_I2C11_MINI5_SDA_S")
	)
	(segment
		(start 64.926972 -110.045246)
		(end 63.332868 -111.522256)
		(width 0.127)
		(layer "In5.Cu")
		(net "BMC_I2C11_MINI5_SDA_S")
	)
	(segment
		(start 114.173 -42.969688)
		(end 114.173 -48.587152)
		(width 0.127)
		(layer "In5.Cu")
		(net "BMC_I2C11_MINI5_SDA_S")
	)
	(segment
		(start 64.8462 -93.250766)
		(end 66.3702 -94.774766)
		(width 0.127)
		(layer "In5.Cu")
		(net "BMC_I2C11_MINI5_SDA_S")
	)
	(segment
		(start 65.405 -108.044234)
		(end 64.712596 -108.736638)
		(width 0.127)
		(layer "In5.Cu")
		(net "BMC_I2C11_MINI5_SDA_S")
	)
	(segment
		(start 115.650772 -42.3164)
		(end 114.826288 -42.3164)
		(width 0.127)
		(layer "In5.Cu")
		(net "BMC_I2C11_MINI5_SDA_S")
	)
	(segment
		(start 65.278 -77.361034)
		(end 65.278 -81.668366)
		(width 0.127)
		(layer "In5.Cu")
		(net "BMC_I2C11_MINI5_SDA_S")
	)
	(segment
		(start 65.83426 -86.329774)
		(end 64.8462 -87.317834)
		(width 0.127)
		(layer "In5.Cu")
		(net "BMC_I2C11_MINI5_SDA_S")
	)
	(segment
		(start 65.278 -81.668366)
		(end 65.83426 -82.224626)
		(width 0.127)
		(layer "In5.Cu")
		(net "BMC_I2C11_MINI5_SDA_S")
	)
	(segment
		(start 114.826288 -42.3164)
		(end 114.173 -42.969688)
		(width 0.127)
		(layer "In5.Cu")
		(net "BMC_I2C11_MINI5_SDA_S")
	)
	(segment
		(start 114.173 -48.587152)
		(end 95.785432 -66.97472)
		(width 0.127)
		(layer "In5.Cu")
		(net "BMC_I2C11_MINI5_SDA_S")
	)
	(segment
		(start 115.951 -42.016172)
		(end 115.650772 -42.3164)
		(width 0.127)
		(layer "In5.Cu")
		(net "BMC_I2C11_MINI5_SDA_S")
	)
	(segment
		(start 208.456276 -33.099248)
		(end 208.456276 -32.295846)
		(width 0.12065)
		(layer "F.Cu")
		(net "BMC_I2C11_MINI5_SCL_S")
	)
	(segment
		(start 65.4304 -107.7595)
		(end 65.4304 -108.72216)
		(width 0.12065)
		(layer "F.Cu")
		(net "BMC_I2C11_MINI5_SCL_S")
	)
	(segment
		(start 65.4304 -108.72216)
		(end 67.668648 -108.72216)
		(width 0.12065)
		(layer "F.Cu")
		(net "BMC_I2C11_MINI5_SCL_S")
	)
	(segment
		(start 66.3448 -107.315)
		(end 65.8749 -107.315)
		(width 0.12065)
		(layer "F.Cu")
		(net "BMC_I2C11_MINI5_SCL_S")
	)
	(segment
		(start 177.46345 -47.00905)
		(end 178.236626 -47.00905)
		(width 0.12065)
		(layer "F.Cu")
		(net "BMC_I2C11_MINI5_SCL_S")
	)
	(segment
		(start 65.405 -112.6109)
		(end 65.3923 -112.5982)
		(width 0.12065)
		(layer "F.Cu")
		(net "BMC_I2C11_MINI5_SCL_S")
	)
	(segment
		(start 67.0814 -108.0516)
		(end 66.3448 -107.315)
		(width 0.12065)
		(layer "F.Cu")
		(net "BMC_I2C11_MINI5_SCL_S")
	)
	(segment
		(start 208.456276 -34.1376)
		(end 208.456276 -33.099248)
		(width 0.12065)
		(layer "F.Cu")
		(net "BMC_I2C11_MINI5_SCL_S")
	)
	(segment
		(start 65.405 -113.661952)
		(end 65.405 -112.6109)
		(width 0.12065)
		(layer "F.Cu")
		(net "BMC_I2C11_MINI5_SCL_S")
	)
	(segment
		(start 177.163476 -47.309024)
		(end 177.46345 -47.00905)
		(width 0.12065)
		(layer "F.Cu")
		(net "BMC_I2C11_MINI5_SCL_S")
	)
	(segment
		(start 207.32496 -31.672784)
		(end 207.05445 -31.402274)
		(width 0.12065)
		(layer "F.Cu")
		(net "BMC_I2C11_MINI5_SCL_S")
	)
	(segment
		(start 67.668648 -108.72216)
		(end 68.324476 -109.377988)
		(width 0.12065)
		(layer "F.Cu")
		(net "BMC_I2C11_MINI5_SCL_S")
	)
	(segment
		(start 208.456276 -32.295846)
		(end 207.833214 -31.672784)
		(width 0.12065)
		(layer "F.Cu")
		(net "BMC_I2C11_MINI5_SCL_S")
	)
	(segment
		(start 204.119226 -38.47465)
		(end 208.456276 -34.1376)
		(width 0.12065)
		(layer "F.Cu")
		(net "BMC_I2C11_MINI5_SCL_S")
	)
	(segment
		(start 208.456276 -33.099248)
		(end 208.79689 -33.099248)
		(width 0.12065)
		(layer "F.Cu")
		(net "BMC_I2C11_MINI5_SCL_S")
	)
	(segment
		(start 178.236626 -47.00905)
		(end 186.771026 -38.47465)
		(width 0.12065)
		(layer "F.Cu")
		(net "BMC_I2C11_MINI5_SCL_S")
	)
	(segment
		(start 65.8749 -107.315)
		(end 65.4304 -107.7595)
		(width 0.12065)
		(layer "F.Cu")
		(net "BMC_I2C11_MINI5_SCL_S")
	)
	(segment
		(start 207.833214 -31.672784)
		(end 207.32496 -31.672784)
		(width 0.12065)
		(layer "F.Cu")
		(net "BMC_I2C11_MINI5_SCL_S")
	)
	(segment
		(start 68.324476 -109.377988)
		(end 68.324476 -110.668054)
		(width 0.12065)
		(layer "F.Cu")
		(net "BMC_I2C11_MINI5_SCL_S")
	)
	(segment
		(start 186.771026 -38.47465)
		(end 204.119226 -38.47465)
		(width 0.12065)
		(layer "F.Cu")
		(net "BMC_I2C11_MINI5_SCL_S")
	)
	(segment
		(start 66.004694 -111.985552)
		(end 65.3923 -112.5982)
		(width 0.12065)
		(layer "F.Cu")
		(net "BMC_I2C11_MINI5_SCL_S")
	)
	(segment
		(start 68.324476 -110.668054)
		(end 67.006978 -111.985552)
		(width 0.12065)
		(layer "F.Cu")
		(net "BMC_I2C11_MINI5_SCL_S")
	)
	(segment
		(start 67.006978 -111.985552)
		(end 66.004694 -111.985552)
		(width 0.12065)
		(layer "F.Cu")
		(net "BMC_I2C11_MINI5_SCL_S")
	)
	(via
		(at 208.79689 -33.099248)
		(size 0.7112)
		(drill 0.3556)
		(layers "F.Cu" "B.Cu")
		(net "BMC_I2C11_MINI5_SCL_S")
	)
	(via
		(at 177.163476 -47.309024)
		(size 0.508)
		(drill 0.254)
		(layers "F.Cu" "B.Cu")
		(net "BMC_I2C11_MINI5_SCL_S")
	)
	(via
		(at 67.0814 -108.0516)
		(size 0.508)
		(drill 0.254)
		(layers "F.Cu" "B.Cu")
		(net "BMC_I2C11_MINI5_SCL_S")
	)
	(via
		(at 115.951 -43.124882)
		(size 0.508)
		(drill 0.254)
		(layers "F.Cu" "B.Cu")
		(net "BMC_I2C11_MINI5_SCL_S")
	)
	(segment
		(start 117.926866 -42.7482)
		(end 116.327682 -42.7482)
		(width 0.127)
		(layer "In2.Cu")
		(net "BMC_I2C11_MINI5_SCL_S")
	)
	(segment
		(start 130.12547 -45.072554)
		(end 127.801116 -42.7482)
		(width 0.127)
		(layer "In2.Cu")
		(net "BMC_I2C11_MINI5_SCL_S")
	)
	(segment
		(start 127.801116 -42.7482)
		(end 123.237752 -42.7482)
		(width 0.127)
		(layer "In2.Cu")
		(net "BMC_I2C11_MINI5_SCL_S")
	)
	(segment
		(start 119.080788 -43.902122)
		(end 117.926866 -42.7482)
		(width 0.127)
		(layer "In2.Cu")
		(net "BMC_I2C11_MINI5_SCL_S")
	)
	(segment
		(start 153.598372 -48.211994)
		(end 153.356818 -47.97044)
		(width 0.127)
		(layer "In2.Cu")
		(net "BMC_I2C11_MINI5_SCL_S")
	)
	(segment
		(start 173.44644 -49.69256)
		(end 158.43504 -49.69256)
		(width 0.127)
		(layer "In2.Cu")
		(net "BMC_I2C11_MINI5_SCL_S")
	)
	(segment
		(start 153.356818 -47.97044)
		(end 152.967182 -47.97044)
		(width 0.127)
		(layer "In2.Cu")
		(net "BMC_I2C11_MINI5_SCL_S")
	)
	(segment
		(start 123.237752 -42.7482)
		(end 122.08383 -43.902122)
		(width 0.127)
		(layer "In2.Cu")
		(net "BMC_I2C11_MINI5_SCL_S")
	)
	(segment
		(start 116.327682 -42.7482)
		(end 115.951 -43.124882)
		(width 0.127)
		(layer "In2.Cu")
		(net "BMC_I2C11_MINI5_SCL_S")
	)
	(segment
		(start 176.86655 -47.012098)
		(end 176.126902 -47.012098)
		(width 0.127)
		(layer "In2.Cu")
		(net "BMC_I2C11_MINI5_SCL_S")
	)
	(segment
		(start 139.253976 -45.072554)
		(end 130.12547 -45.072554)
		(width 0.127)
		(layer "In2.Cu")
		(net "BMC_I2C11_MINI5_SCL_S")
	)
	(segment
		(start 142.393416 -48.211994)
		(end 139.253976 -45.072554)
		(width 0.127)
		(layer "In2.Cu")
		(net "BMC_I2C11_MINI5_SCL_S")
	)
	(segment
		(start 176.126902 -47.012098)
		(end 173.44644 -49.69256)
		(width 0.127)
		(layer "In2.Cu")
		(net "BMC_I2C11_MINI5_SCL_S")
	)
	(segment
		(start 177.163476 -47.309024)
		(end 176.86655 -47.012098)
		(width 0.127)
		(layer "In2.Cu")
		(net "BMC_I2C11_MINI5_SCL_S")
	)
	(segment
		(start 152.967182 -47.97044)
		(end 152.725628 -48.211994)
		(width 0.127)
		(layer "In2.Cu")
		(net "BMC_I2C11_MINI5_SCL_S")
	)
	(segment
		(start 122.08383 -43.902122)
		(end 119.080788 -43.902122)
		(width 0.127)
		(layer "In2.Cu")
		(net "BMC_I2C11_MINI5_SCL_S")
	)
	(segment
		(start 158.43504 -49.69256)
		(end 156.954474 -48.211994)
		(width 0.127)
		(layer "In2.Cu")
		(net "BMC_I2C11_MINI5_SCL_S")
	)
	(segment
		(start 156.954474 -48.211994)
		(end 153.598372 -48.211994)
		(width 0.127)
		(layer "In2.Cu")
		(net "BMC_I2C11_MINI5_SCL_S")
	)
	(segment
		(start 152.725628 -48.211994)
		(end 142.393416 -48.211994)
		(width 0.127)
		(layer "In2.Cu")
		(net "BMC_I2C11_MINI5_SCL_S")
	)
	(segment
		(start 65.306194 -109.520482)
		(end 65.307464 -109.521752)
		(width 0.127)
		(layer "In5.Cu")
		(net "BMC_I2C11_MINI5_SCL_S")
	)
	(segment
		(start 65.786 -81.4578)
		(end 66.34226 -82.01406)
		(width 0.127)
		(layer "In5.Cu")
		(net "BMC_I2C11_MINI5_SCL_S")
	)
	(segment
		(start 65.220596 -108.947204)
		(end 65.220596 -109.428026)
		(width 0.127)
		(layer "In5.Cu")
		(net "BMC_I2C11_MINI5_SCL_S")
	)
	(segment
		(start 65.913 -108.2548)
		(end 65.220596 -108.947204)
		(width 0.127)
		(layer "In5.Cu")
		(net "BMC_I2C11_MINI5_SCL_S")
	)
	(segment
		(start 95.995998 -67.48272)
		(end 75.87488 -67.48272)
		(width 0.127)
		(layer "In5.Cu")
		(net "BMC_I2C11_MINI5_SCL_S")
	)
	(segment
		(start 65.3542 -93.0402)
		(end 66.8782 -94.5642)
		(width 0.127)
		(layer "In5.Cu")
		(net "BMC_I2C11_MINI5_SCL_S")
	)
	(segment
		(start 66.8782 -100.6602)
		(end 65.913 -101.6254)
		(width 0.127)
		(layer "In5.Cu")
		(net "BMC_I2C11_MINI5_SCL_S")
	)
	(segment
		(start 65.3542 -87.5284)
		(end 65.3542 -93.0402)
		(width 0.127)
		(layer "In5.Cu")
		(net "BMC_I2C11_MINI5_SCL_S")
	)
	(segment
		(start 115.036854 -42.8244)
		(end 114.681 -43.180254)
		(width 0.127)
		(layer "In5.Cu")
		(net "BMC_I2C11_MINI5_SCL_S")
	)
	(segment
		(start 66.34226 -82.01406)
		(end 66.34226 -86.54034)
		(width 0.127)
		(layer "In5.Cu")
		(net "BMC_I2C11_MINI5_SCL_S")
	)
	(segment
		(start 114.681 -43.180254)
		(end 114.681 -48.797718)
		(width 0.127)
		(layer "In5.Cu")
		(net "BMC_I2C11_MINI5_SCL_S")
	)
	(segment
		(start 65.486788 -109.528864)
		(end 67.0814 -108.0516)
		(width 0.127)
		(layer "In5.Cu")
		(net "BMC_I2C11_MINI5_SCL_S")
	)
	(segment
		(start 115.650518 -42.8244)
		(end 115.036854 -42.8244)
		(width 0.127)
		(layer "In5.Cu")
		(net "BMC_I2C11_MINI5_SCL_S")
	)
	(segment
		(start 66.8782 -94.5642)
		(end 66.8782 -100.6602)
		(width 0.127)
		(layer "In5.Cu")
		(net "BMC_I2C11_MINI5_SCL_S")
	)
	(segment
		(start 114.681 -48.797718)
		(end 95.995998 -67.48272)
		(width 0.127)
		(layer "In5.Cu")
		(net "BMC_I2C11_MINI5_SCL_S")
	)
	(segment
		(start 65.220596 -109.428026)
		(end 65.306194 -109.520482)
		(width 0.127)
		(layer "In5.Cu")
		(net "BMC_I2C11_MINI5_SCL_S")
	)
	(segment
		(start 65.786 -77.5716)
		(end 65.786 -81.4578)
		(width 0.127)
		(layer "In5.Cu")
		(net "BMC_I2C11_MINI5_SCL_S")
	)
	(segment
		(start 115.951 -43.124882)
		(end 115.650518 -42.8244)
		(width 0.127)
		(layer "In5.Cu")
		(net "BMC_I2C11_MINI5_SCL_S")
	)
	(segment
		(start 75.87488 -67.48272)
		(end 65.786 -77.5716)
		(width 0.127)
		(layer "In5.Cu")
		(net "BMC_I2C11_MINI5_SCL_S")
	)
	(segment
		(start 65.913 -101.6254)
		(end 65.913 -108.2548)
		(width 0.127)
		(layer "In5.Cu")
		(net "BMC_I2C11_MINI5_SCL_S")
	)
	(segment
		(start 65.307464 -109.521752)
		(end 65.486788 -109.528864)
		(width 0.127)
		(layer "In5.Cu")
		(net "BMC_I2C11_MINI5_SCL_S")
	)
	(segment
		(start 66.34226 -86.54034)
		(end 65.3542 -87.5284)
		(width 0.127)
		(layer "In5.Cu")
		(net "BMC_I2C11_MINI5_SCL_S")
	)
	(segment
		(start 117.30101 -31.9278)
		(end 106.754676 -31.9278)
		(width 0.12065)
		(layer "F.Cu")
		(net "BMC_I2C1_MINI1_SDA_S")
	)
	(segment
		(start 88.44915 -31.059374)
		(end 88.44915 -32.95015)
		(width 0.12065)
		(layer "F.Cu")
		(net "BMC_I2C1_MINI1_SDA_S")
	)
	(segment
		(start 105.059226 -30.23235)
		(end 89.276174 -30.23235)
		(width 0.12065)
		(layer "F.Cu")
		(net "BMC_I2C1_MINI1_SDA_S")
	)
	(segment
		(start 9.14146 -120.2055)
		(end 9.63676 -119.7102)
		(width 0.12065)
		(layer "F.Cu")
		(net "BMC_I2C1_MINI1_SDA_S")
	)
	(segment
		(start 88.44915 -32.95015)
		(end 88.863424 -33.364424)
		(width 0.12065)
		(layer "F.Cu")
		(net "BMC_I2C1_MINI1_SDA_S")
	)
	(segment
		(start 8.016748 -120.094248)
		(end 8.128 -120.2055)
		(width 0.12065)
		(layer "F.Cu")
		(net "BMC_I2C1_MINI1_SDA_S")
	)
	(segment
		(start 10.3378 -117.5258)
		(end 12.1412 -117.5258)
		(width 0.12065)
		(layer "F.Cu")
		(net "BMC_I2C1_MINI1_SDA_S")
	)
	(segment
		(start 117.568472 -31.082996)
		(end 117.771672 -31.286196)
		(width 0.12065)
		(layer "F.Cu")
		(net "BMC_I2C1_MINI1_SDA_S")
	)
	(segment
		(start 13.5128 -119.4181)
		(end 14.5542 -119.4181)
		(width 0.12065)
		(layer "F.Cu")
		(net "BMC_I2C1_MINI1_SDA_S")
	)
	(segment
		(start 9.017 -117.0686)
		(end 9.8806 -117.0686)
		(width 0.12065)
		(layer "F.Cu")
		(net "BMC_I2C1_MINI1_SDA_S")
	)
	(segment
		(start 8.128 -120.2055)
		(end 9.14146 -120.2055)
		(width 0.12065)
		(layer "F.Cu")
		(net "BMC_I2C1_MINI1_SDA_S")
	)
	(segment
		(start 117.771672 -31.457138)
		(end 117.30101 -31.9278)
		(width 0.12065)
		(layer "F.Cu")
		(net "BMC_I2C1_MINI1_SDA_S")
	)
	(segment
		(start 9.1186 -119.7102)
		(end 8.6106 -119.2022)
		(width 0.12065)
		(layer "F.Cu")
		(net "BMC_I2C1_MINI1_SDA_S")
	)
	(segment
		(start 8.016748 -118.068852)
		(end 9.017 -117.0686)
		(width 0.12065)
		(layer "F.Cu")
		(net "BMC_I2C1_MINI1_SDA_S")
	)
	(segment
		(start 89.260426 -33.364424)
		(end 89.5604 -33.664398)
		(width 0.12065)
		(layer "F.Cu")
		(net "BMC_I2C1_MINI1_SDA_S")
	)
	(segment
		(start 88.863424 -33.364424)
		(end 89.260426 -33.364424)
		(width 0.12065)
		(layer "F.Cu")
		(net "BMC_I2C1_MINI1_SDA_S")
	)
	(segment
		(start 8.016748 -118.15953)
		(end 8.016748 -118.068852)
		(width 0.12065)
		(layer "F.Cu")
		(net "BMC_I2C1_MINI1_SDA_S")
	)
	(segment
		(start 9.63676 -119.7102)
		(end 9.1186 -119.7102)
		(width 0.12065)
		(layer "F.Cu")
		(net "BMC_I2C1_MINI1_SDA_S")
	)
	(segment
		(start 89.276174 -30.23235)
		(end 88.44915 -31.059374)
		(width 0.12065)
		(layer "F.Cu")
		(net "BMC_I2C1_MINI1_SDA_S")
	)
	(segment
		(start 12.1412 -117.5258)
		(end 12.9032 -118.2878)
		(width 0.12065)
		(layer "F.Cu")
		(net "BMC_I2C1_MINI1_SDA_S")
	)
	(segment
		(start 9.8806 -117.0686)
		(end 10.3378 -117.5258)
		(width 0.12065)
		(layer "F.Cu")
		(net "BMC_I2C1_MINI1_SDA_S")
	)
	(segment
		(start 8.016748 -118.15953)
		(end 8.016748 -120.094248)
		(width 0.12065)
		(layer "F.Cu")
		(net "BMC_I2C1_MINI1_SDA_S")
	)
	(segment
		(start 117.771672 -31.286196)
		(end 117.771672 -31.457138)
		(width 0.12065)
		(layer "F.Cu")
		(net "BMC_I2C1_MINI1_SDA_S")
	)
	(segment
		(start 12.9032 -118.2878)
		(end 12.9032 -118.8085)
		(width 0.12065)
		(layer "F.Cu")
		(net "BMC_I2C1_MINI1_SDA_S")
	)
	(segment
		(start 12.9032 -118.8085)
		(end 13.5128 -119.4181)
		(width 0.12065)
		(layer "F.Cu")
		(net "BMC_I2C1_MINI1_SDA_S")
	)
	(segment
		(start 106.754676 -31.9278)
		(end 105.059226 -30.23235)
		(width 0.12065)
		(layer "F.Cu")
		(net "BMC_I2C1_MINI1_SDA_S")
	)
	(segment
		(start 14.5542 -119.4181)
		(end 14.5669 -119.4054)
		(width 0.12065)
		(layer "F.Cu")
		(net "BMC_I2C1_MINI1_SDA_S")
	)
	(via
		(at 89.5604 -33.664398)
		(size 0.508)
		(drill 0.254)
		(layers "F.Cu" "B.Cu")
		(net "BMC_I2C1_MINI1_SDA_S")
	)
	(via
		(at 8.016748 -118.15953)
		(size 0.7112)
		(drill 0.3556)
		(layers "F.Cu" "B.Cu")
		(net "BMC_I2C1_MINI1_SDA_S")
	)
	(via
		(at 6.7564 -64.409828)
		(size 0.508)
		(drill 0.254)
		(layers "F.Cu" "B.Cu")
		(net "BMC_I2C1_MINI1_SDA_S")
	)
	(via
		(at 8.6106 -119.2022)
		(size 0.508)
		(drill 0.254)
		(layers "F.Cu" "B.Cu")
		(net "BMC_I2C1_MINI1_SDA_S")
	)
	(segment
		(start 7.056882 -64.109346)
		(end 6.7564 -64.409828)
		(width 0.127)
		(layer "In2.Cu")
		(net "BMC_I2C1_MINI1_SDA_S")
	)
	(segment
		(start 89.32672 -33.430718)
		(end 88.7222 -33.430718)
		(width 0.127)
		(layer "In2.Cu")
		(net "BMC_I2C1_MINI1_SDA_S")
	)
	(segment
		(start 90.0938 -58.33364)
		(end 82.94624 -65.4812)
		(width 0.127)
		(layer "In2.Cu")
		(net "BMC_I2C1_MINI1_SDA_S")
	)
	(segment
		(start 90.0938 -48.5394)
		(end 90.0938 -58.33364)
		(width 0.127)
		(layer "In2.Cu")
		(net "BMC_I2C1_MINI1_SDA_S")
	)
	(segment
		(start 40.1066 -63.7286)
		(end 35.2806 -63.7286)
		(width 0.127)
		(layer "In2.Cu")
		(net "BMC_I2C1_MINI1_SDA_S")
	)
	(segment
		(start 19.2532 -61.9252)
		(end 16.318992 -64.859408)
		(width 0.127)
		(layer "In2.Cu")
		(net "BMC_I2C1_MINI1_SDA_S")
	)
	(segment
		(start 35.2806 -63.7286)
		(end 33.4772 -61.9252)
		(width 0.127)
		(layer "In2.Cu")
		(net "BMC_I2C1_MINI1_SDA_S")
	)
	(segment
		(start 47.625 -61.8998)
		(end 45.1612 -64.3636)
		(width 0.127)
		(layer "In2.Cu")
		(net "BMC_I2C1_MINI1_SDA_S")
	)
	(segment
		(start 40.7416 -64.3636)
		(end 40.1066 -63.7286)
		(width 0.127)
		(layer "In2.Cu")
		(net "BMC_I2C1_MINI1_SDA_S")
	)
	(segment
		(start 88.4682 -33.684718)
		(end 88.4682 -46.9138)
		(width 0.127)
		(layer "In2.Cu")
		(net "BMC_I2C1_MINI1_SDA_S")
	)
	(segment
		(start 8.247634 -64.109346)
		(end 7.056882 -64.109346)
		(width 0.127)
		(layer "In2.Cu")
		(net "BMC_I2C1_MINI1_SDA_S")
	)
	(segment
		(start 45.1612 -64.3636)
		(end 40.7416 -64.3636)
		(width 0.127)
		(layer "In2.Cu")
		(net "BMC_I2C1_MINI1_SDA_S")
	)
	(segment
		(start 77.026516 -65.4812)
		(end 73.445116 -61.8998)
		(width 0.127)
		(layer "In2.Cu")
		(net "BMC_I2C1_MINI1_SDA_S")
	)
	(segment
		(start 8.997696 -64.859408)
		(end 8.247634 -64.109346)
		(width 0.127)
		(layer "In2.Cu")
		(net "BMC_I2C1_MINI1_SDA_S")
	)
	(segment
		(start 88.7222 -33.430718)
		(end 88.4682 -33.684718)
		(width 0.127)
		(layer "In2.Cu")
		(net "BMC_I2C1_MINI1_SDA_S")
	)
	(segment
		(start 16.318992 -64.859408)
		(end 8.997696 -64.859408)
		(width 0.127)
		(layer "In2.Cu")
		(net "BMC_I2C1_MINI1_SDA_S")
	)
	(segment
		(start 33.4772 -61.9252)
		(end 19.2532 -61.9252)
		(width 0.127)
		(layer "In2.Cu")
		(net "BMC_I2C1_MINI1_SDA_S")
	)
	(segment
		(start 73.445116 -61.8998)
		(end 47.625 -61.8998)
		(width 0.127)
		(layer "In2.Cu")
		(net "BMC_I2C1_MINI1_SDA_S")
	)
	(segment
		(start 82.94624 -65.4812)
		(end 77.026516 -65.4812)
		(width 0.127)
		(layer "In2.Cu")
		(net "BMC_I2C1_MINI1_SDA_S")
	)
	(segment
		(start 88.4682 -46.9138)
		(end 90.0938 -48.5394)
		(width 0.127)
		(layer "In2.Cu")
		(net "BMC_I2C1_MINI1_SDA_S")
	)
	(segment
		(start 89.5604 -33.664398)
		(end 89.32672 -33.430718)
		(width 0.127)
		(layer "In2.Cu")
		(net "BMC_I2C1_MINI1_SDA_S")
	)
	(segment
		(start 10.176002 -120.570244)
		(end 10.15365 -120.392444)
		(width 0.127)
		(layer "In5.Cu")
		(net "BMC_I2C1_MINI1_SDA_S")
	)
	(segment
		(start 5.818124 -64.24803)
		(end 5.818124 -76.124308)
		(width 0.127)
		(layer "In5.Cu")
		(net "BMC_I2C1_MINI1_SDA_S")
	)
	(segment
		(start 5.945124 -64.12103)
		(end 5.818124 -64.24803)
		(width 0.127)
		(layer "In5.Cu")
		(net "BMC_I2C1_MINI1_SDA_S")
	)
	(segment
		(start 6.7564 -64.409828)
		(end 6.467602 -64.12103)
		(width 0.127)
		(layer "In5.Cu")
		(net "BMC_I2C1_MINI1_SDA_S")
	)
	(segment
		(start 8.54964 -120.734074)
		(end 10.029698 -120.734074)
		(width 0.127)
		(layer "In5.Cu")
		(net "BMC_I2C1_MINI1_SDA_S")
	)
	(segment
		(start 5.818124 -76.124308)
		(end 4.445 -77.497432)
		(width 0.127)
		(layer "In5.Cu")
		(net "BMC_I2C1_MINI1_SDA_S")
	)
	(segment
		(start 7.4168 -96.774)
		(end 7.4168 -119.601234)
		(width 0.127)
		(layer "In5.Cu")
		(net "BMC_I2C1_MINI1_SDA_S")
	)
	(segment
		(start 4.445 -93.8022)
		(end 7.4168 -96.774)
		(width 0.127)
		(layer "In5.Cu")
		(net "BMC_I2C1_MINI1_SDA_S")
	)
	(segment
		(start 10.119106 -120.644412)
		(end 10.176002 -120.570244)
		(width 0.127)
		(layer "In5.Cu")
		(net "BMC_I2C1_MINI1_SDA_S")
	)
	(segment
		(start 6.467602 -64.12103)
		(end 5.945124 -64.12103)
		(width 0.127)
		(layer "In5.Cu")
		(net "BMC_I2C1_MINI1_SDA_S")
	)
	(segment
		(start 4.445 -77.497432)
		(end 4.445 -93.8022)
		(width 0.127)
		(layer "In5.Cu")
		(net "BMC_I2C1_MINI1_SDA_S")
	)
	(segment
		(start 10.029698 -120.734074)
		(end 10.119106 -120.644412)
		(width 0.127)
		(layer "In5.Cu")
		(net "BMC_I2C1_MINI1_SDA_S")
	)
	(segment
		(start 10.15365 -120.392444)
		(end 8.6106 -119.2022)
		(width 0.127)
		(layer "In5.Cu")
		(net "BMC_I2C1_MINI1_SDA_S")
	)
	(segment
		(start 7.4168 -119.601234)
		(end 8.54964 -120.734074)
		(width 0.127)
		(layer "In5.Cu")
		(net "BMC_I2C1_MINI1_SDA_S")
	)
	(segment
		(start 106.54665 -32.42945)
		(end 104.8512 -30.734)
		(width 0.12065)
		(layer "F.Cu")
		(net "BMC_I2C1_MINI1_SCL_S")
	)
	(segment
		(start 117.509036 -32.42945)
		(end 106.54665 -32.42945)
		(width 0.12065)
		(layer "F.Cu")
		(net "BMC_I2C1_MINI1_SCL_S")
	)
	(segment
		(start 14.5669 -120.4468)
		(end 14.5669 -120.645174)
		(width 0.12065)
		(layer "F.Cu")
		(net "BMC_I2C1_MINI1_SCL_S")
	)
	(segment
		(start 14.5669 -120.645174)
		(end 15.44574 -121.524014)
		(width 0.12065)
		(layer "F.Cu")
		(net "BMC_I2C1_MINI1_SCL_S")
	)
	(segment
		(start 12.621514 -121.270014)
		(end 12.621514 -121.8692)
		(width 0.12065)
		(layer "F.Cu")
		(net "BMC_I2C1_MINI1_SCL_S")
	)
	(segment
		(start 104.8512 -30.734)
		(end 89.4842 -30.734)
		(width 0.12065)
		(layer "F.Cu")
		(net "BMC_I2C1_MINI1_SCL_S")
	)
	(segment
		(start 88.9508 -32.742124)
		(end 89.07145 -32.862774)
		(width 0.12065)
		(layer "F.Cu")
		(net "BMC_I2C1_MINI1_SCL_S")
	)
	(segment
		(start 14.5542 -120.4595)
		(end 14.5669 -120.4468)
		(width 0.12065)
		(layer "F.Cu")
		(net "BMC_I2C1_MINI1_SCL_S")
	)
	(segment
		(start 12.446 -121.0945)
		(end 12.621514 -121.270014)
		(width 0.12065)
		(layer "F.Cu")
		(net "BMC_I2C1_MINI1_SCL_S")
	)
	(segment
		(start 12.621514 -121.8692)
		(end 12.022328 -121.8692)
		(width 0.12065)
		(layer "F.Cu")
		(net "BMC_I2C1_MINI1_SCL_S")
	)
	(segment
		(start 89.260426 -32.862774)
		(end 89.5604 -32.5628)
		(width 0.12065)
		(layer "F.Cu")
		(net "BMC_I2C1_MINI1_SCL_S")
	)
	(segment
		(start 11.39444 -122.047)
		(end 10.93724 -121.5898)
		(width 0.12065)
		(layer "F.Cu")
		(net "BMC_I2C1_MINI1_SCL_S")
	)
	(segment
		(start 13.081 -120.4595)
		(end 12.446 -121.0945)
		(width 0.12065)
		(layer "F.Cu")
		(net "BMC_I2C1_MINI1_SCL_S")
	)
	(segment
		(start 12.621514 -121.8692)
		(end 12.652248 -121.899934)
		(width 0.12065)
		(layer "F.Cu")
		(net "BMC_I2C1_MINI1_SCL_S")
	)
	(segment
		(start 118.59387 -31.084012)
		(end 118.273322 -31.403544)
		(width 0.12065)
		(layer "F.Cu")
		(net "BMC_I2C1_MINI1_SCL_S")
	)
	(segment
		(start 11.844528 -122.047)
		(end 11.39444 -122.047)
		(width 0.12065)
		(layer "F.Cu")
		(net "BMC_I2C1_MINI1_SCL_S")
	)
	(segment
		(start 89.4842 -30.734)
		(end 88.9508 -31.2674)
		(width 0.12065)
		(layer "F.Cu")
		(net "BMC_I2C1_MINI1_SCL_S")
	)
	(segment
		(start 13.5128 -120.4595)
		(end 13.081 -120.4595)
		(width 0.12065)
		(layer "F.Cu")
		(net "BMC_I2C1_MINI1_SCL_S")
	)
	(segment
		(start 12.022328 -121.8692)
		(end 11.844528 -122.047)
		(width 0.12065)
		(layer "F.Cu")
		(net "BMC_I2C1_MINI1_SCL_S")
	)
	(segment
		(start 88.9508 -31.2674)
		(end 88.9508 -32.742124)
		(width 0.12065)
		(layer "F.Cu")
		(net "BMC_I2C1_MINI1_SCL_S")
	)
	(segment
		(start 89.07145 -32.862774)
		(end 89.260426 -32.862774)
		(width 0.12065)
		(layer "F.Cu")
		(net "BMC_I2C1_MINI1_SCL_S")
	)
	(segment
		(start 118.273322 -31.403544)
		(end 118.273322 -31.665164)
		(width 0.12065)
		(layer "F.Cu")
		(net "BMC_I2C1_MINI1_SCL_S")
	)
	(segment
		(start 13.5128 -120.4595)
		(end 14.5542 -120.4595)
		(width 0.12065)
		(layer "F.Cu")
		(net "BMC_I2C1_MINI1_SCL_S")
	)
	(segment
		(start 118.273322 -31.665164)
		(end 117.509036 -32.42945)
		(width 0.12065)
		(layer "F.Cu")
		(net "BMC_I2C1_MINI1_SCL_S")
	)
	(via
		(at 12.652248 -121.899934)
		(size 0.508)
		(drill 0.254)
		(layers "F.Cu" "B.Cu")
		(net "BMC_I2C1_MINI1_SCL_S")
	)
	(via
		(at 89.5604 -32.5628)
		(size 0.508)
		(drill 0.254)
		(layers "F.Cu" "B.Cu")
		(net "BMC_I2C1_MINI1_SCL_S")
	)
	(via
		(at 6.7564 -63.301118)
		(size 0.508)
		(drill 0.254)
		(layers "F.Cu" "B.Cu")
		(net "BMC_I2C1_MINI1_SCL_S")
	)
	(via
		(at 15.44574 -121.524014)
		(size 0.7112)
		(drill 0.3556)
		(layers "F.Cu" "B.Cu")
		(net "BMC_I2C1_MINI1_SCL_S")
	)
	(segment
		(start 88.511634 -32.922718)
		(end 87.9602 -33.474152)
		(width 0.127)
		(layer "In2.Cu")
		(net "BMC_I2C1_MINI1_SCL_S")
	)
	(segment
		(start 44.950634 -63.8556)
		(end 40.952166 -63.8556)
		(width 0.127)
		(layer "In2.Cu")
		(net "BMC_I2C1_MINI1_SCL_S")
	)
	(segment
		(start 47.414434 -61.3918)
		(end 44.950634 -63.8556)
		(width 0.127)
		(layer "In2.Cu")
		(net "BMC_I2C1_MINI1_SCL_S")
	)
	(segment
		(start 89.5858 -48.749966)
		(end 89.5858 -58.123074)
		(width 0.127)
		(layer "In2.Cu")
		(net "BMC_I2C1_MINI1_SCL_S")
	)
	(segment
		(start 73.655682 -61.3918)
		(end 47.414434 -61.3918)
		(width 0.127)
		(layer "In2.Cu")
		(net "BMC_I2C1_MINI1_SCL_S")
	)
	(segment
		(start 89.5604 -32.5628)
		(end 89.200482 -32.922718)
		(width 0.127)
		(layer "In2.Cu")
		(net "BMC_I2C1_MINI1_SCL_S")
	)
	(segment
		(start 40.317166 -63.2206)
		(end 35.491166 -63.2206)
		(width 0.127)
		(layer "In2.Cu")
		(net "BMC_I2C1_MINI1_SCL_S")
	)
	(segment
		(start 7.056628 -63.601346)
		(end 6.7564 -63.301118)
		(width 0.127)
		(layer "In2.Cu")
		(net "BMC_I2C1_MINI1_SCL_S")
	)
	(segment
		(start 8.4582 -63.601346)
		(end 7.056628 -63.601346)
		(width 0.127)
		(layer "In2.Cu")
		(net "BMC_I2C1_MINI1_SCL_S")
	)
	(segment
		(start 87.9602 -47.124366)
		(end 89.5858 -48.749966)
		(width 0.127)
		(layer "In2.Cu")
		(net "BMC_I2C1_MINI1_SCL_S")
	)
	(segment
		(start 35.491166 -63.2206)
		(end 33.687766 -61.4172)
		(width 0.127)
		(layer "In2.Cu")
		(net "BMC_I2C1_MINI1_SCL_S")
	)
	(segment
		(start 82.735674 -64.9732)
		(end 77.237082 -64.9732)
		(width 0.127)
		(layer "In2.Cu")
		(net "BMC_I2C1_MINI1_SCL_S")
	)
	(segment
		(start 77.237082 -64.9732)
		(end 73.655682 -61.3918)
		(width 0.127)
		(layer "In2.Cu")
		(net "BMC_I2C1_MINI1_SCL_S")
	)
	(segment
		(start 40.952166 -63.8556)
		(end 40.317166 -63.2206)
		(width 0.127)
		(layer "In2.Cu")
		(net "BMC_I2C1_MINI1_SCL_S")
	)
	(segment
		(start 89.5858 -58.123074)
		(end 82.735674 -64.9732)
		(width 0.127)
		(layer "In2.Cu")
		(net "BMC_I2C1_MINI1_SCL_S")
	)
	(segment
		(start 9.208262 -64.351408)
		(end 8.4582 -63.601346)
		(width 0.127)
		(layer "In2.Cu")
		(net "BMC_I2C1_MINI1_SCL_S")
	)
	(segment
		(start 19.042634 -61.4172)
		(end 16.108426 -64.351408)
		(width 0.127)
		(layer "In2.Cu")
		(net "BMC_I2C1_MINI1_SCL_S")
	)
	(segment
		(start 87.9602 -33.474152)
		(end 87.9602 -47.124366)
		(width 0.127)
		(layer "In2.Cu")
		(net "BMC_I2C1_MINI1_SCL_S")
	)
	(segment
		(start 89.200482 -32.922718)
		(end 88.511634 -32.922718)
		(width 0.127)
		(layer "In2.Cu")
		(net "BMC_I2C1_MINI1_SCL_S")
	)
	(segment
		(start 16.108426 -64.351408)
		(end 9.208262 -64.351408)
		(width 0.127)
		(layer "In2.Cu")
		(net "BMC_I2C1_MINI1_SCL_S")
	)
	(segment
		(start 33.687766 -61.4172)
		(end 19.042634 -61.4172)
		(width 0.127)
		(layer "In2.Cu")
		(net "BMC_I2C1_MINI1_SCL_S")
	)
	(segment
		(start 5.734558 -63.61303)
		(end 5.310124 -64.037464)
		(width 0.127)
		(layer "In5.Cu")
		(net "BMC_I2C1_MINI1_SCL_S")
	)
	(segment
		(start 3.937 -77.286866)
		(end 3.937 -94.012766)
		(width 0.127)
		(layer "In5.Cu")
		(net "BMC_I2C1_MINI1_SCL_S")
	)
	(segment
		(start 10.579608 -120.879616)
		(end 10.787634 -120.879616)
		(width 0.127)
		(layer "In5.Cu")
		(net "BMC_I2C1_MINI1_SCL_S")
	)
	(segment
		(start 10.240772 -121.242074)
		(end 10.502392 -120.979946)
		(width 0.127)
		(layer "In5.Cu")
		(net "BMC_I2C1_MINI1_SCL_S")
	)
	(segment
		(start 6.9088 -119.8118)
		(end 8.339074 -121.242074)
		(width 0.127)
		(layer "In5.Cu")
		(net "BMC_I2C1_MINI1_SCL_S")
	)
	(segment
		(start 10.502392 -120.979946)
		(end 10.572496 -120.888506)
		(width 0.127)
		(layer "In5.Cu")
		(net "BMC_I2C1_MINI1_SCL_S")
	)
	(segment
		(start 5.310124 -75.913742)
		(end 3.937 -77.286866)
		(width 0.127)
		(layer "In5.Cu")
		(net "BMC_I2C1_MINI1_SCL_S")
	)
	(segment
		(start 10.572496 -120.888506)
		(end 10.579608 -120.879616)
		(width 0.127)
		(layer "In5.Cu")
		(net "BMC_I2C1_MINI1_SCL_S")
	)
	(segment
		(start 10.787634 -120.879616)
		(end 11.484102 -121.416826)
		(width 0.127)
		(layer "In5.Cu")
		(net "BMC_I2C1_MINI1_SCL_S")
	)
	(segment
		(start 6.7564 -63.301118)
		(end 6.444488 -63.61303)
		(width 0.127)
		(layer "In5.Cu")
		(net "BMC_I2C1_MINI1_SCL_S")
	)
	(segment
		(start 11.484102 -121.416826)
		(end 12.16914 -121.416826)
		(width 0.127)
		(layer "In5.Cu")
		(net "BMC_I2C1_MINI1_SCL_S")
	)
	(segment
		(start 6.9088 -96.984566)
		(end 6.9088 -119.8118)
		(width 0.127)
		(layer "In5.Cu")
		(net "BMC_I2C1_MINI1_SCL_S")
	)
	(segment
		(start 3.937 -94.012766)
		(end 6.9088 -96.984566)
		(width 0.127)
		(layer "In5.Cu")
		(net "BMC_I2C1_MINI1_SCL_S")
	)
	(segment
		(start 8.339074 -121.242074)
		(end 10.240772 -121.242074)
		(width 0.127)
		(layer "In5.Cu")
		(net "BMC_I2C1_MINI1_SCL_S")
	)
	(segment
		(start 5.310124 -64.037464)
		(end 5.310124 -75.913742)
		(width 0.127)
		(layer "In5.Cu")
		(net "BMC_I2C1_MINI1_SCL_S")
	)
	(segment
		(start 12.16914 -121.416826)
		(end 12.652248 -121.899934)
		(width 0.127)
		(layer "In5.Cu")
		(net "BMC_I2C1_MINI1_SCL_S")
	)
	(segment
		(start 6.444488 -63.61303)
		(end 5.734558 -63.61303)
		(width 0.127)
		(layer "In5.Cu")
		(net "BMC_I2C1_MINI1_SCL_S")
	)
	(segment
		(start 263.319768 -9.773158)
		(end 263.319768 -8.569198)
		(width 0.12065)
		(layer "F.Cu")
		(net "ADM6315_PM8536_RST#")
	)
	(segment
		(start 263.510522 -9.963912)
		(end 263.319768 -9.773158)
		(width 0.12065)
		(layer "F.Cu")
		(net "ADM6315_PM8536_RST#")
	)
	(segment
		(start 268.3891 -7.5311)
		(end 267.5636 -8.3566)
		(width 0.12065)
		(layer "F.Cu")
		(net "ADM6315_PM8536_RST#")
	)
	(segment
		(start 267.5636 -8.3566)
		(end 267.5636 -9.294622)
		(width 0.12065)
		(layer "F.Cu")
		(net "ADM6315_PM8536_RST#")
	)
	(segment
		(start 267.9065 -5.6388)
		(end 267.9065 -6.17982)
		(width 0.12065)
		(layer "F.Cu")
		(net "ADM6315_PM8536_RST#")
	)
	(segment
		(start 267.5636 -9.294622)
		(end 266.89431 -9.963912)
		(width 0.12065)
		(layer "F.Cu")
		(net "ADM6315_PM8536_RST#")
	)
	(segment
		(start 268.3891 -6.66242)
		(end 268.3891 -7.2644)
		(width 0.12065)
		(layer "F.Cu")
		(net "ADM6315_PM8536_RST#")
	)
	(segment
		(start 267.9065 -6.17982)
		(end 268.3891 -6.66242)
		(width 0.12065)
		(layer "F.Cu")
		(net "ADM6315_PM8536_RST#")
	)
	(segment
		(start 266.89431 -9.963912)
		(end 263.510522 -9.963912)
		(width 0.12065)
		(layer "F.Cu")
		(net "ADM6315_PM8536_RST#")
	)
	(segment
		(start 263.319768 -8.569198)
		(end 263.363964 -8.525002)
		(width 0.12065)
		(layer "F.Cu")
		(net "ADM6315_PM8536_RST#")
	)
	(segment
		(start 268.3891 -7.2644)
		(end 268.3891 -7.5311)
		(width 0.12065)
		(layer "F.Cu")
		(net "ADM6315_PM8536_RST#")
	)
	(via
		(at 263.319768 -9.773158)
		(size 0.7112)
		(drill 0.3556)
		(layers "F.Cu" "B.Cu")
		(net "ADM6315_PM8536_RST#")
	)
	(segment
		(start 17.281652 -186.414664)
		(end 16.2687 -186.414664)
		(width 0.12065)
		(layer "F.Cu")
		(net "ADM1278_HS_P")
	)
	(segment
		(start 18.9484 -185.6867)
		(end 18.24609 -186.38901)
		(width 0.12065)
		(layer "F.Cu")
		(net "ADM1278_HS_P")
	)
	(segment
		(start 18.24609 -186.38901)
		(end 17.307306 -186.38901)
		(width 0.12065)
		(layer "F.Cu")
		(net "ADM1278_HS_P")
	)
	(segment
		(start 19.8374 -185.6867)
		(end 19.9009 -185.7502)
		(width 0.12065)
		(layer "F.Cu")
		(net "ADM1278_HS_P")
	)
	(segment
		(start 18.9484 -185.6867)
		(end 19.8374 -185.6867)
		(width 0.12065)
		(layer "F.Cu")
		(net "ADM1278_HS_P")
	)
	(segment
		(start 17.307306 -186.38901)
		(end 17.281652 -186.414664)
		(width 0.12065)
		(layer "F.Cu")
		(net "ADM1278_HS_P")
	)
	(segment
		(start 16.2687 -185.914538)
		(end 17.831562 -185.914538)
		(width 0.12065)
		(layer "F.Cu")
		(net "ADM1278_HS_N")
	)
	(segment
		(start 17.831562 -185.914538)
		(end 18.9484 -184.7977)
		(width 0.12065)
		(layer "F.Cu")
		(net "ADM1278_HS_N")
	)
	(segment
		(start 18.9484 -184.7977)
		(end 19.8374 -184.7977)
		(width 0.12065)
		(layer "F.Cu")
		(net "ADM1278_HS_N")
	)
	(segment
		(start 19.8374 -184.7977)
		(end 19.9009 -184.7342)
		(width 0.12065)
		(layer "F.Cu")
		(net "ADM1278_HS_N")
	)
	(segment
		(start 22.733 -159.7025)
		(end 22.733 -158.1658)
		(width 0.12065)
		(layer "F.Cu")
		(net "BMC_RESET#_DDR3")
	)
	(segment
		(start 22.733 -162.8775)
		(end 22.733 -159.7025)
		(width 0.12065)
		(layer "F.Cu")
		(net "BMC_RESET#_DDR3")
	)
	(segment
		(start 22.9235 -163.068)
		(end 22.733 -162.8775)
		(width 0.12065)
		(layer "F.Cu")
		(net "BMC_RESET#_DDR3")
	)
	(segment
		(start 22.733 -158.1658)
		(end 22.7584 -158.1404)
		(width 0.12065)
		(layer "F.Cu")
		(net "BMC_RESET#_DDR3")
	)
	(segment
		(start 22.9235 -164.084)
		(end 22.9235 -163.068)
		(width 0.12065)
		(layer "F.Cu")
		(net "BMC_RESET#_DDR3")
	)
	(via
		(at 22.7584 -158.1404)
		(size 0.7112)
		(drill 0.3556)
		(layers "F.Cu" "B.Cu")
		(net "BMC_RESET#_DDR3")
	)
	(segment
		(start 335.6356 -77.524102)
		(end 335.6356 -76.6191)
		(width 0.12065)
		(layer "F.Cu")
		(net "P0V9_E_VFB_AVS")
	)
	(segment
		(start 332.0034 -75.3618)
		(end 332.0034 -77.6224)
		(width 0.12065)
		(layer "F.Cu")
		(net "P0V9_E_VFB_AVS")
	)
	(segment
		(start 335.216754 -77.942948)
		(end 335.6356 -77.524102)
		(width 0.12065)
		(layer "F.Cu")
		(net "P0V9_E_VFB_AVS")
	)
	(segment
		(start 332.323948 -77.942948)
		(end 335.216754 -77.942948)
		(width 0.12065)
		(layer "F.Cu")
		(net "P0V9_E_VFB_AVS")
	)
	(segment
		(start 332.0034 -77.6224)
		(end 332.323948 -77.942948)
		(width 0.12065)
		(layer "F.Cu")
		(net "P0V9_E_VFB_AVS")
	)
	(segment
		(start 156.361892 -52.587652)
		(end 157.668722 -52.587652)
		(width 0.12065)
		(layer "F.Cu")
		(net "P0V9_VFB_AVS")
	)
	(segment
		(start 154.609546 -54.339998)
		(end 156.361892 -52.587652)
		(width 0.12065)
		(layer "F.Cu")
		(net "P0V9_VFB_AVS")
	)
	(segment
		(start 153.113232 -54.339998)
		(end 154.609546 -54.339998)
		(width 0.12065)
		(layer "F.Cu")
		(net "P0V9_VFB_AVS")
	)
	(segment
		(start 157.668722 -52.587652)
		(end 158.321502 -53.240432)
		(width 0.12065)
		(layer "F.Cu")
		(net "P0V9_VFB_AVS")
	)
	(segment
		(start 213.80704 -19.836638)
		(end 213.511638 -19.836638)
		(width 0.12065)
		(layer "F.Cu")
		(net "HOST8_RST_N_LS")
	)
	(segment
		(start 212.024468 -13.1064)
		(end 212.024468 -18.349468)
		(width 0.12065)
		(layer "F.Cu")
		(net "HOST8_RST_N_LS")
	)
	(segment
		(start 222.25 -22.7965)
		(end 222.25 -22.66188)
		(width 0.12065)
		(layer "F.Cu")
		(net "HOST8_RST_N_LS")
	)
	(segment
		(start 212.024468 -18.349468)
		(end 212.214968 -18.539968)
		(width 0.12065)
		(layer "F.Cu")
		(net "HOST8_RST_N_LS")
	)
	(segment
		(start 213.511638 -19.836638)
		(end 212.214968 -18.539968)
		(width 0.12065)
		(layer "F.Cu")
		(net "HOST8_RST_N_LS")
	)
	(segment
		(start 214.283036 -19.841718)
		(end 213.81212 -19.841718)
		(width 0.12065)
		(layer "F.Cu")
		(net "HOST8_RST_N_LS")
	)
	(segment
		(start 221.410784 -22.118828)
		(end 221.410784 -21.741638)
		(width 0.12065)
		(layer "F.Cu")
		(net "HOST8_RST_N_LS")
	)
	(segment
		(start 213.81212 -19.841718)
		(end 213.80704 -19.836638)
		(width 0.12065)
		(layer "F.Cu")
		(net "HOST8_RST_N_LS")
	)
	(segment
		(start 214.288116 -19.836638)
		(end 214.283036 -19.841718)
		(width 0.12065)
		(layer "F.Cu")
		(net "HOST8_RST_N_LS")
	)
	(segment
		(start 221.706948 -22.118828)
		(end 221.410784 -22.118828)
		(width 0.12065)
		(layer "F.Cu")
		(net "HOST8_RST_N_LS")
	)
	(segment
		(start 222.25 -22.66188)
		(end 221.706948 -22.118828)
		(width 0.12065)
		(layer "F.Cu")
		(net "HOST8_RST_N_LS")
	)
	(segment
		(start 221.410784 -21.741638)
		(end 219.505784 -19.836638)
		(width 0.12065)
		(layer "F.Cu")
		(net "HOST8_RST_N_LS")
	)
	(segment
		(start 219.505784 -19.836638)
		(end 214.288116 -19.836638)
		(width 0.12065)
		(layer "F.Cu")
		(net "HOST8_RST_N_LS")
	)
	(via
		(at 221.410784 -22.118828)
		(size 0.508)
		(drill 0.254)
		(layers "F.Cu" "B.Cu")
		(net "HOST8_RST_N_LS")
	)
	(via
		(at 212.214968 -18.539968)
		(size 0.7112)
		(drill 0.3556)
		(layers "F.Cu" "B.Cu")
		(net "HOST8_RST_N_LS")
	)
	(segment
		(start 222.25 -20.8915)
		(end 222.25 -21.166836)
		(width 0.12065)
		(layer "B.Cu")
		(net "HOST8_RST_N_LS")
	)
	(segment
		(start 221.706948 -22.118828)
		(end 221.410784 -22.118828)
		(width 0.12065)
		(layer "B.Cu")
		(net "HOST8_RST_N_LS")
	)
	(segment
		(start 222.25 -22.7965)
		(end 222.25 -22.66188)
		(width 0.12065)
		(layer "B.Cu")
		(net "HOST8_RST_N_LS")
	)
	(segment
		(start 221.410784 -22.006052)
		(end 221.410784 -22.118828)
		(width 0.12065)
		(layer "B.Cu")
		(net "HOST8_RST_N_LS")
	)
	(segment
		(start 222.25 -21.166836)
		(end 221.410784 -22.006052)
		(width 0.12065)
		(layer "B.Cu")
		(net "HOST8_RST_N_LS")
	)
	(segment
		(start 222.25 -22.66188)
		(end 221.706948 -22.118828)
		(width 0.12065)
		(layer "B.Cu")
		(net "HOST8_RST_N_LS")
	)
	(segment
		(start 227.9904 -21.717)
		(end 224.41535 -18.14195)
		(width 0.12065)
		(layer "F.Cu")
		(net "HOST2_RST_N_LS")
	)
	(segment
		(start 216.351612 -15.875)
		(end 217.424 -15.875)
		(width 0.12065)
		(layer "F.Cu")
		(net "HOST2_RST_N_LS")
	)
	(segment
		(start 224.411286 -18.14195)
		(end 222.144336 -15.875)
		(width 0.12065)
		(layer "F.Cu")
		(net "HOST2_RST_N_LS")
	)
	(segment
		(start 214.423498 -13.1064)
		(end 214.423498 -13.946886)
		(width 0.12065)
		(layer "F.Cu")
		(net "HOST2_RST_N_LS")
	)
	(segment
		(start 229.108 -22.7965)
		(end 228.0285 -21.717)
		(width 0.12065)
		(layer "F.Cu")
		(net "HOST2_RST_N_LS")
	)
	(segment
		(start 224.41535 -18.14195)
		(end 224.411286 -18.14195)
		(width 0.12065)
		(layer "F.Cu")
		(net "HOST2_RST_N_LS")
	)
	(segment
		(start 228.0285 -21.717)
		(end 227.9904 -21.717)
		(width 0.12065)
		(layer "F.Cu")
		(net "HOST2_RST_N_LS")
	)
	(segment
		(start 214.423498 -13.946886)
		(end 216.351612 -15.875)
		(width 0.12065)
		(layer "F.Cu")
		(net "HOST2_RST_N_LS")
	)
	(segment
		(start 222.144336 -15.875)
		(end 217.424 -15.875)
		(width 0.12065)
		(layer "F.Cu")
		(net "HOST2_RST_N_LS")
	)
	(via
		(at 227.9904 -21.717)
		(size 0.508)
		(drill 0.254)
		(layers "F.Cu" "B.Cu")
		(net "HOST2_RST_N_LS")
	)
	(via
		(at 217.424 -15.875)
		(size 0.7112)
		(drill 0.3556)
		(layers "F.Cu" "B.Cu")
		(net "HOST2_RST_N_LS")
	)
	(segment
		(start 229.108 -20.8915)
		(end 228.854 -20.8915)
		(width 0.12065)
		(layer "B.Cu")
		(net "HOST2_RST_N_LS")
	)
	(segment
		(start 228.0285 -21.717)
		(end 229.108 -22.7965)
		(width 0.12065)
		(layer "B.Cu")
		(net "HOST2_RST_N_LS")
	)
	(segment
		(start 227.9904 -21.717)
		(end 228.0285 -21.717)
		(width 0.12065)
		(layer "B.Cu")
		(net "HOST2_RST_N_LS")
	)
	(segment
		(start 228.854 -20.8915)
		(end 228.0285 -21.717)
		(width 0.12065)
		(layer "B.Cu")
		(net "HOST2_RST_N_LS")
	)
	(segment
		(start 221.389702 -17.453102)
		(end 215.319102 -17.453102)
		(width 0.12065)
		(layer "F.Cu")
		(net "HOST4_RST_N_LS")
	)
	(segment
		(start 226.822 -22.7965)
		(end 225.7933 -21.7678)
		(width 0.12065)
		(layer "F.Cu")
		(net "HOST4_RST_N_LS")
	)
	(segment
		(start 213.623398 -15.757398)
		(end 213.9442 -16.0782)
		(width 0.12065)
		(layer "F.Cu")
		(net "HOST4_RST_N_LS")
	)
	(segment
		(start 225.7933 -21.7678)
		(end 225.7044 -21.7678)
		(width 0.12065)
		(layer "F.Cu")
		(net "HOST4_RST_N_LS")
	)
	(segment
		(start 215.319102 -17.453102)
		(end 213.9442 -16.0782)
		(width 0.12065)
		(layer "F.Cu")
		(net "HOST4_RST_N_LS")
	)
	(segment
		(start 213.623398 -13.1064)
		(end 213.623398 -15.757398)
		(width 0.12065)
		(layer "F.Cu")
		(net "HOST4_RST_N_LS")
	)
	(segment
		(start 225.7044 -21.7678)
		(end 221.389702 -17.453102)
		(width 0.12065)
		(layer "F.Cu")
		(net "HOST4_RST_N_LS")
	)
	(via
		(at 213.9442 -16.0782)
		(size 0.7112)
		(drill 0.3556)
		(layers "F.Cu" "B.Cu")
		(net "HOST4_RST_N_LS")
	)
	(via
		(at 225.7044 -21.7678)
		(size 0.508)
		(drill 0.254)
		(layers "F.Cu" "B.Cu")
		(net "HOST4_RST_N_LS")
	)
	(segment
		(start 226.822 -20.8915)
		(end 225.9457 -21.7678)
		(width 0.12065)
		(layer "B.Cu")
		(net "HOST4_RST_N_LS")
	)
	(segment
		(start 226.822 -22.7965)
		(end 225.7933 -21.7678)
		(width 0.12065)
		(layer "B.Cu")
		(net "HOST4_RST_N_LS")
	)
	(segment
		(start 225.7933 -21.7678)
		(end 225.7044 -21.7678)
		(width 0.12065)
		(layer "B.Cu")
		(net "HOST4_RST_N_LS")
	)
	(segment
		(start 225.9457 -21.7678)
		(end 225.7933 -21.7678)
		(width 0.12065)
		(layer "B.Cu")
		(net "HOST4_RST_N_LS")
	)
	(segment
		(start 215.60917 -18.750788)
		(end 214.429848 -17.571466)
		(width 0.12065)
		(layer "F.Cu")
		(net "HOST5_RST_N_LS")
	)
	(segment
		(start 221.887288 -18.750788)
		(end 215.60917 -18.750788)
		(width 0.12065)
		(layer "F.Cu")
		(net "HOST5_RST_N_LS")
	)
	(segment
		(start 224.872804 -21.876004)
		(end 224.872804 -21.736304)
		(width 0.12065)
		(layer "F.Cu")
		(net "HOST5_RST_N_LS")
	)
	(segment
		(start 225.679 -22.7965)
		(end 225.679 -22.6822)
		(width 0.12065)
		(layer "F.Cu")
		(net "HOST5_RST_N_LS")
	)
	(segment
		(start 224.872804 -21.736304)
		(end 224.800668 -21.664168)
		(width 0.12065)
		(layer "F.Cu")
		(net "HOST5_RST_N_LS")
	)
	(segment
		(start 213.224618 -16.366236)
		(end 214.429848 -17.571466)
		(width 0.12065)
		(layer "F.Cu")
		(net "HOST5_RST_N_LS")
	)
	(segment
		(start 225.679 -22.6822)
		(end 224.872804 -21.876004)
		(width 0.12065)
		(layer "F.Cu")
		(net "HOST5_RST_N_LS")
	)
	(segment
		(start 224.800668 -21.664168)
		(end 221.887288 -18.750788)
		(width 0.12065)
		(layer "F.Cu")
		(net "HOST5_RST_N_LS")
	)
	(segment
		(start 213.224618 -13.1064)
		(end 213.224618 -16.366236)
		(width 0.12065)
		(layer "F.Cu")
		(net "HOST5_RST_N_LS")
	)
	(via
		(at 214.429848 -17.571466)
		(size 0.7112)
		(drill 0.3556)
		(layers "F.Cu" "B.Cu")
		(net "HOST5_RST_N_LS")
	)
	(via
		(at 224.800668 -21.664168)
		(size 0.508)
		(drill 0.254)
		(layers "F.Cu" "B.Cu")
		(net "HOST5_RST_N_LS")
	)
	(segment
		(start 225.679 -22.5425)
		(end 224.800668 -21.664168)
		(width 0.12065)
		(layer "B.Cu")
		(net "HOST5_RST_N_LS")
	)
	(segment
		(start 225.679 -20.8915)
		(end 225.573336 -20.8915)
		(width 0.12065)
		(layer "B.Cu")
		(net "HOST5_RST_N_LS")
	)
	(segment
		(start 225.573336 -20.8915)
		(end 224.800668 -21.664168)
		(width 0.12065)
		(layer "B.Cu")
		(net "HOST5_RST_N_LS")
	)
	(segment
		(start 225.679 -22.7965)
		(end 225.679 -22.5425)
		(width 0.12065)
		(layer "B.Cu")
		(net "HOST5_RST_N_LS")
	)
	(segment
		(start 215.8873 -16.6243)
		(end 215.590374 -16.327374)
		(width 0.12065)
		(layer "F.Cu")
		(net "HOST3_RST_N_LS")
	)
	(segment
		(start 226.8347 -21.6662)
		(end 226.7966 -21.6662)
		(width 0.12065)
		(layer "F.Cu")
		(net "HOST3_RST_N_LS")
	)
	(segment
		(start 227.965 -22.7965)
		(end 226.8347 -21.6662)
		(width 0.12065)
		(layer "F.Cu")
		(net "HOST3_RST_N_LS")
	)
	(segment
		(start 214.023448 -14.760448)
		(end 215.590374 -16.327374)
		(width 0.12065)
		(layer "F.Cu")
		(net "HOST3_RST_N_LS")
	)
	(segment
		(start 221.7547 -16.6243)
		(end 215.8873 -16.6243)
		(width 0.12065)
		(layer "F.Cu")
		(net "HOST3_RST_N_LS")
	)
	(segment
		(start 214.023448 -13.1064)
		(end 214.023448 -14.760448)
		(width 0.12065)
		(layer "F.Cu")
		(net "HOST3_RST_N_LS")
	)
	(segment
		(start 226.7966 -21.6662)
		(end 221.7547 -16.6243)
		(width 0.12065)
		(layer "F.Cu")
		(net "HOST3_RST_N_LS")
	)
	(via
		(at 215.590374 -16.327374)
		(size 0.7112)
		(drill 0.3556)
		(layers "F.Cu" "B.Cu")
		(net "HOST3_RST_N_LS")
	)
	(via
		(at 226.7966 -21.6662)
		(size 0.508)
		(drill 0.254)
		(layers "F.Cu" "B.Cu")
		(net "HOST3_RST_N_LS")
	)
	(segment
		(start 227.965 -20.8915)
		(end 227.6729 -20.8915)
		(width 0.12065)
		(layer "B.Cu")
		(net "HOST3_RST_N_LS")
	)
	(segment
		(start 227.965 -22.7965)
		(end 226.8347 -21.6662)
		(width 0.12065)
		(layer "B.Cu")
		(net "HOST3_RST_N_LS")
	)
	(segment
		(start 226.8347 -21.6662)
		(end 226.7966 -21.6662)
		(width 0.12065)
		(layer "B.Cu")
		(net "HOST3_RST_N_LS")
	)
	(segment
		(start 226.8982 -21.6662)
		(end 226.8347 -21.6662)
		(width 0.12065)
		(layer "B.Cu")
		(net "HOST3_RST_N_LS")
	)
	(segment
		(start 227.6729 -20.8915)
		(end 226.8982 -21.6662)
		(width 0.12065)
		(layer "B.Cu")
		(net "HOST3_RST_N_LS")
	)
	(segment
		(start 228.3968 -16.5481)
		(end 229.108 -17.2593)
		(width 0.12065)
		(layer "F.Cu")
		(net "HOST1_RST_N_LS")
	)
	(segment
		(start 224.5614 -17.78)
		(end 227.1649 -17.78)
		(width 0.12065)
		(layer "F.Cu")
		(net "HOST1_RST_N_LS")
	)
	(segment
		(start 229.144068 -21.7932)
		(end 229.108 -21.829268)
		(width 0.12065)
		(layer "F.Cu")
		(net "HOST1_RST_N_LS")
	)
	(segment
		(start 221.869 -15.0876)
		(end 224.5614 -17.78)
		(width 0.12065)
		(layer "F.Cu")
		(net "HOST1_RST_N_LS")
	)
	(segment
		(start 230.147368 -22.7965)
		(end 229.144068 -21.7932)
		(width 0.12065)
		(layer "F.Cu")
		(net "HOST1_RST_N_LS")
	)
	(segment
		(start 216.076276 -15.0876)
		(end 219.329 -15.0876)
		(width 0.12065)
		(layer "F.Cu")
		(net "HOST1_RST_N_LS")
	)
	(segment
		(start 219.329 -15.0876)
		(end 221.869 -15.0876)
		(width 0.12065)
		(layer "F.Cu")
		(net "HOST1_RST_N_LS")
	)
	(segment
		(start 229.108 -17.2593)
		(end 229.108 -21.803614)
		(width 0.12065)
		(layer "F.Cu")
		(net "HOST1_RST_N_LS")
	)
	(segment
		(start 214.823548 -13.834872)
		(end 216.076276 -15.0876)
		(width 0.12065)
		(layer "F.Cu")
		(net "HOST1_RST_N_LS")
	)
	(segment
		(start 227.1649 -17.78)
		(end 228.3968 -16.5481)
		(width 0.12065)
		(layer "F.Cu")
		(net "HOST1_RST_N_LS")
	)
	(segment
		(start 214.823548 -13.1064)
		(end 214.823548 -13.834872)
		(width 0.12065)
		(layer "F.Cu")
		(net "HOST1_RST_N_LS")
	)
	(segment
		(start 230.251 -22.7965)
		(end 230.147368 -22.7965)
		(width 0.12065)
		(layer "F.Cu")
		(net "HOST1_RST_N_LS")
	)
	(segment
		(start 229.108 -21.829268)
		(end 229.082346 -21.829268)
		(width 0.12065)
		(layer "F.Cu")
		(net "HOST1_RST_N_LS")
	)
	(segment
		(start 229.108 -21.803614)
		(end 229.082346 -21.829268)
		(width 0.12065)
		(layer "F.Cu")
		(net "HOST1_RST_N_LS")
	)
	(via
		(at 219.329 -15.0876)
		(size 0.7112)
		(drill 0.3556)
		(layers "F.Cu" "B.Cu")
		(net "HOST1_RST_N_LS")
	)
	(via
		(at 229.082346 -21.829268)
		(size 0.508)
		(drill 0.254)
		(layers "F.Cu" "B.Cu")
		(net "HOST1_RST_N_LS")
	)
	(segment
		(start 230.251 -20.8915)
		(end 230.0097 -20.8915)
		(width 0.12065)
		(layer "B.Cu")
		(net "HOST1_RST_N_LS")
	)
	(segment
		(start 230.049578 -22.7965)
		(end 229.082346 -21.829268)
		(width 0.12065)
		(layer "B.Cu")
		(net "HOST1_RST_N_LS")
	)
	(segment
		(start 230.0097 -20.8915)
		(end 230.0097 -20.901914)
		(width 0.12065)
		(layer "B.Cu")
		(net "HOST1_RST_N_LS")
	)
	(segment
		(start 230.0097 -20.901914)
		(end 229.082346 -21.829268)
		(width 0.12065)
		(layer "B.Cu")
		(net "HOST1_RST_N_LS")
	)
	(segment
		(start 230.251 -22.7965)
		(end 230.049578 -22.7965)
		(width 0.12065)
		(layer "B.Cu")
		(net "HOST1_RST_N_LS")
	)
	(segment
		(start 223.318832 -22.7965)
		(end 222.367094 -21.844762)
		(width 0.12065)
		(layer "F.Cu")
		(net "HOST7_RST_N_LS")
	)
	(segment
		(start 219.88018 -19.474688)
		(end 214.249 -19.474688)
		(width 0.12065)
		(layer "F.Cu")
		(net "HOST7_RST_N_LS")
	)
	(segment
		(start 223.393 -22.7965)
		(end 223.318832 -22.7965)
		(width 0.12065)
		(layer "F.Cu")
		(net "HOST7_RST_N_LS")
	)
	(segment
		(start 222.367094 -21.844762)
		(end 222.250254 -21.844762)
		(width 0.12065)
		(layer "F.Cu")
		(net "HOST7_RST_N_LS")
	)
	(segment
		(start 222.250254 -21.844762)
		(end 219.88018 -19.474688)
		(width 0.12065)
		(layer "F.Cu")
		(net "HOST7_RST_N_LS")
	)
	(segment
		(start 212.424518 -13.1064)
		(end 212.424518 -17.650206)
		(width 0.12065)
		(layer "F.Cu")
		(net "HOST7_RST_N_LS")
	)
	(segment
		(start 214.249 -19.474688)
		(end 214.047578 -19.273266)
		(width 0.12065)
		(layer "F.Cu")
		(net "HOST7_RST_N_LS")
	)
	(segment
		(start 212.424518 -17.650206)
		(end 214.047578 -19.273266)
		(width 0.12065)
		(layer "F.Cu")
		(net "HOST7_RST_N_LS")
	)
	(via
		(at 222.250254 -21.844762)
		(size 0.508)
		(drill 0.254)
		(layers "F.Cu" "B.Cu")
		(net "HOST7_RST_N_LS")
	)
	(via
		(at 214.047578 -19.273266)
		(size 0.7112)
		(drill 0.3556)
		(layers "F.Cu" "B.Cu")
		(net "HOST7_RST_N_LS")
	)
	(segment
		(start 223.393 -20.8915)
		(end 223.1771 -20.8915)
		(width 0.12065)
		(layer "B.Cu")
		(net "HOST7_RST_N_LS")
	)
	(segment
		(start 223.393 -22.7965)
		(end 223.318832 -22.7965)
		(width 0.12065)
		(layer "B.Cu")
		(net "HOST7_RST_N_LS")
	)
	(segment
		(start 222.36303 -21.731986)
		(end 222.250254 -21.844762)
		(width 0.12065)
		(layer "B.Cu")
		(net "HOST7_RST_N_LS")
	)
	(segment
		(start 223.1771 -20.8915)
		(end 222.36303 -21.70557)
		(width 0.12065)
		(layer "B.Cu")
		(net "HOST7_RST_N_LS")
	)
	(segment
		(start 222.367094 -21.844762)
		(end 222.250254 -21.844762)
		(width 0.12065)
		(layer "B.Cu")
		(net "HOST7_RST_N_LS")
	)
	(segment
		(start 223.318832 -22.7965)
		(end 222.367094 -21.844762)
		(width 0.12065)
		(layer "B.Cu")
		(net "HOST7_RST_N_LS")
	)
	(segment
		(start 222.36303 -21.70557)
		(end 222.36303 -21.731986)
		(width 0.12065)
		(layer "B.Cu")
		(net "HOST7_RST_N_LS")
	)
	(segment
		(start 214.94369 -19.112738)
		(end 213.179406 -17.348454)
		(width 0.12065)
		(layer "F.Cu")
		(net "HOST6_RST_N_LS")
	)
	(segment
		(start 223.666304 -22.342348)
		(end 223.112076 -21.78812)
		(width 0.12065)
		(layer "F.Cu")
		(net "HOST6_RST_N_LS")
	)
	(segment
		(start 220.436694 -19.112738)
		(end 214.94369 -19.112738)
		(width 0.12065)
		(layer "F.Cu")
		(net "HOST6_RST_N_LS")
	)
	(segment
		(start 223.74987 -22.342348)
		(end 223.666304 -22.342348)
		(width 0.12065)
		(layer "F.Cu")
		(net "HOST6_RST_N_LS")
	)
	(segment
		(start 212.824568 -16.993616)
		(end 213.179406 -17.348454)
		(width 0.12065)
		(layer "F.Cu")
		(net "HOST6_RST_N_LS")
	)
	(segment
		(start 212.824568 -13.1064)
		(end 212.824568 -16.993616)
		(width 0.12065)
		(layer "F.Cu")
		(net "HOST6_RST_N_LS")
	)
	(segment
		(start 224.536 -22.7965)
		(end 224.204022 -22.7965)
		(width 0.12065)
		(layer "F.Cu")
		(net "HOST6_RST_N_LS")
	)
	(segment
		(start 223.112076 -21.78812)
		(end 220.436694 -19.112738)
		(width 0.12065)
		(layer "F.Cu")
		(net "HOST6_RST_N_LS")
	)
	(segment
		(start 224.204022 -22.7965)
		(end 223.74987 -22.342348)
		(width 0.12065)
		(layer "F.Cu")
		(net "HOST6_RST_N_LS")
	)
	(via
		(at 213.179406 -17.348454)
		(size 0.7112)
		(drill 0.3556)
		(layers "F.Cu" "B.Cu")
		(net "HOST6_RST_N_LS")
	)
	(via
		(at 223.112076 -21.78812)
		(size 0.508)
		(drill 0.254)
		(layers "F.Cu" "B.Cu")
		(net "HOST6_RST_N_LS")
	)
	(segment
		(start 224.536 -20.8915)
		(end 224.204022 -20.8915)
		(width 0.12065)
		(layer "B.Cu")
		(net "HOST6_RST_N_LS")
	)
	(segment
		(start 223.307402 -21.78812)
		(end 223.112076 -21.78812)
		(width 0.12065)
		(layer "B.Cu")
		(net "HOST6_RST_N_LS")
	)
	(segment
		(start 224.536 -22.7965)
		(end 223.9645 -22.225)
		(width 0.12065)
		(layer "B.Cu")
		(net "HOST6_RST_N_LS")
	)
	(segment
		(start 223.52 -22.225)
		(end 223.112076 -21.817076)
		(width 0.12065)
		(layer "B.Cu")
		(net "HOST6_RST_N_LS")
	)
	(segment
		(start 224.204022 -20.8915)
		(end 223.307402 -21.78812)
		(width 0.12065)
		(layer "B.Cu")
		(net "HOST6_RST_N_LS")
	)
	(segment
		(start 223.9645 -22.225)
		(end 223.52 -22.225)
		(width 0.12065)
		(layer "B.Cu")
		(net "HOST6_RST_N_LS")
	)
	(segment
		(start 223.112076 -21.817076)
		(end 223.112076 -21.78812)
		(width 0.12065)
		(layer "B.Cu")
		(net "HOST6_RST_N_LS")
	)
	(segment
		(start 33.102804 -117.1575)
		(end 32.785304 -117.475)
		(width 0.12065)
		(layer "F.Cu")
		(net "PMC_PLX_BOARD")
	)
	(segment
		(start 32.785304 -117.91442)
		(end 34.504884 -119.634)
		(width 0.12065)
		(layer "F.Cu")
		(net "PMC_PLX_BOARD")
	)
	(segment
		(start 33.782 -117.1575)
		(end 34.798 -117.1575)
		(width 0.12065)
		(layer "F.Cu")
		(net "PMC_PLX_BOARD")
	)
	(segment
		(start 32.785304 -117.475)
		(end 32.785304 -117.91442)
		(width 0.12065)
		(layer "F.Cu")
		(net "PMC_PLX_BOARD")
	)
	(segment
		(start 33.782 -117.1575)
		(end 33.102804 -117.1575)
		(width 0.12065)
		(layer "F.Cu")
		(net "PMC_PLX_BOARD")
	)
	(segment
		(start 34.504884 -119.634)
		(end 34.504884 -122.084846)
		(width 0.12065)
		(layer "F.Cu")
		(net "PMC_PLX_BOARD")
	)
	(via
		(at 32.785304 -117.475)
		(size 0.7112)
		(drill 0.3556)
		(layers "F.Cu" "B.Cu")
		(net "PMC_PLX_BOARD")
	)
	(segment
		(start 19.8628 -164.084)
		(end 13.716 -164.084)
		(width 0.12065)
		(layer "F.Cu")
		(net "GPIOB1")
	)
	(segment
		(start 22.0345 -164.084)
		(end 19.8628 -164.084)
		(width 0.12065)
		(layer "F.Cu")
		(net "GPIOB1")
	)
	(segment
		(start 31.304738 -128.484884)
		(end 30.904942 -128.085088)
		(width 0.12065)
		(layer "F.Cu")
		(net "GPIOB1")
	)
	(segment
		(start 13.716 -164.084)
		(end 13.462 -163.83)
		(width 0.12065)
		(layer "F.Cu")
		(net "GPIOB1")
	)
	(via
		(at 19.8628 -164.084)
		(size 0.7112)
		(drill 0.3556)
		(layers "F.Cu" "B.Cu")
		(net "GPIOB1")
	)
	(via
		(at 30.904942 -128.085088)
		(size 0.4572)
		(drill 0.2032)
		(layers "F.Cu" "B.Cu")
		(net "GPIOB1")
	)
	(via
		(at 13.462 -163.83)
		(size 0.508)
		(drill 0.254)
		(layers "F.Cu" "B.Cu")
		(net "GPIOB1")
	)
	(segment
		(start 13.3604 -136.7536)
		(end 13.3604 -163.7284)
		(width 0.127)
		(layer "In5.Cu")
		(net "GPIOB1")
	)
	(segment
		(start 25.69083 -133.2992)
		(end 18.4404 -133.2992)
		(width 0.127)
		(layer "In5.Cu")
		(net "GPIOB1")
	)
	(segment
		(start 17.018 -134.7216)
		(end 15.3924 -134.7216)
		(width 0.127)
		(layer "In5.Cu")
		(net "GPIOB1")
	)
	(segment
		(start 30.904942 -128.085088)
		(end 25.69083 -133.2992)
		(width 0.127)
		(layer "In5.Cu")
		(net "GPIOB1")
	)
	(segment
		(start 18.4404 -133.2992)
		(end 17.018 -134.7216)
		(width 0.127)
		(layer "In5.Cu")
		(net "GPIOB1")
	)
	(segment
		(start 15.3924 -134.7216)
		(end 13.3604 -136.7536)
		(width 0.127)
		(layer "In5.Cu")
		(net "GPIOB1")
	)
	(segment
		(start 13.3604 -163.7284)
		(end 13.462 -163.83)
		(width 0.127)
		(layer "In5.Cu")
		(net "GPIOB1")
	)
	(segment
		(start 269.275052 -10.89533)
		(end 269.275052 -11.890248)
		(width 0.12065)
		(layer "F.Cu")
		(net "PM8536_RST#_LS")
	)
	(segment
		(start 271.559274 -1.870202)
		(end 271.559274 -2.438654)
		(width 0.12065)
		(layer "F.Cu")
		(net "PM8536_RST#_LS")
	)
	(segment
		(start 271.5768 1.0668)
		(end 271.5768 -1.284224)
		(width 0.12065)
		(layer "F.Cu")
		(net "PM8536_RST#_LS")
	)
	(segment
		(start 343.77503 -42.918888)
		(end 344.162634 -42.531284)
		(width 0.12065)
		(layer "F.Cu")
		(net "PM8536_RST#_LS")
	)
	(segment
		(start 271.559274 -2.438654)
		(end 270.347694 -3.650234)
		(width 0.12065)
		(layer "F.Cu")
		(net "PM8536_RST#_LS")
	)
	(segment
		(start 345.188794 -45.449236)
		(end 345.188794 -44.445682)
		(width 0.12065)
		(layer "F.Cu")
		(net "PM8536_RST#_LS")
	)
	(segment
		(start 271.559274 -1.30175)
		(end 271.559274 -1.870202)
		(width 0.12065)
		(layer "F.Cu")
		(net "PM8536_RST#_LS")
	)
	(segment
		(start 269.275052 -11.890248)
		(end 268.7955 -12.3698)
		(width 0.12065)
		(layer "F.Cu")
		(net "PM8536_RST#_LS")
	)
	(segment
		(start 343.77503 -44.161964)
		(end 343.77503 -42.918888)
		(width 0.12065)
		(layer "F.Cu")
		(net "PM8536_RST#_LS")
	)
	(segment
		(start 269.217648 -10.837926)
		(end 269.275052 -10.89533)
		(width 0.12065)
		(layer "F.Cu")
		(net "PM8536_RST#_LS")
	)
	(segment
		(start 344.030046 -44.41698)
		(end 343.77503 -44.161964)
		(width 0.12065)
		(layer "F.Cu")
		(net "PM8536_RST#_LS")
	)
	(segment
		(start 270.347694 -6.927088)
		(end 269.217648 -8.057134)
		(width 0.12065)
		(layer "F.Cu")
		(net "PM8536_RST#_LS")
	)
	(segment
		(start 345.217496 -44.41698)
		(end 344.030046 -44.41698)
		(width 0.12065)
		(layer "F.Cu")
		(net "PM8536_RST#_LS")
	)
	(segment
		(start 269.217648 -8.057134)
		(end 269.217648 -10.837926)
		(width 0.12065)
		(layer "F.Cu")
		(net "PM8536_RST#_LS")
	)
	(segment
		(start 271.5768 -1.284224)
		(end 271.559274 -1.30175)
		(width 0.12065)
		(layer "F.Cu")
		(net "PM8536_RST#_LS")
	)
	(segment
		(start 345.188794 -44.445682)
		(end 345.217496 -44.41698)
		(width 0.12065)
		(layer "F.Cu")
		(net "PM8536_RST#_LS")
	)
	(segment
		(start 270.347694 -3.650234)
		(end 270.347694 -6.927088)
		(width 0.12065)
		(layer "F.Cu")
		(net "PM8536_RST#_LS")
	)
	(via
		(at 271.5768 1.0668)
		(size 0.508)
		(drill 0.254)
		(layers "F.Cu" "B.Cu")
		(net "PM8536_RST#_LS")
	)
	(via
		(at 344.162634 -42.531284)
		(size 0.508)
		(drill 0.254)
		(layers "F.Cu" "B.Cu")
		(net "PM8536_RST#_LS")
	)
	(via
		(at 271.559274 -1.870202)
		(size 0.7112)
		(drill 0.3556)
		(layers "F.Cu" "B.Cu")
		(net "PM8536_RST#_LS")
	)
	(segment
		(start 273.87169 2.98069)
		(end 273.871436 2.98069)
		(width 0.127)
		(layer "In2.Cu")
		(net "PM8536_RST#_LS")
	)
	(segment
		(start 333.756254 -36.934394)
		(end 333.756 -4.42976)
		(width 0.127)
		(layer "In2.Cu")
		(net "PM8536_RST#_LS")
	)
	(segment
		(start 340.370414 -39.565072)
		(end 339.497416 -38.692074)
		(width 0.127)
		(layer "In2.Cu")
		(net "PM8536_RST#_LS")
	)
	(segment
		(start 339.497416 -38.692074)
		(end 335.049876 -38.692074)
		(width 0.127)
		(layer "In2.Cu")
		(net "PM8536_RST#_LS")
	)
	(segment
		(start 344.162888 -42.4053)
		(end 344.162888 -41.18991)
		(width 0.127)
		(layer "In2.Cu")
		(net "PM8536_RST#_LS")
	)
	(segment
		(start 273.875754 2.984754)
		(end 273.87169 2.98069)
		(width 0.127)
		(layer "In2.Cu")
		(net "PM8536_RST#_LS")
	)
	(segment
		(start 273.490182 2.59969)
		(end 273.383756 2.59969)
		(width 0.127)
		(layer "In2.Cu")
		(net "PM8536_RST#_LS")
	)
	(segment
		(start 335.049876 -38.692074)
		(end 333.756254 -37.398452)
		(width 0.127)
		(layer "In2.Cu")
		(net "PM8536_RST#_LS")
	)
	(segment
		(start 273.871436 2.98069)
		(end 273.490182 2.59969)
		(width 0.127)
		(layer "In2.Cu")
		(net "PM8536_RST#_LS")
	)
	(segment
		(start 344.162634 -42.531284)
		(end 344.162634 -42.405554)
		(width 0.127)
		(layer "In2.Cu")
		(net "PM8536_RST#_LS")
	)
	(segment
		(start 326.341486 2.984754)
		(end 273.875754 2.984754)
		(width 0.127)
		(layer "In2.Cu")
		(net "PM8536_RST#_LS")
	)
	(segment
		(start 344.162888 -41.18991)
		(end 342.53805 -39.565072)
		(width 0.127)
		(layer "In2.Cu")
		(net "PM8536_RST#_LS")
	)
	(segment
		(start 342.53805 -39.565072)
		(end 340.370414 -39.565072)
		(width 0.127)
		(layer "In2.Cu")
		(net "PM8536_RST#_LS")
	)
	(segment
		(start 344.162634 -42.405554)
		(end 344.162888 -42.4053)
		(width 0.127)
		(layer "In2.Cu")
		(net "PM8536_RST#_LS")
	)
	(segment
		(start 273.383756 2.59969)
		(end 271.850866 1.0668)
		(width 0.127)
		(layer "In2.Cu")
		(net "PM8536_RST#_LS")
	)
	(segment
		(start 333.756254 -37.398452)
		(end 333.756254 -36.934394)
		(width 0.127)
		(layer "In2.Cu")
		(net "PM8536_RST#_LS")
	)
	(segment
		(start 333.756 -4.42976)
		(end 326.341486 2.984754)
		(width 0.127)
		(layer "In2.Cu")
		(net "PM8536_RST#_LS")
	)
	(segment
		(start 271.850866 1.0668)
		(end 271.5768 1.0668)
		(width 0.127)
		(layer "In2.Cu")
		(net "PM8536_RST#_LS")
	)
	(segment
		(start 329.0824 -77.516228)
		(end 328.747628 -77.516228)
		(width 0.12065)
		(layer "F.Cu")
		(net "AVS_ENB2_R")
	)
	(segment
		(start 329.7682 -76.3778)
		(end 329.7682 -77.0636)
		(width 0.12065)
		(layer "F.Cu")
		(net "AVS_ENB2_R")
	)
	(segment
		(start 328.3585 -77.1271)
		(end 328.3585 -76.2)
		(width 0.12065)
		(layer "F.Cu")
		(net "AVS_ENB2_R")
	)
	(segment
		(start 328.747628 -77.516228)
		(end 328.3585 -77.1271)
		(width 0.12065)
		(layer "F.Cu")
		(net "AVS_ENB2_R")
	)
	(segment
		(start 328.3585 -76.2)
		(end 328.3585 -74.93)
		(width 0.12065)
		(layer "F.Cu")
		(net "AVS_ENB2_R")
	)
	(segment
		(start 329.315572 -77.516228)
		(end 329.0824 -77.516228)
		(width 0.12065)
		(layer "F.Cu")
		(net "AVS_ENB2_R")
	)
	(segment
		(start 329.7682 -77.0636)
		(end 329.315572 -77.516228)
		(width 0.12065)
		(layer "F.Cu")
		(net "AVS_ENB2_R")
	)
	(via
		(at 329.0824 -77.516228)
		(size 0.7112)
		(drill 0.3556)
		(layers "F.Cu" "B.Cu")
		(net "AVS_ENB2_R")
	)
	(segment
		(start 149.787102 -52.922932)
		(end 149.787102 -53.672232)
		(width 0.12065)
		(layer "F.Cu")
		(net "AVS_ENB1_R")
	)
	(segment
		(start 149.787102 -54.688232)
		(end 149.787102 -53.672232)
		(width 0.12065)
		(layer "F.Cu")
		(net "AVS_ENB1_R")
	)
	(segment
		(start 150.605236 -52.104798)
		(end 150.259034 -52.451)
		(width 0.12065)
		(layer "F.Cu")
		(net "AVS_ENB1_R")
	)
	(segment
		(start 152.097232 -52.104798)
		(end 150.605236 -52.104798)
		(width 0.12065)
		(layer "F.Cu")
		(net "AVS_ENB1_R")
	)
	(segment
		(start 150.259034 -52.451)
		(end 149.787102 -52.922932)
		(width 0.12065)
		(layer "F.Cu")
		(net "AVS_ENB1_R")
	)
	(via
		(at 150.259034 -52.451)
		(size 0.7112)
		(drill 0.3556)
		(layers "F.Cu" "B.Cu")
		(net "AVS_ENB1_R")
	)
	(segment
		(start 33.704784 -123.684792)
		(end 33.304988 -123.284996)
		(width 0.12065)
		(layer "F.Cu")
		(net "BMC_SSD_RST#14")
	)
	(via
		(at 33.304988 -123.284996)
		(size 0.4572)
		(drill 0.2032)
		(layers "F.Cu" "B.Cu")
		(net "BMC_SSD_RST#14")
	)
	(via
		(at 335.407 -182.851552)
		(size 0.7112)
		(drill 0.3556)
		(layers "F.Cu" "B.Cu")
		(net "BMC_SSD_RST#14")
	)
	(via
		(at 9.302496 -169.96537)
		(size 0.508)
		(drill 0.254)
		(layers "F.Cu" "B.Cu")
		(net "BMC_SSD_RST#14")
	)
	(segment
		(start 336.804 -182.813198)
		(end 336.797396 -182.819802)
		(width 0.12065)
		(layer "B.Cu")
		(net "BMC_SSD_RST#14")
	)
	(segment
		(start 53.064664 -167.471598)
		(end 53.429916 -167.83685)
		(width 0.12065)
		(layer "B.Cu")
		(net "BMC_SSD_RST#14")
	)
	(segment
		(start 328.042016 -182.373016)
		(end 328.844148 -183.175148)
		(width 0.12065)
		(layer "B.Cu")
		(net "BMC_SSD_RST#14")
	)
	(segment
		(start 9.302496 -169.96537)
		(end 10.903966 -168.3639)
		(width 0.12065)
		(layer "B.Cu")
		(net "BMC_SSD_RST#14")
	)
	(segment
		(start 225.202496 -152.987248)
		(end 322.561458 -152.987248)
		(width 0.12065)
		(layer "B.Cu")
		(net "BMC_SSD_RST#14")
	)
	(segment
		(start 335.34858 -168.999408)
		(end 334.863186 -169.484802)
		(width 0.12065)
		(layer "B.Cu")
		(net "BMC_SSD_RST#14")
	)
	(segment
		(start 334.863186 -169.484802)
		(end 329.901296 -169.484802)
		(width 0.12065)
		(layer "B.Cu")
		(net "BMC_SSD_RST#14")
	)
	(segment
		(start 10.903966 -168.3639)
		(end 34.590228 -168.3639)
		(width 0.12065)
		(layer "B.Cu")
		(net "BMC_SSD_RST#14")
	)
	(segment
		(start 335.34858 -165.77437)
		(end 335.34858 -168.999408)
		(width 0.12065)
		(layer "B.Cu")
		(net "BMC_SSD_RST#14")
	)
	(segment
		(start 34.590228 -168.3639)
		(end 35.48253 -167.471598)
		(width 0.12065)
		(layer "B.Cu")
		(net "BMC_SSD_RST#14")
	)
	(segment
		(start 336.797396 -182.819802)
		(end 335.43875 -182.819802)
		(width 0.12065)
		(layer "B.Cu")
		(net "BMC_SSD_RST#14")
	)
	(segment
		(start 210.352894 -167.83685)
		(end 225.202496 -152.987248)
		(width 0.12065)
		(layer "B.Cu")
		(net "BMC_SSD_RST#14")
	)
	(segment
		(start 322.561458 -152.987248)
		(end 335.34858 -165.77437)
		(width 0.12065)
		(layer "B.Cu")
		(net "BMC_SSD_RST#14")
	)
	(segment
		(start 53.429916 -167.83685)
		(end 210.352894 -167.83685)
		(width 0.12065)
		(layer "B.Cu")
		(net "BMC_SSD_RST#14")
	)
	(segment
		(start 328.844148 -183.175148)
		(end 335.083404 -183.175148)
		(width 0.12065)
		(layer "B.Cu")
		(net "BMC_SSD_RST#14")
	)
	(segment
		(start 340.058502 -182.813198)
		(end 336.804 -182.813198)
		(width 0.12065)
		(layer "B.Cu")
		(net "BMC_SSD_RST#14")
	)
	(segment
		(start 340.5886 -182.2831)
		(end 340.058502 -182.813198)
		(width 0.12065)
		(layer "B.Cu")
		(net "BMC_SSD_RST#14")
	)
	(segment
		(start 335.43875 -182.819802)
		(end 335.407 -182.851552)
		(width 0.12065)
		(layer "B.Cu")
		(net "BMC_SSD_RST#14")
	)
	(segment
		(start 335.083404 -183.175148)
		(end 335.407 -182.851552)
		(width 0.12065)
		(layer "B.Cu")
		(net "BMC_SSD_RST#14")
	)
	(segment
		(start 328.042016 -171.344082)
		(end 328.042016 -182.373016)
		(width 0.12065)
		(layer "B.Cu")
		(net "BMC_SSD_RST#14")
	)
	(segment
		(start 35.48253 -167.471598)
		(end 53.064664 -167.471598)
		(width 0.12065)
		(layer "B.Cu")
		(net "BMC_SSD_RST#14")
	)
	(segment
		(start 329.901296 -169.484802)
		(end 328.042016 -171.344082)
		(width 0.12065)
		(layer "B.Cu")
		(net "BMC_SSD_RST#14")
	)
	(segment
		(start 14.026896 -129.233168)
		(end 9.4361 -133.823964)
		(width 0.127)
		(layer "In5.Cu")
		(net "BMC_SSD_RST#14")
	)
	(segment
		(start 33.304988 -123.284996)
		(end 33.127442 -123.10745)
		(width 0.127)
		(layer "In5.Cu")
		(net "BMC_SSD_RST#14")
	)
	(segment
		(start 22.798786 -129.6162)
		(end 18.258282 -129.6162)
		(width 0.127)
		(layer "In5.Cu")
		(net "BMC_SSD_RST#14")
	)
	(segment
		(start 9.302496 -167.95115)
		(end 9.302496 -169.96537)
		(width 0.127)
		(layer "In5.Cu")
		(net "BMC_SSD_RST#14")
	)
	(segment
		(start 9.4361 -133.823964)
		(end 9.4361 -167.817546)
		(width 0.127)
		(layer "In5.Cu")
		(net "BMC_SSD_RST#14")
	)
	(segment
		(start 33.127442 -123.10745)
		(end 33.127442 -123.026932)
		(width 0.127)
		(layer "In5.Cu")
		(net "BMC_SSD_RST#14")
	)
	(segment
		(start 9.4361 -167.817546)
		(end 9.302496 -167.95115)
		(width 0.127)
		(layer "In5.Cu")
		(net "BMC_SSD_RST#14")
	)
	(segment
		(start 33.127442 -123.026932)
		(end 32.763206 -122.662696)
		(width 0.127)
		(layer "In5.Cu")
		(net "BMC_SSD_RST#14")
	)
	(segment
		(start 29.752544 -122.662696)
		(end 22.798786 -129.6162)
		(width 0.127)
		(layer "In5.Cu")
		(net "BMC_SSD_RST#14")
	)
	(segment
		(start 17.87525 -129.233168)
		(end 14.026896 -129.233168)
		(width 0.127)
		(layer "In5.Cu")
		(net "BMC_SSD_RST#14")
	)
	(segment
		(start 18.258282 -129.6162)
		(end 17.87525 -129.233168)
		(width 0.127)
		(layer "In5.Cu")
		(net "BMC_SSD_RST#14")
	)
	(segment
		(start 32.763206 -122.662696)
		(end 29.752544 -122.662696)
		(width 0.127)
		(layer "In5.Cu")
		(net "BMC_SSD_RST#14")
	)
	(segment
		(start 32.904938 -122.884946)
		(end 32.904938 -122.601228)
		(width 0.12065)
		(layer "F.Cu")
		(net "BMC_SSD_RST#11")
	)
	(segment
		(start 32.512 -121.069608)
		(end 31.203392 -119.761)
		(width 0.12065)
		(layer "F.Cu")
		(net "BMC_SSD_RST#11")
	)
	(segment
		(start 32.512 -122.20829)
		(end 32.512 -121.069608)
		(width 0.12065)
		(layer "F.Cu")
		(net "BMC_SSD_RST#11")
	)
	(segment
		(start 32.904938 -122.601228)
		(end 32.512 -122.20829)
		(width 0.12065)
		(layer "F.Cu")
		(net "BMC_SSD_RST#11")
	)
	(segment
		(start 31.203392 -119.761)
		(end 31.1404 -119.761)
		(width 0.12065)
		(layer "F.Cu")
		(net "BMC_SSD_RST#11")
	)
	(via
		(at 7.493 -171.831)
		(size 0.508)
		(drill 0.254)
		(layers "F.Cu" "B.Cu")
		(net "BMC_SSD_RST#11")
	)
	(via
		(at 65.462912 -183.457088)
		(size 0.7112)
		(drill 0.3556)
		(layers "F.Cu" "B.Cu")
		(net "BMC_SSD_RST#11")
	)
	(via
		(at 31.1404 -119.761)
		(size 0.4572)
		(drill 0.2032)
		(layers "F.Cu" "B.Cu")
		(net "BMC_SSD_RST#11")
	)
	(segment
		(start 40.016938 -171.958)
		(end 26.289 -171.958)
		(width 0.12065)
		(layer "B.Cu")
		(net "BMC_SSD_RST#11")
	)
	(segment
		(start 66.802 -191.9605)
		(end 64.8589 -190.0174)
		(width 0.12065)
		(layer "B.Cu")
		(net "BMC_SSD_RST#11")
	)
	(segment
		(start 25.511252 -172.735748)
		(end 8.397748 -172.735748)
		(width 0.12065)
		(layer "B.Cu")
		(net "BMC_SSD_RST#11")
	)
	(segment
		(start 54.936136 -172.688504)
		(end 54.636416 -172.688504)
		(width 0.12065)
		(layer "B.Cu")
		(net "BMC_SSD_RST#11")
	)
	(segment
		(start 64.8589 -190.0174)
		(end 64.8589 -184.0611)
		(width 0.12065)
		(layer "B.Cu")
		(net "BMC_SSD_RST#11")
	)
	(segment
		(start 67.71005 -181.20995)
		(end 78.145386 -181.20995)
		(width 0.12065)
		(layer "B.Cu")
		(net "BMC_SSD_RST#11")
	)
	(segment
		(start 65.462912 -183.457088)
		(end 67.71005 -181.20995)
		(width 0.12065)
		(layer "B.Cu")
		(net "BMC_SSD_RST#11")
	)
	(segment
		(start 54.93639 -172.68825)
		(end 54.936136 -172.688504)
		(width 0.12065)
		(layer "B.Cu")
		(net "BMC_SSD_RST#11")
	)
	(segment
		(start 51.010566 -172.688758)
		(end 51.010058 -172.68825)
		(width 0.12065)
		(layer "B.Cu")
		(net "BMC_SSD_RST#11")
	)
	(segment
		(start 47.074074 -172.68825)
		(end 46.350174 -173.41215)
		(width 0.12065)
		(layer "B.Cu")
		(net "BMC_SSD_RST#11")
	)
	(segment
		(start 46.350174 -173.41215)
		(end 41.471088 -173.41215)
		(width 0.12065)
		(layer "B.Cu")
		(net "BMC_SSD_RST#11")
	)
	(segment
		(start 51.010058 -172.68825)
		(end 47.074074 -172.68825)
		(width 0.12065)
		(layer "B.Cu")
		(net "BMC_SSD_RST#11")
	)
	(segment
		(start 79.46517 -177.242978)
		(end 74.910442 -172.68825)
		(width 0.12065)
		(layer "B.Cu")
		(net "BMC_SSD_RST#11")
	)
	(segment
		(start 64.8589 -184.0611)
		(end 65.462912 -183.457088)
		(width 0.12065)
		(layer "B.Cu")
		(net "BMC_SSD_RST#11")
	)
	(segment
		(start 78.145386 -181.20995)
		(end 79.46517 -179.890166)
		(width 0.12065)
		(layer "B.Cu")
		(net "BMC_SSD_RST#11")
	)
	(segment
		(start 54.636416 -172.688504)
		(end 54.636162 -172.688758)
		(width 0.12065)
		(layer "B.Cu")
		(net "BMC_SSD_RST#11")
	)
	(segment
		(start 41.471088 -173.41215)
		(end 40.016938 -171.958)
		(width 0.12065)
		(layer "B.Cu")
		(net "BMC_SSD_RST#11")
	)
	(segment
		(start 74.910442 -172.68825)
		(end 54.93639 -172.68825)
		(width 0.12065)
		(layer "B.Cu")
		(net "BMC_SSD_RST#11")
	)
	(segment
		(start 54.636162 -172.688758)
		(end 51.010566 -172.688758)
		(width 0.12065)
		(layer "B.Cu")
		(net "BMC_SSD_RST#11")
	)
	(segment
		(start 8.397748 -172.735748)
		(end 7.493 -171.831)
		(width 0.12065)
		(layer "B.Cu")
		(net "BMC_SSD_RST#11")
	)
	(segment
		(start 26.289 -171.958)
		(end 25.511252 -172.735748)
		(width 0.12065)
		(layer "B.Cu")
		(net "BMC_SSD_RST#11")
	)
	(segment
		(start 79.46517 -179.890166)
		(end 79.46517 -177.242978)
		(width 0.12065)
		(layer "B.Cu")
		(net "BMC_SSD_RST#11")
	)
	(segment
		(start 22.479 -125.1966)
		(end 19.87423 -125.1966)
		(width 0.127)
		(layer "In5.Cu")
		(net "BMC_SSD_RST#11")
	)
	(segment
		(start 7.9121 -167.185594)
		(end 7.493 -167.604694)
		(width 0.127)
		(layer "In5.Cu")
		(net "BMC_SSD_RST#11")
	)
	(segment
		(start 14.811248 -126.292864)
		(end 7.9121 -133.192012)
		(width 0.127)
		(layer "In5.Cu")
		(net "BMC_SSD_RST#11")
	)
	(segment
		(start 16.540226 -125.59792)
		(end 15.845282 -126.292864)
		(width 0.127)
		(layer "In5.Cu")
		(net "BMC_SSD_RST#11")
	)
	(segment
		(start 15.845282 -126.292864)
		(end 14.811248 -126.292864)
		(width 0.127)
		(layer "In5.Cu")
		(net "BMC_SSD_RST#11")
	)
	(segment
		(start 7.9121 -133.192012)
		(end 7.9121 -167.185594)
		(width 0.127)
		(layer "In5.Cu")
		(net "BMC_SSD_RST#11")
	)
	(segment
		(start 19.87423 -125.1966)
		(end 19.47291 -125.59792)
		(width 0.127)
		(layer "In5.Cu")
		(net "BMC_SSD_RST#11")
	)
	(segment
		(start 19.47291 -125.59792)
		(end 16.540226 -125.59792)
		(width 0.127)
		(layer "In5.Cu")
		(net "BMC_SSD_RST#11")
	)
	(segment
		(start 7.493 -167.604694)
		(end 7.493 -171.831)
		(width 0.127)
		(layer "In5.Cu")
		(net "BMC_SSD_RST#11")
	)
	(segment
		(start 31.1404 -119.761)
		(end 27.9146 -119.761)
		(width 0.127)
		(layer "In5.Cu")
		(net "BMC_SSD_RST#11")
	)
	(segment
		(start 27.9146 -119.761)
		(end 22.479 -125.1966)
		(width 0.127)
		(layer "In5.Cu")
		(net "BMC_SSD_RST#11")
	)
	(segment
		(start 34.504884 -125.284992)
		(end 34.105088 -124.885196)
		(width 0.12065)
		(layer "F.Cu")
		(net "BMC_SSD_RST#13")
	)
	(via
		(at 211.201 -196.7865)
		(size 0.7112)
		(drill 0.3556)
		(layers "F.Cu" "B.Cu")
		(net "BMC_SSD_RST#13")
	)
	(via
		(at 34.105088 -124.885196)
		(size 0.4572)
		(drill 0.2032)
		(layers "F.Cu" "B.Cu")
		(net "BMC_SSD_RST#13")
	)
	(via
		(at 10.9474 -170.4086)
		(size 0.508)
		(drill 0.254)
		(layers "F.Cu" "B.Cu")
		(net "BMC_SSD_RST#13")
	)
	(segment
		(start 91.521534 -176.174146)
		(end 95.13443 -176.174146)
		(width 0.12065)
		(layer "B.Cu")
		(net "BMC_SSD_RST#13")
	)
	(segment
		(start 14.976602 -170.45305)
		(end 14.976856 -170.452796)
		(width 0.12065)
		(layer "B.Cu")
		(net "BMC_SSD_RST#13")
	)
	(segment
		(start 53.735224 -169.792904)
		(end 53.735478 -169.79265)
		(width 0.12065)
		(layer "B.Cu")
		(net "BMC_SSD_RST#13")
	)
	(segment
		(start 14.562328 -170.45305)
		(end 14.976602 -170.45305)
		(width 0.12065)
		(layer "B.Cu")
		(net "BMC_SSD_RST#13")
	)
	(segment
		(start 53.435504 -169.792904)
		(end 53.735224 -169.792904)
		(width 0.12065)
		(layer "B.Cu")
		(net "BMC_SSD_RST#13")
	)
	(segment
		(start 212.598 -196.7865)
		(end 211.201 -196.7865)
		(width 0.12065)
		(layer "B.Cu")
		(net "BMC_SSD_RST#13")
	)
	(segment
		(start 53.43525 -169.793158)
		(end 53.435504 -169.792904)
		(width 0.12065)
		(layer "B.Cu")
		(net "BMC_SSD_RST#13")
	)
	(segment
		(start 130.7846 -188.468)
		(end 199.136 -188.468)
		(width 0.12065)
		(layer "B.Cu")
		(net "BMC_SSD_RST#13")
	)
	(segment
		(start 199.136 -188.468)
		(end 207.4545 -196.7865)
		(width 0.12065)
		(layer "B.Cu")
		(net "BMC_SSD_RST#13")
	)
	(segment
		(start 52.314094 -169.281348)
		(end 52.825396 -169.79265)
		(width 0.12065)
		(layer "B.Cu")
		(net "BMC_SSD_RST#13")
	)
	(segment
		(start 53.735478 -169.79265)
		(end 79.52994 -169.79265)
		(width 0.12065)
		(layer "B.Cu")
		(net "BMC_SSD_RST#13")
	)
	(segment
		(start 90.194892 -177.327052)
		(end 91.347544 -176.1744)
		(width 0.12065)
		(layer "B.Cu")
		(net "BMC_SSD_RST#13")
	)
	(segment
		(start 15.577058 -170.45305)
		(end 35.061398 -170.45305)
		(width 0.12065)
		(layer "B.Cu")
		(net "BMC_SSD_RST#13")
	)
	(segment
		(start 10.9474 -170.4086)
		(end 11.18235 -170.64355)
		(width 0.12065)
		(layer "B.Cu")
		(net "BMC_SSD_RST#13")
	)
	(segment
		(start 14.371828 -170.64355)
		(end 14.562328 -170.45305)
		(width 0.12065)
		(layer "B.Cu")
		(net "BMC_SSD_RST#13")
	)
	(segment
		(start 95.13443 -176.174146)
		(end 95.134684 -176.1744)
		(width 0.12065)
		(layer "B.Cu")
		(net "BMC_SSD_RST#13")
	)
	(segment
		(start 11.18235 -170.64355)
		(end 14.371828 -170.64355)
		(width 0.12065)
		(layer "B.Cu")
		(net "BMC_SSD_RST#13")
	)
	(segment
		(start 91.52128 -176.1744)
		(end 91.521534 -176.174146)
		(width 0.12065)
		(layer "B.Cu")
		(net "BMC_SSD_RST#13")
	)
	(segment
		(start 52.835302 -169.793158)
		(end 53.43525 -169.793158)
		(width 0.12065)
		(layer "B.Cu")
		(net "BMC_SSD_RST#13")
	)
	(segment
		(start 14.976856 -170.452796)
		(end 15.576804 -170.452796)
		(width 0.12065)
		(layer "B.Cu")
		(net "BMC_SSD_RST#13")
	)
	(segment
		(start 95.134684 -176.1744)
		(end 118.491 -176.1744)
		(width 0.12065)
		(layer "B.Cu")
		(net "BMC_SSD_RST#13")
	)
	(segment
		(start 35.061398 -170.45305)
		(end 36.2331 -169.281348)
		(width 0.12065)
		(layer "B.Cu")
		(net "BMC_SSD_RST#13")
	)
	(segment
		(start 15.576804 -170.452796)
		(end 15.577058 -170.45305)
		(width 0.12065)
		(layer "B.Cu")
		(net "BMC_SSD_RST#13")
	)
	(segment
		(start 52.834794 -169.79265)
		(end 52.835302 -169.793158)
		(width 0.12065)
		(layer "B.Cu")
		(net "BMC_SSD_RST#13")
	)
	(segment
		(start 79.52994 -169.79265)
		(end 87.064342 -177.327052)
		(width 0.12065)
		(layer "B.Cu")
		(net "BMC_SSD_RST#13")
	)
	(segment
		(start 52.825396 -169.79265)
		(end 52.834794 -169.79265)
		(width 0.12065)
		(layer "B.Cu")
		(net "BMC_SSD_RST#13")
	)
	(segment
		(start 91.347544 -176.1744)
		(end 91.52128 -176.1744)
		(width 0.12065)
		(layer "B.Cu")
		(net "BMC_SSD_RST#13")
	)
	(segment
		(start 36.2331 -169.281348)
		(end 52.314094 -169.281348)
		(width 0.12065)
		(layer "B.Cu")
		(net "BMC_SSD_RST#13")
	)
	(segment
		(start 118.491 -176.1744)
		(end 130.7846 -188.468)
		(width 0.12065)
		(layer "B.Cu")
		(net "BMC_SSD_RST#13")
	)
	(segment
		(start 207.4545 -196.7865)
		(end 211.201 -196.7865)
		(width 0.12065)
		(layer "B.Cu")
		(net "BMC_SSD_RST#13")
	)
	(segment
		(start 87.064342 -177.327052)
		(end 90.194892 -177.327052)
		(width 0.12065)
		(layer "B.Cu")
		(net "BMC_SSD_RST#13")
	)
	(segment
		(start 17.401286 -130.376168)
		(end 14.50086 -130.376168)
		(width 0.127)
		(layer "In5.Cu")
		(net "BMC_SSD_RST#13")
	)
	(segment
		(start 14.50086 -130.376168)
		(end 10.6045 -134.272528)
		(width 0.127)
		(layer "In5.Cu")
		(net "BMC_SSD_RST#13")
	)
	(segment
		(start 23.512272 -130.7592)
		(end 17.784318 -130.7592)
		(width 0.127)
		(layer "In5.Cu")
		(net "BMC_SSD_RST#13")
	)
	(segment
		(start 29.780484 -124.490988)
		(end 23.512272 -130.7592)
		(width 0.127)
		(layer "In5.Cu")
		(net "BMC_SSD_RST#13")
	)
	(segment
		(start 33.71088 -124.490988)
		(end 29.780484 -124.490988)
		(width 0.127)
		(layer "In5.Cu")
		(net "BMC_SSD_RST#13")
	)
	(segment
		(start 10.6045 -170.0657)
		(end 10.9474 -170.4086)
		(width 0.127)
		(layer "In5.Cu")
		(net "BMC_SSD_RST#13")
	)
	(segment
		(start 34.105088 -124.885196)
		(end 33.71088 -124.490988)
		(width 0.127)
		(layer "In5.Cu")
		(net "BMC_SSD_RST#13")
	)
	(segment
		(start 10.6045 -134.272528)
		(end 10.6045 -170.0657)
		(width 0.127)
		(layer "In5.Cu")
		(net "BMC_SSD_RST#13")
	)
	(segment
		(start 17.784318 -130.7592)
		(end 17.401286 -130.376168)
		(width 0.127)
		(layer "In5.Cu")
		(net "BMC_SSD_RST#13")
	)
	(segment
		(start 31.228792 -120.3452)
		(end 31.1404 -120.3452)
		(width 0.12065)
		(layer "F.Cu")
		(net "BMC_SSD_RST#12")
	)
	(segment
		(start 32.104838 -121.221246)
		(end 31.228792 -120.3452)
		(width 0.12065)
		(layer "F.Cu")
		(net "BMC_SSD_RST#12")
	)
	(segment
		(start 32.104838 -122.084846)
		(end 32.104838 -121.221246)
		(width 0.12065)
		(layer "F.Cu")
		(net "BMC_SSD_RST#12")
	)
	(via
		(at 31.1404 -120.3452)
		(size 0.4572)
		(drill 0.2032)
		(layers "F.Cu" "B.Cu")
		(net "BMC_SSD_RST#12")
	)
	(via
		(at 203.062586 -196.13245)
		(size 0.7112)
		(drill 0.3556)
		(layers "F.Cu" "B.Cu")
		(net "BMC_SSD_RST#12")
	)
	(via
		(at 8.5344 -171.6532)
		(size 0.508)
		(drill 0.254)
		(layers "F.Cu" "B.Cu")
		(net "BMC_SSD_RST#12")
	)
	(segment
		(start 219.179648 -201.764392)
		(end 208.694528 -201.764392)
		(width 0.12065)
		(layer "B.Cu")
		(net "BMC_SSD_RST#12")
	)
	(segment
		(start 52.38496 -170.879008)
		(end 53.885592 -170.879008)
		(width 0.12065)
		(layer "B.Cu")
		(net "BMC_SSD_RST#12")
	)
	(segment
		(start 90.645234 -178.412902)
		(end 91.797886 -177.26025)
		(width 0.12065)
		(layer "B.Cu")
		(net "BMC_SSD_RST#12")
	)
	(segment
		(start 224.94494 -201.2823)
		(end 224.3328 -201.89444)
		(width 0.12065)
		(layer "B.Cu")
		(net "BMC_SSD_RST#12")
	)
	(segment
		(start 91.797886 -177.26025)
		(end 117.968522 -177.26025)
		(width 0.12065)
		(layer "B.Cu")
		(net "BMC_SSD_RST#12")
	)
	(segment
		(start 47.731172 -170.6499)
		(end 48.013874 -170.367198)
		(width 0.12065)
		(layer "B.Cu")
		(net "BMC_SSD_RST#12")
	)
	(segment
		(start 224.3328 -201.89444)
		(end 222.0214 -201.89444)
		(width 0.12065)
		(layer "B.Cu")
		(net "BMC_SSD_RST#12")
	)
	(segment
		(start 10.206736 -171.6532)
		(end 10.492486 -171.36745)
		(width 0.12065)
		(layer "B.Cu")
		(net "BMC_SSD_RST#12")
	)
	(segment
		(start 225.770186 -201.2823)
		(end 224.94494 -201.2823)
		(width 0.12065)
		(layer "B.Cu")
		(net "BMC_SSD_RST#12")
	)
	(segment
		(start 86.614 -178.412902)
		(end 90.645234 -178.412902)
		(width 0.12065)
		(layer "B.Cu")
		(net "BMC_SSD_RST#12")
	)
	(segment
		(start 35.888676 -170.6499)
		(end 47.731172 -170.6499)
		(width 0.12065)
		(layer "B.Cu")
		(net "BMC_SSD_RST#12")
	)
	(segment
		(start 48.013874 -170.367198)
		(end 51.863752 -170.367198)
		(width 0.12065)
		(layer "B.Cu")
		(net "BMC_SSD_RST#12")
	)
	(segment
		(start 226.600512 -200.451974)
		(end 225.770186 -201.2823)
		(width 0.12065)
		(layer "B.Cu")
		(net "BMC_SSD_RST#12")
	)
	(segment
		(start 221.46006 -201.3331)
		(end 219.61094 -201.3331)
		(width 0.12065)
		(layer "B.Cu")
		(net "BMC_SSD_RST#12")
	)
	(segment
		(start 208.694528 -201.764392)
		(end 203.062586 -196.13245)
		(width 0.12065)
		(layer "B.Cu")
		(net "BMC_SSD_RST#12")
	)
	(segment
		(start 197.017386 -190.08725)
		(end 203.062586 -196.13245)
		(width 0.12065)
		(layer "B.Cu")
		(net "BMC_SSD_RST#12")
	)
	(segment
		(start 54.185566 -170.878754)
		(end 54.18582 -170.8785)
		(width 0.12065)
		(layer "B.Cu")
		(net "BMC_SSD_RST#12")
	)
	(segment
		(start 15.27683 -171.17695)
		(end 35.361626 -171.17695)
		(width 0.12065)
		(layer "B.Cu")
		(net "BMC_SSD_RST#12")
	)
	(segment
		(start 130.795522 -190.08725)
		(end 197.017386 -190.08725)
		(width 0.12065)
		(layer "B.Cu")
		(net "BMC_SSD_RST#12")
	)
	(segment
		(start 222.0214 -201.89444)
		(end 221.46006 -201.3331)
		(width 0.12065)
		(layer "B.Cu")
		(net "BMC_SSD_RST#12")
	)
	(segment
		(start 15.08633 -171.36745)
		(end 15.27683 -171.17695)
		(width 0.12065)
		(layer "B.Cu")
		(net "BMC_SSD_RST#12")
	)
	(segment
		(start 54.18582 -170.8785)
		(end 79.079598 -170.8785)
		(width 0.12065)
		(layer "B.Cu")
		(net "BMC_SSD_RST#12")
	)
	(segment
		(start 8.5344 -171.6532)
		(end 10.206736 -171.6532)
		(width 0.12065)
		(layer "B.Cu")
		(net "BMC_SSD_RST#12")
	)
	(segment
		(start 51.863752 -170.367198)
		(end 52.375054 -170.8785)
		(width 0.12065)
		(layer "B.Cu")
		(net "BMC_SSD_RST#12")
	)
	(segment
		(start 53.885846 -170.878754)
		(end 54.185566 -170.878754)
		(width 0.12065)
		(layer "B.Cu")
		(net "BMC_SSD_RST#12")
	)
	(segment
		(start 10.492486 -171.36745)
		(end 15.08633 -171.36745)
		(width 0.12065)
		(layer "B.Cu")
		(net "BMC_SSD_RST#12")
	)
	(segment
		(start 79.079598 -170.8785)
		(end 86.614 -178.412902)
		(width 0.12065)
		(layer "B.Cu")
		(net "BMC_SSD_RST#12")
	)
	(segment
		(start 52.384452 -170.8785)
		(end 52.38496 -170.879008)
		(width 0.12065)
		(layer "B.Cu")
		(net "BMC_SSD_RST#12")
	)
	(segment
		(start 226.613212 -200.451974)
		(end 226.600512 -200.451974)
		(width 0.12065)
		(layer "B.Cu")
		(net "BMC_SSD_RST#12")
	)
	(segment
		(start 52.375054 -170.8785)
		(end 52.384452 -170.8785)
		(width 0.12065)
		(layer "B.Cu")
		(net "BMC_SSD_RST#12")
	)
	(segment
		(start 35.361626 -171.17695)
		(end 35.888676 -170.6499)
		(width 0.12065)
		(layer "B.Cu")
		(net "BMC_SSD_RST#12")
	)
	(segment
		(start 53.885592 -170.879008)
		(end 53.885846 -170.878754)
		(width 0.12065)
		(layer "B.Cu")
		(net "BMC_SSD_RST#12")
	)
	(segment
		(start 219.61094 -201.3331)
		(end 219.179648 -201.764392)
		(width 0.12065)
		(layer "B.Cu")
		(net "BMC_SSD_RST#12")
	)
	(segment
		(start 117.968522 -177.26025)
		(end 130.795522 -190.08725)
		(width 0.12065)
		(layer "B.Cu")
		(net "BMC_SSD_RST#12")
	)
	(segment
		(start 8.5344 -171.1198)
		(end 7.9121 -170.4975)
		(width 0.127)
		(layer "In5.Cu")
		(net "BMC_SSD_RST#12")
	)
	(segment
		(start 16.184372 -126.771146)
		(end 16.671036 -126.284482)
		(width 0.127)
		(layer "In5.Cu")
		(net "BMC_SSD_RST#12")
	)
	(segment
		(start 7.9121 -170.4975)
		(end 7.9121 -167.724582)
		(width 0.127)
		(layer "In5.Cu")
		(net "BMC_SSD_RST#12")
	)
	(segment
		(start 28.04668 -120.3452)
		(end 31.1404 -120.3452)
		(width 0.127)
		(layer "In5.Cu")
		(net "BMC_SSD_RST#12")
	)
	(segment
		(start 7.9121 -167.724582)
		(end 8.2931 -167.343582)
		(width 0.127)
		(layer "In5.Cu")
		(net "BMC_SSD_RST#12")
	)
	(segment
		(start 14.871954 -126.771146)
		(end 16.184372 -126.771146)
		(width 0.127)
		(layer "In5.Cu")
		(net "BMC_SSD_RST#12")
	)
	(segment
		(start 16.671036 -126.284482)
		(end 22.107398 -126.284482)
		(width 0.127)
		(layer "In5.Cu")
		(net "BMC_SSD_RST#12")
	)
	(segment
		(start 22.107398 -126.284482)
		(end 28.04668 -120.3452)
		(width 0.127)
		(layer "In5.Cu")
		(net "BMC_SSD_RST#12")
	)
	(segment
		(start 8.5344 -171.6532)
		(end 8.5344 -171.1198)
		(width 0.127)
		(layer "In5.Cu")
		(net "BMC_SSD_RST#12")
	)
	(segment
		(start 8.2931 -133.35)
		(end 14.871954 -126.771146)
		(width 0.127)
		(layer "In5.Cu")
		(net "BMC_SSD_RST#12")
	)
	(segment
		(start 8.2931 -167.343582)
		(end 8.2931 -133.35)
		(width 0.127)
		(layer "In5.Cu")
		(net "BMC_SSD_RST#12")
	)
	(segment
		(start 33.704784 -124.484892)
		(end 33.304988 -124.085096)
		(width 0.12065)
		(layer "F.Cu")
		(net "BMC_SSD_RST#10")
	)
	(via
		(at 33.304988 -124.085096)
		(size 0.4572)
		(drill 0.2032)
		(layers "F.Cu" "B.Cu")
		(net "BMC_SSD_RST#10")
	)
	(via
		(at 64.569848 -180.921152)
		(size 0.7112)
		(drill 0.3556)
		(layers "F.Cu" "B.Cu")
		(net "BMC_SSD_RST#10")
	)
	(via
		(at 9.652 -173.736)
		(size 0.508)
		(drill 0.254)
		(layers "F.Cu" "B.Cu")
		(net "BMC_SSD_RST#10")
	)
	(segment
		(start 42.784776 -173.7741)
		(end 43.702478 -174.691802)
		(width 0.12065)
		(layer "B.Cu")
		(net "BMC_SSD_RST#10")
	)
	(segment
		(start 12.5222 -173.1264)
		(end 13.1699 -173.7741)
		(width 0.12065)
		(layer "B.Cu")
		(net "BMC_SSD_RST#10")
	)
	(segment
		(start 43.702478 -174.691802)
		(end 48.824134 -174.691802)
		(width 0.12065)
		(layer "B.Cu")
		(net "BMC_SSD_RST#10")
	)
	(segment
		(start 71.841106 -193.978022)
		(end 71.546974 -194.272154)
		(width 0.12065)
		(layer "B.Cu")
		(net "BMC_SSD_RST#10")
	)
	(segment
		(start 77.875384 -193.944748)
		(end 75.676506 -193.944748)
		(width 0.12065)
		(layer "B.Cu")
		(net "BMC_SSD_RST#10")
	)
	(segment
		(start 10.2616 -173.1264)
		(end 12.5222 -173.1264)
		(width 0.12065)
		(layer "B.Cu")
		(net "BMC_SSD_RST#10")
	)
	(segment
		(start 39.866824 -172.31995)
		(end 41.320974 -173.7741)
		(width 0.12065)
		(layer "B.Cu")
		(net "BMC_SSD_RST#10")
	)
	(segment
		(start 78.37932 -177.69332)
		(end 78.37932 -179.43068)
		(width 0.12065)
		(layer "B.Cu")
		(net "BMC_SSD_RST#10")
	)
	(segment
		(start 78.37932 -179.43068)
		(end 78.293976 -179.516024)
		(width 0.12065)
		(layer "B.Cu")
		(net "BMC_SSD_RST#10")
	)
	(segment
		(start 81.706212 -193.085974)
		(end 81.25206 -193.540126)
		(width 0.12065)
		(layer "B.Cu")
		(net "BMC_SSD_RST#10")
	)
	(segment
		(start 13.1699 -173.7741)
		(end 24.984964 -173.7741)
		(width 0.12065)
		(layer "B.Cu")
		(net "BMC_SSD_RST#10")
	)
	(segment
		(start 26.439114 -172.31995)
		(end 39.866824 -172.31995)
		(width 0.12065)
		(layer "B.Cu")
		(net "BMC_SSD_RST#10")
	)
	(segment
		(start 49.741836 -173.7741)
		(end 50.559716 -173.7741)
		(width 0.12065)
		(layer "B.Cu")
		(net "BMC_SSD_RST#10")
	)
	(segment
		(start 79.844392 -193.531998)
		(end 79.836264 -193.540126)
		(width 0.12065)
		(layer "B.Cu")
		(net "BMC_SSD_RST#10")
	)
	(segment
		(start 78.293976 -179.525168)
		(end 78.020418 -179.798726)
		(width 0.12065)
		(layer "B.Cu")
		(net "BMC_SSD_RST#10")
	)
	(segment
		(start 65.692274 -179.798726)
		(end 64.569848 -180.921152)
		(width 0.12065)
		(layer "B.Cu")
		(net "BMC_SSD_RST#10")
	)
	(segment
		(start 41.320974 -173.7741)
		(end 42.784776 -173.7741)
		(width 0.12065)
		(layer "B.Cu")
		(net "BMC_SSD_RST#10")
	)
	(segment
		(start 63.627 -181.864)
		(end 64.569848 -180.921152)
		(width 0.12065)
		(layer "B.Cu")
		(net "BMC_SSD_RST#10")
	)
	(segment
		(start 80.531208 -193.531998)
		(end 79.844392 -193.531998)
		(width 0.12065)
		(layer "B.Cu")
		(net "BMC_SSD_RST#10")
	)
	(segment
		(start 71.546974 -194.272154)
		(end 66.256154 -194.272154)
		(width 0.12065)
		(layer "B.Cu")
		(net "BMC_SSD_RST#10")
	)
	(segment
		(start 55.086758 -173.774354)
		(end 55.386478 -173.774354)
		(width 0.12065)
		(layer "B.Cu")
		(net "BMC_SSD_RST#10")
	)
	(segment
		(start 74.4601 -173.7741)
		(end 78.37932 -177.69332)
		(width 0.12065)
		(layer "B.Cu")
		(net "BMC_SSD_RST#10")
	)
	(segment
		(start 78.020418 -179.798726)
		(end 65.692274 -179.798726)
		(width 0.12065)
		(layer "B.Cu")
		(net "BMC_SSD_RST#10")
	)
	(segment
		(start 78.280006 -193.540126)
		(end 77.875384 -193.944748)
		(width 0.12065)
		(layer "B.Cu")
		(net "BMC_SSD_RST#10")
	)
	(segment
		(start 48.824134 -174.691802)
		(end 49.741836 -173.7741)
		(width 0.12065)
		(layer "B.Cu")
		(net "BMC_SSD_RST#10")
	)
	(segment
		(start 50.560224 -173.774608)
		(end 55.086504 -173.774608)
		(width 0.12065)
		(layer "B.Cu")
		(net "BMC_SSD_RST#10")
	)
	(segment
		(start 9.652 -173.736)
		(end 10.2616 -173.1264)
		(width 0.12065)
		(layer "B.Cu")
		(net "BMC_SSD_RST#10")
	)
	(segment
		(start 55.386732 -173.7741)
		(end 74.4601 -173.7741)
		(width 0.12065)
		(layer "B.Cu")
		(net "BMC_SSD_RST#10")
	)
	(segment
		(start 75.643232 -193.978022)
		(end 71.841106 -193.978022)
		(width 0.12065)
		(layer "B.Cu")
		(net "BMC_SSD_RST#10")
	)
	(segment
		(start 79.836264 -193.540126)
		(end 78.280006 -193.540126)
		(width 0.12065)
		(layer "B.Cu")
		(net "BMC_SSD_RST#10")
	)
	(segment
		(start 63.627 -191.643)
		(end 63.627 -181.864)
		(width 0.12065)
		(layer "B.Cu")
		(net "BMC_SSD_RST#10")
	)
	(segment
		(start 55.386478 -173.774354)
		(end 55.386732 -173.7741)
		(width 0.12065)
		(layer "B.Cu")
		(net "BMC_SSD_RST#10")
	)
	(segment
		(start 50.559716 -173.7741)
		(end 50.560224 -173.774608)
		(width 0.12065)
		(layer "B.Cu")
		(net "BMC_SSD_RST#10")
	)
	(segment
		(start 81.25206 -193.540126)
		(end 80.539336 -193.540126)
		(width 0.12065)
		(layer "B.Cu")
		(net "BMC_SSD_RST#10")
	)
	(segment
		(start 75.676506 -193.944748)
		(end 75.643232 -193.978022)
		(width 0.12065)
		(layer "B.Cu")
		(net "BMC_SSD_RST#10")
	)
	(segment
		(start 24.984964 -173.7741)
		(end 26.439114 -172.31995)
		(width 0.12065)
		(layer "B.Cu")
		(net "BMC_SSD_RST#10")
	)
	(segment
		(start 80.539336 -193.540126)
		(end 80.531208 -193.531998)
		(width 0.12065)
		(layer "B.Cu")
		(net "BMC_SSD_RST#10")
	)
	(segment
		(start 66.256154 -194.272154)
		(end 63.627 -191.643)
		(width 0.12065)
		(layer "B.Cu")
		(net "BMC_SSD_RST#10")
	)
	(segment
		(start 78.293976 -179.516024)
		(end 78.293976 -179.525168)
		(width 0.12065)
		(layer "B.Cu")
		(net "BMC_SSD_RST#10")
	)
	(segment
		(start 55.086504 -173.774608)
		(end 55.086758 -173.774354)
		(width 0.12065)
		(layer "B.Cu")
		(net "BMC_SSD_RST#10")
	)
	(segment
		(start 30.062932 -122.891296)
		(end 23.204678 -129.74955)
		(width 0.127)
		(layer "In5.Cu")
		(net "BMC_SSD_RST#10")
	)
	(segment
		(start 23.204678 -129.74955)
		(end 22.956774 -129.9972)
		(width 0.127)
		(layer "In5.Cu")
		(net "BMC_SSD_RST#10")
	)
	(segment
		(start 33.304988 -124.085096)
		(end 32.898842 -123.67895)
		(width 0.127)
		(layer "In5.Cu")
		(net "BMC_SSD_RST#10")
	)
	(segment
		(start 9.8171 -133.981952)
		(end 9.8171 -170.115484)
		(width 0.127)
		(layer "In5.Cu")
		(net "BMC_SSD_RST#10")
	)
	(segment
		(start 32.898842 -123.121674)
		(end 32.668464 -122.891296)
		(width 0.127)
		(layer "In5.Cu")
		(net "BMC_SSD_RST#10")
	)
	(segment
		(start 22.956774 -129.9972)
		(end 18.100294 -129.9972)
		(width 0.127)
		(layer "In5.Cu")
		(net "BMC_SSD_RST#10")
	)
	(segment
		(start 9.8171 -170.115484)
		(end 9.652 -170.280584)
		(width 0.127)
		(layer "In5.Cu")
		(net "BMC_SSD_RST#10")
	)
	(segment
		(start 14.184884 -129.614168)
		(end 9.8171 -133.981952)
		(width 0.127)
		(layer "In5.Cu")
		(net "BMC_SSD_RST#10")
	)
	(segment
		(start 32.668464 -122.891296)
		(end 30.062932 -122.891296)
		(width 0.127)
		(layer "In5.Cu")
		(net "BMC_SSD_RST#10")
	)
	(segment
		(start 18.100294 -129.9972)
		(end 17.717262 -129.614168)
		(width 0.127)
		(layer "In5.Cu")
		(net "BMC_SSD_RST#10")
	)
	(segment
		(start 17.717262 -129.614168)
		(end 14.184884 -129.614168)
		(width 0.127)
		(layer "In5.Cu")
		(net "BMC_SSD_RST#10")
	)
	(segment
		(start 32.898842 -123.67895)
		(end 32.898842 -123.121674)
		(width 0.127)
		(layer "In5.Cu")
		(net "BMC_SSD_RST#10")
	)
	(segment
		(start 9.652 -170.280584)
		(end 9.652 -173.736)
		(width 0.127)
		(layer "In5.Cu")
		(net "BMC_SSD_RST#10")
	)
	(segment
		(start 43.304714 -135.684768)
		(end 43.70451 -135.284972)
		(width 0.12065)
		(layer "F.Cu")
		(net "BMC_SSD_RST#6")
	)
	(via
		(at 44.5008 -172.339)
		(size 0.508)
		(drill 0.254)
		(layers "F.Cu" "B.Cu")
		(net "BMC_SSD_RST#6")
	)
	(via
		(at 43.70451 -135.284972)
		(size 0.4572)
		(drill 0.2032)
		(layers "F.Cu" "B.Cu")
		(net "BMC_SSD_RST#6")
	)
	(via
		(at 122.174 -207.772)
		(size 0.7112)
		(drill 0.3556)
		(layers "F.Cu" "B.Cu")
		(net "BMC_SSD_RST#6")
	)
	(segment
		(start 83.34883 -182.675022)
		(end 97.06483 -182.675022)
		(width 0.12065)
		(layer "B.Cu")
		(net "BMC_SSD_RST#6")
	)
	(segment
		(start 130.896106 -207.178148)
		(end 126.044706 -207.178148)
		(width 0.12065)
		(layer "B.Cu")
		(net "BMC_SSD_RST#6")
	)
	(segment
		(start 135.808212 -206.293974)
		(end 135.285988 -206.816198)
		(width 0.12065)
		(layer "B.Cu")
		(net "BMC_SSD_RST#6")
	)
	(segment
		(start 54.486302 -172.326554)
		(end 54.786022 -172.326554)
		(width 0.12065)
		(layer "B.Cu")
		(net "BMC_SSD_RST#6")
	)
	(segment
		(start 51.16068 -172.326808)
		(end 54.486048 -172.326808)
		(width 0.12065)
		(layer "B.Cu")
		(net "BMC_SSD_RST#6")
	)
	(segment
		(start 97.06483 -182.675022)
		(end 122.161808 -207.772)
		(width 0.12065)
		(layer "B.Cu")
		(net "BMC_SSD_RST#6")
	)
	(segment
		(start 75.060556 -172.3263)
		(end 79.82712 -177.092864)
		(width 0.12065)
		(layer "B.Cu")
		(net "BMC_SSD_RST#6")
	)
	(segment
		(start 131.258056 -206.816198)
		(end 130.896106 -207.178148)
		(width 0.12065)
		(layer "B.Cu")
		(net "BMC_SSD_RST#6")
	)
	(segment
		(start 79.82712 -177.092864)
		(end 79.82712 -177.093372)
		(width 0.12065)
		(layer "B.Cu")
		(net "BMC_SSD_RST#6")
	)
	(segment
		(start 80.772 -178.038252)
		(end 80.772 -180.098192)
		(width 0.12065)
		(layer "B.Cu")
		(net "BMC_SSD_RST#6")
	)
	(segment
		(start 122.161808 -207.772)
		(end 122.174 -207.772)
		(width 0.12065)
		(layer "B.Cu")
		(net "BMC_SSD_RST#6")
	)
	(segment
		(start 125.704854 -207.518)
		(end 122.428 -207.518)
		(width 0.12065)
		(layer "B.Cu")
		(net "BMC_SSD_RST#6")
	)
	(segment
		(start 54.786276 -172.3263)
		(end 75.060556 -172.3263)
		(width 0.12065)
		(layer "B.Cu")
		(net "BMC_SSD_RST#6")
	)
	(segment
		(start 51.160172 -172.3263)
		(end 51.16068 -172.326808)
		(width 0.12065)
		(layer "B.Cu")
		(net "BMC_SSD_RST#6")
	)
	(segment
		(start 126.044706 -207.178148)
		(end 125.704854 -207.518)
		(width 0.12065)
		(layer "B.Cu")
		(net "BMC_SSD_RST#6")
	)
	(segment
		(start 79.82712 -177.093372)
		(end 80.772 -178.038252)
		(width 0.12065)
		(layer "B.Cu")
		(net "BMC_SSD_RST#6")
	)
	(segment
		(start 44.5135 -172.3263)
		(end 51.160172 -172.3263)
		(width 0.12065)
		(layer "B.Cu")
		(net "BMC_SSD_RST#6")
	)
	(segment
		(start 122.428 -207.518)
		(end 122.174 -207.772)
		(width 0.12065)
		(layer "B.Cu")
		(net "BMC_SSD_RST#6")
	)
	(segment
		(start 54.486048 -172.326808)
		(end 54.486302 -172.326554)
		(width 0.12065)
		(layer "B.Cu")
		(net "BMC_SSD_RST#6")
	)
	(segment
		(start 44.5008 -172.339)
		(end 44.5135 -172.3263)
		(width 0.12065)
		(layer "B.Cu")
		(net "BMC_SSD_RST#6")
	)
	(segment
		(start 80.772 -180.098192)
		(end 83.34883 -182.675022)
		(width 0.12065)
		(layer "B.Cu")
		(net "BMC_SSD_RST#6")
	)
	(segment
		(start 135.285988 -206.816198)
		(end 131.258056 -206.816198)
		(width 0.12065)
		(layer "B.Cu")
		(net "BMC_SSD_RST#6")
	)
	(segment
		(start 54.786022 -172.326554)
		(end 54.786276 -172.3263)
		(width 0.12065)
		(layer "B.Cu")
		(net "BMC_SSD_RST#6")
	)
	(segment
		(start 44.2722 -172.1104)
		(end 44.2722 -171.181776)
		(width 0.127)
		(layer "In5.Cu")
		(net "BMC_SSD_RST#6")
	)
	(segment
		(start 44.09821 -134.891272)
		(end 43.70451 -135.284972)
		(width 0.127)
		(layer "In5.Cu")
		(net "BMC_SSD_RST#6")
	)
	(segment
		(start 48.121824 -141.960346)
		(end 48.172624 -141.909546)
		(width 0.127)
		(layer "In5.Cu")
		(net "BMC_SSD_RST#6")
	)
	(segment
		(start 44.2722 -171.181776)
		(end 48.552354 -166.901622)
		(width 0.127)
		(layer "In5.Cu")
		(net "BMC_SSD_RST#6")
	)
	(segment
		(start 48.6029 -144.390618)
		(end 48.6029 -144.000982)
		(width 0.127)
		(layer "In5.Cu")
		(net "BMC_SSD_RST#6")
	)
	(segment
		(start 48.552354 -144.441164)
		(end 48.6029 -144.390618)
		(width 0.127)
		(layer "In5.Cu")
		(net "BMC_SSD_RST#6")
	)
	(segment
		(start 45.468032 -134.891272)
		(end 44.09821 -134.891272)
		(width 0.127)
		(layer "In5.Cu")
		(net "BMC_SSD_RST#6")
	)
	(segment
		(start 44.5008 -172.339)
		(end 44.2722 -172.1104)
		(width 0.127)
		(layer "In5.Cu")
		(net "BMC_SSD_RST#6")
	)
	(segment
		(start 48.172624 -137.595864)
		(end 45.468032 -134.891272)
		(width 0.127)
		(layer "In5.Cu")
		(net "BMC_SSD_RST#6")
	)
	(segment
		(start 48.121824 -143.519906)
		(end 48.121824 -141.960346)
		(width 0.127)
		(layer "In5.Cu")
		(net "BMC_SSD_RST#6")
	)
	(segment
		(start 48.552354 -166.901622)
		(end 48.552354 -144.441164)
		(width 0.127)
		(layer "In5.Cu")
		(net "BMC_SSD_RST#6")
	)
	(segment
		(start 48.172624 -141.909546)
		(end 48.172624 -137.595864)
		(width 0.127)
		(layer "In5.Cu")
		(net "BMC_SSD_RST#6")
	)
	(segment
		(start 48.6029 -144.000982)
		(end 48.121824 -143.519906)
		(width 0.127)
		(layer "In5.Cu")
		(net "BMC_SSD_RST#6")
	)
	(segment
		(start 46.673262 -138.253216)
		(end 46.50486 -138.084814)
		(width 0.12065)
		(layer "F.Cu")
		(net "BMC_SSD_RST#5")
	)
	(segment
		(start 50.428144 -141.605)
		(end 50.083974 -141.26083)
		(width 0.12065)
		(layer "F.Cu")
		(net "BMC_SSD_RST#5")
	)
	(segment
		(start 52.2478 -142.179802)
		(end 52.2478 -141.964918)
		(width 0.12065)
		(layer "F.Cu")
		(net "BMC_SSD_RST#5")
	)
	(segment
		(start 52.2478 -141.964918)
		(end 51.887882 -141.605)
		(width 0.12065)
		(layer "F.Cu")
		(net "BMC_SSD_RST#5")
	)
	(segment
		(start 50.083974 -141.26083)
		(end 50.06213 -141.26083)
		(width 0.12065)
		(layer "F.Cu")
		(net "BMC_SSD_RST#5")
	)
	(segment
		(start 50.06213 -141.26083)
		(end 47.054516 -138.253216)
		(width 0.12065)
		(layer "F.Cu")
		(net "BMC_SSD_RST#5")
	)
	(segment
		(start 51.887882 -141.605)
		(end 50.428144 -141.605)
		(width 0.12065)
		(layer "F.Cu")
		(net "BMC_SSD_RST#5")
	)
	(segment
		(start 47.054516 -138.253216)
		(end 46.673262 -138.253216)
		(width 0.12065)
		(layer "F.Cu")
		(net "BMC_SSD_RST#5")
	)
	(via
		(at 52.2478 -142.179802)
		(size 0.508)
		(drill 0.254)
		(layers "F.Cu" "B.Cu")
		(net "BMC_SSD_RST#5")
	)
	(via
		(at 66.247264 -180.386736)
		(size 0.7112)
		(drill 0.3556)
		(layers "F.Cu" "B.Cu")
		(net "BMC_SSD_RST#5")
	)
	(via
		(at 46.99 -173.863)
		(size 0.508)
		(drill 0.254)
		(layers "F.Cu" "B.Cu")
		(net "BMC_SSD_RST#5")
	)
	(segment
		(start 78.74127 -179.589938)
		(end 78.74127 -177.543206)
		(width 0.12065)
		(layer "B.Cu")
		(net "BMC_SSD_RST#5")
	)
	(segment
		(start 64.135 -191.389)
		(end 64.135 -182.499)
		(width 0.12065)
		(layer "B.Cu")
		(net "BMC_SSD_RST#5")
	)
	(segment
		(start 78.021434 -193.087752)
		(end 76.895706 -193.087752)
		(width 0.12065)
		(layer "B.Cu")
		(net "BMC_SSD_RST#5")
	)
	(segment
		(start 66.473324 -180.160676)
		(end 78.170532 -180.160676)
		(width 0.12065)
		(layer "B.Cu")
		(net "BMC_SSD_RST#5")
	)
	(segment
		(start 78.170532 -180.160676)
		(end 78.74127 -179.589938)
		(width 0.12065)
		(layer "B.Cu")
		(net "BMC_SSD_RST#5")
	)
	(segment
		(start 78.74127 -177.543206)
		(end 74.610214 -173.41215)
		(width 0.12065)
		(layer "B.Cu")
		(net "BMC_SSD_RST#5")
	)
	(segment
		(start 49.591722 -173.41215)
		(end 48.67402 -174.329852)
		(width 0.12065)
		(layer "B.Cu")
		(net "BMC_SSD_RST#5")
	)
	(segment
		(start 74.610214 -173.41215)
		(end 55.236618 -173.41215)
		(width 0.12065)
		(layer "B.Cu")
		(net "BMC_SSD_RST#5")
	)
	(segment
		(start 76.40066 -193.582798)
		(end 75.526392 -193.582798)
		(width 0.12065)
		(layer "B.Cu")
		(net "BMC_SSD_RST#5")
	)
	(segment
		(start 50.710338 -173.412658)
		(end 50.70983 -173.41215)
		(width 0.12065)
		(layer "B.Cu")
		(net "BMC_SSD_RST#5")
	)
	(segment
		(start 78.023212 -193.085974)
		(end 78.021434 -193.087752)
		(width 0.12065)
		(layer "B.Cu")
		(net "BMC_SSD_RST#5")
	)
	(segment
		(start 55.236618 -173.41215)
		(end 55.236364 -173.412404)
		(width 0.12065)
		(layer "B.Cu")
		(net "BMC_SSD_RST#5")
	)
	(segment
		(start 48.67402 -174.329852)
		(end 47.456852 -174.329852)
		(width 0.12065)
		(layer "B.Cu")
		(net "BMC_SSD_RST#5")
	)
	(segment
		(start 75.526392 -193.582798)
		(end 75.493118 -193.616072)
		(width 0.12065)
		(layer "B.Cu")
		(net "BMC_SSD_RST#5")
	)
	(segment
		(start 71.690992 -193.616072)
		(end 71.397114 -193.90995)
		(width 0.12065)
		(layer "B.Cu")
		(net "BMC_SSD_RST#5")
	)
	(segment
		(start 55.236364 -173.412404)
		(end 54.936644 -173.412404)
		(width 0.12065)
		(layer "B.Cu")
		(net "BMC_SSD_RST#5")
	)
	(segment
		(start 47.456852 -174.329852)
		(end 46.99 -173.863)
		(width 0.12065)
		(layer "B.Cu")
		(net "BMC_SSD_RST#5")
	)
	(segment
		(start 66.247264 -180.386736)
		(end 66.473324 -180.160676)
		(width 0.12065)
		(layer "B.Cu")
		(net "BMC_SSD_RST#5")
	)
	(segment
		(start 50.70983 -173.41215)
		(end 49.591722 -173.41215)
		(width 0.12065)
		(layer "B.Cu")
		(net "BMC_SSD_RST#5")
	)
	(segment
		(start 75.493118 -193.616072)
		(end 71.690992 -193.616072)
		(width 0.12065)
		(layer "B.Cu")
		(net "BMC_SSD_RST#5")
	)
	(segment
		(start 71.397114 -193.90995)
		(end 66.65595 -193.90995)
		(width 0.12065)
		(layer "B.Cu")
		(net "BMC_SSD_RST#5")
	)
	(segment
		(start 64.135 -182.499)
		(end 66.247264 -180.386736)
		(width 0.12065)
		(layer "B.Cu")
		(net "BMC_SSD_RST#5")
	)
	(segment
		(start 66.65595 -193.90995)
		(end 64.135 -191.389)
		(width 0.12065)
		(layer "B.Cu")
		(net "BMC_SSD_RST#5")
	)
	(segment
		(start 54.93639 -173.412658)
		(end 50.710338 -173.412658)
		(width 0.12065)
		(layer "B.Cu")
		(net "BMC_SSD_RST#5")
	)
	(segment
		(start 76.895706 -193.087752)
		(end 76.40066 -193.582798)
		(width 0.12065)
		(layer "B.Cu")
		(net "BMC_SSD_RST#5")
	)
	(segment
		(start 54.936644 -173.412404)
		(end 54.93639 -173.412658)
		(width 0.12065)
		(layer "B.Cu")
		(net "BMC_SSD_RST#5")
	)
	(segment
		(start 46.99 -173.228)
		(end 46.99 -173.863)
		(width 0.127)
		(layer "In5.Cu")
		(net "BMC_SSD_RST#5")
	)
	(segment
		(start 52.2478 -142.179802)
		(end 52.2478 -165.452044)
		(width 0.127)
		(layer "In5.Cu")
		(net "BMC_SSD_RST#5")
	)
	(segment
		(start 51.96078 -168.25722)
		(end 46.99 -173.228)
		(width 0.127)
		(layer "In5.Cu")
		(net "BMC_SSD_RST#5")
	)
	(segment
		(start 52.2478 -165.452044)
		(end 51.96078 -165.739064)
		(width 0.127)
		(layer "In5.Cu")
		(net "BMC_SSD_RST#5")
	)
	(segment
		(start 51.96078 -165.739064)
		(end 51.96078 -168.25722)
		(width 0.127)
		(layer "In5.Cu")
		(net "BMC_SSD_RST#5")
	)
	(segment
		(start 32.904938 -124.484892)
		(end 32.505142 -124.085096)
		(width 0.12065)
		(layer "F.Cu")
		(net "BMC_SSD_RST#7")
	)
	(via
		(at 10.1346 -172.2374)
		(size 0.508)
		(drill 0.254)
		(layers "F.Cu" "B.Cu")
		(net "BMC_SSD_RST#7")
	)
	(via
		(at 32.505142 -124.085096)
		(size 0.4572)
		(drill 0.2032)
		(layers "F.Cu" "B.Cu")
		(net "BMC_SSD_RST#7")
	)
	(via
		(at 83.396074 -179.916074)
		(size 0.7112)
		(drill 0.3556)
		(layers "F.Cu" "B.Cu")
		(net "BMC_SSD_RST#7")
	)
	(segment
		(start 10.6426 -171.7294)
		(end 17.150334 -171.7294)
		(width 0.12065)
		(layer "B.Cu")
		(net "BMC_SSD_RST#7")
	)
	(segment
		(start 17.150334 -171.7294)
		(end 17.283684 -171.59605)
		(width 0.12065)
		(layer "B.Cu")
		(net "BMC_SSD_RST#7")
	)
	(segment
		(start 54.035706 -171.240958)
		(end 54.03596 -171.240704)
		(width 0.12065)
		(layer "B.Cu")
		(net "BMC_SSD_RST#7")
	)
	(segment
		(start 52.234338 -171.24045)
		(end 52.234846 -171.240958)
		(width 0.12065)
		(layer "B.Cu")
		(net "BMC_SSD_RST#7")
	)
	(segment
		(start 52.234846 -171.240958)
		(end 54.035706 -171.240958)
		(width 0.12065)
		(layer "B.Cu")
		(net "BMC_SSD_RST#7")
	)
	(segment
		(start 85.069172 -181.589172)
		(end 83.396074 -179.916074)
		(width 0.12065)
		(layer "B.Cu")
		(net "BMC_SSD_RST#7")
	)
	(segment
		(start 10.1346 -172.2374)
		(end 10.6426 -171.7294)
		(width 0.12065)
		(layer "B.Cu")
		(net "BMC_SSD_RST#7")
	)
	(segment
		(start 82.804 -178.52644)
		(end 82.804 -179.324)
		(width 0.12065)
		(layer "B.Cu")
		(net "BMC_SSD_RST#7")
	)
	(segment
		(start 17.283684 -171.59605)
		(end 35.45459 -171.59605)
		(width 0.12065)
		(layer "B.Cu")
		(net "BMC_SSD_RST#7")
	)
	(segment
		(start 52.22494 -171.24045)
		(end 52.234338 -171.24045)
		(width 0.12065)
		(layer "B.Cu")
		(net "BMC_SSD_RST#7")
	)
	(segment
		(start 82.804 -179.324)
		(end 83.396074 -179.916074)
		(width 0.12065)
		(layer "B.Cu")
		(net "BMC_SSD_RST#7")
	)
	(segment
		(start 97.515172 -181.589172)
		(end 85.069172 -181.589172)
		(width 0.12065)
		(layer "B.Cu")
		(net "BMC_SSD_RST#7")
	)
	(segment
		(start 35.45459 -171.59605)
		(end 35.749738 -171.300902)
		(width 0.12065)
		(layer "B.Cu")
		(net "BMC_SSD_RST#7")
	)
	(segment
		(start 122.1105 -206.1845)
		(end 97.515172 -181.589172)
		(width 0.12065)
		(layer "B.Cu")
		(net "BMC_SSD_RST#7")
	)
	(segment
		(start 122.428 -206.1845)
		(end 122.1105 -206.1845)
		(width 0.12065)
		(layer "B.Cu")
		(net "BMC_SSD_RST#7")
	)
	(segment
		(start 47.592234 -171.300902)
		(end 48.163988 -170.729148)
		(width 0.12065)
		(layer "B.Cu")
		(net "BMC_SSD_RST#7")
	)
	(segment
		(start 54.03596 -171.240704)
		(end 54.33568 -171.240704)
		(width 0.12065)
		(layer "B.Cu")
		(net "BMC_SSD_RST#7")
	)
	(segment
		(start 75.51801 -171.24045)
		(end 82.804 -178.52644)
		(width 0.12065)
		(layer "B.Cu")
		(net "BMC_SSD_RST#7")
	)
	(segment
		(start 54.335934 -171.24045)
		(end 75.51801 -171.24045)
		(width 0.12065)
		(layer "B.Cu")
		(net "BMC_SSD_RST#7")
	)
	(segment
		(start 35.749738 -171.300902)
		(end 47.592234 -171.300902)
		(width 0.12065)
		(layer "B.Cu")
		(net "BMC_SSD_RST#7")
	)
	(segment
		(start 48.163988 -170.729148)
		(end 51.713638 -170.729148)
		(width 0.12065)
		(layer "B.Cu")
		(net "BMC_SSD_RST#7")
	)
	(segment
		(start 51.713638 -170.729148)
		(end 52.22494 -171.24045)
		(width 0.12065)
		(layer "B.Cu")
		(net "BMC_SSD_RST#7")
	)
	(segment
		(start 54.33568 -171.240704)
		(end 54.335934 -171.24045)
		(width 0.12065)
		(layer "B.Cu")
		(net "BMC_SSD_RST#7")
	)
	(segment
		(start 10.1981 -170.273472)
		(end 10.1346 -170.336972)
		(width 0.127)
		(layer "In5.Cu")
		(net "BMC_SSD_RST#7")
	)
	(segment
		(start 17.559274 -129.995168)
		(end 14.342872 -129.995168)
		(width 0.127)
		(layer "In5.Cu")
		(net "BMC_SSD_RST#7")
	)
	(segment
		(start 17.942306 -130.3782)
		(end 17.559274 -129.995168)
		(width 0.127)
		(layer "In5.Cu")
		(net "BMC_SSD_RST#7")
	)
	(segment
		(start 32.111188 -123.691142)
		(end 29.802074 -123.691142)
		(width 0.127)
		(layer "In5.Cu")
		(net "BMC_SSD_RST#7")
	)
	(segment
		(start 29.802074 -123.691142)
		(end 23.419816 -130.0734)
		(width 0.127)
		(layer "In5.Cu")
		(net "BMC_SSD_RST#7")
	)
	(segment
		(start 10.1346 -170.336972)
		(end 10.1346 -172.2374)
		(width 0.127)
		(layer "In5.Cu")
		(net "BMC_SSD_RST#7")
	)
	(segment
		(start 32.505142 -124.085096)
		(end 32.111188 -123.691142)
		(width 0.127)
		(layer "In5.Cu")
		(net "BMC_SSD_RST#7")
	)
	(segment
		(start 23.419816 -130.0734)
		(end 23.114762 -130.3782)
		(width 0.127)
		(layer "In5.Cu")
		(net "BMC_SSD_RST#7")
	)
	(segment
		(start 10.1981 -134.13994)
		(end 10.1981 -170.273472)
		(width 0.127)
		(layer "In5.Cu")
		(net "BMC_SSD_RST#7")
	)
	(segment
		(start 23.114762 -130.3782)
		(end 17.942306 -130.3782)
		(width 0.127)
		(layer "In5.Cu")
		(net "BMC_SSD_RST#7")
	)
	(segment
		(start 14.342872 -129.995168)
		(end 10.1981 -134.13994)
		(width 0.127)
		(layer "In5.Cu")
		(net "BMC_SSD_RST#7")
	)
	(segment
		(start 31.304738 -122.084846)
		(end 31.304738 -121.652538)
		(width 0.12065)
		(layer "F.Cu")
		(net "BMC_SSD_RST#9")
	)
	(segment
		(start 31.304738 -121.652538)
		(end 31.1658 -121.5136)
		(width 0.12065)
		(layer "F.Cu")
		(net "BMC_SSD_RST#9")
	)
	(via
		(at 329.111356 -182.045356)
		(size 0.7112)
		(drill 0.3556)
		(layers "F.Cu" "B.Cu")
		(net "BMC_SSD_RST#9")
	)
	(via
		(at 31.1658 -121.5136)
		(size 0.4572)
		(drill 0.2032)
		(layers "F.Cu" "B.Cu")
		(net "BMC_SSD_RST#9")
	)
	(via
		(at 8.763 -169.291)
		(size 0.508)
		(drill 0.254)
		(layers "F.Cu" "B.Cu")
		(net "BMC_SSD_RST#9")
	)
	(segment
		(start 34.440114 -168.00195)
		(end 10.05205 -168.00195)
		(width 0.12065)
		(layer "B.Cu")
		(net "BMC_SSD_RST#9")
	)
	(segment
		(start 335.71053 -165.14953)
		(end 323.186298 -152.625298)
		(width 0.12065)
		(layer "B.Cu")
		(net "BMC_SSD_RST#9")
	)
	(segment
		(start 323.186298 -152.625298)
		(end 225.052382 -152.625298)
		(width 0.12065)
		(layer "B.Cu")
		(net "BMC_SSD_RST#9")
	)
	(segment
		(start 334.264 -182.813198)
		(end 332.523592 -182.813198)
		(width 0.12065)
		(layer "B.Cu")
		(net "BMC_SSD_RST#9")
	)
	(segment
		(start 53.58003 -167.4749)
		(end 53.214778 -167.109648)
		(width 0.12065)
		(layer "B.Cu")
		(net "BMC_SSD_RST#9")
	)
	(segment
		(start 334.794098 -182.2831)
		(end 334.264 -182.813198)
		(width 0.12065)
		(layer "B.Cu")
		(net "BMC_SSD_RST#9")
	)
	(segment
		(start 332.523592 -182.813198)
		(end 332.463394 -182.753)
		(width 0.12065)
		(layer "B.Cu")
		(net "BMC_SSD_RST#9")
	)
	(segment
		(start 329.111356 -182.045356)
		(end 328.403966 -181.337966)
		(width 0.12065)
		(layer "B.Cu")
		(net "BMC_SSD_RST#9")
	)
	(segment
		(start 10.05205 -168.00195)
		(end 8.763 -169.291)
		(width 0.12065)
		(layer "B.Cu")
		(net "BMC_SSD_RST#9")
	)
	(segment
		(start 336.7786 -182.2831)
		(end 334.794098 -182.2831)
		(width 0.12065)
		(layer "B.Cu")
		(net "BMC_SSD_RST#9")
	)
	(segment
		(start 335.71053 -169.149522)
		(end 335.71053 -165.14953)
		(width 0.12065)
		(layer "B.Cu")
		(net "BMC_SSD_RST#9")
	)
	(segment
		(start 210.20278 -167.4749)
		(end 53.58003 -167.4749)
		(width 0.12065)
		(layer "B.Cu")
		(net "BMC_SSD_RST#9")
	)
	(segment
		(start 330.05141 -169.846752)
		(end 335.0133 -169.846752)
		(width 0.12065)
		(layer "B.Cu")
		(net "BMC_SSD_RST#9")
	)
	(segment
		(start 35.332416 -167.109648)
		(end 34.440114 -168.00195)
		(width 0.12065)
		(layer "B.Cu")
		(net "BMC_SSD_RST#9")
	)
	(segment
		(start 335.0133 -169.846752)
		(end 335.71053 -169.149522)
		(width 0.12065)
		(layer "B.Cu")
		(net "BMC_SSD_RST#9")
	)
	(segment
		(start 53.214778 -167.109648)
		(end 35.332416 -167.109648)
		(width 0.12065)
		(layer "B.Cu")
		(net "BMC_SSD_RST#9")
	)
	(segment
		(start 225.052382 -152.625298)
		(end 210.20278 -167.4749)
		(width 0.12065)
		(layer "B.Cu")
		(net "BMC_SSD_RST#9")
	)
	(segment
		(start 328.403966 -181.337966)
		(end 328.403966 -171.494196)
		(width 0.12065)
		(layer "B.Cu")
		(net "BMC_SSD_RST#9")
	)
	(segment
		(start 329.819 -182.753)
		(end 329.111356 -182.045356)
		(width 0.12065)
		(layer "B.Cu")
		(net "BMC_SSD_RST#9")
	)
	(segment
		(start 332.463394 -182.753)
		(end 329.819 -182.753)
		(width 0.12065)
		(layer "B.Cu")
		(net "BMC_SSD_RST#9")
	)
	(segment
		(start 328.403966 -171.494196)
		(end 330.05141 -169.846752)
		(width 0.12065)
		(layer "B.Cu")
		(net "BMC_SSD_RST#9")
	)
	(segment
		(start 17.311116 -128.651254)
		(end 18.135854 -128.651254)
		(width 0.127)
		(layer "In5.Cu")
		(net "BMC_SSD_RST#9")
	)
	(segment
		(start 14.839696 -127.88138)
		(end 16.541242 -127.88138)
		(width 0.127)
		(layer "In5.Cu")
		(net "BMC_SSD_RST#9")
	)
	(segment
		(start 8.763 -167.951658)
		(end 9.0551 -167.659558)
		(width 0.127)
		(layer "In5.Cu")
		(net "BMC_SSD_RST#9")
	)
	(segment
		(start 8.763 -169.291)
		(end 8.763 -167.951658)
		(width 0.127)
		(layer "In5.Cu")
		(net "BMC_SSD_RST#9")
	)
	(segment
		(start 29.7942 -121.5136)
		(end 31.1658 -121.5136)
		(width 0.127)
		(layer "In5.Cu")
		(net "BMC_SSD_RST#9")
	)
	(segment
		(start 18.597372 -129.112772)
		(end 22.195028 -129.112772)
		(width 0.127)
		(layer "In5.Cu")
		(net "BMC_SSD_RST#9")
	)
	(segment
		(start 18.135854 -128.651254)
		(end 18.597372 -129.112772)
		(width 0.127)
		(layer "In5.Cu")
		(net "BMC_SSD_RST#9")
	)
	(segment
		(start 22.195028 -129.112772)
		(end 29.7942 -121.5136)
		(width 0.127)
		(layer "In5.Cu")
		(net "BMC_SSD_RST#9")
	)
	(segment
		(start 16.541242 -127.88138)
		(end 17.311116 -128.651254)
		(width 0.127)
		(layer "In5.Cu")
		(net "BMC_SSD_RST#9")
	)
	(segment
		(start 9.0551 -133.665976)
		(end 14.839696 -127.88138)
		(width 0.127)
		(layer "In5.Cu")
		(net "BMC_SSD_RST#9")
	)
	(segment
		(start 9.0551 -167.659558)
		(end 9.0551 -133.665976)
		(width 0.127)
		(layer "In5.Cu")
		(net "BMC_SSD_RST#9")
	)
	(segment
		(start 32.104838 -122.601228)
		(end 31.739586 -122.235976)
		(width 0.12065)
		(layer "F.Cu")
		(net "BMC_SSD_RST#8")
	)
	(segment
		(start 31.739586 -122.235976)
		(end 31.739586 -121.503186)
		(width 0.12065)
		(layer "F.Cu")
		(net "BMC_SSD_RST#8")
	)
	(segment
		(start 31.739586 -121.503186)
		(end 31.1658 -120.9294)
		(width 0.12065)
		(layer "F.Cu")
		(net "BMC_SSD_RST#8")
	)
	(segment
		(start 32.104838 -122.884946)
		(end 32.104838 -122.601228)
		(width 0.12065)
		(layer "F.Cu")
		(net "BMC_SSD_RST#8")
	)
	(via
		(at 9.084564 -170.987212)
		(size 0.508)
		(drill 0.254)
		(layers "F.Cu" "B.Cu")
		(net "BMC_SSD_RST#8")
	)
	(via
		(at 31.1658 -120.9294)
		(size 0.4572)
		(drill 0.2032)
		(layers "F.Cu" "B.Cu")
		(net "BMC_SSD_RST#8")
	)
	(via
		(at 205.380336 -197.252336)
		(size 0.7112)
		(drill 0.3556)
		(layers "F.Cu" "B.Cu")
		(net "BMC_SSD_RST#8")
	)
	(segment
		(start 223.1644 -200.3425)
		(end 222.684848 -200.3425)
		(width 0.12065)
		(layer "B.Cu")
		(net "BMC_SSD_RST#8")
	)
	(segment
		(start 15.42669 -170.814746)
		(end 15.426944 -170.815)
		(width 0.12065)
		(layer "B.Cu")
		(net "BMC_SSD_RST#8")
	)
	(segment
		(start 219.462096 -200.96988)
		(end 219.029534 -201.402442)
		(width 0.12065)
		(layer "B.Cu")
		(net "BMC_SSD_RST#8")
	)
	(segment
		(start 14.8844 -171.0055)
		(end 15.0749 -170.815)
		(width 0.12065)
		(layer "B.Cu")
		(net "BMC_SSD_RST#8")
	)
	(segment
		(start 15.0749 -170.815)
		(end 15.126716 -170.815)
		(width 0.12065)
		(layer "B.Cu")
		(net "BMC_SSD_RST#8")
	)
	(segment
		(start 54.035706 -170.51655)
		(end 79.229712 -170.51655)
		(width 0.12065)
		(layer "B.Cu")
		(net "BMC_SSD_RST#8")
	)
	(segment
		(start 47.86376 -170.005248)
		(end 52.013866 -170.005248)
		(width 0.12065)
		(layer "B.Cu")
		(net "BMC_SSD_RST#8")
	)
	(segment
		(start 86.764114 -178.050952)
		(end 90.49512 -178.050952)
		(width 0.12065)
		(layer "B.Cu")
		(net "BMC_SSD_RST#8")
	)
	(segment
		(start 118.118636 -176.8983)
		(end 130.945382 -189.725046)
		(width 0.12065)
		(layer "B.Cu")
		(net "BMC_SSD_RST#8")
	)
	(segment
		(start 79.229712 -170.51655)
		(end 86.764114 -178.050952)
		(width 0.12065)
		(layer "B.Cu")
		(net "BMC_SSD_RST#8")
	)
	(segment
		(start 15.12697 -170.814746)
		(end 15.42669 -170.814746)
		(width 0.12065)
		(layer "B.Cu")
		(net "BMC_SSD_RST#8")
	)
	(segment
		(start 209.530442 -201.402442)
		(end 205.380336 -197.252336)
		(width 0.12065)
		(layer "B.Cu")
		(net "BMC_SSD_RST#8")
	)
	(segment
		(start 9.084564 -170.987212)
		(end 9.219692 -171.12234)
		(width 0.12065)
		(layer "B.Cu")
		(net "BMC_SSD_RST#8")
	)
	(segment
		(start 10.225532 -171.12234)
		(end 10.342372 -171.0055)
		(width 0.12065)
		(layer "B.Cu")
		(net "BMC_SSD_RST#8")
	)
	(segment
		(start 52.525168 -170.51655)
		(end 52.534566 -170.51655)
		(width 0.12065)
		(layer "B.Cu")
		(net "BMC_SSD_RST#8")
	)
	(segment
		(start 10.342372 -171.0055)
		(end 14.8844 -171.0055)
		(width 0.12065)
		(layer "B.Cu")
		(net "BMC_SSD_RST#8")
	)
	(segment
		(start 197.853046 -189.725046)
		(end 205.380336 -197.252336)
		(width 0.12065)
		(layer "B.Cu")
		(net "BMC_SSD_RST#8")
	)
	(segment
		(start 9.219692 -171.12234)
		(end 10.225532 -171.12234)
		(width 0.12065)
		(layer "B.Cu")
		(net "BMC_SSD_RST#8")
	)
	(segment
		(start 91.647772 -176.8983)
		(end 118.118636 -176.8983)
		(width 0.12065)
		(layer "B.Cu")
		(net "BMC_SSD_RST#8")
	)
	(segment
		(start 90.49512 -178.050952)
		(end 91.647772 -176.8983)
		(width 0.12065)
		(layer "B.Cu")
		(net "BMC_SSD_RST#8")
	)
	(segment
		(start 15.426944 -170.815)
		(end 35.211512 -170.815)
		(width 0.12065)
		(layer "B.Cu")
		(net "BMC_SSD_RST#8")
	)
	(segment
		(start 54.035452 -170.516804)
		(end 54.035706 -170.51655)
		(width 0.12065)
		(layer "B.Cu")
		(net "BMC_SSD_RST#8")
	)
	(segment
		(start 222.684848 -200.3425)
		(end 222.057468 -200.96988)
		(width 0.12065)
		(layer "B.Cu")
		(net "BMC_SSD_RST#8")
	)
	(segment
		(start 52.535074 -170.517058)
		(end 53.735478 -170.517058)
		(width 0.12065)
		(layer "B.Cu")
		(net "BMC_SSD_RST#8")
	)
	(segment
		(start 47.581058 -170.28795)
		(end 47.86376 -170.005248)
		(width 0.12065)
		(layer "B.Cu")
		(net "BMC_SSD_RST#8")
	)
	(segment
		(start 35.211512 -170.815)
		(end 35.738562 -170.28795)
		(width 0.12065)
		(layer "B.Cu")
		(net "BMC_SSD_RST#8")
	)
	(segment
		(start 53.735732 -170.516804)
		(end 54.035452 -170.516804)
		(width 0.12065)
		(layer "B.Cu")
		(net "BMC_SSD_RST#8")
	)
	(segment
		(start 53.735478 -170.517058)
		(end 53.735732 -170.516804)
		(width 0.12065)
		(layer "B.Cu")
		(net "BMC_SSD_RST#8")
	)
	(segment
		(start 222.057468 -200.96988)
		(end 219.462096 -200.96988)
		(width 0.12065)
		(layer "B.Cu")
		(net "BMC_SSD_RST#8")
	)
	(segment
		(start 219.029534 -201.402442)
		(end 209.530442 -201.402442)
		(width 0.12065)
		(layer "B.Cu")
		(net "BMC_SSD_RST#8")
	)
	(segment
		(start 15.126716 -170.815)
		(end 15.12697 -170.814746)
		(width 0.12065)
		(layer "B.Cu")
		(net "BMC_SSD_RST#8")
	)
	(segment
		(start 35.738562 -170.28795)
		(end 47.581058 -170.28795)
		(width 0.12065)
		(layer "B.Cu")
		(net "BMC_SSD_RST#8")
	)
	(segment
		(start 52.013866 -170.005248)
		(end 52.525168 -170.51655)
		(width 0.12065)
		(layer "B.Cu")
		(net "BMC_SSD_RST#8")
	)
	(segment
		(start 130.945382 -189.725046)
		(end 197.853046 -189.725046)
		(width 0.12065)
		(layer "B.Cu")
		(net "BMC_SSD_RST#8")
	)
	(segment
		(start 52.534566 -170.51655)
		(end 52.535074 -170.517058)
		(width 0.12065)
		(layer "B.Cu")
		(net "BMC_SSD_RST#8")
	)
	(segment
		(start 31.1658 -120.9294)
		(end 31.115254 -120.979946)
		(width 0.127)
		(layer "In5.Cu")
		(net "BMC_SSD_RST#8")
	)
	(segment
		(start 28.600654 -120.979946)
		(end 21.4757 -128.1049)
		(width 0.127)
		(layer "In5.Cu")
		(net "BMC_SSD_RST#8")
	)
	(segment
		(start 31.115254 -120.979946)
		(end 28.600654 -120.979946)
		(width 0.127)
		(layer "In5.Cu")
		(net "BMC_SSD_RST#8")
	)
	(segment
		(start 8.6741 -133.507988)
		(end 8.6741 -167.50157)
		(width 0.127)
		(layer "In5.Cu")
		(net "BMC_SSD_RST#8")
	)
	(segment
		(start 16.715994 -127.50038)
		(end 14.681708 -127.50038)
		(width 0.127)
		(layer "In5.Cu")
		(net "BMC_SSD_RST#8")
	)
	(segment
		(start 17.320514 -128.1049)
		(end 16.715994 -127.50038)
		(width 0.127)
		(layer "In5.Cu")
		(net "BMC_SSD_RST#8")
	)
	(segment
		(start 8.2931 -170.195748)
		(end 9.084564 -170.987212)
		(width 0.127)
		(layer "In5.Cu")
		(net "BMC_SSD_RST#8")
	)
	(segment
		(start 8.6741 -167.50157)
		(end 8.2931 -167.88257)
		(width 0.127)
		(layer "In5.Cu")
		(net "BMC_SSD_RST#8")
	)
	(segment
		(start 21.4757 -128.1049)
		(end 17.320514 -128.1049)
		(width 0.127)
		(layer "In5.Cu")
		(net "BMC_SSD_RST#8")
	)
	(segment
		(start 14.681708 -127.50038)
		(end 8.6741 -133.507988)
		(width 0.127)
		(layer "In5.Cu")
		(net "BMC_SSD_RST#8")
	)
	(segment
		(start 8.2931 -167.88257)
		(end 8.2931 -170.195748)
		(width 0.127)
		(layer "In5.Cu")
		(net "BMC_SSD_RST#8")
	)
	(segment
		(start 44.904914 -136.484868)
		(end 45.30471 -136.085072)
		(width 0.12065)
		(layer "F.Cu")
		(net "BMC_SSD_RST#3")
	)
	(via
		(at 45.30471 -136.085072)
		(size 0.4572)
		(drill 0.2032)
		(layers "F.Cu" "B.Cu")
		(net "BMC_SSD_RST#3")
	)
	(via
		(at 41.7576 -169.7482)
		(size 0.508)
		(drill 0.254)
		(layers "F.Cu" "B.Cu")
		(net "BMC_SSD_RST#3")
	)
	(via
		(at 207.62087 -198.09587)
		(size 0.7112)
		(drill 0.3556)
		(layers "F.Cu" "B.Cu")
		(net "BMC_SSD_RST#3")
	)
	(segment
		(start 52.16398 -169.643298)
		(end 41.862502 -169.643298)
		(width 0.12065)
		(layer "B.Cu")
		(net "BMC_SSD_RST#3")
	)
	(segment
		(start 207.62087 -198.09587)
		(end 210.565492 -201.040492)
		(width 0.12065)
		(layer "B.Cu")
		(net "BMC_SSD_RST#3")
	)
	(segment
		(start 86.914228 -177.689002)
		(end 79.379826 -170.1546)
		(width 0.12065)
		(layer "B.Cu")
		(net "BMC_SSD_RST#3")
	)
	(segment
		(start 53.885338 -170.154854)
		(end 53.585618 -170.154854)
		(width 0.12065)
		(layer "B.Cu")
		(net "BMC_SSD_RST#3")
	)
	(segment
		(start 52.685188 -170.155108)
		(end 52.68468 -170.1546)
		(width 0.12065)
		(layer "B.Cu")
		(net "BMC_SSD_RST#3")
	)
	(segment
		(start 53.585364 -170.155108)
		(end 52.685188 -170.155108)
		(width 0.12065)
		(layer "B.Cu")
		(net "BMC_SSD_RST#3")
	)
	(segment
		(start 130.613404 -188.881004)
		(end 118.26875 -176.53635)
		(width 0.12065)
		(layer "B.Cu")
		(net "BMC_SSD_RST#3")
	)
	(segment
		(start 41.862502 -169.643298)
		(end 41.7576 -169.7482)
		(width 0.12065)
		(layer "B.Cu")
		(net "BMC_SSD_RST#3")
	)
	(segment
		(start 79.379826 -170.1546)
		(end 53.885592 -170.1546)
		(width 0.12065)
		(layer "B.Cu")
		(net "BMC_SSD_RST#3")
	)
	(segment
		(start 53.585618 -170.154854)
		(end 53.585364 -170.155108)
		(width 0.12065)
		(layer "B.Cu")
		(net "BMC_SSD_RST#3")
	)
	(segment
		(start 52.68468 -170.1546)
		(end 52.675282 -170.1546)
		(width 0.12065)
		(layer "B.Cu")
		(net "BMC_SSD_RST#3")
	)
	(segment
		(start 91.497658 -176.53635)
		(end 90.345006 -177.689002)
		(width 0.12065)
		(layer "B.Cu")
		(net "BMC_SSD_RST#3")
	)
	(segment
		(start 198.406004 -188.881004)
		(end 130.613404 -188.881004)
		(width 0.12065)
		(layer "B.Cu")
		(net "BMC_SSD_RST#3")
	)
	(segment
		(start 90.345006 -177.689002)
		(end 86.914228 -177.689002)
		(width 0.12065)
		(layer "B.Cu")
		(net "BMC_SSD_RST#3")
	)
	(segment
		(start 207.62087 -198.09587)
		(end 198.406004 -188.881004)
		(width 0.12065)
		(layer "B.Cu")
		(net "BMC_SSD_RST#3")
	)
	(segment
		(start 216.893648 -201.040492)
		(end 217.21826 -200.71588)
		(width 0.12065)
		(layer "B.Cu")
		(net "BMC_SSD_RST#3")
	)
	(segment
		(start 210.565492 -201.040492)
		(end 216.893648 -201.040492)
		(width 0.12065)
		(layer "B.Cu")
		(net "BMC_SSD_RST#3")
	)
	(segment
		(start 52.675282 -170.1546)
		(end 52.16398 -169.643298)
		(width 0.12065)
		(layer "B.Cu")
		(net "BMC_SSD_RST#3")
	)
	(segment
		(start 53.885592 -170.1546)
		(end 53.885338 -170.154854)
		(width 0.12065)
		(layer "B.Cu")
		(net "BMC_SSD_RST#3")
	)
	(segment
		(start 118.26875 -176.53635)
		(end 91.497658 -176.53635)
		(width 0.12065)
		(layer "B.Cu")
		(net "BMC_SSD_RST#3")
	)
	(segment
		(start 45.30471 -137.93851)
		(end 45.30471 -136.085072)
		(width 0.127)
		(layer "In5.Cu")
		(net "BMC_SSD_RST#3")
	)
	(segment
		(start 41.7576 -169.7482)
		(end 45.451268 -166.054532)
		(width 0.127)
		(layer "In5.Cu")
		(net "BMC_SSD_RST#3")
	)
	(segment
		(start 45.451268 -166.054532)
		(end 45.451268 -138.085068)
		(width 0.127)
		(layer "In5.Cu")
		(net "BMC_SSD_RST#3")
	)
	(segment
		(start 45.451268 -138.085068)
		(end 45.30471 -137.93851)
		(width 0.127)
		(layer "In5.Cu")
		(net "BMC_SSD_RST#3")
	)
	(segment
		(start 51.630834 -140.843)
		(end 51.675538 -140.887704)
		(width 0.12065)
		(layer "F.Cu")
		(net "BMC_SSD_RST#4")
	)
	(segment
		(start 50.156364 -140.843)
		(end 51.630834 -140.843)
		(width 0.12065)
		(layer "F.Cu")
		(net "BMC_SSD_RST#4")
	)
	(segment
		(start 46.361604 -137.694162)
		(end 47.007526 -137.694162)
		(width 0.12065)
		(layer "F.Cu")
		(net "BMC_SSD_RST#4")
	)
	(segment
		(start 45.70476 -137.284968)
		(end 45.95241 -137.284968)
		(width 0.12065)
		(layer "F.Cu")
		(net "BMC_SSD_RST#4")
	)
	(segment
		(start 51.675538 -140.887704)
		(end 51.675538 -140.889736)
		(width 0.12065)
		(layer "F.Cu")
		(net "BMC_SSD_RST#4")
	)
	(segment
		(start 45.95241 -137.284968)
		(end 46.361604 -137.694162)
		(width 0.12065)
		(layer "F.Cu")
		(net "BMC_SSD_RST#4")
	)
	(segment
		(start 51.675538 -140.889736)
		(end 51.639216 -140.889736)
		(width 0.12065)
		(layer "F.Cu")
		(net "BMC_SSD_RST#4")
	)
	(segment
		(start 47.007526 -137.694162)
		(end 50.156364 -140.843)
		(width 0.12065)
		(layer "F.Cu")
		(net "BMC_SSD_RST#4")
	)
	(via
		(at 333.863188 -162.159188)
		(size 0.7112)
		(drill 0.3556)
		(layers "F.Cu" "B.Cu")
		(net "BMC_SSD_RST#4")
	)
	(via
		(at 51.639216 -140.889736)
		(size 0.508)
		(drill 0.254)
		(layers "F.Cu" "B.Cu")
		(net "BMC_SSD_RST#4")
	)
	(via
		(at 52.565808 -166.46398)
		(size 0.508)
		(drill 0.254)
		(layers "F.Cu" "B.Cu")
		(net "BMC_SSD_RST#4")
	)
	(segment
		(start 330.043028 -170.367198)
		(end 335.004918 -170.367198)
		(width 0.12065)
		(layer "B.Cu")
		(net "BMC_SSD_RST#4")
	)
	(segment
		(start 323.967348 -152.263348)
		(end 333.863188 -162.159188)
		(width 0.12065)
		(layer "B.Cu")
		(net "BMC_SSD_RST#4")
	)
	(segment
		(start 335.004918 -170.367198)
		(end 336.07248 -169.299636)
		(width 0.12065)
		(layer "B.Cu")
		(net "BMC_SSD_RST#4")
	)
	(segment
		(start 210.052666 -167.11295)
		(end 224.902268 -152.263348)
		(width 0.12065)
		(layer "B.Cu")
		(net "BMC_SSD_RST#4")
	)
	(segment
		(start 336.07248 -164.36848)
		(end 333.863188 -162.159188)
		(width 0.12065)
		(layer "B.Cu")
		(net "BMC_SSD_RST#4")
	)
	(segment
		(start 52.608988 -166.4208)
		(end 55.06593 -166.4208)
		(width 0.12065)
		(layer "B.Cu")
		(net "BMC_SSD_RST#4")
	)
	(segment
		(start 329.692 -180.5305)
		(end 328.765916 -179.604416)
		(width 0.12065)
		(layer "B.Cu")
		(net "BMC_SSD_RST#4")
	)
	(segment
		(start 224.902268 -152.263348)
		(end 323.967348 -152.263348)
		(width 0.12065)
		(layer "B.Cu")
		(net "BMC_SSD_RST#4")
	)
	(segment
		(start 55.06593 -166.4208)
		(end 55.75808 -167.11295)
		(width 0.12065)
		(layer "B.Cu")
		(net "BMC_SSD_RST#4")
	)
	(segment
		(start 328.765916 -179.604416)
		(end 328.765916 -171.64431)
		(width 0.12065)
		(layer "B.Cu")
		(net "BMC_SSD_RST#4")
	)
	(segment
		(start 52.565808 -166.46398)
		(end 52.608988 -166.4208)
		(width 0.12065)
		(layer "B.Cu")
		(net "BMC_SSD_RST#4")
	)
	(segment
		(start 336.07248 -169.299636)
		(end 336.07248 -164.36848)
		(width 0.12065)
		(layer "B.Cu")
		(net "BMC_SSD_RST#4")
	)
	(segment
		(start 328.765916 -171.64431)
		(end 330.043028 -170.367198)
		(width 0.12065)
		(layer "B.Cu")
		(net "BMC_SSD_RST#4")
	)
	(segment
		(start 55.75808 -167.11295)
		(end 210.052666 -167.11295)
		(width 0.12065)
		(layer "B.Cu")
		(net "BMC_SSD_RST#4")
	)
	(segment
		(start 52.565808 -166.46398)
		(end 52.601114 -166.46398)
		(width 0.127)
		(layer "In5.Cu")
		(net "BMC_SSD_RST#4")
	)
	(segment
		(start 52.728114 -165.71214)
		(end 52.728368 -165.711886)
		(width 0.127)
		(layer "In5.Cu")
		(net "BMC_SSD_RST#4")
	)
	(segment
		(start 51.675538 -140.880338)
		(end 51.675538 -140.889736)
		(width 0.127)
		(layer "In5.Cu")
		(net "BMC_SSD_RST#4")
	)
	(segment
		(start 52.728368 -165.711886)
		(end 52.728368 -141.933168)
		(width 0.127)
		(layer "In5.Cu")
		(net "BMC_SSD_RST#4")
	)
	(segment
		(start 52.601114 -166.46398)
		(end 52.728114 -166.337234)
		(width 0.127)
		(layer "In5.Cu")
		(net "BMC_SSD_RST#4")
	)
	(segment
		(start 51.675538 -140.889736)
		(end 51.639216 -140.889736)
		(width 0.127)
		(layer "In5.Cu")
		(net "BMC_SSD_RST#4")
	)
	(segment
		(start 52.728114 -166.337234)
		(end 52.728114 -165.71214)
		(width 0.127)
		(layer "In5.Cu")
		(net "BMC_SSD_RST#4")
	)
	(segment
		(start 52.728368 -141.933168)
		(end 51.675538 -140.880338)
		(width 0.127)
		(layer "In5.Cu")
		(net "BMC_SSD_RST#4")
	)
	(segment
		(start 44.104814 -135.684768)
		(end 44.50461 -135.284972)
		(width 0.12065)
		(layer "F.Cu")
		(net "BMC_SSD_RST#2")
	)
	(via
		(at 44.50461 -135.284972)
		(size 0.4572)
		(drill 0.2032)
		(layers "F.Cu" "B.Cu")
		(net "BMC_SSD_RST#2")
	)
	(via
		(at 81.661 -179.451)
		(size 0.7112)
		(drill 0.3556)
		(layers "F.Cu" "B.Cu")
		(net "BMC_SSD_RST#2")
	)
	(via
		(at 43.5102 -172.2882)
		(size 0.508)
		(drill 0.254)
		(layers "F.Cu" "B.Cu")
		(net "BMC_SSD_RST#2")
	)
	(segment
		(start 80.18907 -176.943258)
		(end 80.18907 -176.94275)
		(width 0.12065)
		(layer "B.Cu")
		(net "BMC_SSD_RST#2")
	)
	(segment
		(start 125.894592 -206.816198)
		(end 125.55474 -207.15605)
		(width 0.12065)
		(layer "B.Cu")
		(net "BMC_SSD_RST#2")
	)
	(segment
		(start 75.21067 -171.96435)
		(end 54.636162 -171.96435)
		(width 0.12065)
		(layer "B.Cu")
		(net "BMC_SSD_RST#2")
	)
	(segment
		(start 54.335934 -171.964858)
		(end 51.310794 -171.964858)
		(width 0.12065)
		(layer "B.Cu")
		(net "BMC_SSD_RST#2")
	)
	(segment
		(start 44.995338 -171.7548)
		(end 44.0436 -171.7548)
		(width 0.12065)
		(layer "B.Cu")
		(net "BMC_SSD_RST#2")
	)
	(segment
		(start 54.336188 -171.964604)
		(end 54.335934 -171.964858)
		(width 0.12065)
		(layer "B.Cu")
		(net "BMC_SSD_RST#2")
	)
	(segment
		(start 80.18907 -176.94275)
		(end 75.21067 -171.96435)
		(width 0.12065)
		(layer "B.Cu")
		(net "BMC_SSD_RST#2")
	)
	(segment
		(start 51.310286 -171.96435)
		(end 45.204888 -171.96435)
		(width 0.12065)
		(layer "B.Cu")
		(net "BMC_SSD_RST#2")
	)
	(segment
		(start 54.636162 -171.96435)
		(end 54.635908 -171.964604)
		(width 0.12065)
		(layer "B.Cu")
		(net "BMC_SSD_RST#2")
	)
	(segment
		(start 81.661 -179.451)
		(end 81.661 -178.415188)
		(width 0.12065)
		(layer "B.Cu")
		(net "BMC_SSD_RST#2")
	)
	(segment
		(start 132.125212 -206.293974)
		(end 131.267962 -206.293974)
		(width 0.12065)
		(layer "B.Cu")
		(net "BMC_SSD_RST#2")
	)
	(segment
		(start 81.661 -178.415188)
		(end 80.18907 -176.943258)
		(width 0.12065)
		(layer "B.Cu")
		(net "BMC_SSD_RST#2")
	)
	(segment
		(start 44.0436 -171.7548)
		(end 43.5102 -172.2882)
		(width 0.12065)
		(layer "B.Cu")
		(net "BMC_SSD_RST#2")
	)
	(segment
		(start 122.057922 -207.15605)
		(end 97.214944 -182.313072)
		(width 0.12065)
		(layer "B.Cu")
		(net "BMC_SSD_RST#2")
	)
	(segment
		(start 130.745738 -206.816198)
		(end 125.894592 -206.816198)
		(width 0.12065)
		(layer "B.Cu")
		(net "BMC_SSD_RST#2")
	)
	(segment
		(start 83.498944 -182.313072)
		(end 81.661 -180.475128)
		(width 0.12065)
		(layer "B.Cu")
		(net "BMC_SSD_RST#2")
	)
	(segment
		(start 54.635908 -171.964604)
		(end 54.336188 -171.964604)
		(width 0.12065)
		(layer "B.Cu")
		(net "BMC_SSD_RST#2")
	)
	(segment
		(start 125.55474 -207.15605)
		(end 122.057922 -207.15605)
		(width 0.12065)
		(layer "B.Cu")
		(net "BMC_SSD_RST#2")
	)
	(segment
		(start 131.267962 -206.293974)
		(end 130.745738 -206.816198)
		(width 0.12065)
		(layer "B.Cu")
		(net "BMC_SSD_RST#2")
	)
	(segment
		(start 51.310794 -171.964858)
		(end 51.310286 -171.96435)
		(width 0.12065)
		(layer "B.Cu")
		(net "BMC_SSD_RST#2")
	)
	(segment
		(start 81.661 -180.475128)
		(end 81.661 -179.451)
		(width 0.12065)
		(layer "B.Cu")
		(net "BMC_SSD_RST#2")
	)
	(segment
		(start 97.214944 -182.313072)
		(end 83.498944 -182.313072)
		(width 0.12065)
		(layer "B.Cu")
		(net "BMC_SSD_RST#2")
	)
	(segment
		(start 45.204888 -171.96435)
		(end 44.995338 -171.7548)
		(width 0.12065)
		(layer "B.Cu")
		(net "BMC_SSD_RST#2")
	)
	(segment
		(start 44.50461 -135.284972)
		(end 44.89831 -135.678672)
		(width 0.127)
		(layer "In5.Cu")
		(net "BMC_SSD_RST#2")
	)
	(segment
		(start 47.6631 -137.88644)
		(end 47.6631 -144.425924)
		(width 0.127)
		(layer "In5.Cu")
		(net "BMC_SSD_RST#2")
	)
	(segment
		(start 43.7642 -172.0342)
		(end 43.5102 -172.2882)
		(width 0.127)
		(layer "In5.Cu")
		(net "BMC_SSD_RST#2")
	)
	(segment
		(start 44.89831 -135.678672)
		(end 45.455332 -135.678672)
		(width 0.127)
		(layer "In5.Cu")
		(net "BMC_SSD_RST#2")
	)
	(segment
		(start 43.7642 -171.150788)
		(end 43.7642 -172.0342)
		(width 0.127)
		(layer "In5.Cu")
		(net "BMC_SSD_RST#2")
	)
	(segment
		(start 48.100234 -144.863058)
		(end 48.100234 -166.814754)
		(width 0.127)
		(layer "In5.Cu")
		(net "BMC_SSD_RST#2")
	)
	(segment
		(start 48.100234 -166.814754)
		(end 43.7642 -171.150788)
		(width 0.127)
		(layer "In5.Cu")
		(net "BMC_SSD_RST#2")
	)
	(segment
		(start 47.6631 -144.425924)
		(end 48.100234 -144.863058)
		(width 0.127)
		(layer "In5.Cu")
		(net "BMC_SSD_RST#2")
	)
	(segment
		(start 45.455332 -135.678672)
		(end 47.6631 -137.88644)
		(width 0.127)
		(layer "In5.Cu")
		(net "BMC_SSD_RST#2")
	)
	(segment
		(start 47.110396 -137.284968)
		(end 50.201576 -140.376148)
		(width 0.12065)
		(layer "F.Cu")
		(net "BMC_SSD_RST#1")
	)
	(segment
		(start 46.50486 -137.284968)
		(end 47.110396 -137.284968)
		(width 0.12065)
		(layer "F.Cu")
		(net "BMC_SSD_RST#1")
	)
	(segment
		(start 50.201576 -140.376148)
		(end 52.034948 -140.376148)
		(width 0.12065)
		(layer "F.Cu")
		(net "BMC_SSD_RST#1")
	)
	(segment
		(start 52.034948 -140.376148)
		(end 52.5018 -140.843)
		(width 0.12065)
		(layer "F.Cu")
		(net "BMC_SSD_RST#1")
	)
	(via
		(at 51.054 -171.196)
		(size 0.508)
		(drill 0.254)
		(layers "F.Cu" "B.Cu")
		(net "BMC_SSD_RST#1")
	)
	(via
		(at 83.797902 -181.460902)
		(size 0.7112)
		(drill 0.3556)
		(layers "F.Cu" "B.Cu")
		(net "BMC_SSD_RST#1")
	)
	(via
		(at 52.5018 -140.843)
		(size 0.508)
		(drill 0.254)
		(layers "F.Cu" "B.Cu")
		(net "BMC_SSD_RST#1")
	)
	(segment
		(start 54.485794 -171.602654)
		(end 54.486048 -171.6024)
		(width 0.12065)
		(layer "B.Cu")
		(net "BMC_SSD_RST#1")
	)
	(segment
		(start 84.288122 -181.951122)
		(end 83.797902 -181.460902)
		(width 0.12065)
		(layer "B.Cu")
		(net "BMC_SSD_RST#1")
	)
	(segment
		(start 82.441796 -178.679856)
		(end 82.441796 -180.104796)
		(width 0.12065)
		(layer "B.Cu")
		(net "BMC_SSD_RST#1")
	)
	(segment
		(start 125.904752 -206.293974)
		(end 125.404626 -206.7941)
		(width 0.12065)
		(layer "B.Cu")
		(net "BMC_SSD_RST#1")
	)
	(segment
		(start 82.441796 -180.104796)
		(end 83.797902 -181.460902)
		(width 0.12065)
		(layer "B.Cu")
		(net "BMC_SSD_RST#1")
	)
	(segment
		(start 54.486048 -171.6024)
		(end 75.36434 -171.6024)
		(width 0.12065)
		(layer "B.Cu")
		(net "BMC_SSD_RST#1")
	)
	(segment
		(start 51.460908 -171.602908)
		(end 54.18582 -171.602908)
		(width 0.12065)
		(layer "B.Cu")
		(net "BMC_SSD_RST#1")
	)
	(segment
		(start 54.18582 -171.602908)
		(end 54.186074 -171.602654)
		(width 0.12065)
		(layer "B.Cu")
		(net "BMC_SSD_RST#1")
	)
	(segment
		(start 97.365058 -181.951122)
		(end 84.288122 -181.951122)
		(width 0.12065)
		(layer "B.Cu")
		(net "BMC_SSD_RST#1")
	)
	(segment
		(start 127.680212 -206.293974)
		(end 125.904752 -206.293974)
		(width 0.12065)
		(layer "B.Cu")
		(net "BMC_SSD_RST#1")
	)
	(segment
		(start 75.36434 -171.6024)
		(end 82.441796 -178.679856)
		(width 0.12065)
		(layer "B.Cu")
		(net "BMC_SSD_RST#1")
	)
	(segment
		(start 54.186074 -171.602654)
		(end 54.485794 -171.602654)
		(width 0.12065)
		(layer "B.Cu")
		(net "BMC_SSD_RST#1")
	)
	(segment
		(start 51.054 -171.196)
		(end 51.460908 -171.602908)
		(width 0.12065)
		(layer "B.Cu")
		(net "BMC_SSD_RST#1")
	)
	(segment
		(start 122.208036 -206.7941)
		(end 97.365058 -181.951122)
		(width 0.12065)
		(layer "B.Cu")
		(net "BMC_SSD_RST#1")
	)
	(segment
		(start 125.404626 -206.7941)
		(end 122.208036 -206.7941)
		(width 0.12065)
		(layer "B.Cu")
		(net "BMC_SSD_RST#1")
	)
	(segment
		(start 53.109114 -166.656004)
		(end 53.109368 -166.971726)
		(width 0.127)
		(layer "In5.Cu")
		(net "BMC_SSD_RST#1")
	)
	(segment
		(start 53.109368 -165.869874)
		(end 53.109114 -166.185596)
		(width 0.127)
		(layer "In5.Cu")
		(net "BMC_SSD_RST#1")
	)
	(segment
		(start 53.109368 -168.988232)
		(end 51.054 -171.0436)
		(width 0.127)
		(layer "In5.Cu")
		(net "BMC_SSD_RST#1")
	)
	(segment
		(start 53.109368 -166.971726)
		(end 53.109368 -168.988232)
		(width 0.127)
		(layer "In5.Cu")
		(net "BMC_SSD_RST#1")
	)
	(segment
		(start 51.054 -171.0436)
		(end 51.054 -171.196)
		(width 0.127)
		(layer "In5.Cu")
		(net "BMC_SSD_RST#1")
	)
	(segment
		(start 53.109368 -141.450568)
		(end 53.109368 -165.869874)
		(width 0.127)
		(layer "In5.Cu")
		(net "BMC_SSD_RST#1")
	)
	(segment
		(start 52.5018 -140.843)
		(end 53.109368 -141.450568)
		(width 0.127)
		(layer "In5.Cu")
		(net "BMC_SSD_RST#1")
	)
	(segment
		(start 53.109114 -166.185596)
		(end 53.109114 -166.656004)
		(width 0.127)
		(layer "In5.Cu")
		(net "BMC_SSD_RST#1")
	)
	(segment
		(start 51.015138 -138.769852)
		(end 51.48199 -138.303)
		(width 0.12065)
		(layer "F.Cu")
		(net "BMC_SSD_RST#0")
	)
	(segment
		(start 49.736248 -138.769852)
		(end 51.015138 -138.769852)
		(width 0.12065)
		(layer "F.Cu")
		(net "BMC_SSD_RST#0")
	)
	(segment
		(start 46.070012 -136.119616)
		(end 47.086012 -136.119616)
		(width 0.12065)
		(layer "F.Cu")
		(net "BMC_SSD_RST#0")
	)
	(segment
		(start 51.48199 -138.303)
		(end 51.6382 -138.303)
		(width 0.12065)
		(layer "F.Cu")
		(net "BMC_SSD_RST#0")
	)
	(segment
		(start 45.70476 -136.484868)
		(end 46.070012 -136.119616)
		(width 0.12065)
		(layer "F.Cu")
		(net "BMC_SSD_RST#0")
	)
	(segment
		(start 47.086012 -136.119616)
		(end 49.736248 -138.769852)
		(width 0.12065)
		(layer "F.Cu")
		(net "BMC_SSD_RST#0")
	)
	(via
		(at 48.006 -173.863)
		(size 0.508)
		(drill 0.254)
		(layers "F.Cu" "B.Cu")
		(net "BMC_SSD_RST#0")
	)
	(via
		(at 51.6382 -138.303)
		(size 0.508)
		(drill 0.254)
		(layers "F.Cu" "B.Cu")
		(net "BMC_SSD_RST#0")
	)
	(via
		(at 65.946782 -181.830218)
		(size 0.7112)
		(drill 0.3556)
		(layers "F.Cu" "B.Cu")
		(net "BMC_SSD_RST#0")
	)
	(segment
		(start 50.859944 -173.0502)
		(end 49.441608 -173.0502)
		(width 0.12065)
		(layer "B.Cu")
		(net "BMC_SSD_RST#0")
	)
	(segment
		(start 55.086504 -173.0502)
		(end 55.08625 -173.050454)
		(width 0.12065)
		(layer "B.Cu")
		(net "BMC_SSD_RST#0")
	)
	(segment
		(start 77.995272 -180.848)
		(end 79.10322 -179.740052)
		(width 0.12065)
		(layer "B.Cu")
		(net "BMC_SSD_RST#0")
	)
	(segment
		(start 64.49695 -191.238886)
		(end 64.49695 -183.28005)
		(width 0.12065)
		(layer "B.Cu")
		(net "BMC_SSD_RST#0")
	)
	(segment
		(start 50.860452 -173.050708)
		(end 50.859944 -173.0502)
		(width 0.12065)
		(layer "B.Cu")
		(net "BMC_SSD_RST#0")
	)
	(segment
		(start 79.10322 -179.740052)
		(end 79.10322 -177.393092)
		(width 0.12065)
		(layer "B.Cu")
		(net "BMC_SSD_RST#0")
	)
	(segment
		(start 64.49695 -183.28005)
		(end 65.946782 -181.830218)
		(width 0.12065)
		(layer "B.Cu")
		(net "BMC_SSD_RST#0")
	)
	(segment
		(start 73.578212 -193.085974)
		(end 71.709026 -193.085974)
		(width 0.12065)
		(layer "B.Cu")
		(net "BMC_SSD_RST#0")
	)
	(segment
		(start 66.929 -180.848)
		(end 77.995272 -180.848)
		(width 0.12065)
		(layer "B.Cu")
		(net "BMC_SSD_RST#0")
	)
	(segment
		(start 65.946782 -181.830218)
		(end 66.929 -180.848)
		(width 0.12065)
		(layer "B.Cu")
		(net "BMC_SSD_RST#0")
	)
	(segment
		(start 49.441608 -173.0502)
		(end 48.628808 -173.863)
		(width 0.12065)
		(layer "B.Cu")
		(net "BMC_SSD_RST#0")
	)
	(segment
		(start 55.08625 -173.050454)
		(end 54.78653 -173.050454)
		(width 0.12065)
		(layer "B.Cu")
		(net "BMC_SSD_RST#0")
	)
	(segment
		(start 71.247 -193.548)
		(end 66.806064 -193.548)
		(width 0.12065)
		(layer "B.Cu")
		(net "BMC_SSD_RST#0")
	)
	(segment
		(start 79.10322 -177.393092)
		(end 74.760328 -173.0502)
		(width 0.12065)
		(layer "B.Cu")
		(net "BMC_SSD_RST#0")
	)
	(segment
		(start 54.786276 -173.050708)
		(end 50.860452 -173.050708)
		(width 0.12065)
		(layer "B.Cu")
		(net "BMC_SSD_RST#0")
	)
	(segment
		(start 48.628808 -173.863)
		(end 48.006 -173.863)
		(width 0.12065)
		(layer "B.Cu")
		(net "BMC_SSD_RST#0")
	)
	(segment
		(start 66.806064 -193.548)
		(end 64.49695 -191.238886)
		(width 0.12065)
		(layer "B.Cu")
		(net "BMC_SSD_RST#0")
	)
	(segment
		(start 71.709026 -193.085974)
		(end 71.247 -193.548)
		(width 0.12065)
		(layer "B.Cu")
		(net "BMC_SSD_RST#0")
	)
	(segment
		(start 54.78653 -173.050454)
		(end 54.786276 -173.050708)
		(width 0.12065)
		(layer "B.Cu")
		(net "BMC_SSD_RST#0")
	)
	(segment
		(start 74.760328 -173.0502)
		(end 55.086504 -173.0502)
		(width 0.12065)
		(layer "B.Cu")
		(net "BMC_SSD_RST#0")
	)
	(segment
		(start 53.490368 -141.29258)
		(end 53.458364 -141.260576)
		(width 0.127)
		(layer "In5.Cu")
		(net "BMC_SSD_RST#0")
	)
	(segment
		(start 53.490368 -165.870128)
		(end 53.490368 -141.29258)
		(width 0.127)
		(layer "In5.Cu")
		(net "BMC_SSD_RST#0")
	)
	(segment
		(start 53.458364 -169.178224)
		(end 53.490368 -169.14622)
		(width 0.127)
		(layer "In5.Cu")
		(net "BMC_SSD_RST#0")
	)
	(segment
		(start 52.696618 -138.8491)
		(end 52.1843 -138.8491)
		(width 0.127)
		(layer "In5.Cu")
		(net "BMC_SSD_RST#0")
	)
	(segment
		(start 48.006 -173.863)
		(end 49.53 -172.339)
		(width 0.127)
		(layer "In5.Cu")
		(net "BMC_SSD_RST#0")
	)
	(segment
		(start 53.490114 -166.18585)
		(end 53.490368 -165.870128)
		(width 0.127)
		(layer "In5.Cu")
		(net "BMC_SSD_RST#0")
	)
	(segment
		(start 52.1843 -138.8491)
		(end 51.6382 -138.303)
		(width 0.127)
		(layer "In5.Cu")
		(net "BMC_SSD_RST#0")
	)
	(segment
		(start 50.673 -172.339)
		(end 53.458364 -169.553636)
		(width 0.127)
		(layer "In5.Cu")
		(net "BMC_SSD_RST#0")
	)
	(segment
		(start 53.490368 -169.14622)
		(end 53.490368 -166.971472)
		(width 0.127)
		(layer "In5.Cu")
		(net "BMC_SSD_RST#0")
	)
	(segment
		(start 53.490368 -166.971472)
		(end 53.490114 -166.65575)
		(width 0.127)
		(layer "In5.Cu")
		(net "BMC_SSD_RST#0")
	)
	(segment
		(start 53.458364 -169.553636)
		(end 53.458364 -169.178224)
		(width 0.127)
		(layer "In5.Cu")
		(net "BMC_SSD_RST#0")
	)
	(segment
		(start 53.458364 -141.260576)
		(end 53.458364 -139.610846)
		(width 0.127)
		(layer "In5.Cu")
		(net "BMC_SSD_RST#0")
	)
	(segment
		(start 49.53 -172.339)
		(end 50.673 -172.339)
		(width 0.127)
		(layer "In5.Cu")
		(net "BMC_SSD_RST#0")
	)
	(segment
		(start 53.490114 -166.65575)
		(end 53.490114 -166.18585)
		(width 0.127)
		(layer "In5.Cu")
		(net "BMC_SSD_RST#0")
	)
	(segment
		(start 53.458364 -139.610846)
		(end 52.696618 -138.8491)
		(width 0.127)
		(layer "In5.Cu")
		(net "BMC_SSD_RST#0")
	)
	(segment
		(start 155.829 -91.4781)
		(end 156.2354 -91.8845)
		(width 0.1524)
		(layer "F.Cu")
		(net "XTAL_X2_CLKGEN")
	)
	(segment
		(start 156.793438 -91.326462)
		(end 156.2354 -91.8845)
		(width 0.1524)
		(layer "F.Cu")
		(net "XTAL_X2_CLKGEN")
	)
	(segment
		(start 158.294578 -91.326462)
		(end 156.793438 -91.326462)
		(width 0.1524)
		(layer "F.Cu")
		(net "XTAL_X2_CLKGEN")
	)
	(segment
		(start 155.829 -90.711782)
		(end 155.829 -91.4781)
		(width 0.1524)
		(layer "F.Cu")
		(net "XTAL_X2_CLKGEN")
	)
	(segment
		(start 154.813 -89.822782)
		(end 155.829 -89.822782)
		(width 0.1524)
		(layer "F.Cu")
		(net "XTAL_X2")
	)
	(segment
		(start 153.283412 -90.674952)
		(end 154.135582 -89.822782)
		(width 0.1524)
		(layer "F.Cu")
		(net "XTAL_X2")
	)
	(segment
		(start 154.135582 -89.822782)
		(end 154.813 -89.822782)
		(width 0.1524)
		(layer "F.Cu")
		(net "XTAL_X2")
	)
	(segment
		(start 154.1526 -93.166946)
		(end 154.1526 -92.367608)
		(width 0.1524)
		(layer "F.Cu")
		(net "XTAL_X1")
	)
	(segment
		(start 156.2354 -92.7735)
		(end 157.182566 -91.826334)
		(width 0.1524)
		(layer "F.Cu")
		(net "XTAL_X1")
	)
	(segment
		(start 155.571698 -93.437202)
		(end 154.813 -93.437202)
		(width 0.1524)
		(layer "F.Cu")
		(net "XTAL_X1")
	)
	(segment
		(start 154.1526 -92.367608)
		(end 153.90114 -92.116148)
		(width 0.1524)
		(layer "F.Cu")
		(net "XTAL_X1")
	)
	(segment
		(start 151.770588 -92.577412)
		(end 151.770588 -93.017848)
		(width 0.1524)
		(layer "F.Cu")
		(net "XTAL_X1")
	)
	(segment
		(start 157.182566 -91.826334)
		(end 158.294578 -91.826334)
		(width 0.1524)
		(layer "F.Cu")
		(net "XTAL_X1")
	)
	(segment
		(start 156.2354 -92.7735)
		(end 155.571698 -93.437202)
		(width 0.1524)
		(layer "F.Cu")
		(net "XTAL_X1")
	)
	(segment
		(start 154.422856 -93.437202)
		(end 154.1526 -93.166946)
		(width 0.1524)
		(layer "F.Cu")
		(net "XTAL_X1")
	)
	(segment
		(start 154.813 -93.437202)
		(end 154.422856 -93.437202)
		(width 0.1524)
		(layer "F.Cu")
		(net "XTAL_X1")
	)
	(segment
		(start 153.90114 -92.116148)
		(end 152.231852 -92.116148)
		(width 0.1524)
		(layer "F.Cu")
		(net "XTAL_X1")
	)
	(segment
		(start 152.231852 -92.116148)
		(end 151.770588 -92.577412)
		(width 0.1524)
		(layer "F.Cu")
		(net "XTAL_X1")
	)
	(segment
		(start 250.599956 -38.999922)
		(end 251.099828 -38.50005)
		(width 0.12065)
		(layer "F.Cu")
		(net "VSS_573")
	)
	(via
		(at 251.099828 -38.50005)
		(size 0.4572)
		(drill 0.2032)
		(layers "F.Cu" "B.Cu")
		(net "VSS_573")
	)
	(via
		(at 251.868432 -39.110666)
		(size 0.7112)
		(drill 0.3556)
		(layers "F.Cu" "B.Cu")
		(net "VSS_573")
	)
	(segment
		(start 251.868432 -38.84422)
		(end 251.868432 -39.110666)
		(width 0.12065)
		(layer "B.Cu")
		(net "VSS_573")
	)
	(segment
		(start 251.524262 -38.50005)
		(end 251.868432 -38.84422)
		(width 0.12065)
		(layer "B.Cu")
		(net "VSS_573")
	)
	(segment
		(start 251.12599 -39.05631)
		(end 251.180346 -39.110666)
		(width 0.12065)
		(layer "B.Cu")
		(net "VSS_573")
	)
	(segment
		(start 250.707906 -39.05631)
		(end 251.12599 -39.05631)
		(width 0.12065)
		(layer "B.Cu")
		(net "VSS_573")
	)
	(segment
		(start 251.099828 -38.50005)
		(end 251.524262 -38.50005)
		(width 0.12065)
		(layer "B.Cu")
		(net "VSS_573")
	)
	(segment
		(start 251.180346 -39.110666)
		(end 251.868432 -39.110666)
		(width 0.12065)
		(layer "B.Cu")
		(net "VSS_573")
	)
	(segment
		(start 245.599966 -39.99992)
		(end 246.099838 -39.500048)
		(width 0.12065)
		(layer "F.Cu")
		(net "VSS_572")
	)
	(via
		(at 243.787422 -19.250152)
		(size 0.7112)
		(drill 0.3556)
		(layers "F.Cu" "B.Cu")
		(net "VSS_572")
	)
	(via
		(at 246.099838 -39.500048)
		(size 0.4572)
		(drill 0.2032)
		(layers "F.Cu" "B.Cu")
		(net "VSS_572")
	)
	(via
		(at 243.6622 -18.288)
		(size 0.508)
		(drill 0.254)
		(layers "F.Cu" "B.Cu")
		(net "VSS_572")
	)
	(segment
		(start 242.8875 -18.288)
		(end 242.8875 -19.0373)
		(width 0.12065)
		(layer "B.Cu")
		(net "VSS_572")
	)
	(segment
		(start 243.787422 -18.413222)
		(end 243.787422 -19.250152)
		(width 0.12065)
		(layer "B.Cu")
		(net "VSS_572")
	)
	(segment
		(start 242.8875 -19.0373)
		(end 243.100352 -19.250152)
		(width 0.12065)
		(layer "B.Cu")
		(net "VSS_572")
	)
	(segment
		(start 243.100352 -19.250152)
		(end 243.787422 -19.250152)
		(width 0.12065)
		(layer "B.Cu")
		(net "VSS_572")
	)
	(segment
		(start 243.6622 -18.288)
		(end 243.787422 -18.413222)
		(width 0.12065)
		(layer "B.Cu")
		(net "VSS_572")
	)
	(segment
		(start 246.506238 -20.511262)
		(end 246.506238 -38.668452)
		(width 0.127)
		(layer "In5.Cu")
		(net "VSS_572")
	)
	(segment
		(start 243.865146 -18.490946)
		(end 244.485922 -18.490946)
		(width 0.127)
		(layer "In5.Cu")
		(net "VSS_572")
	)
	(segment
		(start 246.099838 -39.074852)
		(end 246.099838 -39.500048)
		(width 0.127)
		(layer "In5.Cu")
		(net "VSS_572")
	)
	(segment
		(start 246.506238 -38.668452)
		(end 246.099838 -39.074852)
		(width 0.127)
		(layer "In5.Cu")
		(net "VSS_572")
	)
	(segment
		(start 244.485922 -18.490946)
		(end 246.506238 -20.511262)
		(width 0.127)
		(layer "In5.Cu")
		(net "VSS_572")
	)
	(segment
		(start 243.6622 -18.288)
		(end 243.865146 -18.490946)
		(width 0.127)
		(layer "In5.Cu")
		(net "VSS_572")
	)
	(segment
		(start 231.599994 -35.999928)
		(end 231.100122 -35.500056)
		(width 0.12065)
		(layer "F.Cu")
		(net "VSS_571")
	)
	(via
		(at 228.092 -29.718)
		(size 0.7112)
		(drill 0.3556)
		(layers "F.Cu" "B.Cu")
		(net "VSS_571")
	)
	(via
		(at 231.100122 -35.500056)
		(size 0.4572)
		(drill 0.2032)
		(layers "F.Cu" "B.Cu")
		(net "VSS_571")
	)
	(segment
		(start 229.1461 -28.575)
		(end 228.6 -28.575)
		(width 0.12065)
		(layer "B.Cu")
		(net "VSS_571")
	)
	(segment
		(start 229.706424 -30.549342)
		(end 229.706424 -32.663384)
		(width 0.1016)
		(layer "B.Cu")
		(net "VSS_571")
	)
	(segment
		(start 230.5177 -34.971228)
		(end 231.046528 -35.500056)
		(width 0.1016)
		(layer "B.Cu")
		(net "VSS_571")
	)
	(segment
		(start 229.936802 -32.893762)
		(end 230.322882 -32.893762)
		(width 0.1016)
		(layer "B.Cu")
		(net "VSS_571")
	)
	(segment
		(start 228.092 -29.770832)
		(end 228.346 -30.024832)
		(width 0.1016)
		(layer "B.Cu")
		(net "VSS_571")
	)
	(segment
		(start 230.322882 -32.893762)
		(end 230.5177 -33.08858)
		(width 0.1016)
		(layer "B.Cu")
		(net "VSS_571")
	)
	(segment
		(start 228.346 -30.024832)
		(end 229.181914 -30.024832)
		(width 0.1016)
		(layer "B.Cu")
		(net "VSS_571")
	)
	(segment
		(start 229.706424 -32.663384)
		(end 229.936802 -32.893762)
		(width 0.1016)
		(layer "B.Cu")
		(net "VSS_571")
	)
	(segment
		(start 229.181914 -30.024832)
		(end 229.706424 -30.549342)
		(width 0.1016)
		(layer "B.Cu")
		(net "VSS_571")
	)
	(segment
		(start 228.092 -29.083)
		(end 228.092 -29.718)
		(width 0.12065)
		(layer "B.Cu")
		(net "VSS_571")
	)
	(segment
		(start 228.092 -29.718)
		(end 228.092 -29.770832)
		(width 0.1016)
		(layer "B.Cu")
		(net "VSS_571")
	)
	(segment
		(start 230.5177 -33.08858)
		(end 230.5177 -34.971228)
		(width 0.1016)
		(layer "B.Cu")
		(net "VSS_571")
	)
	(segment
		(start 231.046528 -35.500056)
		(end 231.100122 -35.500056)
		(width 0.1016)
		(layer "B.Cu")
		(net "VSS_571")
	)
	(segment
		(start 228.6 -28.575)
		(end 228.092 -29.083)
		(width 0.12065)
		(layer "B.Cu")
		(net "VSS_571")
	)
	(segment
		(start 292.6715 -59.563)
		(end 293.624 -59.563)
		(width 0.12065)
		(layer "F.Cu")
		(net "VS6_LED_R")
	)
	(segment
		(start 293.624 -59.563)
		(end 293.21125 -59.15025)
		(width 0.12065)
		(layer "F.Cu")
		(net "VS6_LED_R")
	)
	(segment
		(start 293.21125 -59.15025)
		(end 293.21125 -58.1025)
		(width 0.12065)
		(layer "F.Cu")
		(net "VS6_LED_R")
	)
	(via
		(at 293.624 -59.563)
		(size 0.7112)
		(drill 0.3556)
		(layers "F.Cu" "B.Cu")
		(net "VS6_LED_R")
	)
	(segment
		(start 326.517 -99.06)
		(end 325.628 -98.171)
		(width 0.12065)
		(layer "F.Cu")
		(net "VS6_LED")
	)
	(segment
		(start 326.517 -99.1235)
		(end 326.517 -99.06)
		(width 0.12065)
		(layer "F.Cu")
		(net "VS6_LED")
	)
	(segment
		(start 325.16572 -95.885)
		(end 325.16572 -97.70872)
		(width 0.12065)
		(layer "F.Cu")
		(net "VS6_LED")
	)
	(segment
		(start 325.16572 -97.70872)
		(end 325.628 -98.171)
		(width 0.12065)
		(layer "F.Cu")
		(net "VS6_LED")
	)
	(segment
		(start 291.7825 -59.563)
		(end 292.354 -60.1345)
		(width 0.12065)
		(layer "F.Cu")
		(net "VS6_LED")
	)
	(segment
		(start 292.354 -61.468)
		(end 293.37 -61.468)
		(width 0.12065)
		(layer "F.Cu")
		(net "VS6_LED")
	)
	(segment
		(start 292.354 -60.1345)
		(end 292.354 -61.468)
		(width 0.12065)
		(layer "F.Cu")
		(net "VS6_LED")
	)
	(via
		(at 293.37 -61.468)
		(size 0.7112)
		(drill 0.3556)
		(layers "F.Cu" "B.Cu")
		(net "VS6_LED")
	)
	(via
		(at 292.354 -61.468)
		(size 0.508)
		(drill 0.254)
		(layers "F.Cu" "B.Cu")
		(net "VS6_LED")
	)
	(via
		(at 325.628 -98.171)
		(size 0.508)
		(drill 0.254)
		(layers "F.Cu" "B.Cu")
		(net "VS6_LED")
	)
	(segment
		(start 294.894 -64.008)
		(end 292.354 -61.468)
		(width 0.127)
		(layer "In2.Cu")
		(net "VS6_LED")
	)
	(segment
		(start 325.628 -98.171)
		(end 324.612762 -98.171)
		(width 0.127)
		(layer "In2.Cu")
		(net "VS6_LED")
	)
	(segment
		(start 323.469762 -97.028)
		(end 309.626 -97.028)
		(width 0.127)
		(layer "In2.Cu")
		(net "VS6_LED")
	)
	(segment
		(start 309.626 -97.028)
		(end 298.247054 -85.649054)
		(width 0.127)
		(layer "In2.Cu")
		(net "VS6_LED")
	)
	(segment
		(start 294.894 -71.9328)
		(end 294.894 -64.008)
		(width 0.127)
		(layer "In2.Cu")
		(net "VS6_LED")
	)
	(segment
		(start 298.247054 -85.649054)
		(end 298.247054 -75.285854)
		(width 0.127)
		(layer "In2.Cu")
		(net "VS6_LED")
	)
	(segment
		(start 324.612762 -98.171)
		(end 323.469762 -97.028)
		(width 0.127)
		(layer "In2.Cu")
		(net "VS6_LED")
	)
	(segment
		(start 298.247054 -75.285854)
		(end 294.894 -71.9328)
		(width 0.127)
		(layer "In2.Cu")
		(net "VS6_LED")
	)
	(segment
		(start 288.9885 -59.563)
		(end 289.814 -59.563)
		(width 0.12065)
		(layer "F.Cu")
		(net "VS5_LED_R")
	)
	(segment
		(start 289.814 -59.563)
		(end 289.941 -59.436)
		(width 0.12065)
		(layer "F.Cu")
		(net "VS5_LED_R")
	)
	(segment
		(start 289.52825 -58.1025)
		(end 289.941 -58.51525)
		(width 0.12065)
		(layer "F.Cu")
		(net "VS5_LED_R")
	)
	(segment
		(start 289.941 -58.51525)
		(end 289.941 -59.436)
		(width 0.12065)
		(layer "F.Cu")
		(net "VS5_LED_R")
	)
	(via
		(at 289.941 -59.436)
		(size 0.7112)
		(drill 0.3556)
		(layers "F.Cu" "B.Cu")
		(net "VS5_LED_R")
	)
	(segment
		(start 290.505896 -60.635896)
		(end 291.338 -61.468)
		(width 0.12065)
		(layer "F.Cu")
		(net "VS5_LED")
	)
	(segment
		(start 288.0995 -59.563)
		(end 288.0995 -60.567316)
		(width 0.12065)
		(layer "F.Cu")
		(net "VS5_LED")
	)
	(segment
		(start 288.0995 -60.567316)
		(end 288.083498 -60.583318)
		(width 0.12065)
		(layer "F.Cu")
		(net "VS5_LED")
	)
	(segment
		(start 288.136076 -60.635896)
		(end 290.505896 -60.635896)
		(width 0.12065)
		(layer "F.Cu")
		(net "VS5_LED")
	)
	(segment
		(start 325.81596 -97.40646)
		(end 325.81596 -97.282)
		(width 0.12065)
		(layer "F.Cu")
		(net "VS5_LED")
	)
	(segment
		(start 288.083498 -60.583318)
		(end 288.136076 -60.635896)
		(width 0.12065)
		(layer "F.Cu")
		(net "VS5_LED")
	)
	(segment
		(start 325.81596 -97.282)
		(end 325.81596 -95.885)
		(width 0.12065)
		(layer "F.Cu")
		(net "VS5_LED")
	)
	(segment
		(start 327.533 -99.1235)
		(end 325.81596 -97.40646)
		(width 0.12065)
		(layer "F.Cu")
		(net "VS5_LED")
	)
	(via
		(at 288.083498 -60.583318)
		(size 0.7112)
		(drill 0.3556)
		(layers "F.Cu" "B.Cu")
		(net "VS5_LED")
	)
	(via
		(at 325.81596 -97.282)
		(size 0.508)
		(drill 0.254)
		(layers "F.Cu" "B.Cu")
		(net "VS5_LED")
	)
	(via
		(at 291.338 -61.468)
		(size 0.508)
		(drill 0.254)
		(layers "F.Cu" "B.Cu")
		(net "VS5_LED")
	)
	(segment
		(start 294.513 -64.643)
		(end 294.513 -72.090788)
		(width 0.127)
		(layer "In2.Cu")
		(net "VS5_LED")
	)
	(segment
		(start 297.8658 -75.443588)
		(end 297.8658 -86.441788)
		(width 0.127)
		(layer "In2.Cu")
		(net "VS5_LED")
	)
	(segment
		(start 309.595012 -98.171)
		(end 321.28841 -98.171)
		(width 0.127)
		(layer "In2.Cu")
		(net "VS5_LED")
	)
	(segment
		(start 326.0979 -97.56394)
		(end 325.81596 -97.282)
		(width 0.127)
		(layer "In2.Cu")
		(net "VS5_LED")
	)
	(segment
		(start 326.0979 -98.365818)
		(end 326.0979 -97.56394)
		(width 0.127)
		(layer "In2.Cu")
		(net "VS5_LED")
	)
	(segment
		(start 294.513 -72.090788)
		(end 297.8658 -75.443588)
		(width 0.127)
		(layer "In2.Cu")
		(net "VS5_LED")
	)
	(segment
		(start 325.822818 -98.6409)
		(end 326.0979 -98.365818)
		(width 0.127)
		(layer "In2.Cu")
		(net "VS5_LED")
	)
	(segment
		(start 297.8658 -86.441788)
		(end 309.595012 -98.171)
		(width 0.127)
		(layer "In2.Cu")
		(net "VS5_LED")
	)
	(segment
		(start 321.28841 -98.171)
		(end 321.75831 -98.6409)
		(width 0.127)
		(layer "In2.Cu")
		(net "VS5_LED")
	)
	(segment
		(start 321.75831 -98.6409)
		(end 325.822818 -98.6409)
		(width 0.127)
		(layer "In2.Cu")
		(net "VS5_LED")
	)
	(segment
		(start 291.338 -61.468)
		(end 294.513 -64.643)
		(width 0.127)
		(layer "In2.Cu")
		(net "VS5_LED")
	)
	(segment
		(start 285.84525 -58.1025)
		(end 286.385 -58.64225)
		(width 0.12065)
		(layer "F.Cu")
		(net "VS4_LED_R")
	)
	(segment
		(start 285.4325 -59.69)
		(end 286.258 -59.69)
		(width 0.12065)
		(layer "F.Cu")
		(net "VS4_LED_R")
	)
	(segment
		(start 286.258 -59.69)
		(end 286.385 -59.563)
		(width 0.12065)
		(layer "F.Cu")
		(net "VS4_LED_R")
	)
	(segment
		(start 286.385 -58.64225)
		(end 286.385 -59.563)
		(width 0.12065)
		(layer "F.Cu")
		(net "VS4_LED_R")
	)
	(via
		(at 286.385 -59.563)
		(size 0.7112)
		(drill 0.3556)
		(layers "F.Cu" "B.Cu")
		(net "VS4_LED_R")
	)
	(segment
		(start 284.5435 -60.699904)
		(end 284.53207 -60.711334)
		(width 0.12065)
		(layer "F.Cu")
		(net "VS4_LED")
	)
	(segment
		(start 326.4662 -97.1042)
		(end 327.533 -98.171)
		(width 0.12065)
		(layer "F.Cu")
		(net "VS4_LED")
	)
	(segment
		(start 290.322 -61.468)
		(end 285.288736 -61.468)
		(width 0.12065)
		(layer "F.Cu")
		(net "VS4_LED")
	)
	(segment
		(start 326.4662 -95.885)
		(end 326.4662 -97.1042)
		(width 0.12065)
		(layer "F.Cu")
		(net "VS4_LED")
	)
	(segment
		(start 327.5965 -98.171)
		(end 327.533 -98.171)
		(width 0.12065)
		(layer "F.Cu")
		(net "VS4_LED")
	)
	(segment
		(start 284.5435 -59.69)
		(end 284.5435 -60.699904)
		(width 0.12065)
		(layer "F.Cu")
		(net "VS4_LED")
	)
	(segment
		(start 328.549 -99.1235)
		(end 327.5965 -98.171)
		(width 0.12065)
		(layer "F.Cu")
		(net "VS4_LED")
	)
	(segment
		(start 285.288736 -61.468)
		(end 284.53207 -60.711334)
		(width 0.12065)
		(layer "F.Cu")
		(net "VS4_LED")
	)
	(via
		(at 284.53207 -60.711334)
		(size 0.7112)
		(drill 0.3556)
		(layers "F.Cu" "B.Cu")
		(net "VS4_LED")
	)
	(via
		(at 327.533 -98.171)
		(size 0.508)
		(drill 0.254)
		(layers "F.Cu" "B.Cu")
		(net "VS4_LED")
	)
	(via
		(at 290.322 -61.468)
		(size 0.508)
		(drill 0.254)
		(layers "F.Cu" "B.Cu")
		(net "VS4_LED")
	)
	(segment
		(start 326.6821 -99.0219)
		(end 327.533 -98.171)
		(width 0.127)
		(layer "In2.Cu")
		(net "VS4_LED")
	)
	(segment
		(start 321.600322 -99.0219)
		(end 326.6821 -99.0219)
		(width 0.127)
		(layer "In2.Cu")
		(net "VS4_LED")
	)
	(segment
		(start 297.4848 -86.717378)
		(end 309.319422 -98.552)
		(width 0.127)
		(layer "In2.Cu")
		(net "VS4_LED")
	)
	(segment
		(start 321.130422 -98.552)
		(end 321.600322 -99.0219)
		(width 0.127)
		(layer "In2.Cu")
		(net "VS4_LED")
	)
	(segment
		(start 309.319422 -98.552)
		(end 321.130422 -98.552)
		(width 0.127)
		(layer "In2.Cu")
		(net "VS4_LED")
	)
	(segment
		(start 297.4848 -75.601576)
		(end 297.4848 -86.717378)
		(width 0.127)
		(layer "In2.Cu")
		(net "VS4_LED")
	)
	(segment
		(start 294.132 -72.248776)
		(end 297.4848 -75.601576)
		(width 0.127)
		(layer "In2.Cu")
		(net "VS4_LED")
	)
	(segment
		(start 294.132 -65.278)
		(end 294.132 -72.248776)
		(width 0.127)
		(layer "In2.Cu")
		(net "VS4_LED")
	)
	(segment
		(start 290.322 -61.468)
		(end 294.132 -65.278)
		(width 0.127)
		(layer "In2.Cu")
		(net "VS4_LED")
	)
	(segment
		(start 175.9331 -52.282344)
		(end 175.9331 -53.8988)
		(width 0.12065)
		(layer "F.Cu")
		(net "VS3_LED_R")
	)
	(segment
		(start 175.706024 -52.055268)
		(end 175.9331 -52.282344)
		(width 0.12065)
		(layer "F.Cu")
		(net "VS3_LED_R")
	)
	(segment
		(start 327.11644 -95.885)
		(end 327.11644 -96.67494)
		(width 0.12065)
		(layer "F.Cu")
		(net "VS3_LED")
	)
	(segment
		(start 174.7266 -53.5813)
		(end 175.0441 -53.8988)
		(width 0.12065)
		(layer "F.Cu")
		(net "VS3_LED")
	)
	(segment
		(start 174.7266 -52.8574)
		(end 174.7266 -53.5813)
		(width 0.12065)
		(layer "F.Cu")
		(net "VS3_LED")
	)
	(segment
		(start 329.565 -99.1235)
		(end 327.69175 -97.25025)
		(width 0.12065)
		(layer "F.Cu")
		(net "VS3_LED")
	)
	(segment
		(start 327.11644 -96.67494)
		(end 327.69175 -97.25025)
		(width 0.12065)
		(layer "F.Cu")
		(net "VS3_LED")
	)
	(via
		(at 329.819 -95.631)
		(size 0.7112)
		(drill 0.3556)
		(layers "F.Cu" "B.Cu")
		(net "VS3_LED")
	)
	(via
		(at 174.7266 -52.8574)
		(size 0.508)
		(drill 0.254)
		(layers "F.Cu" "B.Cu")
		(net "VS3_LED")
	)
	(via
		(at 327.69175 -97.25025)
		(size 0.508)
		(drill 0.254)
		(layers "F.Cu" "B.Cu")
		(net "VS3_LED")
	)
	(segment
		(start 145.324322 -101.54285)
		(end 152.899872 -109.1184)
		(width 0.12065)
		(layer "B.Cu")
		(net "VS3_LED")
	)
	(segment
		(start 165.555676 -53.75148)
		(end 161.01568 -53.75148)
		(width 0.12065)
		(layer "B.Cu")
		(net "VS3_LED")
	)
	(segment
		(start 174.7266 -52.8574)
		(end 174.666402 -52.917598)
		(width 0.12065)
		(layer "B.Cu")
		(net "VS3_LED")
	)
	(segment
		(start 144.61363 -57.74817)
		(end 144.61363 -58.653426)
		(width 0.12065)
		(layer "B.Cu")
		(net "VS3_LED")
	)
	(segment
		(start 152.899872 -109.1184)
		(end 324.908418 -109.1184)
		(width 0.12065)
		(layer "B.Cu")
		(net "VS3_LED")
	)
	(segment
		(start 329.311 -95.631)
		(end 329.819 -95.631)
		(width 0.12065)
		(layer "B.Cu")
		(net "VS3_LED")
	)
	(segment
		(start 138.48715 -97.245424)
		(end 142.784576 -101.54285)
		(width 0.12065)
		(layer "B.Cu")
		(net "VS3_LED")
	)
	(segment
		(start 139.793726 -75.674474)
		(end 138.48715 -76.98105)
		(width 0.12065)
		(layer "B.Cu")
		(net "VS3_LED")
	)
	(segment
		(start 334.391508 -97.236534)
		(end 332.785974 -95.631)
		(width 0.12065)
		(layer "B.Cu")
		(net "VS3_LED")
	)
	(segment
		(start 174.666402 -52.917598)
		(end 166.389558 -52.917598)
		(width 0.12065)
		(layer "B.Cu")
		(net "VS3_LED")
	)
	(segment
		(start 334.391508 -99.63531)
		(end 334.391508 -97.236534)
		(width 0.12065)
		(layer "B.Cu")
		(net "VS3_LED")
	)
	(segment
		(start 332.785974 -95.631)
		(end 329.819 -95.631)
		(width 0.12065)
		(layer "B.Cu")
		(net "VS3_LED")
	)
	(segment
		(start 327.69175 -97.25025)
		(end 329.311 -95.631)
		(width 0.12065)
		(layer "B.Cu")
		(net "VS3_LED")
	)
	(segment
		(start 139.793726 -63.47333)
		(end 139.793726 -75.674474)
		(width 0.12065)
		(layer "B.Cu")
		(net "VS3_LED")
	)
	(segment
		(start 159.96158 -54.80558)
		(end 147.55622 -54.80558)
		(width 0.12065)
		(layer "B.Cu")
		(net "VS3_LED")
	)
	(segment
		(start 144.61363 -58.653426)
		(end 139.793726 -63.47333)
		(width 0.12065)
		(layer "B.Cu")
		(net "VS3_LED")
	)
	(segment
		(start 166.389558 -52.917598)
		(end 165.555676 -53.75148)
		(width 0.12065)
		(layer "B.Cu")
		(net "VS3_LED")
	)
	(segment
		(start 324.908418 -109.1184)
		(end 334.391508 -99.63531)
		(width 0.12065)
		(layer "B.Cu")
		(net "VS3_LED")
	)
	(segment
		(start 147.55622 -54.80558)
		(end 144.61363 -57.74817)
		(width 0.12065)
		(layer "B.Cu")
		(net "VS3_LED")
	)
	(segment
		(start 161.01568 -53.75148)
		(end 159.96158 -54.80558)
		(width 0.12065)
		(layer "B.Cu")
		(net "VS3_LED")
	)
	(segment
		(start 142.784576 -101.54285)
		(end 145.324322 -101.54285)
		(width 0.12065)
		(layer "B.Cu")
		(net "VS3_LED")
	)
	(segment
		(start 138.48715 -76.98105)
		(end 138.48715 -97.245424)
		(width 0.12065)
		(layer "B.Cu")
		(net "VS3_LED")
	)
	(segment
		(start 173.99 -54.61)
		(end 173.7995 -54.61)
		(width 0.12065)
		(layer "F.Cu")
		(net "VS2_LED_R")
	)
	(segment
		(start 172.150024 -52.960524)
		(end 173.0375 -53.848)
		(width 0.12065)
		(layer "F.Cu")
		(net "VS2_LED_R")
	)
	(segment
		(start 172.150024 -52.055268)
		(end 172.150024 -52.960524)
		(width 0.12065)
		(layer "F.Cu")
		(net "VS2_LED_R")
	)
	(segment
		(start 173.7995 -54.61)
		(end 173.0375 -53.848)
		(width 0.12065)
		(layer "F.Cu")
		(net "VS2_LED_R")
	)
	(via
		(at 173.99 -54.61)
		(size 0.7112)
		(drill 0.3556)
		(layers "F.Cu" "B.Cu")
		(net "VS2_LED_R")
	)
	(segment
		(start 330.581 -99.1235)
		(end 329.6285 -98.171)
		(width 0.12065)
		(layer "F.Cu")
		(net "VS2_LED")
	)
	(segment
		(start 327.76668 -96.665034)
		(end 329.272646 -98.171)
		(width 0.12065)
		(layer "F.Cu")
		(net "VS2_LED")
	)
	(segment
		(start 327.76668 -95.885)
		(end 327.76668 -96.665034)
		(width 0.12065)
		(layer "F.Cu")
		(net "VS2_LED")
	)
	(segment
		(start 329.272646 -98.171)
		(end 329.311 -98.171)
		(width 0.12065)
		(layer "F.Cu")
		(net "VS2_LED")
	)
	(segment
		(start 329.6285 -98.171)
		(end 329.311 -98.171)
		(width 0.12065)
		(layer "F.Cu")
		(net "VS2_LED")
	)
	(segment
		(start 172.1485 -53.848)
		(end 171.323 -53.848)
		(width 0.12065)
		(layer "F.Cu")
		(net "VS2_LED")
	)
	(via
		(at 331.597 -96.393)
		(size 0.7112)
		(drill 0.3556)
		(layers "F.Cu" "B.Cu")
		(net "VS2_LED")
	)
	(via
		(at 171.323 -53.848)
		(size 0.508)
		(drill 0.254)
		(layers "F.Cu" "B.Cu")
		(net "VS2_LED")
	)
	(via
		(at 329.311 -98.171)
		(size 0.508)
		(drill 0.254)
		(layers "F.Cu" "B.Cu")
		(net "VS2_LED")
	)
	(segment
		(start 142.93469 -101.1809)
		(end 138.8491 -97.09531)
		(width 0.12065)
		(layer "B.Cu")
		(net "VS2_LED")
	)
	(segment
		(start 166.539926 -53.279548)
		(end 169.549318 -53.279548)
		(width 0.12065)
		(layer "B.Cu")
		(net "VS2_LED")
	)
	(segment
		(start 147.706334 -55.16753)
		(end 160.111694 -55.16753)
		(width 0.12065)
		(layer "B.Cu")
		(net "VS2_LED")
	)
	(segment
		(start 166.01694 -53.802534)
		(end 166.539926 -53.279548)
		(width 0.12065)
		(layer "B.Cu")
		(net "VS2_LED")
	)
	(segment
		(start 328.93 -96.901)
		(end 329.438 -96.393)
		(width 0.12065)
		(layer "B.Cu")
		(net "VS2_LED")
	)
	(segment
		(start 170.272202 -54.002432)
		(end 170.65879 -54.002432)
		(width 0.12065)
		(layer "B.Cu")
		(net "VS2_LED")
	)
	(segment
		(start 144.975834 -58.803286)
		(end 144.975834 -57.89803)
		(width 0.12065)
		(layer "B.Cu")
		(net "VS2_LED")
	)
	(segment
		(start 331.597 -96.393)
		(end 333.03591 -96.393)
		(width 0.12065)
		(layer "B.Cu")
		(net "VS2_LED")
	)
	(segment
		(start 333.03591 -96.393)
		(end 334.029558 -97.386648)
		(width 0.12065)
		(layer "B.Cu")
		(net "VS2_LED")
	)
	(segment
		(start 334.029558 -99.485196)
		(end 324.758304 -108.75645)
		(width 0.12065)
		(layer "B.Cu")
		(net "VS2_LED")
	)
	(segment
		(start 153.049986 -108.75645)
		(end 145.474436 -101.1809)
		(width 0.12065)
		(layer "B.Cu")
		(net "VS2_LED")
	)
	(segment
		(start 140.155676 -63.623444)
		(end 144.975834 -58.803286)
		(width 0.12065)
		(layer "B.Cu")
		(net "VS2_LED")
	)
	(segment
		(start 329.311 -98.171)
		(end 328.93 -97.79)
		(width 0.12065)
		(layer "B.Cu")
		(net "VS2_LED")
	)
	(segment
		(start 329.438 -96.393)
		(end 331.597 -96.393)
		(width 0.12065)
		(layer "B.Cu")
		(net "VS2_LED")
	)
	(segment
		(start 324.758304 -108.75645)
		(end 153.049986 -108.75645)
		(width 0.12065)
		(layer "B.Cu")
		(net "VS2_LED")
	)
	(segment
		(start 140.155676 -75.896724)
		(end 140.155676 -63.623444)
		(width 0.12065)
		(layer "B.Cu")
		(net "VS2_LED")
	)
	(segment
		(start 334.029558 -97.386648)
		(end 334.029558 -99.485196)
		(width 0.12065)
		(layer "B.Cu")
		(net "VS2_LED")
	)
	(segment
		(start 328.93 -97.79)
		(end 328.93 -96.901)
		(width 0.12065)
		(layer "B.Cu")
		(net "VS2_LED")
	)
	(segment
		(start 170.813222 -53.848)
		(end 171.323 -53.848)
		(width 0.12065)
		(layer "B.Cu")
		(net "VS2_LED")
	)
	(segment
		(start 145.474436 -101.1809)
		(end 142.93469 -101.1809)
		(width 0.12065)
		(layer "B.Cu")
		(net "VS2_LED")
	)
	(segment
		(start 170.65879 -54.002432)
		(end 170.813222 -53.848)
		(width 0.12065)
		(layer "B.Cu")
		(net "VS2_LED")
	)
	(segment
		(start 144.975834 -57.89803)
		(end 147.706334 -55.16753)
		(width 0.12065)
		(layer "B.Cu")
		(net "VS2_LED")
	)
	(segment
		(start 138.8491 -97.09531)
		(end 138.8491 -77.2033)
		(width 0.12065)
		(layer "B.Cu")
		(net "VS2_LED")
	)
	(segment
		(start 165.70579 -54.11343)
		(end 166.016686 -53.802534)
		(width 0.12065)
		(layer "B.Cu")
		(net "VS2_LED")
	)
	(segment
		(start 166.016686 -53.802534)
		(end 166.01694 -53.802534)
		(width 0.12065)
		(layer "B.Cu")
		(net "VS2_LED")
	)
	(segment
		(start 160.111694 -55.16753)
		(end 161.165794 -54.11343)
		(width 0.12065)
		(layer "B.Cu")
		(net "VS2_LED")
	)
	(segment
		(start 138.8491 -77.2033)
		(end 140.155676 -75.896724)
		(width 0.12065)
		(layer "B.Cu")
		(net "VS2_LED")
	)
	(segment
		(start 169.549318 -53.279548)
		(end 170.272202 -54.002432)
		(width 0.12065)
		(layer "B.Cu")
		(net "VS2_LED")
	)
	(segment
		(start 161.165794 -54.11343)
		(end 165.70579 -54.11343)
		(width 0.12065)
		(layer "B.Cu")
		(net "VS2_LED")
	)
	(segment
		(start 168.594024 -52.055268)
		(end 168.594024 -52.960524)
		(width 0.12065)
		(layer "F.Cu")
		(net "VS1_LED_R")
	)
	(segment
		(start 170.434 -54.61)
		(end 170.2435 -54.61)
		(width 0.12065)
		(layer "F.Cu")
		(net "VS1_LED_R")
	)
	(segment
		(start 170.2435 -54.61)
		(end 169.4815 -53.848)
		(width 0.12065)
		(layer "F.Cu")
		(net "VS1_LED_R")
	)
	(segment
		(start 168.594024 -52.960524)
		(end 169.4815 -53.848)
		(width 0.12065)
		(layer "F.Cu")
		(net "VS1_LED_R")
	)
	(via
		(at 170.434 -54.61)
		(size 0.7112)
		(drill 0.3556)
		(layers "F.Cu" "B.Cu")
		(net "VS1_LED_R")
	)
	(segment
		(start 328.41692 -95.885)
		(end 328.41692 -96.51492)
		(width 0.12065)
		(layer "F.Cu")
		(net "VS1_LED")
	)
	(segment
		(start 328.41692 -96.51492)
		(end 329.02525 -97.12325)
		(width 0.12065)
		(layer "F.Cu")
		(net "VS1_LED")
	)
	(segment
		(start 331.597 -99.1235)
		(end 329.59675 -97.12325)
		(width 0.12065)
		(layer "F.Cu")
		(net "VS1_LED")
	)
	(segment
		(start 329.02525 -97.12325)
		(end 329.59675 -97.12325)
		(width 0.12065)
		(layer "F.Cu")
		(net "VS1_LED")
	)
	(segment
		(start 168.5925 -53.848)
		(end 167.8178 -53.848)
		(width 0.12065)
		(layer "F.Cu")
		(net "VS1_LED")
	)
	(via
		(at 333.461106 -97.622106)
		(size 0.7112)
		(drill 0.3556)
		(layers "F.Cu" "B.Cu")
		(net "VS1_LED")
	)
	(via
		(at 167.8178 -53.848)
		(size 0.508)
		(drill 0.254)
		(layers "F.Cu" "B.Cu")
		(net "VS1_LED")
	)
	(via
		(at 329.59675 -97.12325)
		(size 0.508)
		(drill 0.254)
		(layers "F.Cu" "B.Cu")
		(net "VS1_LED")
	)
	(segment
		(start 145.62455 -100.81895)
		(end 153.2001 -108.3945)
		(width 0.12065)
		(layer "B.Cu")
		(net "VS1_LED")
	)
	(segment
		(start 329.6285 -97.155)
		(end 332.994 -97.155)
		(width 0.12065)
		(layer "B.Cu")
		(net "VS1_LED")
	)
	(segment
		(start 166.963852 -54.422294)
		(end 166.690294 -54.695852)
		(width 0.12065)
		(layer "B.Cu")
		(net "VS1_LED")
	)
	(segment
		(start 140.517626 -63.773558)
		(end 140.517626 -76.093574)
		(width 0.12065)
		(layer "B.Cu")
		(net "VS1_LED")
	)
	(segment
		(start 147.856448 -55.52948)
		(end 145.337784 -58.048144)
		(width 0.12065)
		(layer "B.Cu")
		(net "VS1_LED")
	)
	(segment
		(start 332.994 -97.155)
		(end 333.461106 -97.622106)
		(width 0.12065)
		(layer "B.Cu")
		(net "VS1_LED")
	)
	(segment
		(start 322.688712 -108.3945)
		(end 333.461106 -97.622106)
		(width 0.12065)
		(layer "B.Cu")
		(net "VS1_LED")
	)
	(segment
		(start 160.261808 -55.52948)
		(end 147.856448 -55.52948)
		(width 0.12065)
		(layer "B.Cu")
		(net "VS1_LED")
	)
	(segment
		(start 166.690294 -54.695852)
		(end 163.28136 -54.695852)
		(width 0.12065)
		(layer "B.Cu")
		(net "VS1_LED")
	)
	(segment
		(start 167.8178 -53.848)
		(end 167.524176 -53.848)
		(width 0.12065)
		(layer "B.Cu")
		(net "VS1_LED")
	)
	(segment
		(start 163.28136 -54.695852)
		(end 163.060888 -54.47538)
		(width 0.12065)
		(layer "B.Cu")
		(net "VS1_LED")
	)
	(segment
		(start 166.963852 -54.408324)
		(end 166.963852 -54.422294)
		(width 0.12065)
		(layer "B.Cu")
		(net "VS1_LED")
	)
	(segment
		(start 167.524176 -53.848)
		(end 166.963852 -54.408324)
		(width 0.12065)
		(layer "B.Cu")
		(net "VS1_LED")
	)
	(segment
		(start 161.315908 -54.47538)
		(end 160.261808 -55.52948)
		(width 0.12065)
		(layer "B.Cu")
		(net "VS1_LED")
	)
	(segment
		(start 143.084804 -100.81895)
		(end 145.62455 -100.81895)
		(width 0.12065)
		(layer "B.Cu")
		(net "VS1_LED")
	)
	(segment
		(start 139.21105 -77.40015)
		(end 139.21105 -96.945196)
		(width 0.12065)
		(layer "B.Cu")
		(net "VS1_LED")
	)
	(segment
		(start 145.337784 -58.9534)
		(end 140.517626 -63.773558)
		(width 0.12065)
		(layer "B.Cu")
		(net "VS1_LED")
	)
	(segment
		(start 139.21105 -96.945196)
		(end 143.084804 -100.81895)
		(width 0.12065)
		(layer "B.Cu")
		(net "VS1_LED")
	)
	(segment
		(start 145.337784 -58.048144)
		(end 145.337784 -58.9534)
		(width 0.12065)
		(layer "B.Cu")
		(net "VS1_LED")
	)
	(segment
		(start 163.060888 -54.47538)
		(end 161.315908 -54.47538)
		(width 0.12065)
		(layer "B.Cu")
		(net "VS1_LED")
	)
	(segment
		(start 329.59675 -97.12325)
		(end 329.6285 -97.155)
		(width 0.12065)
		(layer "B.Cu")
		(net "VS1_LED")
	)
	(segment
		(start 153.2001 -108.3945)
		(end 322.688712 -108.3945)
		(width 0.12065)
		(layer "B.Cu")
		(net "VS1_LED")
	)
	(segment
		(start 140.517626 -76.093574)
		(end 139.21105 -77.40015)
		(width 0.12065)
		(layer "B.Cu")
		(net "VS1_LED")
	)
	(segment
		(start 141.426946 -88.4682)
		(end 139.718034 -88.4682)
		(width 0.254)
		(layer "F.Cu")
		(net "VR_P1V8_STBY_SS_C")
	)
	(segment
		(start 141.429486 -88.47074)
		(end 141.426946 -88.4682)
		(width 0.254)
		(layer "F.Cu")
		(net "VR_P1V8_STBY_SS_C")
	)
	(segment
		(start 139.718034 -88.4682)
		(end 139.427712 -88.177878)
		(width 0.254)
		(layer "F.Cu")
		(net "VR_P1V8_STBY_SS_C")
	)
	(segment
		(start 139.427712 -88.177878)
		(end 139.427712 -87.587328)
		(width 0.254)
		(layer "F.Cu")
		(net "VR_P1V8_STBY_SS_C")
	)
	(segment
		(start 141.874494 -89.40292)
		(end 141.874494 -88.915494)
		(width 0.254)
		(layer "F.Cu")
		(net "VR_P1V8_STBY_SS_C")
	)
	(segment
		(start 139.93114 -87.0839)
		(end 140.8176 -87.0839)
		(width 0.254)
		(layer "F.Cu")
		(net "VR_P1V8_STBY_SS_C")
	)
	(segment
		(start 141.42974 -88.47074)
		(end 141.429486 -88.47074)
		(width 0.254)
		(layer "F.Cu")
		(net "VR_P1V8_STBY_SS_C")
	)
	(segment
		(start 139.427712 -87.587328)
		(end 139.93114 -87.0839)
		(width 0.254)
		(layer "F.Cu")
		(net "VR_P1V8_STBY_SS_C")
	)
	(segment
		(start 141.874494 -88.915494)
		(end 141.42974 -88.47074)
		(width 0.254)
		(layer "F.Cu")
		(net "VR_P1V8_STBY_SS_C")
	)
	(via
		(at 139.427712 -88.177878)
		(size 0.7112)
		(drill 0.3556)
		(layers "F.Cu" "B.Cu")
		(net "VR_P1V8_STBY_SS_C")
	)
	(segment
		(start 143.374364 -92.955364)
		(end 144.7038 -94.2848)
		(width 0.254)
		(layer "F.Cu")
		(net "VR_P1V8_STBY_IN")
	)
	(segment
		(start 145.669 -96.774)
		(end 144.88668 -97.55632)
		(width 0.254)
		(layer "F.Cu")
		(net "VR_P1V8_STBY_IN")
	)
	(segment
		(start 144.4752 -94.9198)
		(end 142.875254 -93.319854)
		(width 0.254)
		(layer "F.Cu")
		(net "VR_P1V8_STBY_IN")
	)
	(segment
		(start 142.875254 -93.319854)
		(end 142.875254 -92.50172)
		(width 0.254)
		(layer "F.Cu")
		(net "VR_P1V8_STBY_IN")
	)
	(segment
		(start 143.374364 -92.50172)
		(end 143.374364 -92.955364)
		(width 0.254)
		(layer "F.Cu")
		(net "VR_P1V8_STBY_IN")
	)
	(segment
		(start 144.88668 -97.55632)
		(end 144.660874 -97.55632)
		(width 0.254)
		(layer "F.Cu")
		(net "VR_P1V8_STBY_IN")
	)
	(segment
		(start 144.5768 -95.6818)
		(end 145.669 -96.774)
		(width 0.254)
		(layer "F.Cu")
		(net "VR_P1V8_STBY_IN")
	)
	(segment
		(start 144.7038 -95.123)
		(end 144.5768 -95.25)
		(width 0.254)
		(layer "F.Cu")
		(net "VR_P1V8_STBY_IN")
	)
	(segment
		(start 144.5768 -95.25)
		(end 144.5768 -95.6818)
		(width 0.254)
		(layer "F.Cu")
		(net "VR_P1V8_STBY_IN")
	)
	(segment
		(start 144.5768 -95.25)
		(end 144.4752 -95.1484)
		(width 0.254)
		(layer "F.Cu")
		(net "VR_P1V8_STBY_IN")
	)
	(segment
		(start 144.7038 -94.2848)
		(end 144.7038 -95.123)
		(width 0.254)
		(layer "F.Cu")
		(net "VR_P1V8_STBY_IN")
	)
	(segment
		(start 144.4752 -95.1484)
		(end 144.4752 -94.9198)
		(width 0.254)
		(layer "F.Cu")
		(net "VR_P1V8_STBY_IN")
	)
	(via
		(at 145.669 -96.774)
		(size 0.7112)
		(drill 0.3556)
		(layers "F.Cu" "B.Cu")
		(net "VR_P1V8_STBY_IN")
	)
	(segment
		(start 141.803374 -87.11692)
		(end 141.803374 -88.082374)
		(width 0.254)
		(layer "F.Cu")
		(net "VR_P1V8_STBY_FB")
	)
	(segment
		(start 142.374874 -88.653874)
		(end 142.374874 -89.40292)
		(width 0.254)
		(layer "F.Cu")
		(net "VR_P1V8_STBY_FB")
	)
	(segment
		(start 141.803374 -86.10092)
		(end 141.803374 -85.08492)
		(width 0.254)
		(layer "F.Cu")
		(net "VR_P1V8_STBY_FB")
	)
	(segment
		(start 141.803374 -88.082374)
		(end 142.374874 -88.653874)
		(width 0.254)
		(layer "F.Cu")
		(net "VR_P1V8_STBY_FB")
	)
	(segment
		(start 141.803374 -87.11692)
		(end 141.803374 -86.10092)
		(width 0.254)
		(layer "F.Cu")
		(net "VR_P1V8_STBY_FB")
	)
	(segment
		(start 139.98448 -92.09532)
		(end 140.39088 -92.50172)
		(width 0.254)
		(layer "F.Cu")
		(net "VR_P1V8_STBY_EN_R")
	)
	(segment
		(start 139.326874 -92.09532)
		(end 139.98448 -92.09532)
		(width 0.254)
		(layer "F.Cu")
		(net "VR_P1V8_STBY_EN_R")
	)
	(segment
		(start 140.39088 -92.50172)
		(end 141.375384 -92.50172)
		(width 0.254)
		(layer "F.Cu")
		(net "VR_P1V8_STBY_EN_R")
	)
	(via
		(at 140.7922 -93.5482)
		(size 0.7112)
		(drill 0.3556)
		(layers "F.Cu" "B.Cu")
		(net "VR_P1V8_STBY_EN_R")
	)
	(via
		(at 140.39088 -92.50172)
		(size 0.508)
		(drill 0.254)
		(layers "F.Cu" "B.Cu")
		(net "VR_P1V8_STBY_EN_R")
	)
	(segment
		(start 140.7922 -93.5482)
		(end 141.358874 -92.981526)
		(width 0.254)
		(layer "B.Cu")
		(net "VR_P1V8_STBY_EN_R")
	)
	(segment
		(start 140.39088 -92.50172)
		(end 140.39088 -93.14688)
		(width 0.254)
		(layer "B.Cu")
		(net "VR_P1V8_STBY_EN_R")
	)
	(segment
		(start 140.39088 -93.14688)
		(end 140.7922 -93.5482)
		(width 0.254)
		(layer "B.Cu")
		(net "VR_P1V8_STBY_EN_R")
	)
	(segment
		(start 141.358874 -92.981526)
		(end 141.358874 -92.66682)
		(width 0.254)
		(layer "B.Cu")
		(net "VR_P1V8_STBY_EN_R")
	)
	(segment
		(start 141.874494 -92.50172)
		(end 141.874494 -95.2119)
		(width 0.254)
		(layer "F.Cu")
		(net "VR_P1V8_STBY_BIAS")
	)
	(segment
		(start 141.874494 -95.2119)
		(end 141.816074 -95.27032)
		(width 0.254)
		(layer "F.Cu")
		(net "VR_P1V8_STBY_BIAS")
	)
	(segment
		(start 140.843 -96.243394)
		(end 140.843 -96.647)
		(width 0.254)
		(layer "F.Cu")
		(net "VR_P1V8_STBY_BIAS")
	)
	(segment
		(start 141.816074 -95.27032)
		(end 140.843 -96.243394)
		(width 0.254)
		(layer "F.Cu")
		(net "VR_P1V8_STBY_BIAS")
	)
	(segment
		(start 140.92682 -96.73082)
		(end 140.843 -96.647)
		(width 0.254)
		(layer "F.Cu")
		(net "VR_P1V8_STBY_BIAS")
	)
	(segment
		(start 141.866874 -96.73082)
		(end 140.92682 -96.73082)
		(width 0.254)
		(layer "F.Cu")
		(net "VR_P1V8_STBY_BIAS")
	)
	(via
		(at 140.843 -96.647)
		(size 0.7112)
		(drill 0.3556)
		(layers "F.Cu" "B.Cu")
		(net "VR_P1V8_STBY_BIAS")
	)
	(segment
		(start 63.64732 -162.01898)
		(end 64.3128 -162.01898)
		(width 0.254)
		(layer "F.Cu")
		(net "VR_P1V538_STBY_SS_C")
	)
	(segment
		(start 62.2427 -164.3634)
		(end 62.2427 -163.4236)
		(width 0.254)
		(layer "F.Cu")
		(net "VR_P1V538_STBY_SS_C")
	)
	(segment
		(start 62.2427 -163.4236)
		(end 63.64732 -162.01898)
		(width 0.254)
		(layer "F.Cu")
		(net "VR_P1V538_STBY_SS_C")
	)
	(via
		(at 62.2427 -164.3634)
		(size 0.7112)
		(drill 0.3556)
		(layers "F.Cu" "B.Cu")
		(net "VR_P1V538_STBY_SS_C")
	)
	(via
		(at 68.7578 -159.3342)
		(size 0.7112)
		(drill 0.3556)
		(layers "F.Cu" "B.Cu")
		(net "VR_P1V538_STBY_IN")
	)
	(segment
		(start 62.3062 -162.3441)
		(end 61.2902 -162.3441)
		(width 0.254)
		(layer "F.Cu")
		(net "VR_P1V538_STBY_FB")
	)
	(segment
		(start 61.2902 -162.3441)
		(end 60.2742 -162.3441)
		(width 0.254)
		(layer "F.Cu")
		(net "VR_P1V538_STBY_FB")
	)
	(segment
		(start 62.649354 -162.3441)
		(end 63.474854 -161.5186)
		(width 0.254)
		(layer "F.Cu")
		(net "VR_P1V538_STBY_FB")
	)
	(segment
		(start 63.474854 -161.5186)
		(end 64.3128 -161.5186)
		(width 0.254)
		(layer "F.Cu")
		(net "VR_P1V538_STBY_FB")
	)
	(segment
		(start 62.3062 -162.3441)
		(end 62.649354 -162.3441)
		(width 0.254)
		(layer "F.Cu")
		(net "VR_P1V538_STBY_FB")
	)
	(segment
		(start 68.7832 -165.8366)
		(end 68.0212 -165.8366)
		(width 0.254)
		(layer "F.Cu")
		(net "VR_P1V538_STBY_EN_R")
	)
	(segment
		(start 68.7832 -164.719)
		(end 68.7832 -165.8366)
		(width 0.254)
		(layer "F.Cu")
		(net "VR_P1V538_STBY_EN_R")
	)
	(segment
		(start 67.4116 -162.51809)
		(end 67.8307 -162.93719)
		(width 0.254)
		(layer "F.Cu")
		(net "VR_P1V538_STBY_EN_R")
	)
	(segment
		(start 67.8307 -164.4396)
		(end 68.5038 -164.4396)
		(width 0.254)
		(layer "F.Cu")
		(net "VR_P1V538_STBY_EN_R")
	)
	(segment
		(start 67.8307 -162.93719)
		(end 67.8307 -164.4396)
		(width 0.254)
		(layer "F.Cu")
		(net "VR_P1V538_STBY_EN_R")
	)
	(segment
		(start 68.5038 -164.4396)
		(end 68.7832 -164.719)
		(width 0.254)
		(layer "F.Cu")
		(net "VR_P1V538_STBY_EN_R")
	)
	(segment
		(start 68.0212 -165.8366)
		(end 67.7672 -165.5826)
		(width 0.254)
		(layer "F.Cu")
		(net "VR_P1V538_STBY_EN_R")
	)
	(via
		(at 68.7832 -165.8366)
		(size 0.7112)
		(drill 0.3556)
		(layers "F.Cu" "B.Cu")
		(net "VR_P1V538_STBY_EN_R")
	)
	(segment
		(start 67.8815 -162.01898)
		(end 68.326 -162.46348)
		(width 0.254)
		(layer "F.Cu")
		(net "VR_P1V538_STBY_BIAS")
	)
	(segment
		(start 70.231 -163.5506)
		(end 71.6407 -163.5506)
		(width 0.254)
		(layer "F.Cu")
		(net "VR_P1V538_STBY_BIAS")
	)
	(segment
		(start 70.1802 -163.6014)
		(end 70.231 -163.5506)
		(width 0.254)
		(layer "F.Cu")
		(net "VR_P1V538_STBY_BIAS")
	)
	(segment
		(start 71.6407 -163.5506)
		(end 71.755 -163.6649)
		(width 0.254)
		(layer "F.Cu")
		(net "VR_P1V538_STBY_BIAS")
	)
	(segment
		(start 68.326 -162.6616)
		(end 69.2658 -163.6014)
		(width 0.254)
		(layer "F.Cu")
		(net "VR_P1V538_STBY_BIAS")
	)
	(segment
		(start 67.4116 -162.01898)
		(end 67.8815 -162.01898)
		(width 0.254)
		(layer "F.Cu")
		(net "VR_P1V538_STBY_BIAS")
	)
	(segment
		(start 68.326 -162.46348)
		(end 68.326 -162.6616)
		(width 0.254)
		(layer "F.Cu")
		(net "VR_P1V538_STBY_BIAS")
	)
	(segment
		(start 69.2658 -163.6014)
		(end 70.1802 -163.6014)
		(width 0.254)
		(layer "F.Cu")
		(net "VR_P1V538_STBY_BIAS")
	)
	(segment
		(start 71.755 -163.6649)
		(end 71.755 -164.5158)
		(width 0.254)
		(layer "F.Cu")
		(net "VR_P1V538_STBY_BIAS")
	)
	(via
		(at 71.755 -164.5158)
		(size 0.7112)
		(drill 0.3556)
		(layers "F.Cu" "B.Cu")
		(net "VR_P1V538_STBY_BIAS")
	)
	(segment
		(start 15.494 -105.918)
		(end 16.4465 -105.918)
		(width 0.254)
		(layer "F.Cu")
		(net "VR_P1V26_STBY_SS_C")
	)
	(segment
		(start 13.7414 -107.70362)
		(end 14.66088 -107.70362)
		(width 0.254)
		(layer "F.Cu")
		(net "VR_P1V26_STBY_SS_C")
	)
	(segment
		(start 14.66088 -107.70362)
		(end 15.2908 -107.0737)
		(width 0.254)
		(layer "F.Cu")
		(net "VR_P1V26_STBY_SS_C")
	)
	(segment
		(start 15.2908 -107.0737)
		(end 15.2908 -106.1212)
		(width 0.254)
		(layer "F.Cu")
		(net "VR_P1V26_STBY_SS_C")
	)
	(segment
		(start 15.367 -106.045)
		(end 15.494 -105.918)
		(width 0.254)
		(layer "F.Cu")
		(net "VR_P1V26_STBY_SS_C")
	)
	(segment
		(start 15.2908 -106.1212)
		(end 15.367 -106.045)
		(width 0.254)
		(layer "F.Cu")
		(net "VR_P1V26_STBY_SS_C")
	)
	(via
		(at 15.367 -106.045)
		(size 0.7112)
		(drill 0.3556)
		(layers "F.Cu" "B.Cu")
		(net "VR_P1V26_STBY_SS_C")
	)
	(via
		(at 5.08635 -110.541562)
		(size 0.7112)
		(drill 0.3556)
		(layers "F.Cu" "B.Cu")
		(net "VR_P1V26_STBY_IN")
	)
	(segment
		(start 15.0495 -108.204)
		(end 13.7414 -108.204)
		(width 0.254)
		(layer "F.Cu")
		(net "VR_P1V26_STBY_FB")
	)
	(segment
		(start 17.399 -106.8705)
		(end 18.415 -106.8705)
		(width 0.254)
		(layer "F.Cu")
		(net "VR_P1V26_STBY_FB")
	)
	(segment
		(start 16.383 -106.8705)
		(end 17.399 -106.8705)
		(width 0.254)
		(layer "F.Cu")
		(net "VR_P1V26_STBY_FB")
	)
	(segment
		(start 16.383 -106.8705)
		(end 15.0495 -108.204)
		(width 0.254)
		(layer "F.Cu")
		(net "VR_P1V26_STBY_FB")
	)
	(segment
		(start 11.049 -106.934)
		(end 11.049 -106.375708)
		(width 0.254)
		(layer "F.Cu")
		(net "VR_P1V26_STBY_EN_R")
	)
	(segment
		(start 10.77849 -107.20451)
		(end 11.049 -106.934)
		(width 0.254)
		(layer "F.Cu")
		(net "VR_P1V26_STBY_EN_R")
	)
	(segment
		(start 10.6426 -107.20451)
		(end 10.77849 -107.20451)
		(width 0.254)
		(layer "F.Cu")
		(net "VR_P1V26_STBY_EN_R")
	)
	(segment
		(start 11.049 -105.156)
		(end 12.065 -105.156)
		(width 0.254)
		(layer "F.Cu")
		(net "VR_P1V26_STBY_EN_R")
	)
	(segment
		(start 11.049 -106.375708)
		(end 11.049 -105.156)
		(width 0.254)
		(layer "F.Cu")
		(net "VR_P1V26_STBY_EN_R")
	)
	(via
		(at 11.049 -106.375708)
		(size 0.508)
		(drill 0.254)
		(layers "F.Cu" "B.Cu")
		(net "VR_P1V26_STBY_EN_R")
	)
	(via
		(at 12.065 -105.156)
		(size 0.7112)
		(drill 0.3556)
		(layers "F.Cu" "B.Cu")
		(net "VR_P1V26_STBY_EN_R")
	)
	(segment
		(start 10.4775 -107.188)
		(end 10.4775 -106.853228)
		(width 0.254)
		(layer "B.Cu")
		(net "VR_P1V26_STBY_EN_R")
	)
	(segment
		(start 10.4775 -106.853228)
		(end 10.95502 -106.375708)
		(width 0.254)
		(layer "B.Cu")
		(net "VR_P1V26_STBY_EN_R")
	)
	(segment
		(start 10.95502 -106.375708)
		(end 11.049 -106.375708)
		(width 0.254)
		(layer "B.Cu")
		(net "VR_P1V26_STBY_EN_R")
	)
	(segment
		(start 6.4135 -107.696)
		(end 6.879844 -107.696)
		(width 0.254)
		(layer "F.Cu")
		(net "VR_P1V26_STBY_BIAS")
	)
	(segment
		(start 6.4135 -106.7435)
		(end 6.4135 -107.696)
		(width 0.254)
		(layer "F.Cu")
		(net "VR_P1V26_STBY_BIAS")
	)
	(segment
		(start 9.134856 -107.6452)
		(end 9.193276 -107.70362)
		(width 0.254)
		(layer "F.Cu")
		(net "VR_P1V26_STBY_BIAS")
	)
	(segment
		(start 6.930644 -107.6452)
		(end 7.874 -107.6452)
		(width 0.254)
		(layer "F.Cu")
		(net "VR_P1V26_STBY_BIAS")
	)
	(segment
		(start 6.879844 -107.696)
		(end 6.930644 -107.6452)
		(width 0.254)
		(layer "F.Cu")
		(net "VR_P1V26_STBY_BIAS")
	)
	(segment
		(start 7.874 -107.6452)
		(end 9.134856 -107.6452)
		(width 0.254)
		(layer "F.Cu")
		(net "VR_P1V26_STBY_BIAS")
	)
	(segment
		(start 6.477 -106.68)
		(end 6.4135 -106.7435)
		(width 0.254)
		(layer "F.Cu")
		(net "VR_P1V26_STBY_BIAS")
	)
	(segment
		(start 9.193276 -107.70362)
		(end 10.6426 -107.70362)
		(width 0.254)
		(layer "F.Cu")
		(net "VR_P1V26_STBY_BIAS")
	)
	(via
		(at 6.477 -106.68)
		(size 0.7112)
		(drill 0.3556)
		(layers "F.Cu" "B.Cu")
		(net "VR_P1V26_STBY_BIAS")
	)
	(segment
		(start 22.1488 -143.70939)
		(end 21.45411 -143.70939)
		(width 0.508)
		(layer "F.Cu")
		(net "V1PLLAV12")
	)
	(segment
		(start 19.177 -143.8275)
		(end 18.796 -143.4465)
		(width 0.508)
		(layer "F.Cu")
		(net "V1PLLAV12")
	)
	(segment
		(start 20.447 -143.8275)
		(end 21.336 -143.8275)
		(width 0.508)
		(layer "F.Cu")
		(net "V1PLLAV12")
	)
	(segment
		(start 20.447 -143.8275)
		(end 19.177 -143.8275)
		(width 0.508)
		(layer "F.Cu")
		(net "V1PLLAV12")
	)
	(segment
		(start 18.7325 -143.383)
		(end 18.796 -143.4465)
		(width 0.508)
		(layer "F.Cu")
		(net "V1PLLAV12")
	)
	(segment
		(start 31.304738 -137.284968)
		(end 31.704788 -136.884918)
		(width 0.3556)
		(layer "F.Cu")
		(net "V1PLLAV12")
	)
	(segment
		(start 17.2212 -143.383)
		(end 18.7325 -143.383)
		(width 0.508)
		(layer "F.Cu")
		(net "V1PLLAV12")
	)
	(segment
		(start 31.704788 -136.884918)
		(end 32.104838 -136.484868)
		(width 0.3556)
		(layer "F.Cu")
		(net "V1PLLAV12")
	)
	(segment
		(start 21.45411 -143.70939)
		(end 21.336 -143.8275)
		(width 0.508)
		(layer "F.Cu")
		(net "V1PLLAV12")
	)
	(via
		(at 31.704788 -136.884918)
		(size 0.4572)
		(drill 0.2032)
		(layers "F.Cu" "B.Cu")
		(net "V1PLLAV12")
	)
	(via
		(at 22.1488 -143.70939)
		(size 0.508)
		(drill 0.254)
		(layers "F.Cu" "B.Cu")
		(net "V1PLLAV12")
	)
	(via
		(at 31.000192 -137.590022)
		(size 0.7112)
		(drill 0.3556)
		(layers "F.Cu" "B.Cu")
		(net "V1PLLAV12")
	)
	(segment
		(start 31.704788 -136.884918)
		(end 31.000192 -137.589514)
		(width 0.254)
		(layer "B.Cu")
		(net "V1PLLAV12")
	)
	(segment
		(start 31.000192 -137.589514)
		(end 31.000192 -137.590022)
		(width 0.254)
		(layer "B.Cu")
		(net "V1PLLAV12")
	)
	(segment
		(start 22.144736 -143.696944)
		(end 22.1488 -143.69288)
		(width 0.381)
		(layer "In2.Cu")
		(net "V1PLLAV12")
	)
	(segment
		(start 23.904702 -141.73454)
		(end 23.904702 -140.509498)
		(width 0.381)
		(layer "In2.Cu")
		(net "V1PLLAV12")
	)
	(segment
		(start 22.1488 -143.490442)
		(end 23.904702 -141.73454)
		(width 0.381)
		(layer "In2.Cu")
		(net "V1PLLAV12")
	)
	(segment
		(start 22.1488 -143.70939)
		(end 22.144736 -143.70939)
		(width 0.381)
		(layer "In2.Cu")
		(net "V1PLLAV12")
	)
	(segment
		(start 27.0002 -137.414)
		(end 31.175706 -137.414)
		(width 0.381)
		(layer "In2.Cu")
		(net "V1PLLAV12")
	)
	(segment
		(start 22.144736 -143.70939)
		(end 22.144736 -143.696944)
		(width 0.381)
		(layer "In2.Cu")
		(net "V1PLLAV12")
	)
	(segment
		(start 31.175706 -137.414)
		(end 31.704788 -136.884918)
		(width 0.381)
		(layer "In2.Cu")
		(net "V1PLLAV12")
	)
	(segment
		(start 22.1488 -143.69288)
		(end 22.1488 -143.490442)
		(width 0.381)
		(layer "In2.Cu")
		(net "V1PLLAV12")
	)
	(segment
		(start 23.904702 -140.509498)
		(end 27.0002 -137.414)
		(width 0.381)
		(layer "In2.Cu")
		(net "V1PLLAV12")
	)
	(segment
		(start 43.457876 -60.442094)
		(end 43.350942 -60.33516)
		(width 0.12065)
		(layer "F.Cu")
		(net "USB5V_EN")
	)
	(segment
		(start 42.39006 -60.33516)
		(end 41.3766 -60.33516)
		(width 0.12065)
		(layer "F.Cu")
		(net "USB5V_EN")
	)
	(segment
		(start 43.350942 -60.33516)
		(end 42.39006 -60.33516)
		(width 0.12065)
		(layer "F.Cu")
		(net "USB5V_EN")
	)
	(segment
		(start 41.3766 -60.33516)
		(end 39.81196 -58.77052)
		(width 0.12065)
		(layer "F.Cu")
		(net "USB5V_EN")
	)
	(segment
		(start 39.81196 -58.77052)
		(end 39.81196 -58.039)
		(width 0.12065)
		(layer "F.Cu")
		(net "USB5V_EN")
	)
	(via
		(at 42.39006 -60.33516)
		(size 0.7112)
		(drill 0.3556)
		(layers "F.Cu" "B.Cu")
		(net "USB5V_EN")
	)
	(segment
		(start 182.166006 3.263138)
		(end 197.93204 3.263138)
		(width 0.136652)
		(layer "B.Cu")
		(net "USB_P4_DP_BMC")
	)
	(segment
		(start 53.522118 -85.400896)
		(end 51.306222 -83.185)
		(width 0.136652)
		(layer "B.Cu")
		(net "USB_P4_DP_BMC")
	)
	(segment
		(start 265.63701 -15.97025)
		(end 267.358368 -17.691608)
		(width 0.136652)
		(layer "B.Cu")
		(net "USB_P4_DP_BMC")
	)
	(segment
		(start 73.483978 -119.157242)
		(end 73.1266 -118.799864)
		(width 0.136652)
		(layer "B.Cu")
		(net "USB_P4_DP_BMC")
	)
	(segment
		(start 262.485378 -10.35177)
		(end 263.69137 -10.35177)
		(width 0.136652)
		(layer "B.Cu")
		(net "USB_P4_DP_BMC")
	)
	(segment
		(start 227.613972 3.339846)
		(end 230.48976 0.464058)
		(width 0.136652)
		(layer "B.Cu")
		(net "USB_P4_DP_BMC")
	)
	(segment
		(start 258.002024 -9.764776)
		(end 259.02031 -9.764776)
		(width 0.136652)
		(layer "B.Cu")
		(net "USB_P4_DP_BMC")
	)
	(segment
		(start 230.48976 0.464058)
		(end 230.48976 -3.845306)
		(width 0.136652)
		(layer "B.Cu")
		(net "USB_P4_DP_BMC")
	)
	(segment
		(start 259.02031 -9.764776)
		(end 259.567934 -9.217152)
		(width 0.136652)
		(layer "B.Cu")
		(net "USB_P4_DP_BMC")
	)
	(segment
		(start 73.483978 -121.595134)
		(end 73.483978 -119.157242)
		(width 0.136652)
		(layer "B.Cu")
		(net "USB_P4_DP_BMC")
	)
	(segment
		(start 90.066368 -54.99354)
		(end 90.066368 -49.177448)
		(width 0.136652)
		(layer "B.Cu")
		(net "USB_P4_DP_BMC")
	)
	(segment
		(start 268.385036 -17.691608)
		(end 268.705584 -17.37106)
		(width 0.136652)
		(layer "B.Cu")
		(net "USB_P4_DP_BMC")
	)
	(segment
		(start 197.93204 3.263138)
		(end 198.38543 3.716528)
		(width 0.136652)
		(layer "B.Cu")
		(net "USB_P4_DP_BMC")
	)
	(segment
		(start 126.744222 -15.391384)
		(end 126.744222 -7.267194)
		(width 0.136652)
		(layer "B.Cu")
		(net "USB_P4_DP_BMC")
	)
	(segment
		(start 74.840084 -129.016252)
		(end 74.840084 -122.95124)
		(width 0.136652)
		(layer "B.Cu")
		(net "USB_P4_DP_BMC")
	)
	(segment
		(start 51.306222 -80.215486)
		(end 58.100214 -73.421494)
		(width 0.136652)
		(layer "B.Cu")
		(net "USB_P4_DP_BMC")
	)
	(segment
		(start 72.25919 -131.597146)
		(end 74.840084 -129.016252)
		(width 0.136652)
		(layer "B.Cu")
		(net "USB_P4_DP_BMC")
	)
	(segment
		(start 51.9811 -129.7686)
		(end 52.208176 -129.995676)
		(width 0.136652)
		(layer "B.Cu")
		(net "USB_P4_DP_BMC")
	)
	(segment
		(start 209.541618 3.716528)
		(end 209.9183 3.339846)
		(width 0.136652)
		(layer "B.Cu")
		(net "USB_P4_DP_BMC")
	)
	(segment
		(start 230.48976 -3.845306)
		(end 231.368854 -4.7244)
		(width 0.136652)
		(layer "B.Cu")
		(net "USB_P4_DP_BMC")
	)
	(segment
		(start 126.744222 -7.267194)
		(end 132.786628 -1.224788)
		(width 0.136652)
		(layer "B.Cu")
		(net "USB_P4_DP_BMC")
	)
	(segment
		(start 51.306222 -83.185)
		(end 51.306222 -80.215486)
		(width 0.136652)
		(layer "B.Cu")
		(net "USB_P4_DP_BMC")
	)
	(segment
		(start 246.158512 -7.047992)
		(end 246.649494 -7.538974)
		(width 0.136652)
		(layer "B.Cu")
		(net "USB_P4_DP_BMC")
	)
	(segment
		(start 57.192418 -129.684526)
		(end 60.418218 -129.684526)
		(width 0.136652)
		(layer "B.Cu")
		(net "USB_P4_DP_BMC")
	)
	(segment
		(start 259.567934 -9.217152)
		(end 261.35076 -9.217152)
		(width 0.136652)
		(layer "B.Cu")
		(net "USB_P4_DP_BMC")
	)
	(segment
		(start 246.649494 -7.538974)
		(end 251.841 -7.538974)
		(width 0.136652)
		(layer "B.Cu")
		(net "USB_P4_DP_BMC")
	)
	(segment
		(start 57.2008 -91.059)
		(end 53.522118 -87.380318)
		(width 0.136652)
		(layer "B.Cu")
		(net "USB_P4_DP_BMC")
	)
	(segment
		(start 74.840084 -122.95124)
		(end 73.483978 -121.595134)
		(width 0.136652)
		(layer "B.Cu")
		(net "USB_P4_DP_BMC")
	)
	(segment
		(start 62.31636 -73.421494)
		(end 77.584554 -58.1533)
		(width 0.136652)
		(layer "B.Cu")
		(net "USB_P4_DP_BMC")
	)
	(segment
		(start 53.522118 -87.380318)
		(end 53.522118 -85.400896)
		(width 0.136652)
		(layer "B.Cu")
		(net "USB_P4_DP_BMC")
	)
	(segment
		(start 55.363364 -128.445768)
		(end 55.378858 -128.430274)
		(width 0.136652)
		(layer "B.Cu")
		(net "USB_P4_DP_BMC")
	)
	(segment
		(start 77.584554 -58.1533)
		(end 86.906608 -58.1533)
		(width 0.136652)
		(layer "B.Cu")
		(net "USB_P4_DP_BMC")
	)
	(segment
		(start 52.56022 -130.141472)
		(end 52.944268 -130.141472)
		(width 0.136652)
		(layer "B.Cu")
		(net "USB_P4_DP_BMC")
	)
	(segment
		(start 255.545336 -11.24331)
		(end 256.52349 -11.24331)
		(width 0.136652)
		(layer "B.Cu")
		(net "USB_P4_DP_BMC")
	)
	(segment
		(start 261.35076 -9.217152)
		(end 262.485378 -10.35177)
		(width 0.136652)
		(layer "B.Cu")
		(net "USB_P4_DP_BMC")
	)
	(segment
		(start 56.025542 -128.430274)
		(end 56.481726 -128.886458)
		(width 0.136652)
		(layer "B.Cu")
		(net "USB_P4_DP_BMC")
	)
	(segment
		(start 56.481726 -128.973834)
		(end 57.192418 -129.684526)
		(width 0.136652)
		(layer "B.Cu")
		(net "USB_P4_DP_BMC")
	)
	(segment
		(start 110.374938 -29.350462)
		(end 115.6462 -24.0792)
		(width 0.136652)
		(layer "B.Cu")
		(net "USB_P4_DP_BMC")
	)
	(segment
		(start 86.906608 -58.1533)
		(end 90.066368 -54.99354)
		(width 0.136652)
		(layer "B.Cu")
		(net "USB_P4_DP_BMC")
	)
	(segment
		(start 58.100214 -73.421494)
		(end 62.31636 -73.421494)
		(width 0.136652)
		(layer "B.Cu")
		(net "USB_P4_DP_BMC")
	)
	(segment
		(start 55.378858 -128.430274)
		(end 56.025542 -128.430274)
		(width 0.136652)
		(layer "B.Cu")
		(net "USB_P4_DP_BMC")
	)
	(segment
		(start 53.201062 -130.035046)
		(end 54.79034 -128.445768)
		(width 0.136652)
		(layer "B.Cu")
		(net "USB_P4_DP_BMC")
	)
	(segment
		(start 60.418218 -129.684526)
		(end 62.330838 -131.597146)
		(width 0.136652)
		(layer "B.Cu")
		(net "USB_P4_DP_BMC")
	)
	(segment
		(start 251.841 -7.538974)
		(end 255.545336 -11.24331)
		(width 0.136652)
		(layer "B.Cu")
		(net "USB_P4_DP_BMC")
	)
	(segment
		(start 62.330838 -131.597146)
		(end 72.25919 -131.597146)
		(width 0.136652)
		(layer "B.Cu")
		(net "USB_P4_DP_BMC")
	)
	(segment
		(start 99.768152 -39.475664)
		(end 99.768152 -36.706556)
		(width 0.136652)
		(layer "B.Cu")
		(net "USB_P4_DP_BMC")
	)
	(segment
		(start 107.124246 -29.350462)
		(end 110.374938 -29.350462)
		(width 0.136652)
		(layer "B.Cu")
		(net "USB_P4_DP_BMC")
	)
	(segment
		(start 90.066368 -49.177448)
		(end 99.768152 -39.475664)
		(width 0.136652)
		(layer "B.Cu")
		(net "USB_P4_DP_BMC")
	)
	(segment
		(start 56.481726 -128.886458)
		(end 56.481726 -128.973834)
		(width 0.136652)
		(layer "B.Cu")
		(net "USB_P4_DP_BMC")
	)
	(segment
		(start 267.358368 -17.691608)
		(end 268.385036 -17.691608)
		(width 0.136652)
		(layer "B.Cu")
		(net "USB_P4_DP_BMC")
	)
	(segment
		(start 209.9183 3.339846)
		(end 227.613972 3.339846)
		(width 0.136652)
		(layer "B.Cu")
		(net "USB_P4_DP_BMC")
	)
	(segment
		(start 132.786628 -1.224788)
		(end 177.67808 -1.224788)
		(width 0.136652)
		(layer "B.Cu")
		(net "USB_P4_DP_BMC")
	)
	(segment
		(start 73.1266 -105.463848)
		(end 58.720736 -91.059)
		(width 0.136652)
		(layer "B.Cu")
		(net "USB_P4_DP_BMC")
	)
	(segment
		(start 118.056406 -24.0792)
		(end 126.744222 -15.391384)
		(width 0.136652)
		(layer "B.Cu")
		(net "USB_P4_DP_BMC")
	)
	(segment
		(start 265.63701 -12.29741)
		(end 265.63701 -15.97025)
		(width 0.136652)
		(layer "B.Cu")
		(net "USB_P4_DP_BMC")
	)
	(segment
		(start 245.5418 -4.7244)
		(end 246.158512 -5.341112)
		(width 0.136652)
		(layer "B.Cu")
		(net "USB_P4_DP_BMC")
	)
	(segment
		(start 246.158512 -5.341112)
		(end 246.158512 -7.047992)
		(width 0.136652)
		(layer "B.Cu")
		(net "USB_P4_DP_BMC")
	)
	(segment
		(start 263.69137 -10.35177)
		(end 265.63701 -12.29741)
		(width 0.136652)
		(layer "B.Cu")
		(net "USB_P4_DP_BMC")
	)
	(segment
		(start 73.1266 -118.799864)
		(end 73.1266 -105.463848)
		(width 0.136652)
		(layer "B.Cu")
		(net "USB_P4_DP_BMC")
	)
	(segment
		(start 231.368854 -4.7244)
		(end 245.5418 -4.7244)
		(width 0.136652)
		(layer "B.Cu")
		(net "USB_P4_DP_BMC")
	)
	(segment
		(start 54.79034 -128.445768)
		(end 55.363364 -128.445768)
		(width 0.136652)
		(layer "B.Cu")
		(net "USB_P4_DP_BMC")
	)
	(segment
		(start 256.52349 -11.24331)
		(end 258.002024 -9.764776)
		(width 0.136652)
		(layer "B.Cu")
		(net "USB_P4_DP_BMC")
	)
	(segment
		(start 115.6462 -24.0792)
		(end 118.056406 -24.0792)
		(width 0.136652)
		(layer "B.Cu")
		(net "USB_P4_DP_BMC")
	)
	(segment
		(start 99.768152 -36.706556)
		(end 107.124246 -29.350462)
		(width 0.136652)
		(layer "B.Cu")
		(net "USB_P4_DP_BMC")
	)
	(segment
		(start 177.67808 -1.224788)
		(end 182.166006 3.263138)
		(width 0.136652)
		(layer "B.Cu")
		(net "USB_P4_DP_BMC")
	)
	(segment
		(start 58.720736 -91.059)
		(end 57.2008 -91.059)
		(width 0.136652)
		(layer "B.Cu")
		(net "USB_P4_DP_BMC")
	)
	(segment
		(start 198.38543 3.716528)
		(end 209.541618 3.716528)
		(width 0.136652)
		(layer "B.Cu")
		(net "USB_P4_DP_BMC")
	)
	(arc
		(start 52.208176 -129.995676)
		(mid 52.369695 -130.1036)
		(end 52.56022 -130.141472)
		(width 0.136652)
		(layer "B.Cu")
		(net "USB_P4_DP_BMC")
	)
	(arc
		(start 52.944268 -130.141472)
		(mid 53.083252 -130.113808)
		(end 53.201062 -130.035046)
		(width 0.136652)
		(layer "B.Cu")
		(net "USB_P4_DP_BMC")
	)
	(segment
		(start 265.33221 -12.423902)
		(end 265.33221 -16.096742)
		(width 0.136652)
		(layer "B.Cu")
		(net "USB_P4_DN_BMC")
	)
	(segment
		(start 263.564878 -10.65657)
		(end 265.33221 -12.423902)
		(width 0.136652)
		(layer "B.Cu")
		(net "USB_P4_DN_BMC")
	)
	(segment
		(start 90.371168 -49.30394)
		(end 100.072952 -39.602156)
		(width 0.136652)
		(layer "B.Cu")
		(net "USB_P4_DN_BMC")
	)
	(segment
		(start 100.072952 -39.602156)
		(end 100.072952 -36.833048)
		(width 0.136652)
		(layer "B.Cu")
		(net "USB_P4_DN_BMC")
	)
	(segment
		(start 62.442852 -73.726294)
		(end 77.711046 -58.4581)
		(width 0.136652)
		(layer "B.Cu")
		(net "USB_P4_DN_BMC")
	)
	(segment
		(start 177.804572 -1.529588)
		(end 182.292498 2.958338)
		(width 0.136652)
		(layer "B.Cu")
		(net "USB_P4_DN_BMC")
	)
	(segment
		(start 209.415126 3.411728)
		(end 209.791808 3.035046)
		(width 0.136652)
		(layer "B.Cu")
		(net "USB_P4_DN_BMC")
	)
	(segment
		(start 246.523002 -7.843774)
		(end 251.714508 -7.843774)
		(width 0.136652)
		(layer "B.Cu")
		(net "USB_P4_DN_BMC")
	)
	(segment
		(start 245.853712 -7.174484)
		(end 246.523002 -7.843774)
		(width 0.136652)
		(layer "B.Cu")
		(net "USB_P4_DN_BMC")
	)
	(segment
		(start 51.611022 -80.341978)
		(end 58.226706 -73.726294)
		(width 0.136652)
		(layer "B.Cu")
		(net "USB_P4_DN_BMC")
	)
	(segment
		(start 132.91312 -1.529588)
		(end 177.804572 -1.529588)
		(width 0.136652)
		(layer "B.Cu")
		(net "USB_P4_DN_BMC")
	)
	(segment
		(start 227.48748 3.035046)
		(end 230.18496 0.337566)
		(width 0.136652)
		(layer "B.Cu")
		(net "USB_P4_DN_BMC")
	)
	(segment
		(start 51.611022 -83.058508)
		(end 51.611022 -80.341978)
		(width 0.136652)
		(layer "B.Cu")
		(net "USB_P4_DN_BMC")
	)
	(segment
		(start 55.89905 -128.735074)
		(end 56.176926 -129.01295)
		(width 0.136652)
		(layer "B.Cu")
		(net "USB_P4_DN_BMC")
	)
	(segment
		(start 53.826918 -85.274404)
		(end 51.611022 -83.058508)
		(width 0.136652)
		(layer "B.Cu")
		(net "USB_P4_DN_BMC")
	)
	(segment
		(start 251.714508 -7.843774)
		(end 255.418844 -11.54811)
		(width 0.136652)
		(layer "B.Cu")
		(net "USB_P4_DN_BMC")
	)
	(segment
		(start 265.33221 -16.096742)
		(end 267.231876 -17.996408)
		(width 0.136652)
		(layer "B.Cu")
		(net "USB_P4_DN_BMC")
	)
	(segment
		(start 261.224268 -9.521952)
		(end 262.358886 -10.65657)
		(width 0.136652)
		(layer "B.Cu")
		(net "USB_P4_DN_BMC")
	)
	(segment
		(start 259.694426 -9.521952)
		(end 261.224268 -9.521952)
		(width 0.136652)
		(layer "B.Cu")
		(net "USB_P4_DN_BMC")
	)
	(segment
		(start 75.144884 -122.824748)
		(end 73.788778 -121.468642)
		(width 0.136652)
		(layer "B.Cu")
		(net "USB_P4_DN_BMC")
	)
	(segment
		(start 62.204346 -131.901946)
		(end 72.385682 -131.901946)
		(width 0.136652)
		(layer "B.Cu")
		(net "USB_P4_DN_BMC")
	)
	(segment
		(start 118.182898 -24.384)
		(end 127.049022 -15.517876)
		(width 0.136652)
		(layer "B.Cu")
		(net "USB_P4_DN_BMC")
	)
	(segment
		(start 58.847228 -90.7542)
		(end 57.327292 -90.7542)
		(width 0.136652)
		(layer "B.Cu")
		(net "USB_P4_DN_BMC")
	)
	(segment
		(start 256.649982 -11.54811)
		(end 258.128516 -10.069576)
		(width 0.136652)
		(layer "B.Cu")
		(net "USB_P4_DN_BMC")
	)
	(segment
		(start 56.176926 -129.01295)
		(end 56.176926 -129.100326)
		(width 0.136652)
		(layer "B.Cu")
		(net "USB_P4_DN_BMC")
	)
	(segment
		(start 57.327292 -90.7542)
		(end 53.826918 -87.253826)
		(width 0.136652)
		(layer "B.Cu")
		(net "USB_P4_DN_BMC")
	)
	(segment
		(start 55.489856 -128.750568)
		(end 55.50535 -128.735074)
		(width 0.136652)
		(layer "B.Cu")
		(net "USB_P4_DN_BMC")
	)
	(segment
		(start 73.4314 -118.673372)
		(end 73.4314 -105.337356)
		(width 0.136652)
		(layer "B.Cu")
		(net "USB_P4_DN_BMC")
	)
	(segment
		(start 75.144884 -129.142744)
		(end 75.144884 -122.824748)
		(width 0.136652)
		(layer "B.Cu")
		(net "USB_P4_DN_BMC")
	)
	(segment
		(start 245.415054 -5.029454)
		(end 245.415308 -5.0292)
		(width 0.136652)
		(layer "B.Cu")
		(net "USB_P4_DN_BMC")
	)
	(segment
		(start 100.072952 -36.833048)
		(end 107.250738 -29.655262)
		(width 0.136652)
		(layer "B.Cu")
		(net "USB_P4_DN_BMC")
	)
	(segment
		(start 231.242616 -5.029454)
		(end 245.415054 -5.029454)
		(width 0.136652)
		(layer "B.Cu")
		(net "USB_P4_DN_BMC")
	)
	(segment
		(start 259.146802 -10.069576)
		(end 259.694426 -9.521952)
		(width 0.136652)
		(layer "B.Cu")
		(net "USB_P4_DN_BMC")
	)
	(segment
		(start 245.415308 -5.0292)
		(end 245.853712 -5.467604)
		(width 0.136652)
		(layer "B.Cu")
		(net "USB_P4_DN_BMC")
	)
	(segment
		(start 55.50535 -128.735074)
		(end 55.89905 -128.735074)
		(width 0.136652)
		(layer "B.Cu")
		(net "USB_P4_DN_BMC")
	)
	(segment
		(start 262.358886 -10.65657)
		(end 263.564878 -10.65657)
		(width 0.136652)
		(layer "B.Cu")
		(net "USB_P4_DN_BMC")
	)
	(segment
		(start 268.312392 -17.996408)
		(end 268.705584 -18.3896)
		(width 0.136652)
		(layer "B.Cu")
		(net "USB_P4_DN_BMC")
	)
	(segment
		(start 230.18496 0.337566)
		(end 230.18496 -3.971798)
		(width 0.136652)
		(layer "B.Cu")
		(net "USB_P4_DN_BMC")
	)
	(segment
		(start 258.128516 -10.069576)
		(end 259.146802 -10.069576)
		(width 0.136652)
		(layer "B.Cu")
		(net "USB_P4_DN_BMC")
	)
	(segment
		(start 54.916832 -128.750568)
		(end 55.489856 -128.750568)
		(width 0.136652)
		(layer "B.Cu")
		(net "USB_P4_DN_BMC")
	)
	(segment
		(start 58.226706 -73.726294)
		(end 62.442852 -73.726294)
		(width 0.136652)
		(layer "B.Cu")
		(net "USB_P4_DN_BMC")
	)
	(segment
		(start 73.788778 -119.03075)
		(end 73.4314 -118.673372)
		(width 0.136652)
		(layer "B.Cu")
		(net "USB_P4_DN_BMC")
	)
	(segment
		(start 255.418844 -11.54811)
		(end 256.649982 -11.54811)
		(width 0.136652)
		(layer "B.Cu")
		(net "USB_P4_DN_BMC")
	)
	(segment
		(start 127.049022 -7.393686)
		(end 132.91312 -1.529588)
		(width 0.136652)
		(layer "B.Cu")
		(net "USB_P4_DN_BMC")
	)
	(segment
		(start 57.065926 -129.989326)
		(end 60.291726 -129.989326)
		(width 0.136652)
		(layer "B.Cu")
		(net "USB_P4_DN_BMC")
	)
	(segment
		(start 115.772692 -24.384)
		(end 118.182898 -24.384)
		(width 0.136652)
		(layer "B.Cu")
		(net "USB_P4_DN_BMC")
	)
	(segment
		(start 52.534058 -130.446272)
		(end 52.944014 -130.446272)
		(width 0.136652)
		(layer "B.Cu")
		(net "USB_P4_DN_BMC")
	)
	(segment
		(start 209.791808 3.035046)
		(end 227.48748 3.035046)
		(width 0.136652)
		(layer "B.Cu")
		(net "USB_P4_DN_BMC")
	)
	(segment
		(start 53.826918 -87.253826)
		(end 53.826918 -85.274404)
		(width 0.136652)
		(layer "B.Cu")
		(net "USB_P4_DN_BMC")
	)
	(segment
		(start 73.788778 -121.468642)
		(end 73.788778 -119.03075)
		(width 0.136652)
		(layer "B.Cu")
		(net "USB_P4_DN_BMC")
	)
	(segment
		(start 245.853712 -5.467604)
		(end 245.853712 -7.174484)
		(width 0.136652)
		(layer "B.Cu")
		(net "USB_P4_DN_BMC")
	)
	(segment
		(start 127.049022 -15.517876)
		(end 127.049022 -7.393686)
		(width 0.136652)
		(layer "B.Cu")
		(net "USB_P4_DN_BMC")
	)
	(segment
		(start 73.4314 -105.337356)
		(end 58.847228 -90.7542)
		(width 0.136652)
		(layer "B.Cu")
		(net "USB_P4_DN_BMC")
	)
	(segment
		(start 51.9811 -130.7846)
		(end 52.16779 -130.598164)
		(width 0.136652)
		(layer "B.Cu")
		(net "USB_P4_DN_BMC")
	)
	(segment
		(start 110.50143 -29.655262)
		(end 115.772692 -24.384)
		(width 0.136652)
		(layer "B.Cu")
		(net "USB_P4_DN_BMC")
	)
	(segment
		(start 182.292498 2.958338)
		(end 198.058532 2.958338)
		(width 0.136652)
		(layer "B.Cu")
		(net "USB_P4_DN_BMC")
	)
	(segment
		(start 87.0331 -58.4581)
		(end 90.371168 -55.120032)
		(width 0.136652)
		(layer "B.Cu")
		(net "USB_P4_DN_BMC")
	)
	(segment
		(start 107.250738 -29.655262)
		(end 110.50143 -29.655262)
		(width 0.136652)
		(layer "B.Cu")
		(net "USB_P4_DN_BMC")
	)
	(segment
		(start 198.058532 2.958338)
		(end 198.511922 3.411728)
		(width 0.136652)
		(layer "B.Cu")
		(net "USB_P4_DN_BMC")
	)
	(segment
		(start 198.511922 3.411728)
		(end 209.415126 3.411728)
		(width 0.136652)
		(layer "B.Cu")
		(net "USB_P4_DN_BMC")
	)
	(segment
		(start 267.231876 -17.996408)
		(end 268.312392 -17.996408)
		(width 0.136652)
		(layer "B.Cu")
		(net "USB_P4_DN_BMC")
	)
	(segment
		(start 90.371168 -55.120032)
		(end 90.371168 -49.30394)
		(width 0.136652)
		(layer "B.Cu")
		(net "USB_P4_DN_BMC")
	)
	(segment
		(start 53.416708 -130.250692)
		(end 54.916832 -128.750568)
		(width 0.136652)
		(layer "B.Cu")
		(net "USB_P4_DN_BMC")
	)
	(segment
		(start 72.385682 -131.901946)
		(end 75.144884 -129.142744)
		(width 0.136652)
		(layer "B.Cu")
		(net "USB_P4_DN_BMC")
	)
	(segment
		(start 77.711046 -58.4581)
		(end 87.0331 -58.4581)
		(width 0.136652)
		(layer "B.Cu")
		(net "USB_P4_DN_BMC")
	)
	(segment
		(start 230.18496 -3.971798)
		(end 231.242616 -5.029454)
		(width 0.136652)
		(layer "B.Cu")
		(net "USB_P4_DN_BMC")
	)
	(segment
		(start 56.176926 -129.100326)
		(end 57.065926 -129.989326)
		(width 0.136652)
		(layer "B.Cu")
		(net "USB_P4_DN_BMC")
	)
	(segment
		(start 60.291726 -129.989326)
		(end 62.204346 -131.901946)
		(width 0.136652)
		(layer "B.Cu")
		(net "USB_P4_DN_BMC")
	)
	(arc
		(start 52.944014 -130.446272)
		(mid 53.19983 -130.395539)
		(end 53.416708 -130.250692)
		(width 0.136652)
		(layer "B.Cu")
		(net "USB_P4_DN_BMC")
	)
	(arc
		(start 52.16779 -130.598164)
		(mid 52.33582 -130.485797)
		(end 52.534058 -130.446272)
		(width 0.136652)
		(layer "B.Cu")
		(net "USB_P4_DN_BMC")
	)
	(segment
		(start 56.175656 -127.846074)
		(end 54.503574 -127.846074)
		(width 0.136652)
		(layer "F.Cu")
		(net "USB_P2_DP")
	)
	(segment
		(start 65.344294 -128.259332)
		(end 64.346582 -128.259332)
		(width 0.136652)
		(layer "F.Cu")
		(net "USB_P2_DP")
	)
	(segment
		(start 65.584832 -128.018794)
		(end 65.344294 -128.259332)
		(width 0.136652)
		(layer "F.Cu")
		(net "USB_P2_DP")
	)
	(segment
		(start 54.503574 -127.846074)
		(end 54.1655 -127.508)
		(width 0.136652)
		(layer "F.Cu")
		(net "USB_P2_DP")
	)
	(segment
		(start 57.215278 -126.806452)
		(end 56.175656 -127.846074)
		(width 0.136652)
		(layer "F.Cu")
		(net "USB_P2_DP")
	)
	(segment
		(start 63.92545 -127.8382)
		(end 59.0042 -127.8382)
		(width 0.136652)
		(layer "F.Cu")
		(net "USB_P2_DP")
	)
	(segment
		(start 57.972452 -126.806452)
		(end 57.215278 -126.806452)
		(width 0.136652)
		(layer "F.Cu")
		(net "USB_P2_DP")
	)
	(segment
		(start 64.346582 -128.259332)
		(end 63.92545 -127.8382)
		(width 0.136652)
		(layer "F.Cu")
		(net "USB_P2_DP")
	)
	(segment
		(start 65.584832 -127.93345)
		(end 65.584832 -128.018794)
		(width 0.136652)
		(layer "F.Cu")
		(net "USB_P2_DP")
	)
	(segment
		(start 65.330578 -127.679196)
		(end 65.584832 -127.93345)
		(width 0.136652)
		(layer "F.Cu")
		(net "USB_P2_DP")
	)
	(segment
		(start 59.0042 -127.8382)
		(end 57.972452 -126.806452)
		(width 0.136652)
		(layer "F.Cu")
		(net "USB_P2_DP")
	)
	(via
		(at 65.330578 -127.679196)
		(size 0.508)
		(drill 0.254)
		(layers "F.Cu" "B.Cu")
		(net "USB_P2_DP")
	)
	(segment
		(start 68.8086 -118.491)
		(end 68.8086 -106.096308)
		(width 0.136652)
		(layer "B.Cu")
		(net "USB_P2_DP")
	)
	(segment
		(start 65.588896 -127.937514)
		(end 65.588896 -129.066036)
		(width 0.136652)
		(layer "B.Cu")
		(net "USB_P2_DP")
	)
	(segment
		(start 53.004974 -52.810918)
		(end 53.361844 -52.454048)
		(width 0.136652)
		(layer "B.Cu")
		(net "USB_P2_DP")
	)
	(segment
		(start 53.361844 -52.454048)
		(end 53.361844 -52.0319)
		(width 0.136652)
		(layer "B.Cu")
		(net "USB_P2_DP")
	)
	(segment
		(start 70.82282 -120.50522)
		(end 68.8086 -118.491)
		(width 0.136652)
		(layer "B.Cu")
		(net "USB_P2_DP")
	)
	(segment
		(start 66.00571 -129.48285)
		(end 70.03669 -129.48285)
		(width 0.136652)
		(layer "B.Cu")
		(net "USB_P2_DP")
	)
	(segment
		(start 56.150764 -63.400686)
		(end 53.004974 -60.254896)
		(width 0.136652)
		(layer "B.Cu")
		(net "USB_P2_DP")
	)
	(segment
		(start 52.3494 -85.60689)
		(end 50.243486 -83.500976)
		(width 0.136652)
		(layer "B.Cu")
		(net "USB_P2_DP")
	)
	(segment
		(start 52.3494 -89.637108)
		(end 52.3494 -85.60689)
		(width 0.136652)
		(layer "B.Cu")
		(net "USB_P2_DP")
	)
	(segment
		(start 50.243486 -79.481934)
		(end 56.150764 -73.574656)
		(width 0.136652)
		(layer "B.Cu")
		(net "USB_P2_DP")
	)
	(segment
		(start 65.330578 -127.679196)
		(end 65.588896 -127.937514)
		(width 0.136652)
		(layer "B.Cu")
		(net "USB_P2_DP")
	)
	(segment
		(start 53.004974 -60.254896)
		(end 53.004974 -52.810918)
		(width 0.136652)
		(layer "B.Cu")
		(net "USB_P2_DP")
	)
	(segment
		(start 56.150764 -73.574656)
		(end 56.150764 -63.400686)
		(width 0.136652)
		(layer "B.Cu")
		(net "USB_P2_DP")
	)
	(segment
		(start 65.588896 -129.066036)
		(end 66.00571 -129.48285)
		(width 0.136652)
		(layer "B.Cu")
		(net "USB_P2_DP")
	)
	(segment
		(start 70.82282 -128.69672)
		(end 70.82282 -120.50522)
		(width 0.136652)
		(layer "B.Cu")
		(net "USB_P2_DP")
	)
	(segment
		(start 68.8086 -106.096308)
		(end 52.3494 -89.637108)
		(width 0.136652)
		(layer "B.Cu")
		(net "USB_P2_DP")
	)
	(segment
		(start 50.243486 -83.500976)
		(end 50.243486 -79.481934)
		(width 0.136652)
		(layer "B.Cu")
		(net "USB_P2_DP")
	)
	(segment
		(start 70.03669 -129.48285)
		(end 70.82282 -128.69672)
		(width 0.136652)
		(layer "B.Cu")
		(net "USB_P2_DP")
	)
	(segment
		(start 65.470786 -128.564132)
		(end 64.22009 -128.564132)
		(width 0.136652)
		(layer "F.Cu")
		(net "USB_P2_DN")
	)
	(segment
		(start 57.84596 -127.111252)
		(end 57.34177 -127.111252)
		(width 0.136652)
		(layer "F.Cu")
		(net "USB_P2_DN")
	)
	(segment
		(start 58.877708 -128.143)
		(end 57.84596 -127.111252)
		(width 0.136652)
		(layer "F.Cu")
		(net "USB_P2_DN")
	)
	(segment
		(start 64.22009 -128.564132)
		(end 63.798958 -128.143)
		(width 0.136652)
		(layer "F.Cu")
		(net "USB_P2_DN")
	)
	(segment
		(start 63.798958 -128.143)
		(end 58.877708 -128.143)
		(width 0.136652)
		(layer "F.Cu")
		(net "USB_P2_DN")
	)
	(segment
		(start 57.34177 -127.111252)
		(end 56.302148 -128.150874)
		(width 0.136652)
		(layer "F.Cu")
		(net "USB_P2_DN")
	)
	(segment
		(start 56.302148 -128.150874)
		(end 54.538626 -128.150874)
		(width 0.136652)
		(layer "F.Cu")
		(net "USB_P2_DN")
	)
	(segment
		(start 54.538626 -128.150874)
		(end 54.1655 -128.524)
		(width 0.136652)
		(layer "F.Cu")
		(net "USB_P2_DN")
	)
	(segment
		(start 66.143378 -127.679196)
		(end 65.889632 -127.932942)
		(width 0.136652)
		(layer "F.Cu")
		(net "USB_P2_DN")
	)
	(segment
		(start 65.889632 -128.145286)
		(end 65.470786 -128.564132)
		(width 0.136652)
		(layer "F.Cu")
		(net "USB_P2_DN")
	)
	(segment
		(start 65.889632 -127.932942)
		(end 65.889632 -128.145286)
		(width 0.136652)
		(layer "F.Cu")
		(net "USB_P2_DN")
	)
	(via
		(at 66.143378 -127.679196)
		(size 0.508)
		(drill 0.254)
		(layers "F.Cu" "B.Cu")
		(net "USB_P2_DN")
	)
	(segment
		(start 52.343304 -52.454048)
		(end 52.700174 -52.810918)
		(width 0.136652)
		(layer "B.Cu")
		(net "USB_P2_DN")
	)
	(segment
		(start 52.343304 -52.0319)
		(end 52.343304 -52.454048)
		(width 0.136652)
		(layer "B.Cu")
		(net "USB_P2_DN")
	)
	(segment
		(start 55.845964 -73.448164)
		(end 49.938686 -79.355442)
		(width 0.136652)
		(layer "B.Cu")
		(net "USB_P2_DN")
	)
	(segment
		(start 65.893696 -127.928878)
		(end 66.143378 -127.679196)
		(width 0.136652)
		(layer "B.Cu")
		(net "USB_P2_DN")
	)
	(segment
		(start 63.920116 -101.639116)
		(end 63.920116 -101.858826)
		(width 0.136652)
		(layer "B.Cu")
		(net "USB_P2_DN")
	)
	(segment
		(start 68.5038 -118.617492)
		(end 70.51802 -120.631712)
		(width 0.136652)
		(layer "B.Cu")
		(net "USB_P2_DN")
	)
	(segment
		(start 65.5193 -103.45801)
		(end 65.809114 -103.748078)
		(width 0.136652)
		(layer "B.Cu")
		(net "USB_P2_DN")
	)
	(segment
		(start 68.5038 -106.2228)
		(end 68.5038 -118.617492)
		(width 0.136652)
		(layer "B.Cu")
		(net "USB_P2_DN")
	)
	(segment
		(start 64.719708 -102.438708)
		(end 64.719708 -102.658418)
		(width 0.136652)
		(layer "B.Cu")
		(net "USB_P2_DN")
	)
	(segment
		(start 70.51802 -128.570228)
		(end 69.910198 -129.17805)
		(width 0.136652)
		(layer "B.Cu")
		(net "USB_P2_DN")
	)
	(segment
		(start 66.318892 -104.257602)
		(end 66.608706 -104.54767)
		(width 0.136652)
		(layer "B.Cu")
		(net "USB_P2_DN")
	)
	(segment
		(start 65.009522 -102.948486)
		(end 65.229486 -102.948486)
		(width 0.136652)
		(layer "B.Cu")
		(net "USB_P2_DN")
	)
	(segment
		(start 55.845964 -63.527178)
		(end 55.845964 -73.448164)
		(width 0.136652)
		(layer "B.Cu")
		(net "USB_P2_DN")
	)
	(segment
		(start 63.920116 -101.858826)
		(end 64.20993 -102.148894)
		(width 0.136652)
		(layer "B.Cu")
		(net "USB_P2_DN")
	)
	(segment
		(start 66.608706 -104.54767)
		(end 66.82867 -104.54767)
		(width 0.136652)
		(layer "B.Cu")
		(net "USB_P2_DN")
	)
	(segment
		(start 49.938686 -79.355442)
		(end 49.938686 -83.627468)
		(width 0.136652)
		(layer "B.Cu")
		(net "USB_P2_DN")
	)
	(segment
		(start 65.229486 -102.948486)
		(end 65.5193 -103.2383)
		(width 0.136652)
		(layer "B.Cu")
		(net "USB_P2_DN")
	)
	(segment
		(start 70.51802 -120.631712)
		(end 70.51802 -128.570228)
		(width 0.136652)
		(layer "B.Cu")
		(net "USB_P2_DN")
	)
	(segment
		(start 66.132202 -129.17805)
		(end 65.893696 -128.939544)
		(width 0.136652)
		(layer "B.Cu")
		(net "USB_P2_DN")
	)
	(segment
		(start 52.0446 -89.7636)
		(end 63.920116 -101.639116)
		(width 0.136652)
		(layer "B.Cu")
		(net "USB_P2_DN")
	)
	(segment
		(start 66.029078 -103.748078)
		(end 66.318892 -104.037892)
		(width 0.136652)
		(layer "B.Cu")
		(net "USB_P2_DN")
	)
	(segment
		(start 49.938686 -83.627468)
		(end 52.0446 -85.733382)
		(width 0.136652)
		(layer "B.Cu")
		(net "USB_P2_DN")
	)
	(segment
		(start 52.0446 -85.733382)
		(end 52.0446 -89.7636)
		(width 0.136652)
		(layer "B.Cu")
		(net "USB_P2_DN")
	)
	(segment
		(start 64.719708 -102.658418)
		(end 65.009522 -102.948486)
		(width 0.136652)
		(layer "B.Cu")
		(net "USB_P2_DN")
	)
	(segment
		(start 65.893696 -128.939544)
		(end 65.893696 -127.928878)
		(width 0.136652)
		(layer "B.Cu")
		(net "USB_P2_DN")
	)
	(segment
		(start 64.429894 -102.148894)
		(end 64.719708 -102.438708)
		(width 0.136652)
		(layer "B.Cu")
		(net "USB_P2_DN")
	)
	(segment
		(start 66.318892 -104.037892)
		(end 66.318892 -104.257602)
		(width 0.136652)
		(layer "B.Cu")
		(net "USB_P2_DN")
	)
	(segment
		(start 52.700174 -60.381388)
		(end 55.845964 -63.527178)
		(width 0.136652)
		(layer "B.Cu")
		(net "USB_P2_DN")
	)
	(segment
		(start 69.910198 -129.17805)
		(end 66.132202 -129.17805)
		(width 0.136652)
		(layer "B.Cu")
		(net "USB_P2_DN")
	)
	(segment
		(start 65.809114 -103.748078)
		(end 66.029078 -103.748078)
		(width 0.136652)
		(layer "B.Cu")
		(net "USB_P2_DN")
	)
	(segment
		(start 66.82867 -104.54767)
		(end 68.5038 -106.2228)
		(width 0.136652)
		(layer "B.Cu")
		(net "USB_P2_DN")
	)
	(segment
		(start 65.5193 -103.2383)
		(end 65.5193 -103.45801)
		(width 0.136652)
		(layer "B.Cu")
		(net "USB_P2_DN")
	)
	(segment
		(start 64.20993 -102.148894)
		(end 64.429894 -102.148894)
		(width 0.136652)
		(layer "B.Cu")
		(net "USB_P2_DN")
	)
	(segment
		(start 52.700174 -52.810918)
		(end 52.700174 -60.381388)
		(width 0.136652)
		(layer "B.Cu")
		(net "USB_P2_DN")
	)
	(segment
		(start 39.19982 -44.774612)
		(end 38.89502 -45.079412)
		(width 0.136652)
		(layer "F.Cu")
		(net "USB_P1_F_DP1")
	)
	(segment
		(start 39.19982 -42.026332)
		(end 39.19982 -42.50182)
		(width 0.136652)
		(layer "F.Cu")
		(net "USB_P1_F_DP1")
	)
	(segment
		(start 39.19982 -44.14774)
		(end 39.19982 -44.774612)
		(width 0.136652)
		(layer "F.Cu")
		(net "USB_P1_F_DP1")
	)
	(segment
		(start 41.598088 -46.630844)
		(end 41.928288 -46.300644)
		(width 0.136652)
		(layer "F.Cu")
		(net "USB_P1_F_DP1")
	)
	(segment
		(start 39.18712 -47.29988)
		(end 40.02024 -47.29988)
		(width 0.136652)
		(layer "F.Cu")
		(net "USB_P1_F_DP1")
	)
	(segment
		(start 37.817044 -40.433244)
		(end 39.050976 -41.667176)
		(width 0.136652)
		(layer "F.Cu")
		(net "USB_P1_F_DP1")
	)
	(segment
		(start 42.782236 -46.300644)
		(end 42.934636 -46.148244)
		(width 0.136652)
		(layer "F.Cu")
		(net "USB_P1_F_DP1")
	)
	(segment
		(start 41.928288 -46.300644)
		(end 42.540936 -46.300644)
		(width 0.136652)
		(layer "F.Cu")
		(net "USB_P1_F_DP1")
	)
	(segment
		(start 37.815012 -39.06647)
		(end 37.77488 -39.106602)
		(width 0.136652)
		(layer "F.Cu")
		(net "USB_P1_F_DP1")
	)
	(segment
		(start 38.89502 -46.007274)
		(end 38.89502 -47.00778)
		(width 0.136652)
		(layer "F.Cu")
		(net "USB_P1_F_DP1")
	)
	(segment
		(start 39.19982 -42.50182)
		(end 39.41826 -42.72026)
		(width 0.136652)
		(layer "F.Cu")
		(net "USB_P1_F_DP1")
	)
	(segment
		(start 38.89502 -45.079412)
		(end 38.89502 -46.007274)
		(width 0.136652)
		(layer "F.Cu")
		(net "USB_P1_F_DP1")
	)
	(segment
		(start 38.599872 -38.999922)
		(end 37.975794 -38.999922)
		(width 0.136652)
		(layer "F.Cu")
		(net "USB_P1_F_DP1")
	)
	(segment
		(start 37.6682 -39.364158)
		(end 37.6682 -40.074088)
		(width 0.136652)
		(layer "F.Cu")
		(net "USB_P1_F_DP1")
	)
	(segment
		(start 40.02024 -47.29988)
		(end 40.689276 -46.630844)
		(width 0.136652)
		(layer "F.Cu")
		(net "USB_P1_F_DP1")
	)
	(segment
		(start 40.689276 -46.630844)
		(end 41.598088 -46.630844)
		(width 0.136652)
		(layer "F.Cu")
		(net "USB_P1_F_DP1")
	)
	(segment
		(start 39.41826 -43.9293)
		(end 39.19982 -44.14774)
		(width 0.136652)
		(layer "F.Cu")
		(net "USB_P1_F_DP1")
	)
	(segment
		(start 39.41826 -42.72026)
		(end 39.41826 -43.9293)
		(width 0.136652)
		(layer "F.Cu")
		(net "USB_P1_F_DP1")
	)
	(segment
		(start 42.540936 -46.300644)
		(end 42.782236 -46.300644)
		(width 0.136652)
		(layer "F.Cu")
		(net "USB_P1_F_DP1")
	)
	(segment
		(start 38.89502 -47.00778)
		(end 39.18712 -47.29988)
		(width 0.136652)
		(layer "F.Cu")
		(net "USB_P1_F_DP1")
	)
	(arc
		(start 39.050976 -41.667176)
		(mid 39.161134 -41.831944)
		(end 39.19982 -42.026332)
		(width 0.136652)
		(layer "F.Cu")
		(net "USB_P1_F_DP1")
	)
	(arc
		(start 37.975794 -38.999922)
		(mid 37.888784 -39.017211)
		(end 37.815012 -39.06647)
		(width 0.136652)
		(layer "F.Cu")
		(net "USB_P1_F_DP1")
	)
	(arc
		(start 37.77488 -39.106602)
		(mid 37.695923 -39.22477)
		(end 37.6682 -39.364158)
		(width 0.136652)
		(layer "F.Cu")
		(net "USB_P1_F_DP1")
	)
	(arc
		(start 37.6682 -40.074088)
		(mid 37.706884 -40.268477)
		(end 37.817044 -40.433244)
		(width 0.136652)
		(layer "F.Cu")
		(net "USB_P1_F_DP1")
	)
	(segment
		(start 40.815768 -46.935644)
		(end 40.146732 -47.60468)
		(width 0.136652)
		(layer "F.Cu")
		(net "USB_P1_F_DN1")
	)
	(segment
		(start 41.598088 -46.935644)
		(end 40.815768 -46.935644)
		(width 0.136652)
		(layer "F.Cu")
		(net "USB_P1_F_DN1")
	)
	(segment
		(start 42.540936 -47.265844)
		(end 42.782236 -47.265844)
		(width 0.136652)
		(layer "F.Cu")
		(net "USB_P1_F_DN1")
	)
	(segment
		(start 37.304726 -39.704772)
		(end 36.599876 -38.999922)
		(width 0.136652)
		(layer "F.Cu")
		(net "USB_P1_F_DN1")
	)
	(segment
		(start 38.83533 -41.882822)
		(end 37.601398 -40.64889)
		(width 0.136652)
		(layer "F.Cu")
		(net "USB_P1_F_DN1")
	)
	(segment
		(start 41.928288 -47.265844)
		(end 41.598088 -46.935644)
		(width 0.136652)
		(layer "F.Cu")
		(net "USB_P1_F_DN1")
	)
	(segment
		(start 38.89502 -44.64812)
		(end 38.89502 -43.314874)
		(width 0.136652)
		(layer "F.Cu")
		(net "USB_P1_F_DN1")
	)
	(segment
		(start 39.060628 -47.60468)
		(end 38.404546 -46.948598)
		(width 0.136652)
		(layer "F.Cu")
		(net "USB_P1_F_DN1")
	)
	(segment
		(start 37.3634 -40.074088)
		(end 37.3634 -39.846504)
		(width 0.136652)
		(layer "F.Cu")
		(net "USB_P1_F_DN1")
	)
	(segment
		(start 38.404546 -45.138594)
		(end 38.89502 -44.64812)
		(width 0.136652)
		(layer "F.Cu")
		(net "USB_P1_F_DN1")
	)
	(segment
		(start 40.146732 -47.60468)
		(end 39.060628 -47.60468)
		(width 0.136652)
		(layer "F.Cu")
		(net "USB_P1_F_DN1")
	)
	(segment
		(start 42.782236 -47.265844)
		(end 42.934636 -47.418244)
		(width 0.136652)
		(layer "F.Cu")
		(net "USB_P1_F_DN1")
	)
	(segment
		(start 38.89502 -43.314874)
		(end 38.89502 -42.026332)
		(width 0.136652)
		(layer "F.Cu")
		(net "USB_P1_F_DN1")
	)
	(segment
		(start 42.540936 -47.265844)
		(end 41.928288 -47.265844)
		(width 0.136652)
		(layer "F.Cu")
		(net "USB_P1_F_DN1")
	)
	(segment
		(start 38.404546 -46.948598)
		(end 38.404546 -45.138594)
		(width 0.136652)
		(layer "F.Cu")
		(net "USB_P1_F_DN1")
	)
	(arc
		(start 37.601398 -40.64889)
		(mid 37.425214 -40.385168)
		(end 37.3634 -40.074088)
		(width 0.136652)
		(layer "F.Cu")
		(net "USB_P1_F_DN1")
	)
	(arc
		(start 38.89502 -42.026332)
		(mid 38.879454 -41.948639)
		(end 38.83533 -41.882822)
		(width 0.136652)
		(layer "F.Cu")
		(net "USB_P1_F_DN1")
	)
	(arc
		(start 37.3634 -39.846504)
		(mid 37.348145 -39.769812)
		(end 37.304726 -39.704772)
		(width 0.136652)
		(layer "F.Cu")
		(net "USB_P1_F_DN1")
	)
	(segment
		(start 41.275 -56.388)
		(end 40.64 -55.753)
		(width 0.12065)
		(layer "F.Cu")
		(net "USB_OC#")
	)
	(segment
		(start 40.64 -55.753)
		(end 39.81196 -55.753)
		(width 0.12065)
		(layer "F.Cu")
		(net "USB_OC#")
	)
	(segment
		(start 45.160184 -46.630844)
		(end 44.829984 -46.300644)
		(width 0.136652)
		(layer "F.Cu")
		(net "USB_DP_R")
	)
	(segment
		(start 52.362608 -46.4058)
		(end 46.0248 -46.4058)
		(width 0.136652)
		(layer "F.Cu")
		(net "USB_DP_R")
	)
	(segment
		(start 46.0248 -46.4058)
		(end 45.799756 -46.630844)
		(width 0.136652)
		(layer "F.Cu")
		(net "USB_DP_R")
	)
	(segment
		(start 44.829984 -46.300644)
		(end 44.217336 -46.300644)
		(width 0.136652)
		(layer "F.Cu")
		(net "USB_DP_R")
	)
	(segment
		(start 53.004974 -47.575978)
		(end 53.004974 -47.048166)
		(width 0.136652)
		(layer "F.Cu")
		(net "USB_DP_R")
	)
	(segment
		(start 53.305964 -47.876968)
		(end 53.004974 -47.575978)
		(width 0.136652)
		(layer "F.Cu")
		(net "USB_DP_R")
	)
	(segment
		(start 53.004974 -47.048166)
		(end 52.362608 -46.4058)
		(width 0.136652)
		(layer "F.Cu")
		(net "USB_DP_R")
	)
	(segment
		(start 45.799756 -46.630844)
		(end 45.160184 -46.630844)
		(width 0.136652)
		(layer "F.Cu")
		(net "USB_DP_R")
	)
	(via
		(at 53.305964 -47.876968)
		(size 0.508)
		(drill 0.254)
		(layers "F.Cu" "B.Cu")
		(net "USB_DP_R")
	)
	(segment
		(start 53.305964 -47.876968)
		(end 52.99456 -48.188372)
		(width 0.136652)
		(layer "B.Cu")
		(net "USB_DP_R")
	)
	(segment
		(start 52.99456 -48.188372)
		(end 52.99456 -50.353468)
		(width 0.136652)
		(layer "B.Cu")
		(net "USB_DP_R")
	)
	(segment
		(start 53.361844 -50.720752)
		(end 53.361844 -51.1429)
		(width 0.136652)
		(layer "B.Cu")
		(net "USB_DP_R")
	)
	(segment
		(start 52.99456 -50.353468)
		(end 53.361844 -50.720752)
		(width 0.136652)
		(layer "B.Cu")
		(net "USB_DP_R")
	)
	(segment
		(start 46.151292 -46.7106)
		(end 45.926248 -46.935644)
		(width 0.136652)
		(layer "F.Cu")
		(net "USB_DN_R")
	)
	(segment
		(start 51.606196 -46.866048)
		(end 51.19624 -46.866048)
		(width 0.136652)
		(layer "F.Cu")
		(net "USB_DN_R")
	)
	(segment
		(start 44.829984 -47.265844)
		(end 44.217336 -47.265844)
		(width 0.136652)
		(layer "F.Cu")
		(net "USB_DN_R")
	)
	(segment
		(start 47.803816 -46.866048)
		(end 47.648368 -46.7106)
		(width 0.136652)
		(layer "F.Cu")
		(net "USB_DN_R")
	)
	(segment
		(start 48.934624 -46.866048)
		(end 48.779176 -46.7106)
		(width 0.136652)
		(layer "F.Cu")
		(net "USB_DN_R")
	)
	(segment
		(start 45.160184 -46.935644)
		(end 44.829984 -47.265844)
		(width 0.136652)
		(layer "F.Cu")
		(net "USB_DN_R")
	)
	(segment
		(start 49.909984 -46.7106)
		(end 49.500028 -46.7106)
		(width 0.136652)
		(layer "F.Cu")
		(net "USB_DN_R")
	)
	(segment
		(start 48.36922 -46.7106)
		(end 48.213772 -46.866048)
		(width 0.136652)
		(layer "F.Cu")
		(net "USB_DN_R")
	)
	(segment
		(start 52.700174 -47.174658)
		(end 52.236116 -46.7106)
		(width 0.136652)
		(layer "F.Cu")
		(net "USB_DN_R")
	)
	(segment
		(start 51.19624 -46.866048)
		(end 51.040792 -46.7106)
		(width 0.136652)
		(layer "F.Cu")
		(net "USB_DN_R")
	)
	(segment
		(start 50.065432 -46.866048)
		(end 49.909984 -46.7106)
		(width 0.136652)
		(layer "F.Cu")
		(net "USB_DN_R")
	)
	(segment
		(start 49.500028 -46.7106)
		(end 49.34458 -46.866048)
		(width 0.136652)
		(layer "F.Cu")
		(net "USB_DN_R")
	)
	(segment
		(start 52.399438 -47.876968)
		(end 52.700174 -47.576232)
		(width 0.136652)
		(layer "F.Cu")
		(net "USB_DN_R")
	)
	(segment
		(start 48.213772 -46.866048)
		(end 47.803816 -46.866048)
		(width 0.136652)
		(layer "F.Cu")
		(net "USB_DN_R")
	)
	(segment
		(start 51.040792 -46.7106)
		(end 50.630836 -46.7106)
		(width 0.136652)
		(layer "F.Cu")
		(net "USB_DN_R")
	)
	(segment
		(start 48.779176 -46.7106)
		(end 48.36922 -46.7106)
		(width 0.136652)
		(layer "F.Cu")
		(net "USB_DN_R")
	)
	(segment
		(start 47.648368 -46.7106)
		(end 46.151292 -46.7106)
		(width 0.136652)
		(layer "F.Cu")
		(net "USB_DN_R")
	)
	(segment
		(start 45.926248 -46.935644)
		(end 45.160184 -46.935644)
		(width 0.136652)
		(layer "F.Cu")
		(net "USB_DN_R")
	)
	(segment
		(start 50.630836 -46.7106)
		(end 50.475388 -46.866048)
		(width 0.136652)
		(layer "F.Cu")
		(net "USB_DN_R")
	)
	(segment
		(start 52.700174 -47.576232)
		(end 52.700174 -47.174658)
		(width 0.136652)
		(layer "F.Cu")
		(net "USB_DN_R")
	)
	(segment
		(start 51.761644 -46.7106)
		(end 51.606196 -46.866048)
		(width 0.136652)
		(layer "F.Cu")
		(net "USB_DN_R")
	)
	(segment
		(start 50.475388 -46.866048)
		(end 50.065432 -46.866048)
		(width 0.136652)
		(layer "F.Cu")
		(net "USB_DN_R")
	)
	(segment
		(start 49.34458 -46.866048)
		(end 48.934624 -46.866048)
		(width 0.136652)
		(layer "F.Cu")
		(net "USB_DN_R")
	)
	(segment
		(start 52.236116 -46.7106)
		(end 51.761644 -46.7106)
		(width 0.136652)
		(layer "F.Cu")
		(net "USB_DN_R")
	)
	(via
		(at 52.399438 -47.876968)
		(size 0.508)
		(drill 0.254)
		(layers "F.Cu" "B.Cu")
		(net "USB_DN_R")
	)
	(segment
		(start 52.343304 -50.720752)
		(end 52.343304 -51.1429)
		(width 0.136652)
		(layer "B.Cu")
		(net "USB_DN_R")
	)
	(segment
		(start 52.399438 -47.876968)
		(end 52.68976 -48.16729)
		(width 0.136652)
		(layer "B.Cu")
		(net "USB_DN_R")
	)
	(segment
		(start 52.68976 -48.16729)
		(end 52.68976 -50.374296)
		(width 0.136652)
		(layer "B.Cu")
		(net "USB_DN_R")
	)
	(segment
		(start 52.68976 -50.374296)
		(end 52.343304 -50.720752)
		(width 0.136652)
		(layer "B.Cu")
		(net "USB_DN_R")
	)
	(segment
		(start 337.788504 -34.418524)
		(end 337.722972 -34.352992)
		(width 0.12065)
		(layer "F.Cu")
		(net "UPLINK8_R")
	)
	(segment
		(start 338.817204 -34.418524)
		(end 337.788504 -34.418524)
		(width 0.12065)
		(layer "F.Cu")
		(net "UPLINK8_R")
	)
	(segment
		(start 339.108034 -34.127694)
		(end 338.817204 -34.418524)
		(width 0.12065)
		(layer "F.Cu")
		(net "UPLINK8_R")
	)
	(segment
		(start 337.59013 -34.22015)
		(end 337.722972 -34.352992)
		(width 0.12065)
		(layer "F.Cu")
		(net "UPLINK8_R")
	)
	(segment
		(start 337.59013 -32.85998)
		(end 337.59013 -34.22015)
		(width 0.12065)
		(layer "F.Cu")
		(net "UPLINK8_R")
	)
	(via
		(at 337.722972 -34.352992)
		(size 0.7112)
		(drill 0.3556)
		(layers "F.Cu" "B.Cu")
		(net "UPLINK8_R")
	)
	(segment
		(start 327.76668 -89.68232)
		(end 327.76668 -90.2462)
		(width 0.12065)
		(layer "F.Cu")
		(net "UPLINK8")
	)
	(segment
		(start 339.108034 -35.016694)
		(end 339.465412 -35.374072)
		(width 0.12065)
		(layer "F.Cu")
		(net "UPLINK8")
	)
	(segment
		(start 330.835 -87.376)
		(end 330.835 -86.9315)
		(width 0.12065)
		(layer "F.Cu")
		(net "UPLINK8")
	)
	(segment
		(start 329.946 -88.265)
		(end 329.184 -89.027)
		(width 0.12065)
		(layer "F.Cu")
		(net "UPLINK8")
	)
	(segment
		(start 329.184 -89.027)
		(end 328.422 -89.027)
		(width 0.12065)
		(layer "F.Cu")
		(net "UPLINK8")
	)
	(segment
		(start 329.946 -88.265)
		(end 330.835 -87.376)
		(width 0.12065)
		(layer "F.Cu")
		(net "UPLINK8")
	)
	(segment
		(start 339.465412 -35.374072)
		(end 340.225634 -35.374072)
		(width 0.12065)
		(layer "F.Cu")
		(net "UPLINK8")
	)
	(segment
		(start 328.422 -89.027)
		(end 327.76668 -89.68232)
		(width 0.12065)
		(layer "F.Cu")
		(net "UPLINK8")
	)
	(via
		(at 329.946 -88.265)
		(size 0.7112)
		(drill 0.254)
		(layers "F.Cu" "B.Cu")
		(net "UPLINK8")
	)
	(via
		(at 340.225634 -35.374072)
		(size 0.508)
		(drill 0.254)
		(layers "F.Cu" "B.Cu")
		(net "UPLINK8")
	)
	(segment
		(start 345.570556 -87.630254)
		(end 345.570302 -87.63)
		(width 0.127)
		(layer "In2.Cu")
		(net "UPLINK8")
	)
	(segment
		(start 340.225634 -35.374072)
		(end 340.225634 -36.213034)
		(width 0.127)
		(layer "In2.Cu")
		(net "UPLINK8")
	)
	(segment
		(start 340.225634 -36.213034)
		(end 342.053672 -38.041072)
		(width 0.127)
		(layer "In2.Cu")
		(net "UPLINK8")
	)
	(segment
		(start 350.566736 -41.109138)
		(end 350.56699 -41.108884)
		(width 0.127)
		(layer "In2.Cu")
		(net "UPLINK8")
	)
	(segment
		(start 350.882458 -41.108884)
		(end 353.198684 -43.42511)
		(width 0.127)
		(layer "In2.Cu")
		(net "UPLINK8")
	)
	(segment
		(start 346.517722 -87.630508)
		(end 345.886278 -87.630508)
		(width 0.127)
		(layer "In2.Cu")
		(net "UPLINK8")
	)
	(segment
		(start 342.053672 -38.041072)
		(end 343.170002 -38.041072)
		(width 0.127)
		(layer "In2.Cu")
		(net "UPLINK8")
	)
	(segment
		(start 343.170002 -38.041072)
		(end 346.238068 -41.109138)
		(width 0.127)
		(layer "In2.Cu")
		(net "UPLINK8")
	)
	(segment
		(start 345.570302 -87.63)
		(end 330.581 -87.63)
		(width 0.127)
		(layer "In2.Cu")
		(net "UPLINK8")
	)
	(segment
		(start 345.886278 -87.630508)
		(end 345.886024 -87.630254)
		(width 0.127)
		(layer "In2.Cu")
		(net "UPLINK8")
	)
	(segment
		(start 353.198684 -80.949546)
		(end 346.517722 -87.630508)
		(width 0.127)
		(layer "In2.Cu")
		(net "UPLINK8")
	)
	(segment
		(start 345.886024 -87.630254)
		(end 345.570556 -87.630254)
		(width 0.127)
		(layer "In2.Cu")
		(net "UPLINK8")
	)
	(segment
		(start 353.198684 -43.42511)
		(end 353.198684 -80.949546)
		(width 0.127)
		(layer "In2.Cu")
		(net "UPLINK8")
	)
	(segment
		(start 350.56699 -41.108884)
		(end 350.882458 -41.108884)
		(width 0.127)
		(layer "In2.Cu")
		(net "UPLINK8")
	)
	(segment
		(start 330.581 -87.63)
		(end 329.946 -88.265)
		(width 0.127)
		(layer "In2.Cu")
		(net "UPLINK8")
	)
	(segment
		(start 346.238068 -41.109138)
		(end 350.566736 -41.109138)
		(width 0.127)
		(layer "In2.Cu")
		(net "UPLINK8")
	)
	(segment
		(start 338.394294 -37.657786)
		(end 339.1154 -36.93668)
		(width 0.12065)
		(layer "F.Cu")
		(net "UPLINK7_R")
	)
	(segment
		(start 337.66887 -37.657786)
		(end 338.394294 -37.657786)
		(width 0.12065)
		(layer "F.Cu")
		(net "UPLINK7_R")
	)
	(segment
		(start 329.819 -86.9315)
		(end 329.819 -87.503)
		(width 0.12065)
		(layer "F.Cu")
		(net "UPLINK7")
	)
	(segment
		(start 329.819 -87.503)
		(end 328.676 -88.646)
		(width 0.12065)
		(layer "F.Cu")
		(net "UPLINK7")
	)
	(segment
		(start 339.1154 -36.04768)
		(end 339.36178 -36.04768)
		(width 0.12065)
		(layer "F.Cu")
		(net "UPLINK7")
	)
	(segment
		(start 327.87844 -88.646)
		(end 327.64984 -88.8746)
		(width 0.12065)
		(layer "F.Cu")
		(net "UPLINK7")
	)
	(segment
		(start 327.64984 -88.8746)
		(end 327.11644 -89.408)
		(width 0.12065)
		(layer "F.Cu")
		(net "UPLINK7")
	)
	(segment
		(start 328.676 -88.646)
		(end 327.87844 -88.646)
		(width 0.12065)
		(layer "F.Cu")
		(net "UPLINK7")
	)
	(segment
		(start 339.36178 -36.04768)
		(end 340.39302 -37.07892)
		(width 0.12065)
		(layer "F.Cu")
		(net "UPLINK7")
	)
	(segment
		(start 327.11644 -89.408)
		(end 327.11644 -90.2462)
		(width 0.12065)
		(layer "F.Cu")
		(net "UPLINK7")
	)
	(via
		(at 340.39302 -37.07892)
		(size 0.508)
		(drill 0.254)
		(layers "F.Cu" "B.Cu")
		(net "UPLINK7")
	)
	(via
		(at 327.64984 -88.8746)
		(size 0.7112)
		(drill 0.254)
		(layers "F.Cu" "B.Cu")
		(net "UPLINK7")
	)
	(segment
		(start 346.08008 -41.490138)
		(end 350.724724 -41.490138)
		(width 0.127)
		(layer "In2.Cu")
		(net "UPLINK7")
	)
	(segment
		(start 346.044012 -87.249254)
		(end 345.728544 -87.249254)
		(width 0.127)
		(layer "In2.Cu")
		(net "UPLINK7")
	)
	(segment
		(start 345.72829 -87.249)
		(end 329.946 -87.249)
		(width 0.127)
		(layer "In2.Cu")
		(net "UPLINK7")
	)
	(segment
		(start 346.359734 -87.249508)
		(end 346.044012 -87.249254)
		(width 0.127)
		(layer "In2.Cu")
		(net "UPLINK7")
	)
	(segment
		(start 340.39302 -37.07892)
		(end 341.736172 -38.422072)
		(width 0.127)
		(layer "In2.Cu")
		(net "UPLINK7")
	)
	(segment
		(start 350.724724 -41.490138)
		(end 352.817684 -43.583098)
		(width 0.127)
		(layer "In2.Cu")
		(net "UPLINK7")
	)
	(segment
		(start 329.946 -87.249)
		(end 328.215752 -88.979248)
		(width 0.127)
		(layer "In2.Cu")
		(net "UPLINK7")
	)
	(segment
		(start 352.817684 -80.791558)
		(end 346.359734 -87.249508)
		(width 0.127)
		(layer "In2.Cu")
		(net "UPLINK7")
	)
	(segment
		(start 352.817684 -43.583098)
		(end 352.817684 -80.791558)
		(width 0.127)
		(layer "In2.Cu")
		(net "UPLINK7")
	)
	(segment
		(start 327.754488 -88.979248)
		(end 327.64984 -88.8746)
		(width 0.127)
		(layer "In2.Cu")
		(net "UPLINK7")
	)
	(segment
		(start 345.728544 -87.249254)
		(end 345.72829 -87.249)
		(width 0.127)
		(layer "In2.Cu")
		(net "UPLINK7")
	)
	(segment
		(start 343.012014 -38.422072)
		(end 346.08008 -41.490138)
		(width 0.127)
		(layer "In2.Cu")
		(net "UPLINK7")
	)
	(segment
		(start 341.736172 -38.422072)
		(end 343.012014 -38.422072)
		(width 0.127)
		(layer "In2.Cu")
		(net "UPLINK7")
	)
	(segment
		(start 328.215752 -88.979248)
		(end 327.754488 -88.979248)
		(width 0.127)
		(layer "In2.Cu")
		(net "UPLINK7")
	)
	(segment
		(start 331.650848 -35.672522)
		(end 331.650848 -35.839654)
		(width 0.12065)
		(layer "F.Cu")
		(net "UPLINK6_R")
	)
	(segment
		(start 331.65034 -35.840162)
		(end 331.65034 -36.65728)
		(width 0.12065)
		(layer "F.Cu")
		(net "UPLINK6_R")
	)
	(segment
		(start 332.75524 -36.90874)
		(end 331.9018 -36.90874)
		(width 0.12065)
		(layer "F.Cu")
		(net "UPLINK6_R")
	)
	(segment
		(start 331.650848 -35.839654)
		(end 331.65034 -35.840162)
		(width 0.12065)
		(layer "F.Cu")
		(net "UPLINK6_R")
	)
	(segment
		(start 331.9018 -36.90874)
		(end 331.65034 -36.65728)
		(width 0.12065)
		(layer "F.Cu")
		(net "UPLINK6_R")
	)
	(segment
		(start 331.97038 -35.35299)
		(end 331.650848 -35.672522)
		(width 0.12065)
		(layer "F.Cu")
		(net "UPLINK6_R")
	)
	(via
		(at 331.65034 -36.65728)
		(size 0.7112)
		(drill 0.3556)
		(layers "F.Cu" "B.Cu")
		(net "UPLINK6_R")
	)
	(segment
		(start 326.4662 -89.2048)
		(end 326.4662 -90.2462)
		(width 0.12065)
		(layer "F.Cu")
		(net "UPLINK6")
	)
	(segment
		(start 328.803 -87.5157)
		(end 328.49312 -87.82558)
		(width 0.12065)
		(layer "F.Cu")
		(net "UPLINK6")
	)
	(segment
		(start 333.64424 -36.90874)
		(end 334.0735 -36.47948)
		(width 0.12065)
		(layer "F.Cu")
		(net "UPLINK6")
	)
	(segment
		(start 327.84542 -87.82558)
		(end 326.4662 -89.2048)
		(width 0.12065)
		(layer "F.Cu")
		(net "UPLINK6")
	)
	(segment
		(start 328.803 -86.9315)
		(end 328.803 -87.5157)
		(width 0.12065)
		(layer "F.Cu")
		(net "UPLINK6")
	)
	(segment
		(start 328.49312 -87.82558)
		(end 327.84542 -87.82558)
		(width 0.12065)
		(layer "F.Cu")
		(net "UPLINK6")
	)
	(segment
		(start 334.0735 -36.47948)
		(end 334.6196 -36.47948)
		(width 0.12065)
		(layer "F.Cu")
		(net "UPLINK6")
	)
	(via
		(at 328.49312 -87.82558)
		(size 0.7112)
		(drill 0.254)
		(layers "F.Cu" "B.Cu")
		(net "UPLINK6")
	)
	(via
		(at 334.6196 -36.47948)
		(size 0.508)
		(drill 0.254)
		(layers "F.Cu" "B.Cu")
		(net "UPLINK6")
	)
	(segment
		(start 351.872042 -43.176444)
		(end 351.872042 -44.452286)
		(width 0.127)
		(layer "In2.Cu")
		(net "UPLINK6")
	)
	(segment
		(start 352.425 -45.005244)
		(end 352.425 -80.645254)
		(width 0.127)
		(layer "In2.Cu")
		(net "UPLINK6")
	)
	(segment
		(start 345.922092 -41.871138)
		(end 350.566736 -41.871138)
		(width 0.127)
		(layer "In2.Cu")
		(net "UPLINK6")
	)
	(segment
		(start 351.872042 -44.452286)
		(end 352.425 -45.005244)
		(width 0.127)
		(layer "In2.Cu")
		(net "UPLINK6")
	)
	(segment
		(start 346.202 -86.868254)
		(end 345.886278 -86.868)
		(width 0.127)
		(layer "In2.Cu")
		(net "UPLINK6")
	)
	(segment
		(start 334.6196 -36.47948)
		(end 338.475828 -36.47948)
		(width 0.127)
		(layer "In2.Cu")
		(net "UPLINK6")
	)
	(segment
		(start 338.475828 -36.47948)
		(end 340.79942 -38.803072)
		(width 0.127)
		(layer "In2.Cu")
		(net "UPLINK6")
	)
	(segment
		(start 329.4507 -86.868)
		(end 328.49312 -87.82558)
		(width 0.127)
		(layer "In2.Cu")
		(net "UPLINK6")
	)
	(segment
		(start 350.566736 -41.871138)
		(end 351.872042 -43.176444)
		(width 0.127)
		(layer "In2.Cu")
		(net "UPLINK6")
	)
	(segment
		(start 345.886278 -86.868)
		(end 329.4507 -86.868)
		(width 0.127)
		(layer "In2.Cu")
		(net "UPLINK6")
	)
	(segment
		(start 340.79942 -38.803072)
		(end 342.854026 -38.803072)
		(width 0.127)
		(layer "In2.Cu")
		(net "UPLINK6")
	)
	(segment
		(start 352.425 -80.645254)
		(end 346.202 -86.868254)
		(width 0.127)
		(layer "In2.Cu")
		(net "UPLINK6")
	)
	(segment
		(start 342.854026 -38.803072)
		(end 345.922092 -41.871138)
		(width 0.127)
		(layer "In2.Cu")
		(net "UPLINK6")
	)
	(segment
		(start 331.576172 -40.59809)
		(end 331.576172 -39.765478)
		(width 0.12065)
		(layer "F.Cu")
		(net "UPLINK5_R")
	)
	(segment
		(start 331.576172 -39.765478)
		(end 332.937104 -38.404546)
		(width 0.12065)
		(layer "F.Cu")
		(net "UPLINK5_R")
	)
	(segment
		(start 327.787 -86.9315)
		(end 327.22185 -87.49665)
		(width 0.12065)
		(layer "F.Cu")
		(net "UPLINK5")
	)
	(segment
		(start 333.943452 -38.404546)
		(end 334.41386 -37.934138)
		(width 0.12065)
		(layer "F.Cu")
		(net "UPLINK5")
	)
	(segment
		(start 327.22185 -87.52967)
		(end 326.58304 -88.16848)
		(width 0.12065)
		(layer "F.Cu")
		(net "UPLINK5")
	)
	(segment
		(start 325.81596 -88.90254)
		(end 325.81596 -90.2462)
		(width 0.12065)
		(layer "F.Cu")
		(net "UPLINK5")
	)
	(segment
		(start 334.41386 -37.934138)
		(end 334.41386 -37.39134)
		(width 0.12065)
		(layer "F.Cu")
		(net "UPLINK5")
	)
	(segment
		(start 327.22185 -87.49665)
		(end 327.22185 -87.52967)
		(width 0.12065)
		(layer "F.Cu")
		(net "UPLINK5")
	)
	(segment
		(start 333.826104 -38.404546)
		(end 333.943452 -38.404546)
		(width 0.12065)
		(layer "F.Cu")
		(net "UPLINK5")
	)
	(segment
		(start 326.58304 -88.16848)
		(end 325.84898 -88.90254)
		(width 0.12065)
		(layer "F.Cu")
		(net "UPLINK5")
	)
	(segment
		(start 325.84898 -88.90254)
		(end 325.81596 -88.90254)
		(width 0.12065)
		(layer "F.Cu")
		(net "UPLINK5")
	)
	(via
		(at 325.81596 -88.90254)
		(size 0.508)
		(drill 0.254)
		(layers "F.Cu" "B.Cu")
		(net "UPLINK5")
	)
	(via
		(at 334.41386 -37.39134)
		(size 0.508)
		(drill 0.254)
		(layers "F.Cu" "B.Cu")
		(net "UPLINK5")
	)
	(via
		(at 326.58304 -88.16848)
		(size 0.7112)
		(drill 0.3556)
		(layers "F.Cu" "B.Cu")
		(net "UPLINK5")
	)
	(segment
		(start 338.326222 -36.981892)
		(end 334.823308 -36.981892)
		(width 0.127)
		(layer "In2.Cu")
		(net "UPLINK5")
	)
	(segment
		(start 342.696038 -39.184072)
		(end 340.528402 -39.184072)
		(width 0.127)
		(layer "In2.Cu")
		(net "UPLINK5")
	)
	(segment
		(start 334.823308 -36.981892)
		(end 334.41386 -37.39134)
		(width 0.127)
		(layer "In2.Cu")
		(net "UPLINK5")
	)
	(segment
		(start 325.81596 -88.90254)
		(end 327.8505 -86.868)
		(width 0.127)
		(layer "In2.Cu")
		(net "UPLINK5")
	)
	(segment
		(start 351.964752 -46.79696)
		(end 351.418144 -46.250352)
		(width 0.127)
		(layer "In2.Cu")
		(net "UPLINK5")
	)
	(segment
		(start 351.964752 -80.566514)
		(end 351.964752 -46.79696)
		(width 0.127)
		(layer "In2.Cu")
		(net "UPLINK5")
	)
	(segment
		(start 351.491042 -44.65066)
		(end 351.491042 -43.334432)
		(width 0.127)
		(layer "In2.Cu")
		(net "UPLINK5")
	)
	(segment
		(start 327.8505 -86.868)
		(end 328.137012 -86.868)
		(width 0.127)
		(layer "In2.Cu")
		(net "UPLINK5")
	)
	(segment
		(start 340.528402 -39.184072)
		(end 338.326222 -36.981892)
		(width 0.127)
		(layer "In2.Cu")
		(net "UPLINK5")
	)
	(segment
		(start 328.137012 -86.868)
		(end 328.518012 -86.487)
		(width 0.127)
		(layer "In2.Cu")
		(net "UPLINK5")
	)
	(segment
		(start 351.418144 -46.250352)
		(end 351.418144 -44.723558)
		(width 0.127)
		(layer "In2.Cu")
		(net "UPLINK5")
	)
	(segment
		(start 351.418144 -44.723558)
		(end 351.491042 -44.65066)
		(width 0.127)
		(layer "In2.Cu")
		(net "UPLINK5")
	)
	(segment
		(start 328.518012 -86.487)
		(end 346.044266 -86.487)
		(width 0.127)
		(layer "In2.Cu")
		(net "UPLINK5")
	)
	(segment
		(start 345.764104 -42.252138)
		(end 342.696038 -39.184072)
		(width 0.127)
		(layer "In2.Cu")
		(net "UPLINK5")
	)
	(segment
		(start 351.491042 -43.334432)
		(end 350.408748 -42.252138)
		(width 0.127)
		(layer "In2.Cu")
		(net "UPLINK5")
	)
	(segment
		(start 346.044266 -86.487)
		(end 351.964752 -80.566514)
		(width 0.127)
		(layer "In2.Cu")
		(net "UPLINK5")
	)
	(segment
		(start 350.408748 -42.252138)
		(end 345.764104 -42.252138)
		(width 0.127)
		(layer "In2.Cu")
		(net "UPLINK5")
	)
	(segment
		(start 128.9558 -41.83888)
		(end 130.372612 -40.422068)
		(width 0.12065)
		(layer "F.Cu")
		(net "UPLINK4_R")
	)
	(segment
		(start 128.9558 -42.6847)
		(end 128.9558 -41.83888)
		(width 0.12065)
		(layer "F.Cu")
		(net "UPLINK4_R")
	)
	(segment
		(start 325.16572 -88.53678)
		(end 325.16572 -90.2462)
		(width 0.12065)
		(layer "F.Cu")
		(net "UPLINK4")
	)
	(segment
		(start 325.6026 -88.0999)
		(end 325.16572 -88.53678)
		(width 0.12065)
		(layer "F.Cu")
		(net "UPLINK4")
	)
	(segment
		(start 128.33985 -43.452288)
		(end 128.00965 -43.782488)
		(width 0.12065)
		(layer "F.Cu")
		(net "UPLINK4")
	)
	(segment
		(start 325.6026 -88.03132)
		(end 325.6026 -88.0999)
		(width 0.12065)
		(layer "F.Cu")
		(net "UPLINK4")
	)
	(segment
		(start 128.9558 -43.5737)
		(end 128.834388 -43.452288)
		(width 0.12065)
		(layer "F.Cu")
		(net "UPLINK4")
	)
	(segment
		(start 128.834388 -43.452288)
		(end 128.33985 -43.452288)
		(width 0.12065)
		(layer "F.Cu")
		(net "UPLINK4")
	)
	(segment
		(start 326.771 -86.9315)
		(end 325.67118 -88.03132)
		(width 0.12065)
		(layer "F.Cu")
		(net "UPLINK4")
	)
	(segment
		(start 325.67118 -88.03132)
		(end 325.6026 -88.03132)
		(width 0.12065)
		(layer "F.Cu")
		(net "UPLINK4")
	)
	(via
		(at 325.6026 -88.03132)
		(size 0.508)
		(drill 0.254)
		(layers "F.Cu" "B.Cu")
		(net "UPLINK4")
	)
	(via
		(at 332.105 -86.487)
		(size 0.7112)
		(drill 0.3556)
		(layers "F.Cu" "B.Cu")
		(net "UPLINK4")
	)
	(via
		(at 128.00965 -43.782488)
		(size 0.508)
		(drill 0.254)
		(layers "F.Cu" "B.Cu")
		(net "UPLINK4")
	)
	(segment
		(start 143.794734 -102.3112)
		(end 141.94028 -102.3112)
		(width 0.12065)
		(layer "B.Cu")
		(net "UPLINK4")
	)
	(segment
		(start 126.002542 -48.423068)
		(end 128.00965 -46.41596)
		(width 0.12065)
		(layer "B.Cu")
		(net "UPLINK4")
	)
	(segment
		(start 141.94028 -102.3112)
		(end 126.002542 -86.373462)
		(width 0.12065)
		(layer "B.Cu")
		(net "UPLINK4")
	)
	(segment
		(start 126.002542 -86.373462)
		(end 126.002542 -85.1154)
		(width 0.12065)
		(layer "B.Cu")
		(net "UPLINK4")
	)
	(segment
		(start 327.2155 -86.487)
		(end 332.105 -86.487)
		(width 0.12065)
		(layer "B.Cu")
		(net "UPLINK4")
	)
	(segment
		(start 125.942598 -85.055456)
		(end 125.942598 -71.36511)
		(width 0.12065)
		(layer "B.Cu")
		(net "UPLINK4")
	)
	(segment
		(start 325.058532 -109.48035)
		(end 150.963884 -109.48035)
		(width 0.12065)
		(layer "B.Cu")
		(net "UPLINK4")
	)
	(segment
		(start 150.963884 -109.48035)
		(end 143.794734 -102.3112)
		(width 0.12065)
		(layer "B.Cu")
		(net "UPLINK4")
	)
	(segment
		(start 126.002542 -50.400458)
		(end 126.002542 -48.423068)
		(width 0.12065)
		(layer "B.Cu")
		(net "UPLINK4")
	)
	(segment
		(start 123.4948 -52.9082)
		(end 126.002542 -50.400458)
		(width 0.12065)
		(layer "B.Cu")
		(net "UPLINK4")
	)
	(segment
		(start 332.105 -86.487)
		(end 334.753458 -89.135458)
		(width 0.12065)
		(layer "B.Cu")
		(net "UPLINK4")
	)
	(segment
		(start 125.942598 -71.36511)
		(end 126.002542 -71.305166)
		(width 0.12065)
		(layer "B.Cu")
		(net "UPLINK4")
	)
	(segment
		(start 126.002542 -71.305166)
		(end 126.002542 -64.407542)
		(width 0.12065)
		(layer "B.Cu")
		(net "UPLINK4")
	)
	(segment
		(start 334.753458 -99.785424)
		(end 325.058532 -109.48035)
		(width 0.12065)
		(layer "B.Cu")
		(net "UPLINK4")
	)
	(segment
		(start 128.00965 -46.41596)
		(end 128.00965 -43.782488)
		(width 0.12065)
		(layer "B.Cu")
		(net "UPLINK4")
	)
	(segment
		(start 126.002542 -64.407542)
		(end 123.4948 -61.8998)
		(width 0.12065)
		(layer "B.Cu")
		(net "UPLINK4")
	)
	(segment
		(start 325.6026 -88.03132)
		(end 325.67118 -88.03132)
		(width 0.12065)
		(layer "B.Cu")
		(net "UPLINK4")
	)
	(segment
		(start 325.67118 -88.03132)
		(end 327.2155 -86.487)
		(width 0.12065)
		(layer "B.Cu")
		(net "UPLINK4")
	)
	(segment
		(start 126.002542 -85.1154)
		(end 125.942598 -85.055456)
		(width 0.12065)
		(layer "B.Cu")
		(net "UPLINK4")
	)
	(segment
		(start 334.753458 -89.135458)
		(end 334.753458 -99.785424)
		(width 0.12065)
		(layer "B.Cu")
		(net "UPLINK4")
	)
	(segment
		(start 123.4948 -61.8998)
		(end 123.4948 -52.9082)
		(width 0.12065)
		(layer "B.Cu")
		(net "UPLINK4")
	)
	(segment
		(start 126.816612 -41.850818)
		(end 126.721362 -41.946068)
		(width 0.12065)
		(layer "F.Cu")
		(net "UPLINK3_R")
	)
	(segment
		(start 126.816612 -40.422068)
		(end 126.816612 -41.850818)
		(width 0.12065)
		(layer "F.Cu")
		(net "UPLINK3_R")
	)
	(segment
		(start 126.721362 -42.835068)
		(end 126.7206 -42.83583)
		(width 0.12065)
		(layer "F.Cu")
		(net "UPLINK3")
	)
	(segment
		(start 325.755 -86.9315)
		(end 324.51548 -88.17102)
		(width 0.12065)
		(layer "F.Cu")
		(net "UPLINK3")
	)
	(segment
		(start 324.51548 -88.17102)
		(end 324.51548 -88.773)
		(width 0.12065)
		(layer "F.Cu")
		(net "UPLINK3")
	)
	(segment
		(start 324.51548 -88.773)
		(end 324.51548 -90.2462)
		(width 0.12065)
		(layer "F.Cu")
		(net "UPLINK3")
	)
	(segment
		(start 126.7206 -42.83583)
		(end 126.7206 -43.6372)
		(width 0.12065)
		(layer "F.Cu")
		(net "UPLINK3")
	)
	(via
		(at 328.93 -85.852)
		(size 0.7112)
		(drill 0.3556)
		(layers "F.Cu" "B.Cu")
		(net "UPLINK3")
	)
	(via
		(at 324.51548 -88.773)
		(size 0.508)
		(drill 0.254)
		(layers "F.Cu" "B.Cu")
		(net "UPLINK3")
	)
	(via
		(at 126.7206 -43.6372)
		(size 0.508)
		(drill 0.254)
		(layers "F.Cu" "B.Cu")
		(net "UPLINK3")
	)
	(segment
		(start 122.696478 -45.680122)
		(end 123.5964 -44.7802)
		(width 0.12065)
		(layer "B.Cu")
		(net "UPLINK3")
	)
	(segment
		(start 123.2535 -84.136484)
		(end 123.2535 -81.114646)
		(width 0.12065)
		(layer "B.Cu")
		(net "UPLINK3")
	)
	(segment
		(start 150.81377 -109.8423)
		(end 143.64462 -102.67315)
		(width 0.12065)
		(layer "B.Cu")
		(net "UPLINK3")
	)
	(segment
		(start 325.208646 -109.8423)
		(end 150.81377 -109.8423)
		(width 0.12065)
		(layer "B.Cu")
		(net "UPLINK3")
	)
	(segment
		(start 141.790166 -102.67315)
		(end 123.2535 -84.136484)
		(width 0.12065)
		(layer "B.Cu")
		(net "UPLINK3")
	)
	(segment
		(start 324.51548 -87.98052)
		(end 326.644 -85.852)
		(width 0.12065)
		(layer "B.Cu")
		(net "UPLINK3")
	)
	(segment
		(start 335.115408 -88.693498)
		(end 335.115408 -99.935538)
		(width 0.12065)
		(layer "B.Cu")
		(net "UPLINK3")
	)
	(segment
		(start 123.5964 -44.7802)
		(end 125.5776 -44.7802)
		(width 0.12065)
		(layer "B.Cu")
		(net "UPLINK3")
	)
	(segment
		(start 122.696478 -80.557624)
		(end 122.696478 -45.680122)
		(width 0.12065)
		(layer "B.Cu")
		(net "UPLINK3")
	)
	(segment
		(start 335.115408 -99.935538)
		(end 325.208646 -109.8423)
		(width 0.12065)
		(layer "B.Cu")
		(net "UPLINK3")
	)
	(segment
		(start 143.64462 -102.67315)
		(end 141.790166 -102.67315)
		(width 0.12065)
		(layer "B.Cu")
		(net "UPLINK3")
	)
	(segment
		(start 324.51548 -88.773)
		(end 324.51548 -87.98052)
		(width 0.12065)
		(layer "B.Cu")
		(net "UPLINK3")
	)
	(segment
		(start 328.93 -85.852)
		(end 332.27391 -85.852)
		(width 0.12065)
		(layer "B.Cu")
		(net "UPLINK3")
	)
	(segment
		(start 326.644 -85.852)
		(end 328.93 -85.852)
		(width 0.12065)
		(layer "B.Cu")
		(net "UPLINK3")
	)
	(segment
		(start 125.5776 -44.7802)
		(end 126.7206 -43.6372)
		(width 0.12065)
		(layer "B.Cu")
		(net "UPLINK3")
	)
	(segment
		(start 332.27391 -85.852)
		(end 335.115408 -88.693498)
		(width 0.12065)
		(layer "B.Cu")
		(net "UPLINK3")
	)
	(segment
		(start 123.2535 -81.114646)
		(end 122.696478 -80.557624)
		(width 0.12065)
		(layer "B.Cu")
		(net "UPLINK3")
	)
	(segment
		(start 118.960392 -36.324032)
		(end 118.165626 -37.118798)
		(width 0.12065)
		(layer "F.Cu")
		(net "UPLINK2_R")
	)
	(segment
		(start 118.165626 -37.118798)
		(end 118.165626 -38.7858)
		(width 0.12065)
		(layer "F.Cu")
		(net "UPLINK2_R")
	)
	(segment
		(start 116.377974 -40.573452)
		(end 118.02364 -38.927786)
		(width 0.12065)
		(layer "F.Cu")
		(net "UPLINK2_R")
	)
	(segment
		(start 119.35714 -36.324032)
		(end 118.960392 -36.324032)
		(width 0.12065)
		(layer "F.Cu")
		(net "UPLINK2_R")
	)
	(segment
		(start 115.653312 -40.573452)
		(end 116.377974 -40.573452)
		(width 0.12065)
		(layer "F.Cu")
		(net "UPLINK2_R")
	)
	(segment
		(start 118.165626 -38.7858)
		(end 118.02364 -38.927786)
		(width 0.12065)
		(layer "F.Cu")
		(net "UPLINK2_R")
	)
	(via
		(at 115.653312 -40.573452)
		(size 0.7112)
		(drill 0.3556)
		(layers "F.Cu" "B.Cu")
		(net "UPLINK2_R")
	)
	(segment
		(start 324.739 -86.9315)
		(end 323.86524 -87.80526)
		(width 0.12065)
		(layer "F.Cu")
		(net "UPLINK2")
	)
	(segment
		(start 122.1232 -38.201092)
		(end 120.24614 -36.324032)
		(width 0.12065)
		(layer "F.Cu")
		(net "UPLINK2")
	)
	(segment
		(start 122.1232 -40.8178)
		(end 122.1232 -38.201092)
		(width 0.12065)
		(layer "F.Cu")
		(net "UPLINK2")
	)
	(segment
		(start 323.86524 -87.80526)
		(end 323.86524 -90.2462)
		(width 0.12065)
		(layer "F.Cu")
		(net "UPLINK2")
	)
	(via
		(at 122.1232 -40.8178)
		(size 0.508)
		(drill 0.254)
		(layers "F.Cu" "B.Cu")
		(net "UPLINK2")
	)
	(via
		(at 323.86524 -87.80526)
		(size 0.508)
		(drill 0.254)
		(layers "F.Cu" "B.Cu")
		(net "UPLINK2")
	)
	(via
		(at 325.332344 -85.893656)
		(size 0.7112)
		(drill 0.3556)
		(layers "F.Cu" "B.Cu")
		(net "UPLINK2")
	)
	(segment
		(start 335.73085 -107.384342)
		(end 332.409038 -110.706154)
		(width 0.12065)
		(layer "B.Cu")
		(net "UPLINK2")
	)
	(segment
		(start 122.89155 -81.26476)
		(end 122.290078 -80.663288)
		(width 0.12065)
		(layer "B.Cu")
		(net "UPLINK2")
	)
	(segment
		(start 151.16556 -110.706154)
		(end 143.494506 -103.0351)
		(width 0.12065)
		(layer "B.Cu")
		(net "UPLINK2")
	)
	(segment
		(start 332.217522 -85.283548)
		(end 335.73085 -88.796876)
		(width 0.12065)
		(layer "B.Cu")
		(net "UPLINK2")
	)
	(segment
		(start 332.409038 -110.706154)
		(end 151.16556 -110.706154)
		(width 0.12065)
		(layer "B.Cu")
		(net "UPLINK2")
	)
	(segment
		(start 122.290078 -44.791376)
		(end 122.617992 -44.463462)
		(width 0.12065)
		(layer "B.Cu")
		(net "UPLINK2")
	)
	(segment
		(start 122.89155 -85.176614)
		(end 122.89155 -81.26476)
		(width 0.12065)
		(layer "B.Cu")
		(net "UPLINK2")
	)
	(segment
		(start 122.290078 -80.663288)
		(end 122.290078 -44.791376)
		(width 0.12065)
		(layer "B.Cu")
		(net "UPLINK2")
	)
	(segment
		(start 122.617992 -44.463462)
		(end 122.617992 -41.312592)
		(width 0.12065)
		(layer "B.Cu")
		(net "UPLINK2")
	)
	(segment
		(start 325.332344 -85.893656)
		(end 325.942452 -85.283548)
		(width 0.12065)
		(layer "B.Cu")
		(net "UPLINK2")
	)
	(segment
		(start 140.750036 -103.0351)
		(end 122.89155 -85.176614)
		(width 0.12065)
		(layer "B.Cu")
		(net "UPLINK2")
	)
	(segment
		(start 143.494506 -103.0351)
		(end 140.750036 -103.0351)
		(width 0.12065)
		(layer "B.Cu")
		(net "UPLINK2")
	)
	(segment
		(start 335.73085 -88.796876)
		(end 335.73085 -107.384342)
		(width 0.12065)
		(layer "B.Cu")
		(net "UPLINK2")
	)
	(segment
		(start 325.942452 -85.283548)
		(end 332.217522 -85.283548)
		(width 0.12065)
		(layer "B.Cu")
		(net "UPLINK2")
	)
	(segment
		(start 122.617992 -41.312592)
		(end 122.1232 -40.8178)
		(width 0.12065)
		(layer "B.Cu")
		(net "UPLINK2")
	)
	(segment
		(start 323.86524 -87.36076)
		(end 325.332344 -85.893656)
		(width 0.12065)
		(layer "B.Cu")
		(net "UPLINK2")
	)
	(segment
		(start 323.86524 -87.80526)
		(end 323.86524 -87.36076)
		(width 0.12065)
		(layer "B.Cu")
		(net "UPLINK2")
	)
	(segment
		(start 119.16283 -34.882328)
		(end 119.357902 -34.687256)
		(width 0.12065)
		(layer "F.Cu")
		(net "UPLINK1_R")
	)
	(segment
		(start 119.357902 -34.687256)
		(end 120.794018 -34.687256)
		(width 0.12065)
		(layer "F.Cu")
		(net "UPLINK1_R")
	)
	(segment
		(start 120.794018 -34.687256)
		(end 122.143774 -34.687256)
		(width 0.12065)
		(layer "F.Cu")
		(net "UPLINK1_R")
	)
	(via
		(at 120.794018 -34.687256)
		(size 0.7112)
		(drill 0.3556)
		(layers "F.Cu" "B.Cu")
		(net "UPLINK1_R")
	)
	(segment
		(start 122.143774 -36.18992)
		(end 122.6312 -36.677346)
		(width 0.12065)
		(layer "F.Cu")
		(net "UPLINK1")
	)
	(segment
		(start 323.215 -88.9)
		(end 323.215 -90.2462)
		(width 0.12065)
		(layer "F.Cu")
		(net "UPLINK1")
	)
	(segment
		(start 122.6312 -36.677346)
		(end 122.6312 -41.1226)
		(width 0.12065)
		(layer "F.Cu")
		(net "UPLINK1")
	)
	(segment
		(start 122.6312 -41.1226)
		(end 122.15114 -41.60266)
		(width 0.12065)
		(layer "F.Cu")
		(net "UPLINK1")
	)
	(segment
		(start 122.15114 -41.60266)
		(end 122.15114 -41.681146)
		(width 0.12065)
		(layer "F.Cu")
		(net "UPLINK1")
	)
	(segment
		(start 323.723 -86.9315)
		(end 323.215 -87.4395)
		(width 0.12065)
		(layer "F.Cu")
		(net "UPLINK1")
	)
	(segment
		(start 323.215 -87.4395)
		(end 323.215 -88.9)
		(width 0.12065)
		(layer "F.Cu")
		(net "UPLINK1")
	)
	(segment
		(start 122.143774 -35.576256)
		(end 122.143774 -36.18992)
		(width 0.12065)
		(layer "F.Cu")
		(net "UPLINK1")
	)
	(via
		(at 323.215 -88.9)
		(size 0.508)
		(drill 0.254)
		(layers "F.Cu" "B.Cu")
		(net "UPLINK1")
	)
	(via
		(at 122.15114 -41.681146)
		(size 0.508)
		(drill 0.254)
		(layers "F.Cu" "B.Cu")
		(net "UPLINK1")
	)
	(via
		(at 323.60362 -86.22538)
		(size 0.7112)
		(drill 0.3556)
		(layers "F.Cu" "B.Cu")
		(net "UPLINK1")
	)
	(segment
		(start 151.015446 -111.068104)
		(end 332.559152 -111.068104)
		(width 0.12065)
		(layer "B.Cu")
		(net "UPLINK1")
	)
	(segment
		(start 122.5296 -85.326728)
		(end 140.599922 -103.39705)
		(width 0.12065)
		(layer "B.Cu")
		(net "UPLINK1")
	)
	(segment
		(start 332.559152 -111.068104)
		(end 336.0928 -107.534456)
		(width 0.12065)
		(layer "B.Cu")
		(net "UPLINK1")
	)
	(segment
		(start 143.344392 -103.39705)
		(end 151.015446 -111.068104)
		(width 0.12065)
		(layer "B.Cu")
		(net "UPLINK1")
	)
	(segment
		(start 122.15114 -41.681146)
		(end 122.15114 -44.41825)
		(width 0.12065)
		(layer "B.Cu")
		(net "UPLINK1")
	)
	(segment
		(start 336.0928 -107.534456)
		(end 336.0928 -88.646762)
		(width 0.12065)
		(layer "B.Cu")
		(net "UPLINK1")
	)
	(segment
		(start 323.088 -88.773)
		(end 323.088 -86.741)
		(width 0.12065)
		(layer "B.Cu")
		(net "UPLINK1")
	)
	(segment
		(start 122.15114 -44.41825)
		(end 121.928128 -44.641262)
		(width 0.12065)
		(layer "B.Cu")
		(net "UPLINK1")
	)
	(segment
		(start 121.928128 -80.813402)
		(end 122.5296 -81.414874)
		(width 0.12065)
		(layer "B.Cu")
		(net "UPLINK1")
	)
	(segment
		(start 323.215 -88.9)
		(end 323.088 -88.773)
		(width 0.12065)
		(layer "B.Cu")
		(net "UPLINK1")
	)
	(segment
		(start 121.928128 -44.641262)
		(end 121.928128 -80.813402)
		(width 0.12065)
		(layer "B.Cu")
		(net "UPLINK1")
	)
	(segment
		(start 140.599922 -103.39705)
		(end 143.344392 -103.39705)
		(width 0.12065)
		(layer "B.Cu")
		(net "UPLINK1")
	)
	(segment
		(start 332.367636 -84.921598)
		(end 324.907402 -84.921598)
		(width 0.12065)
		(layer "B.Cu")
		(net "UPLINK1")
	)
	(segment
		(start 336.0928 -88.646762)
		(end 332.367636 -84.921598)
		(width 0.12065)
		(layer "B.Cu")
		(net "UPLINK1")
	)
	(segment
		(start 324.907402 -84.921598)
		(end 323.60362 -86.22538)
		(width 0.12065)
		(layer "B.Cu")
		(net "UPLINK1")
	)
	(segment
		(start 323.088 -86.741)
		(end 323.60362 -86.22538)
		(width 0.12065)
		(layer "B.Cu")
		(net "UPLINK1")
	)
	(segment
		(start 122.5296 -81.414874)
		(end 122.5296 -85.326728)
		(width 0.12065)
		(layer "B.Cu")
		(net "UPLINK1")
	)
	(segment
		(start 87.5157 -80.899)
		(end 87.5157 -80.04302)
		(width 0.12065)
		(layer "F.Cu")
		(net "UART_USOUT")
	)
	(segment
		(start 87.5157 -80.04302)
		(end 87.588344 -79.970376)
		(width 0.12065)
		(layer "F.Cu")
		(net "UART_USOUT")
	)
	(segment
		(start 244.599968 -35.999928)
		(end 245.09984 -35.500056)
		(width 0.12065)
		(layer "F.Cu")
		(net "UART_USOUT")
	)
	(segment
		(start 88.89238 -73.560432)
		(end 88.89238 -65.20688)
		(width 0.12065)
		(layer "F.Cu")
		(net "UART_USOUT")
	)
	(segment
		(start 87.588344 -79.970376)
		(end 88.438228 -79.120492)
		(width 0.12065)
		(layer "F.Cu")
		(net "UART_USOUT")
	)
	(segment
		(start 88.438228 -74.014584)
		(end 88.89238 -73.560432)
		(width 0.12065)
		(layer "F.Cu")
		(net "UART_USOUT")
	)
	(segment
		(start 88.438228 -79.120492)
		(end 88.438228 -74.014584)
		(width 0.12065)
		(layer "F.Cu")
		(net "UART_USOUT")
	)
	(via
		(at 87.588344 -79.970376)
		(size 0.7112)
		(drill 0.3556)
		(layers "F.Cu" "B.Cu")
		(net "UART_USOUT")
	)
	(via
		(at 88.89238 -65.20688)
		(size 0.508)
		(drill 0.254)
		(layers "F.Cu" "B.Cu")
		(net "UART_USOUT")
	)
	(via
		(at 245.09984 -35.500056)
		(size 0.4572)
		(drill 0.2032)
		(layers "F.Cu" "B.Cu")
		(net "UART_USOUT")
	)
	(segment
		(start 113.538 -28.176982)
		(end 126.0729 -15.642082)
		(width 0.127)
		(layer "In5.Cu")
		(net "UART_USOUT")
	)
	(segment
		(start 244.557804 -20.72386)
		(end 244.557804 -23.816564)
		(width 0.127)
		(layer "In5.Cu")
		(net "UART_USOUT")
	)
	(segment
		(start 113.411 -48.271176)
		(end 113.411 -40.976296)
		(width 0.127)
		(layer "In5.Cu")
		(net "UART_USOUT")
	)
	(segment
		(start 96.475296 -65.20688)
		(end 113.411 -48.271176)
		(width 0.127)
		(layer "In5.Cu")
		(net "UART_USOUT")
	)
	(segment
		(start 88.89238 -65.20688)
		(end 96.475296 -65.20688)
		(width 0.127)
		(layer "In5.Cu")
		(net "UART_USOUT")
	)
	(segment
		(start 243.6368 -27.7876)
		(end 242.693444 -28.730956)
		(width 0.127)
		(layer "In5.Cu")
		(net "UART_USOUT")
	)
	(segment
		(start 243.6368 -33.462214)
		(end 243.6368 -33.61182)
		(width 0.127)
		(layer "In5.Cu")
		(net "UART_USOUT")
	)
	(segment
		(start 244.506242 -34.331656)
		(end 244.506242 -34.906458)
		(width 0.127)
		(layer "In5.Cu")
		(net "UART_USOUT")
	)
	(segment
		(start 238.2139 -17.4879)
		(end 240.8428 -20.1168)
		(width 0.127)
		(layer "In5.Cu")
		(net "UART_USOUT")
	)
	(segment
		(start 242.693444 -28.730956)
		(end 242.693444 -32.668464)
		(width 0.127)
		(layer "In5.Cu")
		(net "UART_USOUT")
	)
	(segment
		(start 230.773224 -16.3576)
		(end 231.903524 -17.4879)
		(width 0.127)
		(layer "In5.Cu")
		(net "UART_USOUT")
	)
	(segment
		(start 244.506242 -34.906458)
		(end 245.09984 -35.500056)
		(width 0.127)
		(layer "In5.Cu")
		(net "UART_USOUT")
	)
	(segment
		(start 240.8428 -20.1168)
		(end 243.950744 -20.1168)
		(width 0.127)
		(layer "In5.Cu")
		(net "UART_USOUT")
	)
	(segment
		(start 231.903524 -17.4879)
		(end 238.2139 -17.4879)
		(width 0.127)
		(layer "In5.Cu")
		(net "UART_USOUT")
	)
	(segment
		(start 134.02564 -4.67741)
		(end 174.136558 -4.67741)
		(width 0.127)
		(layer "In5.Cu")
		(net "UART_USOUT")
	)
	(segment
		(start 113.538 -40.849296)
		(end 113.538 -28.176982)
		(width 0.127)
		(layer "In5.Cu")
		(net "UART_USOUT")
	)
	(segment
		(start 243.950744 -20.1168)
		(end 244.557804 -20.72386)
		(width 0.127)
		(layer "In5.Cu")
		(net "UART_USOUT")
	)
	(segment
		(start 243.6368 -33.61182)
		(end 244.118638 -34.093658)
		(width 0.127)
		(layer "In5.Cu")
		(net "UART_USOUT")
	)
	(segment
		(start 243.118386 -33.093406)
		(end 243.267992 -33.093406)
		(width 0.127)
		(layer "In5.Cu")
		(net "UART_USOUT")
	)
	(segment
		(start 183.504078 -11.897106)
		(end 183.504078 -12.953238)
		(width 0.127)
		(layer "In5.Cu")
		(net "UART_USOUT")
	)
	(segment
		(start 195.887848 -17.905476)
		(end 200.543414 -17.905476)
		(width 0.127)
		(layer "In5.Cu")
		(net "UART_USOUT")
	)
	(segment
		(start 200.543414 -17.905476)
		(end 202.09129 -16.3576)
		(width 0.127)
		(layer "In5.Cu")
		(net "UART_USOUT")
	)
	(segment
		(start 174.136558 -4.67741)
		(end 180.062886 -10.603738)
		(width 0.127)
		(layer "In5.Cu")
		(net "UART_USOUT")
	)
	(segment
		(start 192.143888 -14.161516)
		(end 195.887848 -17.905476)
		(width 0.127)
		(layer "In5.Cu")
		(net "UART_USOUT")
	)
	(segment
		(start 126.0729 -12.63015)
		(end 134.02564 -4.67741)
		(width 0.127)
		(layer "In5.Cu")
		(net "UART_USOUT")
	)
	(segment
		(start 244.268244 -34.093658)
		(end 244.506242 -34.331656)
		(width 0.127)
		(layer "In5.Cu")
		(net "UART_USOUT")
	)
	(segment
		(start 243.267992 -33.093406)
		(end 243.6368 -33.462214)
		(width 0.127)
		(layer "In5.Cu")
		(net "UART_USOUT")
	)
	(segment
		(start 180.062886 -10.603738)
		(end 182.21071 -10.603738)
		(width 0.127)
		(layer "In5.Cu")
		(net "UART_USOUT")
	)
	(segment
		(start 184.712356 -14.161516)
		(end 192.143888 -14.161516)
		(width 0.127)
		(layer "In5.Cu")
		(net "UART_USOUT")
	)
	(segment
		(start 243.6368 -24.737568)
		(end 243.6368 -27.7876)
		(width 0.127)
		(layer "In5.Cu")
		(net "UART_USOUT")
	)
	(segment
		(start 242.693444 -32.668464)
		(end 243.118386 -33.093406)
		(width 0.127)
		(layer "In5.Cu")
		(net "UART_USOUT")
	)
	(segment
		(start 126.0729 -15.642082)
		(end 126.0729 -12.63015)
		(width 0.127)
		(layer "In5.Cu")
		(net "UART_USOUT")
	)
	(segment
		(start 244.118638 -34.093658)
		(end 244.268244 -34.093658)
		(width 0.127)
		(layer "In5.Cu")
		(net "UART_USOUT")
	)
	(segment
		(start 244.557804 -23.816564)
		(end 243.6368 -24.737568)
		(width 0.127)
		(layer "In5.Cu")
		(net "UART_USOUT")
	)
	(segment
		(start 182.21071 -10.603738)
		(end 183.504078 -11.897106)
		(width 0.127)
		(layer "In5.Cu")
		(net "UART_USOUT")
	)
	(segment
		(start 202.09129 -16.3576)
		(end 230.773224 -16.3576)
		(width 0.127)
		(layer "In5.Cu")
		(net "UART_USOUT")
	)
	(segment
		(start 113.411 -40.976296)
		(end 113.538 -40.849296)
		(width 0.127)
		(layer "In5.Cu")
		(net "UART_USOUT")
	)
	(segment
		(start 183.504078 -12.953238)
		(end 184.712356 -14.161516)
		(width 0.127)
		(layer "In5.Cu")
		(net "UART_USOUT")
	)
	(segment
		(start 85.4837 -81.0006)
		(end 85.4837 -80.713326)
		(width 0.12065)
		(layer "F.Cu")
		(net "UART_USIN")
	)
	(segment
		(start 87.8332 -73.3552)
		(end 87.8332 -65.17386)
		(width 0.12065)
		(layer "F.Cu")
		(net "UART_USIN")
	)
	(segment
		(start 86.257892 -75.899518)
		(end 86.257892 -74.930508)
		(width 0.12065)
		(layer "F.Cu")
		(net "UART_USIN")
	)
	(segment
		(start 85.4837 -76.67371)
		(end 86.257892 -75.899518)
		(width 0.12065)
		(layer "F.Cu")
		(net "UART_USIN")
	)
	(segment
		(start 85.4837 -79.393034)
		(end 85.4837 -76.67371)
		(width 0.12065)
		(layer "F.Cu")
		(net "UART_USIN")
	)
	(segment
		(start 86.257892 -74.930508)
		(end 87.8332 -73.3552)
		(width 0.12065)
		(layer "F.Cu")
		(net "UART_USIN")
	)
	(segment
		(start 86.143846 -80.05318)
		(end 85.4837 -79.393034)
		(width 0.12065)
		(layer "F.Cu")
		(net "UART_USIN")
	)
	(segment
		(start 244.599968 -34.99993)
		(end 245.09984 -34.500058)
		(width 0.12065)
		(layer "F.Cu")
		(net "UART_USIN")
	)
	(segment
		(start 85.4837 -80.713326)
		(end 86.143846 -80.05318)
		(width 0.12065)
		(layer "F.Cu")
		(net "UART_USIN")
	)
	(segment
		(start 87.8332 -65.17386)
		(end 87.83828 -65.16878)
		(width 0.12065)
		(layer "F.Cu")
		(net "UART_USIN")
	)
	(via
		(at 87.83828 -65.16878)
		(size 0.508)
		(drill 0.254)
		(layers "F.Cu" "B.Cu")
		(net "UART_USIN")
	)
	(via
		(at 86.143846 -80.05318)
		(size 0.7112)
		(drill 0.3556)
		(layers "F.Cu" "B.Cu")
		(net "UART_USIN")
	)
	(via
		(at 245.09984 -34.500058)
		(size 0.4572)
		(drill 0.2032)
		(layers "F.Cu" "B.Cu")
		(net "UART_USIN")
	)
	(segment
		(start 238.371888 -17.1069)
		(end 241.000788 -19.7358)
		(width 0.127)
		(layer "In5.Cu")
		(net "UART_USIN")
	)
	(segment
		(start 186.7027 -10.215118)
		(end 189.162182 -12.6746)
		(width 0.127)
		(layer "In5.Cu")
		(net "UART_USIN")
	)
	(segment
		(start 196.251576 -17.524476)
		(end 200.385426 -17.524476)
		(width 0.127)
		(layer "In5.Cu")
		(net "UART_USIN")
	)
	(segment
		(start 244.6274 -33.452816)
		(end 244.6274 -33.8074)
		(width 0.127)
		(layer "In5.Cu")
		(net "UART_USIN")
	)
	(segment
		(start 87.83828 -65.16878)
		(end 88.33358 -64.67348)
		(width 0.127)
		(layer "In5.Cu")
		(net "UART_USIN")
	)
	(segment
		(start 88.33358 -64.67348)
		(end 96.246188 -64.67348)
		(width 0.127)
		(layer "In5.Cu")
		(net "UART_USIN")
	)
	(segment
		(start 191.4017 -12.6746)
		(end 196.251576 -17.524476)
		(width 0.127)
		(layer "In5.Cu")
		(net "UART_USIN")
	)
	(segment
		(start 133.867652 -4.29641)
		(end 174.294546 -4.29641)
		(width 0.127)
		(layer "In5.Cu")
		(net "UART_USIN")
	)
	(segment
		(start 243.693442 -32.668464)
		(end 244.118638 -33.09366)
		(width 0.127)
		(layer "In5.Cu")
		(net "UART_USIN")
	)
	(segment
		(start 201.933302 -15.9766)
		(end 230.931212 -15.9766)
		(width 0.127)
		(layer "In5.Cu")
		(net "UART_USIN")
	)
	(segment
		(start 181.413404 -10.215626)
		(end 181.834028 -10.215626)
		(width 0.127)
		(layer "In5.Cu")
		(net "UART_USIN")
	)
	(segment
		(start 125.6919 -15.481808)
		(end 125.6919 -12.472162)
		(width 0.127)
		(layer "In5.Cu")
		(net "UART_USIN")
	)
	(segment
		(start 245.09984 -34.27984)
		(end 245.09984 -34.500058)
		(width 0.127)
		(layer "In5.Cu")
		(net "UART_USIN")
	)
	(segment
		(start 244.0178 -28.0162)
		(end 243.693442 -28.340558)
		(width 0.127)
		(layer "In5.Cu")
		(net "UART_USIN")
	)
	(segment
		(start 244.6274 -33.8074)
		(end 245.09984 -34.27984)
		(width 0.127)
		(layer "In5.Cu")
		(net "UART_USIN")
	)
	(segment
		(start 181.834282 -10.215372)
		(end 182.254906 -10.215372)
		(width 0.127)
		(layer "In5.Cu")
		(net "UART_USIN")
	)
	(segment
		(start 180.214778 -10.215118)
		(end 181.412896 -10.215118)
		(width 0.127)
		(layer "In5.Cu")
		(net "UART_USIN")
	)
	(segment
		(start 182.254906 -10.215372)
		(end 182.25516 -10.215118)
		(width 0.127)
		(layer "In5.Cu")
		(net "UART_USIN")
	)
	(segment
		(start 113.157 -40.691308)
		(end 113.157 -28.017216)
		(width 0.127)
		(layer "In5.Cu")
		(net "UART_USIN")
	)
	(segment
		(start 244.938804 -20.565872)
		(end 244.938804 -23.974552)
		(width 0.127)
		(layer "In5.Cu")
		(net "UART_USIN")
	)
	(segment
		(start 125.6919 -12.472162)
		(end 133.867652 -4.29641)
		(width 0.127)
		(layer "In5.Cu")
		(net "UART_USIN")
	)
	(segment
		(start 244.268244 -33.09366)
		(end 244.6274 -33.452816)
		(width 0.127)
		(layer "In5.Cu")
		(net "UART_USIN")
	)
	(segment
		(start 96.246188 -64.67348)
		(end 113.03 -47.889668)
		(width 0.127)
		(layer "In5.Cu")
		(net "UART_USIN")
	)
	(segment
		(start 182.25516 -10.215118)
		(end 186.7027 -10.215118)
		(width 0.127)
		(layer "In5.Cu")
		(net "UART_USIN")
	)
	(segment
		(start 181.412896 -10.215118)
		(end 181.413404 -10.215626)
		(width 0.127)
		(layer "In5.Cu")
		(net "UART_USIN")
	)
	(segment
		(start 113.157 -28.017216)
		(end 125.6919 -15.481808)
		(width 0.127)
		(layer "In5.Cu")
		(net "UART_USIN")
	)
	(segment
		(start 113.03 -40.818308)
		(end 113.157 -40.691308)
		(width 0.127)
		(layer "In5.Cu")
		(net "UART_USIN")
	)
	(segment
		(start 232.061512 -17.1069)
		(end 238.371888 -17.1069)
		(width 0.127)
		(layer "In5.Cu")
		(net "UART_USIN")
	)
	(segment
		(start 241.000788 -19.7358)
		(end 244.108732 -19.7358)
		(width 0.127)
		(layer "In5.Cu")
		(net "UART_USIN")
	)
	(segment
		(start 174.318676 -4.319016)
		(end 180.214778 -10.215118)
		(width 0.127)
		(layer "In5.Cu")
		(net "UART_USIN")
	)
	(segment
		(start 243.693442 -28.340558)
		(end 243.693442 -32.668464)
		(width 0.127)
		(layer "In5.Cu")
		(net "UART_USIN")
	)
	(segment
		(start 113.03 -47.889668)
		(end 113.03 -40.818308)
		(width 0.127)
		(layer "In5.Cu")
		(net "UART_USIN")
	)
	(segment
		(start 244.0178 -24.895556)
		(end 244.0178 -28.0162)
		(width 0.127)
		(layer "In5.Cu")
		(net "UART_USIN")
	)
	(segment
		(start 230.931212 -15.9766)
		(end 232.061512 -17.1069)
		(width 0.127)
		(layer "In5.Cu")
		(net "UART_USIN")
	)
	(segment
		(start 244.118638 -33.09366)
		(end 244.268244 -33.09366)
		(width 0.127)
		(layer "In5.Cu")
		(net "UART_USIN")
	)
	(segment
		(start 174.317152 -4.319016)
		(end 174.318676 -4.319016)
		(width 0.127)
		(layer "In5.Cu")
		(net "UART_USIN")
	)
	(segment
		(start 244.108732 -19.7358)
		(end 244.938804 -20.565872)
		(width 0.127)
		(layer "In5.Cu")
		(net "UART_USIN")
	)
	(segment
		(start 181.834028 -10.215626)
		(end 181.834282 -10.215372)
		(width 0.127)
		(layer "In5.Cu")
		(net "UART_USIN")
	)
	(segment
		(start 244.938804 -23.974552)
		(end 244.0178 -24.895556)
		(width 0.127)
		(layer "In5.Cu")
		(net "UART_USIN")
	)
	(segment
		(start 174.294546 -4.29641)
		(end 174.317152 -4.319016)
		(width 0.127)
		(layer "In5.Cu")
		(net "UART_USIN")
	)
	(segment
		(start 189.162182 -12.6746)
		(end 191.4017 -12.6746)
		(width 0.127)
		(layer "In5.Cu")
		(net "UART_USIN")
	)
	(segment
		(start 200.385426 -17.524476)
		(end 201.933302 -15.9766)
		(width 0.127)
		(layer "In5.Cu")
		(net "UART_USIN")
	)
	(segment
		(start 220.853 -3.7465)
		(end 220.853 -3.8608)
		(width 0.12065)
		(layer "F.Cu")
		(net "UART_SWITCH_R")
	)
	(segment
		(start 222.8342 -1.524)
		(end 222.8342 -0.103632)
		(width 0.12065)
		(layer "F.Cu")
		(net "UART_SWITCH_R")
	)
	(segment
		(start 220.345 -3.2385)
		(end 220.853 -3.7465)
		(width 0.12065)
		(layer "F.Cu")
		(net "UART_SWITCH_R")
	)
	(segment
		(start 225.20783 -4.223258)
		(end 225.17608 -4.255008)
		(width 0.12065)
		(layer "F.Cu")
		(net "UART_SWITCH_R")
	)
	(segment
		(start 221.7039 -1.63449)
		(end 221.7039 -1.84658)
		(width 0.12065)
		(layer "F.Cu")
		(net "UART_SWITCH_R")
	)
	(segment
		(start 224.344738 -1.874012)
		(end 224.112836 -1.64211)
		(width 0.12065)
		(layer "F.Cu")
		(net "UART_SWITCH_R")
	)
	(segment
		(start 225.17608 -4.255008)
		(end 224.344738 -3.423666)
		(width 0.12065)
		(layer "F.Cu")
		(net "UART_SWITCH_R")
	)
	(segment
		(start 222.366078 0.36449)
		(end 221.7039 0.36449)
		(width 0.12065)
		(layer "F.Cu")
		(net "UART_SWITCH_R")
	)
	(segment
		(start 222.8342 -1.524)
		(end 222.72371 -1.63449)
		(width 0.12065)
		(layer "F.Cu")
		(net "UART_SWITCH_R")
	)
	(segment
		(start 222.72371 -1.63449)
		(end 221.7039 -1.63449)
		(width 0.12065)
		(layer "F.Cu")
		(net "UART_SWITCH_R")
	)
	(segment
		(start 220.853 -3.8608)
		(end 221.1324 -4.1402)
		(width 0.12065)
		(layer "F.Cu")
		(net "UART_SWITCH_R")
	)
	(segment
		(start 226.390454 -4.223258)
		(end 225.20783 -4.223258)
		(width 0.12065)
		(layer "F.Cu")
		(net "UART_SWITCH_R")
	)
	(segment
		(start 221.1324 -4.1402)
		(end 221.1324 -4.80441)
		(width 0.12065)
		(layer "F.Cu")
		(net "UART_SWITCH_R")
	)
	(segment
		(start 224.344738 -3.423666)
		(end 224.344738 -1.874012)
		(width 0.12065)
		(layer "F.Cu")
		(net "UART_SWITCH_R")
	)
	(segment
		(start 220.345 -3.20548)
		(end 220.345 -3.2385)
		(width 0.12065)
		(layer "F.Cu")
		(net "UART_SWITCH_R")
	)
	(segment
		(start 221.7039 -1.84658)
		(end 220.345 -3.20548)
		(width 0.12065)
		(layer "F.Cu")
		(net "UART_SWITCH_R")
	)
	(segment
		(start 222.8342 -0.103632)
		(end 222.366078 0.36449)
		(width 0.12065)
		(layer "F.Cu")
		(net "UART_SWITCH_R")
	)
	(segment
		(start 222.95231 -1.64211)
		(end 222.8342 -1.524)
		(width 0.12065)
		(layer "F.Cu")
		(net "UART_SWITCH_R")
	)
	(segment
		(start 224.112836 -1.64211)
		(end 222.95231 -1.64211)
		(width 0.12065)
		(layer "F.Cu")
		(net "UART_SWITCH_R")
	)
	(via
		(at 221.1324 -4.80441)
		(size 0.508)
		(drill 0.254)
		(layers "F.Cu" "B.Cu")
		(net "UART_SWITCH_R")
	)
	(via
		(at 221.4372 -3.888486)
		(size 0.7112)
		(drill 0.3556)
		(layers "F.Cu" "B.Cu")
		(net "UART_SWITCH_R")
	)
	(segment
		(start 221.1324 -4.193286)
		(end 221.4372 -3.888486)
		(width 0.12065)
		(layer "B.Cu")
		(net "UART_SWITCH_R")
	)
	(segment
		(start 221.1324 -4.80441)
		(end 221.1324 -4.193286)
		(width 0.12065)
		(layer "B.Cu")
		(net "UART_SWITCH_R")
	)
	(segment
		(start 234.5182 -3.724656)
		(end 234.5182 -2.469388)
		(width 0.12065)
		(layer "F.Cu")
		(net "UART_COUNT")
	)
	(segment
		(start 238.083852 -5.9055)
		(end 236.893862 -4.71551)
		(width 0.12065)
		(layer "F.Cu")
		(net "UART_COUNT")
	)
	(segment
		(start 238.736378 -5.9055)
		(end 239.275874 -6.444996)
		(width 0.12065)
		(layer "F.Cu")
		(net "UART_COUNT")
	)
	(segment
		(start 234.5182 -2.469388)
		(end 233.549444 -1.500632)
		(width 0.12065)
		(layer "F.Cu")
		(net "UART_COUNT")
	)
	(segment
		(start 238.252 -5.9055)
		(end 238.736378 -5.9055)
		(width 0.12065)
		(layer "F.Cu")
		(net "UART_COUNT")
	)
	(segment
		(start 235.509054 -4.71551)
		(end 234.5182 -3.724656)
		(width 0.12065)
		(layer "F.Cu")
		(net "UART_COUNT")
	)
	(segment
		(start 238.252 -5.9055)
		(end 238.083852 -5.9055)
		(width 0.12065)
		(layer "F.Cu")
		(net "UART_COUNT")
	)
	(segment
		(start 236.893862 -4.71551)
		(end 235.509054 -4.71551)
		(width 0.12065)
		(layer "F.Cu")
		(net "UART_COUNT")
	)
	(via
		(at 58.3692 -141.859)
		(size 0.508)
		(drill 0.254)
		(layers "F.Cu" "B.Cu")
		(net "UART_COUNT")
	)
	(via
		(at 75.0316 -82.64906)
		(size 0.508)
		(drill 0.254)
		(layers "F.Cu" "B.Cu")
		(net "UART_COUNT")
	)
	(via
		(at 71.1708 -140.0556)
		(size 0.508)
		(drill 0.254)
		(layers "F.Cu" "B.Cu")
		(net "UART_COUNT")
	)
	(segment
		(start 57.4675 -141.859)
		(end 58.3692 -141.859)
		(width 0.12065)
		(layer "B.Cu")
		(net "UART_COUNT")
	)
	(segment
		(start 232.685082 -0.63627)
		(end 227.9396 -0.63627)
		(width 0.127)
		(layer "In2.Cu")
		(net "UART_COUNT")
	)
	(segment
		(start 96.190054 -76.521818)
		(end 96.083628 -76.628498)
		(width 0.127)
		(layer "In2.Cu")
		(net "UART_COUNT")
	)
	(segment
		(start 197.655688 -1.9558)
		(end 196.667374 -0.967486)
		(width 0.127)
		(layer "In2.Cu")
		(net "UART_COUNT")
	)
	(segment
		(start 97.91573 -51.114198)
		(end 97.91573 -74.796396)
		(width 0.127)
		(layer "In2.Cu")
		(net "UART_COUNT")
	)
	(segment
		(start 121.009664 -8.546846)
		(end 95.37319 -34.18332)
		(width 0.127)
		(layer "In2.Cu")
		(net "UART_COUNT")
	)
	(segment
		(start 187.97016 -0.220726)
		(end 178.433476 -0.220726)
		(width 0.127)
		(layer "In2.Cu")
		(net "UART_COUNT")
	)
	(segment
		(start 227.9396 -0.63627)
		(end 227.52177 -1.0541)
		(width 0.127)
		(layer "In2.Cu")
		(net "UART_COUNT")
	)
	(segment
		(start 233.549444 -1.500632)
		(end 232.685082 -0.63627)
		(width 0.127)
		(layer "In2.Cu")
		(net "UART_COUNT")
	)
	(segment
		(start 84.710524 -84.963254)
		(end 76.703428 -84.963254)
		(width 0.127)
		(layer "In2.Cu")
		(net "UART_COUNT")
	)
	(segment
		(start 95.643192 -77.070966)
		(end 95.4024 -77.312774)
		(width 0.127)
		(layer "In2.Cu")
		(net "UART_COUNT")
	)
	(segment
		(start 188.71692 -0.967486)
		(end 187.97016 -0.220726)
		(width 0.127)
		(layer "In2.Cu")
		(net "UART_COUNT")
	)
	(segment
		(start 95.4024 -77.312774)
		(end 95.4024 -79.784448)
		(width 0.127)
		(layer "In2.Cu")
		(net "UART_COUNT")
	)
	(segment
		(start 196.667374 -0.967486)
		(end 188.71692 -0.967486)
		(width 0.127)
		(layer "In2.Cu")
		(net "UART_COUNT")
	)
	(segment
		(start 124.531628 -8.546846)
		(end 121.009664 -8.546846)
		(width 0.127)
		(layer "In2.Cu")
		(net "UART_COUNT")
	)
	(segment
		(start 220.666564 1.535938)
		(end 205.796896 1.535938)
		(width 0.127)
		(layer "In2.Cu")
		(net "UART_COUNT")
	)
	(segment
		(start 202.304142 -1.9558)
		(end 197.655688 -1.9558)
		(width 0.127)
		(layer "In2.Cu")
		(net "UART_COUNT")
	)
	(segment
		(start 205.796134 1.53543)
		(end 202.304142 -1.9558)
		(width 0.127)
		(layer "In2.Cu")
		(net "UART_COUNT")
	)
	(segment
		(start 223.256602 -1.0541)
		(end 220.666564 1.535938)
		(width 0.127)
		(layer "In2.Cu")
		(net "UART_COUNT")
	)
	(segment
		(start 131.834382 -1.248156)
		(end 124.531628 -8.546846)
		(width 0.127)
		(layer "In2.Cu")
		(net "UART_COUNT")
	)
	(segment
		(start 69.3674 -141.859)
		(end 58.3692 -141.859)
		(width 0.127)
		(layer "In2.Cu")
		(net "UART_COUNT")
	)
	(segment
		(start 95.37319 -34.18332)
		(end 95.37319 -48.571658)
		(width 0.127)
		(layer "In2.Cu")
		(net "UART_COUNT")
	)
	(segment
		(start 95.37319 -48.571658)
		(end 97.91573 -51.114198)
		(width 0.127)
		(layer "In2.Cu")
		(net "UART_COUNT")
	)
	(segment
		(start 95.4024 -79.784448)
		(end 93.170756 -82.016092)
		(width 0.127)
		(layer "In2.Cu")
		(net "UART_COUNT")
	)
	(segment
		(start 176.774094 -1.248156)
		(end 131.834382 -1.248156)
		(width 0.127)
		(layer "In2.Cu")
		(net "UART_COUNT")
	)
	(segment
		(start 76.703428 -84.963254)
		(end 75.0316 -83.291426)
		(width 0.127)
		(layer "In2.Cu")
		(net "UART_COUNT")
	)
	(segment
		(start 227.52177 -1.0541)
		(end 223.256602 -1.0541)
		(width 0.127)
		(layer "In2.Cu")
		(net "UART_COUNT")
	)
	(segment
		(start 97.91573 -74.796396)
		(end 96.190054 -76.521818)
		(width 0.127)
		(layer "In2.Cu")
		(net "UART_COUNT")
	)
	(segment
		(start 93.170756 -82.016092)
		(end 87.657686 -82.016092)
		(width 0.127)
		(layer "In2.Cu")
		(net "UART_COUNT")
	)
	(segment
		(start 96.083628 -76.628498)
		(end 95.754698 -76.957682)
		(width 0.127)
		(layer "In2.Cu")
		(net "UART_COUNT")
	)
	(segment
		(start 177.801778 -0.220472)
		(end 176.774094 -1.248156)
		(width 0.127)
		(layer "In2.Cu")
		(net "UART_COUNT")
	)
	(segment
		(start 95.754698 -76.957682)
		(end 95.643192 -77.069442)
		(width 0.127)
		(layer "In2.Cu")
		(net "UART_COUNT")
	)
	(segment
		(start 95.643192 -77.069442)
		(end 95.643192 -77.070966)
		(width 0.127)
		(layer "In2.Cu")
		(net "UART_COUNT")
	)
	(segment
		(start 87.657686 -82.016092)
		(end 84.710524 -84.963254)
		(width 0.127)
		(layer "In2.Cu")
		(net "UART_COUNT")
	)
	(segment
		(start 205.796896 1.535938)
		(end 205.796134 1.53543)
		(width 0.127)
		(layer "In2.Cu")
		(net "UART_COUNT")
	)
	(segment
		(start 75.0316 -83.291426)
		(end 75.0316 -82.64906)
		(width 0.127)
		(layer "In2.Cu")
		(net "UART_COUNT")
	)
	(segment
		(start 178.433476 -0.220726)
		(end 178.433222 -0.220472)
		(width 0.127)
		(layer "In2.Cu")
		(net "UART_COUNT")
	)
	(segment
		(start 71.1708 -140.0556)
		(end 69.3674 -141.859)
		(width 0.127)
		(layer "In2.Cu")
		(net "UART_COUNT")
	)
	(segment
		(start 178.433222 -0.220472)
		(end 177.801778 -0.220472)
		(width 0.127)
		(layer "In2.Cu")
		(net "UART_COUNT")
	)
	(segment
		(start 75.0316 -82.64906)
		(end 75.0316 -89.34069)
		(width 0.127)
		(layer "In5.Cu")
		(net "UART_COUNT")
	)
	(segment
		(start 74.605134 -124.257054)
		(end 74.605134 -124.313442)
		(width 0.127)
		(layer "In5.Cu")
		(net "UART_COUNT")
	)
	(segment
		(start 77.00518 -93.23959)
		(end 75.183746 -95.061024)
		(width 0.127)
		(layer "In5.Cu")
		(net "UART_COUNT")
	)
	(segment
		(start 75.183746 -123.678442)
		(end 74.605134 -124.257054)
		(width 0.127)
		(layer "In5.Cu")
		(net "UART_COUNT")
	)
	(segment
		(start 71.1708 -131.295648)
		(end 71.1708 -140.0556)
		(width 0.127)
		(layer "In5.Cu")
		(net "UART_COUNT")
	)
	(segment
		(start 74.605134 -124.313442)
		(end 73.2536 -125.664976)
		(width 0.127)
		(layer "In5.Cu")
		(net "UART_COUNT")
	)
	(segment
		(start 75.183746 -95.061024)
		(end 75.183746 -123.678442)
		(width 0.127)
		(layer "In5.Cu")
		(net "UART_COUNT")
	)
	(segment
		(start 75.0316 -89.34069)
		(end 77.00518 -91.31427)
		(width 0.127)
		(layer "In5.Cu")
		(net "UART_COUNT")
	)
	(segment
		(start 73.2536 -125.664976)
		(end 73.2536 -128.101344)
		(width 0.127)
		(layer "In5.Cu")
		(net "UART_COUNT")
	)
	(segment
		(start 72.035162 -130.431286)
		(end 71.1708 -131.295648)
		(width 0.127)
		(layer "In5.Cu")
		(net "UART_COUNT")
	)
	(segment
		(start 73.2536 -128.101344)
		(end 72.035162 -129.319782)
		(width 0.127)
		(layer "In5.Cu")
		(net "UART_COUNT")
	)
	(segment
		(start 72.035162 -129.319782)
		(end 72.035162 -130.431286)
		(width 0.127)
		(layer "In5.Cu")
		(net "UART_COUNT")
	)
	(segment
		(start 77.00518 -91.31427)
		(end 77.00518 -93.23959)
		(width 0.127)
		(layer "In5.Cu")
		(net "UART_COUNT")
	)
	(segment
		(start 247.599962 -33.999932)
		(end 248.099834 -33.50006)
		(width 0.12065)
		(layer "F.Cu")
		(net "TWI_SDA9")
	)
	(via
		(at 248.099834 -33.50006)
		(size 0.4572)
		(drill 0.2032)
		(layers "F.Cu" "B.Cu")
		(net "TWI_SDA9")
	)
	(segment
		(start 247.599962 -33.999932)
		(end 248.099834 -33.50006)
		(width 0.12065)
		(layer "B.Cu")
		(net "TWI_SDA9")
	)
	(segment
		(start 244.599968 -38.999922)
		(end 245.09984 -38.50005)
		(width 0.12065)
		(layer "F.Cu")
		(net "TWI_SDA4")
	)
	(via
		(at 245.09984 -38.50005)
		(size 0.4572)
		(drill 0.2032)
		(layers "F.Cu" "B.Cu")
		(net "TWI_SDA4")
	)
	(segment
		(start 245.564152 -26.406348)
		(end 245.684802 -26.526998)
		(width 0.12065)
		(layer "B.Cu")
		(net "TWI_SDA4")
	)
	(segment
		(start 244.48516 -29.819854)
		(end 244.48516 -29.39923)
		(width 0.1016)
		(layer "B.Cu")
		(net "TWI_SDA4")
	)
	(segment
		(start 245.177818 -26.406348)
		(end 245.564152 -26.406348)
		(width 0.12065)
		(layer "B.Cu")
		(net "TWI_SDA4")
	)
	(segment
		(start 244.634512 -28.560268)
		(end 245.056914 -28.137866)
		(width 0.12065)
		(layer "B.Cu")
		(net "TWI_SDA4")
	)
	(segment
		(start 245.09984 -38.50005)
		(end 244.793262 -38.50005)
		(width 0.1016)
		(layer "B.Cu")
		(net "TWI_SDA4")
	)
	(segment
		(start 245.056914 -28.137866)
		(end 245.056914 -26.527252)
		(width 0.12065)
		(layer "B.Cu")
		(net "TWI_SDA4")
	)
	(segment
		(start 245.684802 -26.526998)
		(end 245.684802 -26.67)
		(width 0.12065)
		(layer "B.Cu")
		(net "TWI_SDA4")
	)
	(segment
		(start 245.056914 -26.527252)
		(end 245.177818 -26.406348)
		(width 0.12065)
		(layer "B.Cu")
		(net "TWI_SDA4")
	)
	(segment
		(start 244.634512 -29.249878)
		(end 244.634512 -29.224478)
		(width 0.1016)
		(layer "B.Cu")
		(net "TWI_SDA4")
	)
	(segment
		(start 244.696742 -38.40353)
		(end 244.696742 -30.031436)
		(width 0.1016)
		(layer "B.Cu")
		(net "TWI_SDA4")
	)
	(segment
		(start 244.696742 -30.031436)
		(end 244.48516 -29.819854)
		(width 0.1016)
		(layer "B.Cu")
		(net "TWI_SDA4")
	)
	(segment
		(start 244.793262 -38.50005)
		(end 244.696742 -38.40353)
		(width 0.1016)
		(layer "B.Cu")
		(net "TWI_SDA4")
	)
	(segment
		(start 244.48516 -29.39923)
		(end 244.634512 -29.249878)
		(width 0.1016)
		(layer "B.Cu")
		(net "TWI_SDA4")
	)
	(segment
		(start 244.634512 -29.224478)
		(end 244.634512 -28.560268)
		(width 0.12065)
		(layer "B.Cu")
		(net "TWI_SDA4")
	)
	(segment
		(start 231.383586 -7.565898)
		(end 233.154728 -9.33704)
		(width 0.12065)
		(layer "F.Cu")
		(net "TWI_SDA2")
	)
	(segment
		(start 230.6955 -7.366)
		(end 230.895398 -7.565898)
		(width 0.12065)
		(layer "F.Cu")
		(net "TWI_SDA2")
	)
	(segment
		(start 233.154728 -9.33704)
		(end 233.154728 -10.07364)
		(width 0.12065)
		(layer "F.Cu")
		(net "TWI_SDA2")
	)
	(segment
		(start 249.599958 -33.999932)
		(end 250.09983 -33.50006)
		(width 0.12065)
		(layer "F.Cu")
		(net "TWI_SDA2")
	)
	(segment
		(start 230.895398 -7.565898)
		(end 231.383586 -7.565898)
		(width 0.12065)
		(layer "F.Cu")
		(net "TWI_SDA2")
	)
	(segment
		(start 233.154728 -10.07364)
		(end 233.413808 -10.33272)
		(width 0.12065)
		(layer "F.Cu")
		(net "TWI_SDA2")
	)
	(via
		(at 233.413808 -10.33272)
		(size 0.508)
		(drill 0.254)
		(layers "F.Cu" "B.Cu")
		(net "TWI_SDA2")
	)
	(via
		(at 250.12904 -28.496006)
		(size 0.7112)
		(drill 0.3556)
		(layers "F.Cu" "B.Cu")
		(net "TWI_SDA2")
	)
	(via
		(at 250.09983 -33.50006)
		(size 0.4572)
		(drill 0.2032)
		(layers "F.Cu" "B.Cu")
		(net "TWI_SDA2")
	)
	(segment
		(start 250.49353 -30.336744)
		(end 250.49353 -33.10636)
		(width 0.1016)
		(layer "B.Cu")
		(net "TWI_SDA2")
	)
	(segment
		(start 250.376436 -28.743402)
		(end 249.96902 -29.150818)
		(width 0.12065)
		(layer "B.Cu")
		(net "TWI_SDA2")
	)
	(segment
		(start 250.376436 -28.743402)
		(end 250.841256 -28.278582)
		(width 0.12065)
		(layer "B.Cu")
		(net "TWI_SDA2")
	)
	(segment
		(start 250.841256 -28.278582)
		(end 250.841256 -26.812748)
		(width 0.12065)
		(layer "B.Cu")
		(net "TWI_SDA2")
	)
	(segment
		(start 250.118118 -29.702252)
		(end 250.118118 -29.961332)
		(width 0.1016)
		(layer "B.Cu")
		(net "TWI_SDA2")
	)
	(segment
		(start 250.841256 -26.812748)
		(end 250.584208 -26.5557)
		(width 0.12065)
		(layer "B.Cu")
		(net "TWI_SDA2")
	)
	(segment
		(start 250.49353 -33.10636)
		(end 250.09983 -33.50006)
		(width 0.1016)
		(layer "B.Cu")
		(net "TWI_SDA2")
	)
	(segment
		(start 249.96902 -29.150818)
		(end 249.96902 -29.527754)
		(width 0.12065)
		(layer "B.Cu")
		(net "TWI_SDA2")
	)
	(segment
		(start 250.118118 -29.961332)
		(end 250.49353 -30.336744)
		(width 0.1016)
		(layer "B.Cu")
		(net "TWI_SDA2")
	)
	(segment
		(start 249.96902 -29.553154)
		(end 250.118118 -29.702252)
		(width 0.1016)
		(layer "B.Cu")
		(net "TWI_SDA2")
	)
	(segment
		(start 249.96902 -29.527754)
		(end 249.96902 -29.553154)
		(width 0.1016)
		(layer "B.Cu")
		(net "TWI_SDA2")
	)
	(segment
		(start 250.12904 -28.496006)
		(end 250.376436 -28.743402)
		(width 0.12065)
		(layer "B.Cu")
		(net "TWI_SDA2")
	)
	(segment
		(start 243.95557 -16.2179)
		(end 234.4801 -16.2179)
		(width 0.127)
		(layer "In5.Cu")
		(net "TWI_SDA2")
	)
	(segment
		(start 248.506234 -30.331664)
		(end 248.031 -29.85643)
		(width 0.127)
		(layer "In5.Cu")
		(net "TWI_SDA2")
	)
	(segment
		(start 249.501152 -32.32658)
		(end 249.076972 -31.9024)
		(width 0.1016)
		(layer "In5.Cu")
		(net "TWI_SDA2")
	)
	(segment
		(start 234.4801 -16.2179)
		(end 233.147616 -14.885416)
		(width 0.127)
		(layer "In5.Cu")
		(net "TWI_SDA2")
	)
	(segment
		(start 233.147616 -14.885416)
		(end 233.147616 -10.598912)
		(width 0.127)
		(layer "In5.Cu")
		(net "TWI_SDA2")
	)
	(segment
		(start 250.09983 -33.50006)
		(end 249.501152 -32.901382)
		(width 0.1016)
		(layer "In5.Cu")
		(net "TWI_SDA2")
	)
	(segment
		(start 248.684034 -31.9024)
		(end 248.506234 -31.7246)
		(width 0.1016)
		(layer "In5.Cu")
		(net "TWI_SDA2")
	)
	(segment
		(start 233.147616 -10.598912)
		(end 233.413808 -10.33272)
		(width 0.127)
		(layer "In5.Cu")
		(net "TWI_SDA2")
	)
	(segment
		(start 249.501152 -32.901382)
		(end 249.501152 -32.32658)
		(width 0.1016)
		(layer "In5.Cu")
		(net "TWI_SDA2")
	)
	(segment
		(start 248.031 -27.15006)
		(end 247.840754 -26.959814)
		(width 0.127)
		(layer "In5.Cu")
		(net "TWI_SDA2")
	)
	(segment
		(start 248.506234 -31.7246)
		(end 248.506234 -30.331664)
		(width 0.127)
		(layer "In5.Cu")
		(net "TWI_SDA2")
	)
	(segment
		(start 247.840754 -20.103084)
		(end 243.95557 -16.2179)
		(width 0.127)
		(layer "In5.Cu")
		(net "TWI_SDA2")
	)
	(segment
		(start 249.076972 -31.9024)
		(end 248.684034 -31.9024)
		(width 0.1016)
		(layer "In5.Cu")
		(net "TWI_SDA2")
	)
	(segment
		(start 247.840754 -26.959814)
		(end 247.840754 -20.103084)
		(width 0.127)
		(layer "In5.Cu")
		(net "TWI_SDA2")
	)
	(segment
		(start 248.031 -29.85643)
		(end 248.031 -27.15006)
		(width 0.127)
		(layer "In5.Cu")
		(net "TWI_SDA2")
	)
	(segment
		(start 246.599964 -33.999932)
		(end 247.099836 -33.50006)
		(width 0.12065)
		(layer "F.Cu")
		(net "TWI_SDA10")
	)
	(via
		(at 247.099836 -33.50006)
		(size 0.4572)
		(drill 0.2032)
		(layers "F.Cu" "B.Cu")
		(net "TWI_SDA10")
	)
	(segment
		(start 246.514112 -29.115766)
		(end 246.514112 -29.141166)
		(width 0.1016)
		(layer "B.Cu")
		(net "TWI_SDA10")
	)
	(segment
		(start 246.36476 -29.818076)
		(end 246.696738 -30.150054)
		(width 0.1016)
		(layer "B.Cu")
		(net "TWI_SDA10")
	)
	(segment
		(start 246.696738 -33.096962)
		(end 247.099836 -33.50006)
		(width 0.1016)
		(layer "B.Cu")
		(net "TWI_SDA10")
	)
	(segment
		(start 247.530366 -26.310336)
		(end 247.146572 -26.310336)
		(width 0.12065)
		(layer "B.Cu")
		(net "TWI_SDA10")
	)
	(segment
		(start 246.891556 -26.565352)
		(end 246.891556 -28.243276)
		(width 0.12065)
		(layer "B.Cu")
		(net "TWI_SDA10")
	)
	(segment
		(start 247.651016 -26.694638)
		(end 247.651016 -26.430986)
		(width 0.12065)
		(layer "B.Cu")
		(net "TWI_SDA10")
	)
	(segment
		(start 246.514112 -28.62072)
		(end 246.514112 -29.115766)
		(width 0.12065)
		(layer "B.Cu")
		(net "TWI_SDA10")
	)
	(segment
		(start 247.651016 -26.430986)
		(end 247.530366 -26.310336)
		(width 0.12065)
		(layer "B.Cu")
		(net "TWI_SDA10")
	)
	(segment
		(start 247.146572 -26.310336)
		(end 246.891556 -26.565352)
		(width 0.12065)
		(layer "B.Cu")
		(net "TWI_SDA10")
	)
	(segment
		(start 246.514112 -29.141166)
		(end 246.36476 -29.290518)
		(width 0.1016)
		(layer "B.Cu")
		(net "TWI_SDA10")
	)
	(segment
		(start 246.696738 -30.150054)
		(end 246.696738 -33.096962)
		(width 0.1016)
		(layer "B.Cu")
		(net "TWI_SDA10")
	)
	(segment
		(start 246.36476 -29.290518)
		(end 246.36476 -29.818076)
		(width 0.1016)
		(layer "B.Cu")
		(net "TWI_SDA10")
	)
	(segment
		(start 246.891556 -28.243276)
		(end 246.514112 -28.62072)
		(width 0.12065)
		(layer "B.Cu")
		(net "TWI_SDA10")
	)
	(segment
		(start 220.341698 -180.802788)
		(end 219.728796 -181.41569)
		(width 0.12065)
		(layer "F.Cu")
		(net "TWI_SDA1")
	)
	(segment
		(start 265.684 -27.2288)
		(end 265.3538 -27.559)
		(width 0.12065)
		(layer "F.Cu")
		(net "TWI_SDA1")
	)
	(segment
		(start 335.5594 -87.304372)
		(end 330.77023 -82.515202)
		(width 0.12065)
		(layer "F.Cu")
		(net "TWI_SDA1")
	)
	(segment
		(start 249.599958 -36.999926)
		(end 250.09983 -36.500054)
		(width 0.12065)
		(layer "F.Cu")
		(net "TWI_SDA1")
	)
	(segment
		(start 160.209738 -201.529696)
		(end 150.42134 -191.741298)
		(width 0.12065)
		(layer "F.Cu")
		(net "TWI_SDA1")
	)
	(segment
		(start 287.943036 -82.515202)
		(end 265.58748 -60.159646)
		(width 0.12065)
		(layer "F.Cu")
		(net "TWI_SDA1")
	)
	(segment
		(start 69.619368 -197.744588)
		(end 66.829686 -197.744588)
		(width 0.12065)
		(layer "F.Cu")
		(net "TWI_SDA1")
	)
	(segment
		(start 124.289312 -210.52155)
		(end 123.928124 -210.160362)
		(width 0.12065)
		(layer "F.Cu")
		(net "TWI_SDA1")
	)
	(segment
		(start 201.68362 -181.41569)
		(end 181.569614 -201.529696)
		(width 0.12065)
		(layer "F.Cu")
		(net "TWI_SDA1")
	)
	(segment
		(start 66.04 -196.954902)
		(end 66.04 -186.170824)
		(width 0.12065)
		(layer "F.Cu")
		(net "TWI_SDA1")
	)
	(segment
		(start 219.728796 -181.41569)
		(end 201.68362 -181.41569)
		(width 0.12065)
		(layer "F.Cu")
		(net "TWI_SDA1")
	)
	(segment
		(start 116.479066 -197.029832)
		(end 116.479066 -206.354934)
		(width 0.12065)
		(layer "F.Cu")
		(net "TWI_SDA1")
	)
	(segment
		(start 330.740512 -185.322718)
		(end 330.740512 -186.149488)
		(width 0.12065)
		(layer "F.Cu")
		(net "TWI_SDA1")
	)
	(segment
		(start 66.704972 -181.358794)
		(end 70.130924 -177.932842)
		(width 0.12065)
		(layer "F.Cu")
		(net "TWI_SDA1")
	)
	(segment
		(start 328.40422 -164.824918)
		(end 328.40422 -161.13887)
		(width 0.12065)
		(layer "F.Cu")
		(net "TWI_SDA1")
	)
	(segment
		(start 265.58748 -27.79268)
		(end 265.3538 -27.559)
		(width 0.12065)
		(layer "F.Cu")
		(net "TWI_SDA1")
	)
	(segment
		(start 124.01296 -211.115148)
		(end 124.289312 -210.838796)
		(width 0.12065)
		(layer "F.Cu")
		(net "TWI_SDA1")
	)
	(segment
		(start 328.40422 -161.13887)
		(end 335.5594 -153.98369)
		(width 0.12065)
		(layer "F.Cu")
		(net "TWI_SDA1")
	)
	(segment
		(start 123.928124 -209.333592)
		(end 123.928124 -210.160362)
		(width 0.12065)
		(layer "F.Cu")
		(net "TWI_SDA1")
	)
	(segment
		(start 69.699124 -196.125592)
		(end 69.968872 -196.39534)
		(width 0.12065)
		(layer "F.Cu")
		(net "TWI_SDA1")
	)
	(segment
		(start 97.382076 -177.932842)
		(end 116.479066 -197.029832)
		(width 0.12065)
		(layer "F.Cu")
		(net "TWI_SDA1")
	)
	(segment
		(start 66.829686 -197.744588)
		(end 66.04 -196.954902)
		(width 0.12065)
		(layer "F.Cu")
		(net "TWI_SDA1")
	)
	(segment
		(start 69.968872 -196.39534)
		(end 69.968872 -197.395084)
		(width 0.12065)
		(layer "F.Cu")
		(net "TWI_SDA1")
	)
	(segment
		(start 220.5228 -179.7558)
		(end 220.341698 -179.936902)
		(width 0.12065)
		(layer "F.Cu")
		(net "TWI_SDA1")
	)
	(segment
		(start 66.04 -186.170824)
		(end 66.704972 -185.505852)
		(width 0.12065)
		(layer "F.Cu")
		(net "TWI_SDA1")
	)
	(segment
		(start 335.5594 -153.98369)
		(end 335.5594 -87.304372)
		(width 0.12065)
		(layer "F.Cu")
		(net "TWI_SDA1")
	)
	(segment
		(start 121.685558 -211.115148)
		(end 124.01296 -211.115148)
		(width 0.12065)
		(layer "F.Cu")
		(net "TWI_SDA1")
	)
	(segment
		(start 124.289312 -210.838796)
		(end 124.289312 -210.52155)
		(width 0.12065)
		(layer "F.Cu")
		(net "TWI_SDA1")
	)
	(segment
		(start 69.968872 -197.395084)
		(end 69.619368 -197.744588)
		(width 0.12065)
		(layer "F.Cu")
		(net "TWI_SDA1")
	)
	(segment
		(start 220.341698 -179.936902)
		(end 220.341698 -180.802788)
		(width 0.12065)
		(layer "F.Cu")
		(net "TWI_SDA1")
	)
	(segment
		(start 70.130924 -177.932842)
		(end 97.382076 -177.932842)
		(width 0.12065)
		(layer "F.Cu")
		(net "TWI_SDA1")
	)
	(segment
		(start 120.250204 -196.12229)
		(end 120.250204 -209.679794)
		(width 0.12065)
		(layer "F.Cu")
		(net "TWI_SDA1")
	)
	(segment
		(start 327.7997 -165.4302)
		(end 328.40422 -164.824918)
		(width 0.12065)
		(layer "F.Cu")
		(net "TWI_SDA1")
	)
	(segment
		(start 150.42134 -191.741298)
		(end 124.631196 -191.741298)
		(width 0.12065)
		(layer "F.Cu")
		(net "TWI_SDA1")
	)
	(segment
		(start 66.704972 -185.505852)
		(end 66.704972 -181.358794)
		(width 0.12065)
		(layer "F.Cu")
		(net "TWI_SDA1")
	)
	(segment
		(start 217.781124 -203.491592)
		(end 217.781124 -204.318362)
		(width 0.12065)
		(layer "F.Cu")
		(net "TWI_SDA1")
	)
	(segment
		(start 330.77023 -82.515202)
		(end 287.943036 -82.515202)
		(width 0.12065)
		(layer "F.Cu")
		(net "TWI_SDA1")
	)
	(segment
		(start 181.569614 -201.529696)
		(end 160.209738 -201.529696)
		(width 0.12065)
		(layer "F.Cu")
		(net "TWI_SDA1")
	)
	(segment
		(start 116.479066 -206.354934)
		(end 116.3066 -206.5274)
		(width 0.12065)
		(layer "F.Cu")
		(net "TWI_SDA1")
	)
	(segment
		(start 120.250204 -209.679794)
		(end 121.685558 -211.115148)
		(width 0.12065)
		(layer "F.Cu")
		(net "TWI_SDA1")
	)
	(segment
		(start 265.684 -26.7335)
		(end 265.684 -27.2288)
		(width 0.12065)
		(layer "F.Cu")
		(net "TWI_SDA1")
	)
	(segment
		(start 124.631196 -191.741298)
		(end 120.250204 -196.12229)
		(width 0.12065)
		(layer "F.Cu")
		(net "TWI_SDA1")
	)
	(segment
		(start 265.58748 -60.159646)
		(end 265.58748 -27.79268)
		(width 0.12065)
		(layer "F.Cu")
		(net "TWI_SDA1")
	)
	(via
		(at 116.3066 -206.5274)
		(size 0.508)
		(drill 0.254)
		(layers "F.Cu" "B.Cu")
		(net "TWI_SDA1")
	)
	(via
		(at 327.7997 -165.4302)
		(size 0.508)
		(drill 0.254)
		(layers "F.Cu" "B.Cu")
		(net "TWI_SDA1")
	)
	(via
		(at 220.5228 -179.7558)
		(size 0.508)
		(drill 0.254)
		(layers "F.Cu" "B.Cu")
		(net "TWI_SDA1")
	)
	(via
		(at 328.1172 -161.988754)
		(size 0.7112)
		(drill 0.3556)
		(layers "F.Cu" "B.Cu")
		(net "TWI_SDA1")
	)
	(via
		(at 217.781124 -204.318362)
		(size 0.508)
		(drill 0.254)
		(layers "F.Cu" "B.Cu")
		(net "TWI_SDA1")
	)
	(via
		(at 250.09983 -36.500054)
		(size 0.4572)
		(drill 0.2032)
		(layers "F.Cu" "B.Cu")
		(net "TWI_SDA1")
	)
	(via
		(at 330.740512 -186.149488)
		(size 0.508)
		(drill 0.254)
		(layers "F.Cu" "B.Cu")
		(net "TWI_SDA1")
	)
	(via
		(at 265.3538 -27.559)
		(size 0.508)
		(drill 0.254)
		(layers "F.Cu" "B.Cu")
		(net "TWI_SDA1")
	)
	(via
		(at 123.928124 -210.160362)
		(size 0.508)
		(drill 0.254)
		(layers "F.Cu" "B.Cu")
		(net "TWI_SDA1")
	)
	(segment
		(start 121.041414 -210.93049)
		(end 124.029724 -210.93049)
		(width 0.12065)
		(layer "B.Cu")
		(net "TWI_SDA1")
	)
	(segment
		(start 118.7196 -208.608676)
		(end 121.041414 -210.93049)
		(width 0.12065)
		(layer "B.Cu")
		(net "TWI_SDA1")
	)
	(segment
		(start 328.422508 -161.988754)
		(end 328.422508 -161.242248)
		(width 0.12065)
		(layer "B.Cu")
		(net "TWI_SDA1")
	)
	(segment
		(start 323.193664 -156.013404)
		(end 320.84518 -156.013404)
		(width 0.12065)
		(layer "B.Cu")
		(net "TWI_SDA1")
	)
	(segment
		(start 328.1172 -161.988754)
		(end 328.422508 -161.988754)
		(width 0.12065)
		(layer "B.Cu")
		(net "TWI_SDA1")
	)
	(segment
		(start 226.808284 -155.59405)
		(end 220.355922 -162.046412)
		(width 0.12065)
		(layer "B.Cu")
		(net "TWI_SDA1")
	)
	(segment
		(start 116.3066 -206.5274)
		(end 116.459 -206.375)
		(width 0.12065)
		(layer "B.Cu")
		(net "TWI_SDA1")
	)
	(segment
		(start 220.355922 -179.588922)
		(end 220.5228 -179.7558)
		(width 0.12065)
		(layer "B.Cu")
		(net "TWI_SDA1")
	)
	(segment
		(start 328.422508 -161.242248)
		(end 323.193664 -156.013404)
		(width 0.12065)
		(layer "B.Cu")
		(net "TWI_SDA1")
	)
	(segment
		(start 118.7196 -205.628494)
		(end 118.7196 -208.608676)
		(width 0.12065)
		(layer "B.Cu")
		(net "TWI_SDA1")
	)
	(segment
		(start 124.029724 -210.93049)
		(end 124.233432 -210.726782)
		(width 0.12065)
		(layer "B.Cu")
		(net "TWI_SDA1")
	)
	(segment
		(start 220.355922 -162.046412)
		(end 220.355922 -179.588922)
		(width 0.12065)
		(layer "B.Cu")
		(net "TWI_SDA1")
	)
	(segment
		(start 118.148862 -205.057756)
		(end 118.7196 -205.628494)
		(width 0.12065)
		(layer "B.Cu")
		(net "TWI_SDA1")
	)
	(segment
		(start 116.459 -205.47203)
		(end 116.873274 -205.057756)
		(width 0.12065)
		(layer "B.Cu")
		(net "TWI_SDA1")
	)
	(segment
		(start 320.425826 -155.59405)
		(end 226.808284 -155.59405)
		(width 0.12065)
		(layer "B.Cu")
		(net "TWI_SDA1")
	)
	(segment
		(start 116.459 -206.375)
		(end 116.459 -205.47203)
		(width 0.12065)
		(layer "B.Cu")
		(net "TWI_SDA1")
	)
	(segment
		(start 124.233432 -210.726782)
		(end 124.233432 -210.46567)
		(width 0.12065)
		(layer "B.Cu")
		(net "TWI_SDA1")
	)
	(segment
		(start 320.84518 -156.013404)
		(end 320.425826 -155.59405)
		(width 0.12065)
		(layer "B.Cu")
		(net "TWI_SDA1")
	)
	(segment
		(start 124.233432 -210.46567)
		(end 123.928124 -210.160362)
		(width 0.12065)
		(layer "B.Cu")
		(net "TWI_SDA1")
	)
	(segment
		(start 328.422508 -164.807392)
		(end 327.7997 -165.4302)
		(width 0.12065)
		(layer "B.Cu")
		(net "TWI_SDA1")
	)
	(segment
		(start 116.873274 -205.057756)
		(end 118.148862 -205.057756)
		(width 0.12065)
		(layer "B.Cu")
		(net "TWI_SDA1")
	)
	(segment
		(start 328.422508 -161.988754)
		(end 328.422508 -164.807392)
		(width 0.12065)
		(layer "B.Cu")
		(net "TWI_SDA1")
	)
	(segment
		(start 264.96391 -28.886912)
		(end 262.136382 -28.886912)
		(width 0.127)
		(layer "In2.Cu")
		(net "TWI_SDA1")
	)
	(segment
		(start 262.136382 -28.886912)
		(end 261.031482 -29.991812)
		(width 0.127)
		(layer "In2.Cu")
		(net "TWI_SDA1")
	)
	(segment
		(start 253.495556 -33.157668)
		(end 253.495556 -33.802574)
		(width 0.1016)
		(layer "In2.Cu")
		(net "TWI_SDA1")
	)
	(segment
		(start 253.75489 -32.898334)
		(end 253.495556 -33.157668)
		(width 0.1016)
		(layer "In2.Cu")
		(net "TWI_SDA1")
	)
	(segment
		(start 254.856234 -30.89402)
		(end 254.499872 -31.250382)
		(width 0.1016)
		(layer "In2.Cu")
		(net "TWI_SDA1")
	)
	(segment
		(start 253.495556 -33.802574)
		(end 253.399798 -33.898332)
		(width 0.1016)
		(layer "In2.Cu")
		(net "TWI_SDA1")
	)
	(segment
		(start 251.355098 -35.894772)
		(end 250.705112 -35.894772)
		(width 0.1016)
		(layer "In2.Cu")
		(net "TWI_SDA1")
	)
	(segment
		(start 260.95833 -30.89402)
		(end 254.856234 -30.89402)
		(width 0.1016)
		(layer "In2.Cu")
		(net "TWI_SDA1")
	)
	(segment
		(start 261.183882 -30.668468)
		(end 260.95833 -30.89402)
		(width 0.1016)
		(layer "In2.Cu")
		(net "TWI_SDA1")
	)
	(segment
		(start 261.183882 -30.522164)
		(end 261.183882 -30.668468)
		(width 0.1016)
		(layer "In2.Cu")
		(net "TWI_SDA1")
	)
	(segment
		(start 265.3538 -27.559)
		(end 265.55446 -27.75966)
		(width 0.127)
		(layer "In2.Cu")
		(net "TWI_SDA1")
	)
	(segment
		(start 265.55446 -27.75966)
		(end 265.55446 -28.296362)
		(width 0.127)
		(layer "In2.Cu")
		(net "TWI_SDA1")
	)
	(segment
		(start 261.031482 -30.369764)
		(end 261.183882 -30.522164)
		(width 0.1016)
		(layer "In2.Cu")
		(net "TWI_SDA1")
	)
	(segment
		(start 252.778768 -33.898332)
		(end 251.50191 -35.17519)
		(width 0.1016)
		(layer "In2.Cu")
		(net "TWI_SDA1")
	)
	(segment
		(start 254.499872 -32.690816)
		(end 254.292354 -32.898334)
		(width 0.1016)
		(layer "In2.Cu")
		(net "TWI_SDA1")
	)
	(segment
		(start 251.50191 -35.17519)
		(end 251.50191 -35.74796)
		(width 0.1016)
		(layer "In2.Cu")
		(net "TWI_SDA1")
	)
	(segment
		(start 253.399798 -33.898332)
		(end 252.778768 -33.898332)
		(width 0.1016)
		(layer "In2.Cu")
		(net "TWI_SDA1")
	)
	(segment
		(start 261.031482 -30.344364)
		(end 261.031482 -30.369764)
		(width 0.1016)
		(layer "In2.Cu")
		(net "TWI_SDA1")
	)
	(segment
		(start 250.705112 -35.894772)
		(end 250.09983 -36.500054)
		(width 0.1016)
		(layer "In2.Cu")
		(net "TWI_SDA1")
	)
	(segment
		(start 254.499872 -31.250382)
		(end 254.499872 -32.690816)
		(width 0.1016)
		(layer "In2.Cu")
		(net "TWI_SDA1")
	)
	(segment
		(start 261.031482 -29.991812)
		(end 261.031482 -30.344364)
		(width 0.127)
		(layer "In2.Cu")
		(net "TWI_SDA1")
	)
	(segment
		(start 254.292354 -32.898334)
		(end 253.75489 -32.898334)
		(width 0.1016)
		(layer "In2.Cu")
		(net "TWI_SDA1")
	)
	(segment
		(start 251.50191 -35.74796)
		(end 251.355098 -35.894772)
		(width 0.1016)
		(layer "In2.Cu")
		(net "TWI_SDA1")
	)
	(segment
		(start 265.55446 -28.296362)
		(end 264.96391 -28.886912)
		(width 0.127)
		(layer "In2.Cu")
		(net "TWI_SDA1")
	)
	(segment
		(start 218.2622 -178.500024)
		(end 219.940124 -178.500024)
		(width 0.127)
		(layer "In5.Cu")
		(net "TWI_SDA1")
	)
	(segment
		(start 328.7903 -176.658524)
		(end 331.108812 -178.977036)
		(width 0.127)
		(layer "In5.Cu")
		(net "TWI_SDA1")
	)
	(segment
		(start 327.7997 -165.4302)
		(end 328.0156 -165.4302)
		(width 0.127)
		(layer "In5.Cu")
		(net "TWI_SDA1")
	)
	(segment
		(start 218.0336 -200.320148)
		(end 215.6841 -197.970648)
		(width 0.127)
		(layer "In5.Cu")
		(net "TWI_SDA1")
	)
	(segment
		(start 217.7796 -186.405012)
		(end 217.7796 -178.982624)
		(width 0.127)
		(layer "In5.Cu")
		(net "TWI_SDA1")
	)
	(segment
		(start 220.2307 -178.7906)
		(end 220.2307 -179.039012)
		(width 0.127)
		(layer "In5.Cu")
		(net "TWI_SDA1")
	)
	(segment
		(start 328.7903 -166.2049)
		(end 328.7903 -176.658524)
		(width 0.127)
		(layer "In5.Cu")
		(net "TWI_SDA1")
	)
	(segment
		(start 331.108812 -178.977036)
		(end 331.108812 -185.781188)
		(width 0.127)
		(layer "In5.Cu")
		(net "TWI_SDA1")
	)
	(segment
		(start 215.6841 -188.500512)
		(end 217.7796 -186.405012)
		(width 0.127)
		(layer "In5.Cu")
		(net "TWI_SDA1")
	)
	(segment
		(start 215.6841 -197.970648)
		(end 215.6841 -188.500512)
		(width 0.127)
		(layer "In5.Cu")
		(net "TWI_SDA1")
	)
	(segment
		(start 219.940124 -178.500024)
		(end 220.2307 -178.7906)
		(width 0.127)
		(layer "In5.Cu")
		(net "TWI_SDA1")
	)
	(segment
		(start 220.2307 -179.039012)
		(end 220.5228 -179.331112)
		(width 0.127)
		(layer "In5.Cu")
		(net "TWI_SDA1")
	)
	(segment
		(start 220.5228 -179.331112)
		(end 220.5228 -179.7558)
		(width 0.127)
		(layer "In5.Cu")
		(net "TWI_SDA1")
	)
	(segment
		(start 331.108812 -185.781188)
		(end 330.740512 -186.149488)
		(width 0.127)
		(layer "In5.Cu")
		(net "TWI_SDA1")
	)
	(segment
		(start 217.7796 -178.982624)
		(end 218.2622 -178.500024)
		(width 0.127)
		(layer "In5.Cu")
		(net "TWI_SDA1")
	)
	(segment
		(start 217.781124 -204.318362)
		(end 218.0336 -204.065886)
		(width 0.127)
		(layer "In5.Cu")
		(net "TWI_SDA1")
	)
	(segment
		(start 218.0336 -204.065886)
		(end 218.0336 -200.320148)
		(width 0.127)
		(layer "In5.Cu")
		(net "TWI_SDA1")
	)
	(segment
		(start 328.0156 -165.4302)
		(end 328.7903 -166.2049)
		(width 0.127)
		(layer "In5.Cu")
		(net "TWI_SDA1")
	)
	(segment
		(start 121.272554 -102.790244)
		(end 121.038874 -103.023924)
		(width 0.12065)
		(layer "F.Cu")
		(net "TWI_SDA0")
	)
	(segment
		(start 120.9548 -101.8667)
		(end 121.272554 -102.184454)
		(width 0.12065)
		(layer "F.Cu")
		(net "TWI_SDA0")
	)
	(segment
		(start 250.599956 -34.99993)
		(end 251.099828 -34.500058)
		(width 0.12065)
		(layer "F.Cu")
		(net "TWI_SDA0")
	)
	(segment
		(start 121.272554 -102.184454)
		(end 121.272554 -102.790244)
		(width 0.12065)
		(layer "F.Cu")
		(net "TWI_SDA0")
	)
	(via
		(at 121.038874 -103.023924)
		(size 0.508)
		(drill 0.254)
		(layers "F.Cu" "B.Cu")
		(net "TWI_SDA0")
	)
	(via
		(at 110.530894 -42.390568)
		(size 0.508)
		(drill 0.254)
		(layers "F.Cu" "B.Cu")
		(net "TWI_SDA0")
	)
	(via
		(at 251.099828 -34.500058)
		(size 0.4572)
		(drill 0.2032)
		(layers "F.Cu" "B.Cu")
		(net "TWI_SDA0")
	)
	(via
		(at 120.90654 -101.592634)
		(size 0.7112)
		(drill 0.3556)
		(layers "F.Cu" "B.Cu")
		(net "TWI_SDA0")
	)
	(segment
		(start 251.6632 -35.620452)
		(end 251.6632 -35.06343)
		(width 0.1016)
		(layer "B.Cu")
		(net "TWI_SDA0")
	)
	(segment
		(start 252.263148 -35.893756)
		(end 251.936504 -35.893756)
		(width 0.1016)
		(layer "B.Cu")
		(net "TWI_SDA0")
	)
	(segment
		(start 252.833632 -29.708348)
		(end 252.49886 -30.04312)
		(width 0.1016)
		(layer "B.Cu")
		(net "TWI_SDA0")
	)
	(segment
		(start 121.25452 -102.808278)
		(end 121.038874 -103.023924)
		(width 0.12065)
		(layer "B.Cu")
		(net "TWI_SDA0")
	)
	(segment
		(start 254.015748 -27.94762)
		(end 253.19482 -28.768548)
		(width 0.12065)
		(layer "B.Cu")
		(net "TWI_SDA0")
	)
	(segment
		(start 251.936504 -35.893756)
		(end 251.6632 -35.620452)
		(width 0.1016)
		(layer "B.Cu")
		(net "TWI_SDA0")
	)
	(segment
		(start 252.49886 -30.04312)
		(end 252.49886 -35.658044)
		(width 0.1016)
		(layer "B.Cu")
		(net "TWI_SDA0")
	)
	(segment
		(start 121.25452 -101.592634)
		(end 120.90654 -101.592634)
		(width 0.12065)
		(layer "B.Cu")
		(net "TWI_SDA0")
	)
	(segment
		(start 120.9548 -96.6343)
		(end 121.25452 -96.93402)
		(width 0.12065)
		(layer "B.Cu")
		(net "TWI_SDA0")
	)
	(segment
		(start 252.49886 -35.658044)
		(end 252.263148 -35.893756)
		(width 0.1016)
		(layer "B.Cu")
		(net "TWI_SDA0")
	)
	(segment
		(start 253.19482 -29.13634)
		(end 252.851412 -29.479748)
		(width 0.12065)
		(layer "B.Cu")
		(net "TWI_SDA0")
	)
	(segment
		(start 121.25452 -101.592634)
		(end 121.25452 -102.808278)
		(width 0.12065)
		(layer "B.Cu")
		(net "TWI_SDA0")
	)
	(segment
		(start 254.015748 -27.244548)
		(end 254.015748 -27.94762)
		(width 0.12065)
		(layer "B.Cu")
		(net "TWI_SDA0")
	)
	(segment
		(start 252.851412 -29.479748)
		(end 252.833632 -29.497528)
		(width 0.1016)
		(layer "B.Cu")
		(net "TWI_SDA0")
	)
	(segment
		(start 251.6632 -35.06343)
		(end 251.099828 -34.500058)
		(width 0.1016)
		(layer "B.Cu")
		(net "TWI_SDA0")
	)
	(segment
		(start 121.25452 -96.93402)
		(end 121.25452 -101.592634)
		(width 0.12065)
		(layer "B.Cu")
		(net "TWI_SDA0")
	)
	(segment
		(start 253.746 -26.5557)
		(end 253.746 -26.9748)
		(width 0.12065)
		(layer "B.Cu")
		(net "TWI_SDA0")
	)
	(segment
		(start 252.833632 -29.497528)
		(end 252.833632 -29.708348)
		(width 0.1016)
		(layer "B.Cu")
		(net "TWI_SDA0")
	)
	(segment
		(start 253.746 -26.9748)
		(end 254.015748 -27.244548)
		(width 0.12065)
		(layer "B.Cu")
		(net "TWI_SDA0")
	)
	(segment
		(start 253.19482 -28.768548)
		(end 253.19482 -29.13634)
		(width 0.12065)
		(layer "B.Cu")
		(net "TWI_SDA0")
	)
	(segment
		(start 121.2977 -97.820734)
		(end 121.2977 -102.765098)
		(width 0.127)
		(layer "In2.Cu")
		(net "TWI_SDA0")
	)
	(segment
		(start 106.073194 -47.46244)
		(end 106.073194 -72.275446)
		(width 0.127)
		(layer "In2.Cu")
		(net "TWI_SDA0")
	)
	(segment
		(start 106.073194 -72.275446)
		(end 124.1552 -90.357452)
		(width 0.127)
		(layer "In2.Cu")
		(net "TWI_SDA0")
	)
	(segment
		(start 124.1552 -94.963234)
		(end 121.2977 -97.820734)
		(width 0.127)
		(layer "In2.Cu")
		(net "TWI_SDA0")
	)
	(segment
		(start 109.847634 -43.688)
		(end 106.073194 -47.46244)
		(width 0.127)
		(layer "In2.Cu")
		(net "TWI_SDA0")
	)
	(segment
		(start 121.2977 -102.765098)
		(end 121.038874 -103.023924)
		(width 0.127)
		(layer "In2.Cu")
		(net "TWI_SDA0")
	)
	(segment
		(start 110.530894 -42.390568)
		(end 110.721394 -42.581068)
		(width 0.127)
		(layer "In2.Cu")
		(net "TWI_SDA0")
	)
	(segment
		(start 110.721394 -42.581068)
		(end 110.721394 -43.344084)
		(width 0.127)
		(layer "In2.Cu")
		(net "TWI_SDA0")
	)
	(segment
		(start 110.377478 -43.688)
		(end 109.847634 -43.688)
		(width 0.127)
		(layer "In2.Cu")
		(net "TWI_SDA0")
	)
	(segment
		(start 124.1552 -90.357452)
		(end 124.1552 -94.963234)
		(width 0.127)
		(layer "In2.Cu")
		(net "TWI_SDA0")
	)
	(segment
		(start 110.721394 -43.344084)
		(end 110.377478 -43.688)
		(width 0.127)
		(layer "In2.Cu")
		(net "TWI_SDA0")
	)
	(segment
		(start 248.823734 -28.449016)
		(end 248.706132 -28.566618)
		(width 0.1016)
		(layer "In5.Cu")
		(net "TWI_SDA0")
	)
	(segment
		(start 248.976134 -14.98727)
		(end 248.976134 -26.696416)
		(width 0.127)
		(layer "In5.Cu")
		(net "TWI_SDA0")
	)
	(segment
		(start 112.141 -40.270176)
		(end 112.141 -27.551634)
		(width 0.127)
		(layer "In5.Cu")
		(net "TWI_SDA0")
	)
	(segment
		(start 175.91532 -3.28041)
		(end 181.834028 -9.199118)
		(width 0.127)
		(layer "In5.Cu")
		(net "TWI_SDA0")
	)
	(segment
		(start 110.733332 -41.677844)
		(end 112.141 -40.270176)
		(width 0.127)
		(layer "In5.Cu")
		(net "TWI_SDA0")
	)
	(segment
		(start 242.447064 -8.4582)
		(end 248.976134 -14.98727)
		(width 0.127)
		(layer "In5.Cu")
		(net "TWI_SDA0")
	)
	(segment
		(start 249.849894 -31.893764)
		(end 250.050554 -31.893764)
		(width 0.1016)
		(layer "In5.Cu")
		(net "TWI_SDA0")
	)
	(segment
		(start 218.541346 -6.066536)
		(end 218.979242 -6.504432)
		(width 0.127)
		(layer "In5.Cu")
		(net "TWI_SDA0")
	)
	(segment
		(start 224.829116 -7.4422)
		(end 234.058714 -7.4422)
		(width 0.127)
		(layer "In5.Cu")
		(net "TWI_SDA0")
	)
	(segment
		(start 223.891348 -6.504432)
		(end 224.829116 -7.4422)
		(width 0.127)
		(layer "In5.Cu")
		(net "TWI_SDA0")
	)
	(segment
		(start 249.395742 -29.899102)
		(end 249.69724 -30.2006)
		(width 0.1016)
		(layer "In5.Cu")
		(net "TWI_SDA0")
	)
	(segment
		(start 248.706132 -28.566618)
		(end 248.706132 -29.66339)
		(width 0.1016)
		(layer "In5.Cu")
		(net "TWI_SDA0")
	)
	(segment
		(start 248.706132 -29.66339)
		(end 248.941844 -29.899102)
		(width 0.1016)
		(layer "In5.Cu")
		(net "TWI_SDA0")
	)
	(segment
		(start 235.074714 -8.4582)
		(end 242.447064 -8.4582)
		(width 0.127)
		(layer "In5.Cu")
		(net "TWI_SDA0")
	)
	(segment
		(start 112.141 -27.551634)
		(end 124.6759 -15.016734)
		(width 0.127)
		(layer "In5.Cu")
		(net "TWI_SDA0")
	)
	(segment
		(start 248.976134 -26.696416)
		(end 248.976134 -26.721816)
		(width 0.1016)
		(layer "In5.Cu")
		(net "TWI_SDA0")
	)
	(segment
		(start 212.760306 -9.73963)
		(end 216.4334 -6.066536)
		(width 0.127)
		(layer "In5.Cu")
		(net "TWI_SDA0")
	)
	(segment
		(start 250.050554 -31.893764)
		(end 250.698 -32.54121)
		(width 0.1016)
		(layer "In5.Cu")
		(net "TWI_SDA0")
	)
	(segment
		(start 248.941844 -29.899102)
		(end 249.395742 -29.899102)
		(width 0.1016)
		(layer "In5.Cu")
		(net "TWI_SDA0")
	)
	(segment
		(start 250.698 -32.54121)
		(end 250.698 -34.09823)
		(width 0.1016)
		(layer "In5.Cu")
		(net "TWI_SDA0")
	)
	(segment
		(start 234.058714 -7.4422)
		(end 235.074714 -8.4582)
		(width 0.127)
		(layer "In5.Cu")
		(net "TWI_SDA0")
	)
	(segment
		(start 181.834028 -9.199118)
		(end 189.26683 -9.199118)
		(width 0.127)
		(layer "In5.Cu")
		(net "TWI_SDA0")
	)
	(segment
		(start 218.979242 -6.504432)
		(end 223.891348 -6.504432)
		(width 0.127)
		(layer "In5.Cu")
		(net "TWI_SDA0")
	)
	(segment
		(start 189.26683 -9.199118)
		(end 190.375286 -10.307574)
		(width 0.127)
		(layer "In5.Cu")
		(net "TWI_SDA0")
	)
	(segment
		(start 249.69724 -30.2006)
		(end 249.69724 -31.74111)
		(width 0.1016)
		(layer "In5.Cu")
		(net "TWI_SDA0")
	)
	(segment
		(start 110.530894 -42.390568)
		(end 110.733332 -42.187368)
		(width 0.127)
		(layer "In5.Cu")
		(net "TWI_SDA0")
	)
	(segment
		(start 250.698 -34.09823)
		(end 251.099828 -34.500058)
		(width 0.1016)
		(layer "In5.Cu")
		(net "TWI_SDA0")
	)
	(segment
		(start 133.44652 -3.28041)
		(end 175.91532 -3.28041)
		(width 0.127)
		(layer "In5.Cu")
		(net "TWI_SDA0")
	)
	(segment
		(start 190.375286 -10.307574)
		(end 192.669414 -10.307574)
		(width 0.127)
		(layer "In5.Cu")
		(net "TWI_SDA0")
	)
	(segment
		(start 216.4334 -6.066536)
		(end 218.541346 -6.066536)
		(width 0.127)
		(layer "In5.Cu")
		(net "TWI_SDA0")
	)
	(segment
		(start 248.976134 -26.721816)
		(end 248.823734 -26.874216)
		(width 0.1016)
		(layer "In5.Cu")
		(net "TWI_SDA0")
	)
	(segment
		(start 124.6759 -12.05103)
		(end 133.44652 -3.28041)
		(width 0.127)
		(layer "In5.Cu")
		(net "TWI_SDA0")
	)
	(segment
		(start 193.237358 -9.73963)
		(end 212.760306 -9.73963)
		(width 0.127)
		(layer "In5.Cu")
		(net "TWI_SDA0")
	)
	(segment
		(start 249.69724 -31.74111)
		(end 249.849894 -31.893764)
		(width 0.1016)
		(layer "In5.Cu")
		(net "TWI_SDA0")
	)
	(segment
		(start 110.733332 -42.187368)
		(end 110.733332 -41.677844)
		(width 0.127)
		(layer "In5.Cu")
		(net "TWI_SDA0")
	)
	(segment
		(start 192.669414 -10.307574)
		(end 193.237358 -9.73963)
		(width 0.127)
		(layer "In5.Cu")
		(net "TWI_SDA0")
	)
	(segment
		(start 124.6759 -15.016734)
		(end 124.6759 -12.05103)
		(width 0.127)
		(layer "In5.Cu")
		(net "TWI_SDA0")
	)
	(segment
		(start 248.823734 -26.874216)
		(end 248.823734 -28.449016)
		(width 0.1016)
		(layer "In5.Cu")
		(net "TWI_SDA0")
	)
	(segment
		(start 244.599968 -39.99992)
		(end 245.09984 -39.500048)
		(width 0.12065)
		(layer "F.Cu")
		(net "TWI_SCL4")
	)
	(via
		(at 245.09984 -39.500048)
		(size 0.4572)
		(drill 0.2032)
		(layers "F.Cu" "B.Cu")
		(net "TWI_SCL4")
	)
	(segment
		(start 245.684802 -25.663398)
		(end 245.684802 -25.4)
		(width 0.12065)
		(layer "B.Cu")
		(net "TWI_SCL4")
	)
	(segment
		(start 244.493542 -38.487858)
		(end 244.493542 -30.115764)
		(width 0.1016)
		(layer "B.Cu")
		(net "TWI_SCL4")
	)
	(segment
		(start 244.132862 -29.249878)
		(end 244.132862 -29.224478)
		(width 0.1016)
		(layer "B.Cu")
		(net "TWI_SCL4")
	)
	(segment
		(start 244.969792 -25.904698)
		(end 245.442994 -25.904698)
		(width 0.12065)
		(layer "B.Cu")
		(net "TWI_SCL4")
	)
	(segment
		(start 245.09984 -39.094156)
		(end 244.493542 -38.487858)
		(width 0.1016)
		(layer "B.Cu")
		(net "TWI_SCL4")
	)
	(segment
		(start 245.442994 -25.904698)
		(end 245.684802 -25.663398)
		(width 0.12065)
		(layer "B.Cu")
		(net "TWI_SCL4")
	)
	(segment
		(start 244.555264 -26.319226)
		(end 244.969792 -25.904698)
		(width 0.12065)
		(layer "B.Cu")
		(net "TWI_SCL4")
	)
	(segment
		(start 244.132862 -28.352242)
		(end 244.555264 -27.92984)
		(width 0.12065)
		(layer "B.Cu")
		(net "TWI_SCL4")
	)
	(segment
		(start 244.28196 -29.904182)
		(end 244.28196 -29.398976)
		(width 0.1016)
		(layer "B.Cu")
		(net "TWI_SCL4")
	)
	(segment
		(start 244.493542 -30.115764)
		(end 244.28196 -29.904182)
		(width 0.1016)
		(layer "B.Cu")
		(net "TWI_SCL4")
	)
	(segment
		(start 244.28196 -29.398976)
		(end 244.132862 -29.249878)
		(width 0.1016)
		(layer "B.Cu")
		(net "TWI_SCL4")
	)
	(segment
		(start 244.132862 -29.224478)
		(end 244.132862 -28.352242)
		(width 0.12065)
		(layer "B.Cu")
		(net "TWI_SCL4")
	)
	(segment
		(start 245.09984 -39.500048)
		(end 245.09984 -39.094156)
		(width 0.1016)
		(layer "B.Cu")
		(net "TWI_SCL4")
	)
	(segment
		(start 244.555264 -27.92984)
		(end 244.555264 -26.319226)
		(width 0.12065)
		(layer "B.Cu")
		(net "TWI_SCL4")
	)
	(segment
		(start 232.653078 -9.545066)
		(end 232.653078 -10.301986)
		(width 0.12065)
		(layer "F.Cu")
		(net "TWI_SCL2")
	)
	(segment
		(start 231.009952 -8.067548)
		(end 231.17556 -8.067548)
		(width 0.12065)
		(layer "F.Cu")
		(net "TWI_SCL2")
	)
	(segment
		(start 232.653078 -10.301986)
		(end 232.533444 -10.42162)
		(width 0.12065)
		(layer "F.Cu")
		(net "TWI_SCL2")
	)
	(segment
		(start 230.6955 -8.382)
		(end 231.009952 -8.067548)
		(width 0.12065)
		(layer "F.Cu")
		(net "TWI_SCL2")
	)
	(segment
		(start 249.599958 -38.999922)
		(end 250.09983 -38.50005)
		(width 0.12065)
		(layer "F.Cu")
		(net "TWI_SCL2")
	)
	(segment
		(start 231.17556 -8.067548)
		(end 232.653078 -9.545066)
		(width 0.12065)
		(layer "F.Cu")
		(net "TWI_SCL2")
	)
	(via
		(at 251.7902 -37.0332)
		(size 0.7112)
		(drill 0.3556)
		(layers "F.Cu" "B.Cu")
		(net "TWI_SCL2")
	)
	(via
		(at 232.533444 -10.42162)
		(size 0.508)
		(drill 0.254)
		(layers "F.Cu" "B.Cu")
		(net "TWI_SCL2")
	)
	(via
		(at 250.09983 -38.50005)
		(size 0.4572)
		(drill 0.2032)
		(layers "F.Cu" "B.Cu")
		(net "TWI_SCL2")
	)
	(segment
		(start 250.47067 -29.553154)
		(end 250.321318 -29.702506)
		(width 0.1016)
		(layer "B.Cu")
		(net "TWI_SCL2")
	)
	(segment
		(start 250.47067 -29.527754)
		(end 250.47067 -29.553154)
		(width 0.1016)
		(layer "B.Cu")
		(net "TWI_SCL2")
	)
	(segment
		(start 250.69673 -37.90315)
		(end 251.254006 -37.90315)
		(width 0.1016)
		(layer "B.Cu")
		(net "TWI_SCL2")
	)
	(segment
		(start 250.69673 -35.83813)
		(end 250.964954 -36.106354)
		(width 0.1016)
		(layer "B.Cu")
		(net "TWI_SCL2")
	)
	(segment
		(start 250.321318 -29.877004)
		(end 250.69673 -30.252416)
		(width 0.1016)
		(layer "B.Cu")
		(net "TWI_SCL2")
	)
	(segment
		(start 250.09983 -38.50005)
		(end 250.69673 -37.90315)
		(width 0.1016)
		(layer "B.Cu")
		(net "TWI_SCL2")
	)
	(segment
		(start 250.69673 -30.252416)
		(end 250.69673 -35.83813)
		(width 0.1016)
		(layer "B.Cu")
		(net "TWI_SCL2")
	)
	(segment
		(start 250.964954 -36.106354)
		(end 251.26315 -36.106354)
		(width 0.1016)
		(layer "B.Cu")
		(net "TWI_SCL2")
	)
	(segment
		(start 251.254006 -37.90315)
		(end 251.7902 -37.366956)
		(width 0.1016)
		(layer "B.Cu")
		(net "TWI_SCL2")
	)
	(segment
		(start 251.7902 -37.366956)
		(end 251.7902 -37.0332)
		(width 0.1016)
		(layer "B.Cu")
		(net "TWI_SCL2")
	)
	(segment
		(start 251.342906 -26.813002)
		(end 251.342906 -28.486608)
		(width 0.12065)
		(layer "B.Cu")
		(net "TWI_SCL2")
	)
	(segment
		(start 251.600208 -26.5557)
		(end 251.342906 -26.813002)
		(width 0.12065)
		(layer "B.Cu")
		(net "TWI_SCL2")
	)
	(segment
		(start 251.342906 -28.486608)
		(end 250.47067 -29.358844)
		(width 0.12065)
		(layer "B.Cu")
		(net "TWI_SCL2")
	)
	(segment
		(start 251.7902 -36.633404)
		(end 251.7902 -37.0332)
		(width 0.1016)
		(layer "B.Cu")
		(net "TWI_SCL2")
	)
	(segment
		(start 250.47067 -29.358844)
		(end 250.47067 -29.527754)
		(width 0.12065)
		(layer "B.Cu")
		(net "TWI_SCL2")
	)
	(segment
		(start 251.26315 -36.106354)
		(end 251.7902 -36.633404)
		(width 0.1016)
		(layer "B.Cu")
		(net "TWI_SCL2")
	)
	(segment
		(start 250.321318 -29.702506)
		(end 250.321318 -29.877004)
		(width 0.1016)
		(layer "B.Cu")
		(net "TWI_SCL2")
	)
	(segment
		(start 232.639616 -10.528554)
		(end 232.533444 -10.42162)
		(width 0.127)
		(layer "In5.Cu")
		(net "TWI_SCL2")
	)
	(segment
		(start 247.332754 -27.17038)
		(end 247.332754 -20.31365)
		(width 0.127)
		(layer "In5.Cu")
		(net "TWI_SCL2")
	)
	(segment
		(start 249.57278 -37.973)
		(end 247.8786 -37.973)
		(width 0.127)
		(layer "In5.Cu")
		(net "TWI_SCL2")
	)
	(segment
		(start 247.65 -30.193996)
		(end 247.523 -30.066996)
		(width 0.127)
		(layer "In5.Cu")
		(net "TWI_SCL2")
	)
	(segment
		(start 247.523 -27.360626)
		(end 247.332754 -27.17038)
		(width 0.127)
		(layer "In5.Cu")
		(net "TWI_SCL2")
	)
	(segment
		(start 234.269534 -16.7259)
		(end 232.639616 -15.095982)
		(width 0.127)
		(layer "In5.Cu")
		(net "TWI_SCL2")
	)
	(segment
		(start 250.09983 -38.50005)
		(end 249.57278 -37.973)
		(width 0.127)
		(layer "In5.Cu")
		(net "TWI_SCL2")
	)
	(segment
		(start 247.523 -30.066996)
		(end 247.523 -27.360626)
		(width 0.127)
		(layer "In5.Cu")
		(net "TWI_SCL2")
	)
	(segment
		(start 247.332754 -20.31365)
		(end 243.745004 -16.7259)
		(width 0.127)
		(layer "In5.Cu")
		(net "TWI_SCL2")
	)
	(segment
		(start 232.639616 -15.095982)
		(end 232.639616 -10.528554)
		(width 0.127)
		(layer "In5.Cu")
		(net "TWI_SCL2")
	)
	(segment
		(start 247.8786 -37.973)
		(end 247.65 -37.7444)
		(width 0.127)
		(layer "In5.Cu")
		(net "TWI_SCL2")
	)
	(segment
		(start 247.65 -37.7444)
		(end 247.65 -30.193996)
		(width 0.127)
		(layer "In5.Cu")
		(net "TWI_SCL2")
	)
	(segment
		(start 243.745004 -16.7259)
		(end 234.269534 -16.7259)
		(width 0.127)
		(layer "In5.Cu")
		(net "TWI_SCL2")
	)
	(segment
		(start 246.599964 -34.99993)
		(end 247.099836 -34.500058)
		(width 0.12065)
		(layer "F.Cu")
		(net "TWI_SCL10")
	)
	(via
		(at 247.099836 -34.500058)
		(size 0.4572)
		(drill 0.2032)
		(layers "F.Cu" "B.Cu")
		(net "TWI_SCL10")
	)
	(segment
		(start 246.493538 -33.89376)
		(end 247.099836 -34.500058)
		(width 0.1016)
		(layer "B.Cu")
		(net "TWI_SCL10")
	)
	(segment
		(start 246.16156 -29.902404)
		(end 246.493538 -30.234382)
		(width 0.1016)
		(layer "B.Cu")
		(net "TWI_SCL10")
	)
	(segment
		(start 246.938546 -25.808686)
		(end 246.389906 -26.357326)
		(width 0.12065)
		(layer "B.Cu")
		(net "TWI_SCL10")
	)
	(segment
		(start 246.389906 -26.357326)
		(end 246.389906 -28.03525)
		(width 0.12065)
		(layer "B.Cu")
		(net "TWI_SCL10")
	)
	(segment
		(start 247.651016 -25.688036)
		(end 247.530366 -25.808686)
		(width 0.12065)
		(layer "B.Cu")
		(net "TWI_SCL10")
	)
	(segment
		(start 246.16156 -29.290264)
		(end 246.16156 -29.902404)
		(width 0.1016)
		(layer "B.Cu")
		(net "TWI_SCL10")
	)
	(segment
		(start 246.389906 -28.03525)
		(end 246.012462 -28.412694)
		(width 0.12065)
		(layer "B.Cu")
		(net "TWI_SCL10")
	)
	(segment
		(start 246.012462 -29.115766)
		(end 246.012462 -29.141166)
		(width 0.1016)
		(layer "B.Cu")
		(net "TWI_SCL10")
	)
	(segment
		(start 246.012462 -28.412694)
		(end 246.012462 -29.115766)
		(width 0.12065)
		(layer "B.Cu")
		(net "TWI_SCL10")
	)
	(segment
		(start 246.012462 -29.141166)
		(end 246.16156 -29.290264)
		(width 0.1016)
		(layer "B.Cu")
		(net "TWI_SCL10")
	)
	(segment
		(start 246.493538 -30.234382)
		(end 246.493538 -33.89376)
		(width 0.1016)
		(layer "B.Cu")
		(net "TWI_SCL10")
	)
	(segment
		(start 247.651016 -25.424638)
		(end 247.651016 -25.688036)
		(width 0.12065)
		(layer "B.Cu")
		(net "TWI_SCL10")
	)
	(segment
		(start 247.530366 -25.808686)
		(end 246.938546 -25.808686)
		(width 0.12065)
		(layer "B.Cu")
		(net "TWI_SCL10")
	)
	(segment
		(start 70.470522 -196.370194)
		(end 70.470522 -197.60311)
		(width 0.12065)
		(layer "F.Cu")
		(net "TWI_SCL1")
	)
	(segment
		(start 124.42317 -191.239648)
		(end 119.748554 -195.914264)
		(width 0.12065)
		(layer "F.Cu")
		(net "TWI_SCL1")
	)
	(segment
		(start 124.790962 -211.046822)
		(end 124.790962 -210.313524)
		(width 0.12065)
		(layer "F.Cu")
		(net "TWI_SCL1")
	)
	(segment
		(start 66.203322 -181.150768)
		(end 69.922898 -177.431192)
		(width 0.12065)
		(layer "F.Cu")
		(net "TWI_SCL1")
	)
	(segment
		(start 65.53835 -185.962798)
		(end 66.203322 -185.297826)
		(width 0.12065)
		(layer "F.Cu")
		(net "TWI_SCL1")
	)
	(segment
		(start 218.797124 -203.491592)
		(end 218.797124 -204.318362)
		(width 0.12065)
		(layer "F.Cu")
		(net "TWI_SCL1")
	)
	(segment
		(start 219.6592 -179.7558)
		(end 219.840048 -179.936648)
		(width 0.12065)
		(layer "F.Cu")
		(net "TWI_SCL1")
	)
	(segment
		(start 288.151062 -82.013552)
		(end 266.08913 -59.95162)
		(width 0.12065)
		(layer "F.Cu")
		(net "TWI_SCL1")
	)
	(segment
		(start 97.590102 -177.431192)
		(end 116.980716 -196.821806)
		(width 0.12065)
		(layer "F.Cu")
		(net "TWI_SCL1")
	)
	(segment
		(start 249.599958 -39.99992)
		(end 250.09983 -39.500048)
		(width 0.12065)
		(layer "F.Cu")
		(net "TWI_SCL1")
	)
	(segment
		(start 336.06105 -154.191716)
		(end 336.06105 -87.096346)
		(width 0.12065)
		(layer "F.Cu")
		(net "TWI_SCL1")
	)
	(segment
		(start 329.5396 -165.4302)
		(end 328.90587 -164.79647)
		(width 0.12065)
		(layer "F.Cu")
		(net "TWI_SCL1")
	)
	(segment
		(start 219.840048 -180.594762)
		(end 219.52077 -180.91404)
		(width 0.12065)
		(layer "F.Cu")
		(net "TWI_SCL1")
	)
	(segment
		(start 70.470522 -197.60311)
		(end 69.827394 -198.246238)
		(width 0.12065)
		(layer "F.Cu")
		(net "TWI_SCL1")
	)
	(segment
		(start 328.90587 -161.346896)
		(end 336.06105 -154.191716)
		(width 0.12065)
		(layer "F.Cu")
		(net "TWI_SCL1")
	)
	(segment
		(start 331.756512 -185.322718)
		(end 331.756512 -186.149488)
		(width 0.12065)
		(layer "F.Cu")
		(net "TWI_SCL1")
	)
	(segment
		(start 124.220986 -211.616798)
		(end 124.790962 -211.046822)
		(width 0.12065)
		(layer "F.Cu")
		(net "TWI_SCL1")
	)
	(segment
		(start 121.477532 -211.616798)
		(end 124.220986 -211.616798)
		(width 0.12065)
		(layer "F.Cu")
		(net "TWI_SCL1")
	)
	(segment
		(start 266.827 -26.7335)
		(end 266.827 -26.9494)
		(width 0.12065)
		(layer "F.Cu")
		(net "TWI_SCL1")
	)
	(segment
		(start 266.08913 -59.95162)
		(end 266.08913 -27.68727)
		(width 0.12065)
		(layer "F.Cu")
		(net "TWI_SCL1")
	)
	(segment
		(start 116.980716 -206.337916)
		(end 117.1702 -206.5274)
		(width 0.12065)
		(layer "F.Cu")
		(net "TWI_SCL1")
	)
	(segment
		(start 181.361588 -201.028046)
		(end 160.417764 -201.028046)
		(width 0.12065)
		(layer "F.Cu")
		(net "TWI_SCL1")
	)
	(segment
		(start 328.90587 -164.79647)
		(end 328.90587 -161.346896)
		(width 0.12065)
		(layer "F.Cu")
		(net "TWI_SCL1")
	)
	(segment
		(start 219.52077 -180.91404)
		(end 201.475594 -180.91404)
		(width 0.12065)
		(layer "F.Cu")
		(net "TWI_SCL1")
	)
	(segment
		(start 66.62166 -198.246238)
		(end 65.53835 -197.162928)
		(width 0.12065)
		(layer "F.Cu")
		(net "TWI_SCL1")
	)
	(segment
		(start 119.748554 -209.88782)
		(end 121.477532 -211.616798)
		(width 0.12065)
		(layer "F.Cu")
		(net "TWI_SCL1")
	)
	(segment
		(start 119.748554 -195.914264)
		(end 119.748554 -209.88782)
		(width 0.12065)
		(layer "F.Cu")
		(net "TWI_SCL1")
	)
	(segment
		(start 336.06105 -87.096346)
		(end 330.978256 -82.013552)
		(width 0.12065)
		(layer "F.Cu")
		(net "TWI_SCL1")
	)
	(segment
		(start 266.827 -26.9494)
		(end 266.2174 -27.559)
		(width 0.12065)
		(layer "F.Cu")
		(net "TWI_SCL1")
	)
	(segment
		(start 70.715124 -196.125592)
		(end 70.470522 -196.370194)
		(width 0.12065)
		(layer "F.Cu")
		(net "TWI_SCL1")
	)
	(segment
		(start 201.475594 -180.91404)
		(end 181.361588 -201.028046)
		(width 0.12065)
		(layer "F.Cu")
		(net "TWI_SCL1")
	)
	(segment
		(start 150.629366 -191.239648)
		(end 124.42317 -191.239648)
		(width 0.12065)
		(layer "F.Cu")
		(net "TWI_SCL1")
	)
	(segment
		(start 124.944124 -209.333592)
		(end 124.944124 -210.160362)
		(width 0.12065)
		(layer "F.Cu")
		(net "TWI_SCL1")
	)
	(segment
		(start 266.08913 -27.68727)
		(end 266.2174 -27.559)
		(width 0.12065)
		(layer "F.Cu")
		(net "TWI_SCL1")
	)
	(segment
		(start 69.922898 -177.431192)
		(end 97.590102 -177.431192)
		(width 0.12065)
		(layer "F.Cu")
		(net "TWI_SCL1")
	)
	(segment
		(start 124.790962 -210.313524)
		(end 124.944124 -210.160362)
		(width 0.12065)
		(layer "F.Cu")
		(net "TWI_SCL1")
	)
	(segment
		(start 65.53835 -197.162928)
		(end 65.53835 -185.962798)
		(width 0.12065)
		(layer "F.Cu")
		(net "TWI_SCL1")
	)
	(segment
		(start 66.203322 -185.297826)
		(end 66.203322 -181.150768)
		(width 0.12065)
		(layer "F.Cu")
		(net "TWI_SCL1")
	)
	(segment
		(start 116.980716 -196.821806)
		(end 116.980716 -206.337916)
		(width 0.12065)
		(layer "F.Cu")
		(net "TWI_SCL1")
	)
	(segment
		(start 160.417764 -201.028046)
		(end 150.629366 -191.239648)
		(width 0.12065)
		(layer "F.Cu")
		(net "TWI_SCL1")
	)
	(segment
		(start 219.840048 -179.936648)
		(end 219.840048 -180.594762)
		(width 0.12065)
		(layer "F.Cu")
		(net "TWI_SCL1")
	)
	(segment
		(start 330.978256 -82.013552)
		(end 288.151062 -82.013552)
		(width 0.12065)
		(layer "F.Cu")
		(net "TWI_SCL1")
	)
	(segment
		(start 69.827394 -198.246238)
		(end 66.62166 -198.246238)
		(width 0.12065)
		(layer "F.Cu")
		(net "TWI_SCL1")
	)
	(via
		(at 124.944124 -210.160362)
		(size 0.508)
		(drill 0.254)
		(layers "F.Cu" "B.Cu")
		(net "TWI_SCL1")
	)
	(via
		(at 219.6592 -179.7558)
		(size 0.508)
		(drill 0.254)
		(layers "F.Cu" "B.Cu")
		(net "TWI_SCL1")
	)
	(via
		(at 266.2174 -27.559)
		(size 0.508)
		(drill 0.254)
		(layers "F.Cu" "B.Cu")
		(net "TWI_SCL1")
	)
	(via
		(at 117.1702 -206.5274)
		(size 0.508)
		(drill 0.254)
		(layers "F.Cu" "B.Cu")
		(net "TWI_SCL1")
	)
	(via
		(at 329.251056 -163.878514)
		(size 0.7112)
		(drill 0.3556)
		(layers "F.Cu" "B.Cu")
		(net "TWI_SCL1")
	)
	(via
		(at 329.5396 -165.4302)
		(size 0.508)
		(drill 0.254)
		(layers "F.Cu" "B.Cu")
		(net "TWI_SCL1")
	)
	(via
		(at 250.09983 -39.500048)
		(size 0.4572)
		(drill 0.2032)
		(layers "F.Cu" "B.Cu")
		(net "TWI_SCL1")
	)
	(via
		(at 331.756512 -186.149488)
		(size 0.508)
		(drill 0.254)
		(layers "F.Cu" "B.Cu")
		(net "TWI_SCL1")
	)
	(via
		(at 218.797124 -204.318362)
		(size 0.508)
		(drill 0.254)
		(layers "F.Cu" "B.Cu")
		(net "TWI_SCL1")
	)
	(segment
		(start 120.833388 -211.43214)
		(end 124.23775 -211.43214)
		(width 0.12065)
		(layer "B.Cu")
		(net "TWI_SCL1")
	)
	(segment
		(start 116.96065 -206.31785)
		(end 116.96065 -205.680056)
		(width 0.12065)
		(layer "B.Cu")
		(net "TWI_SCL1")
	)
	(segment
		(start 117.1702 -206.5274)
		(end 116.96065 -206.31785)
		(width 0.12065)
		(layer "B.Cu")
		(net "TWI_SCL1")
	)
	(segment
		(start 329.251056 -163.878514)
		(end 328.924158 -163.878514)
		(width 0.12065)
		(layer "B.Cu")
		(net "TWI_SCL1")
	)
	(segment
		(start 219.854272 -161.838386)
		(end 226.600258 -155.0924)
		(width 0.12065)
		(layer "B.Cu")
		(net "TWI_SCL1")
	)
	(segment
		(start 219.6592 -179.7558)
		(end 219.854272 -179.560728)
		(width 0.12065)
		(layer "B.Cu")
		(net "TWI_SCL1")
	)
	(segment
		(start 124.735082 -210.369404)
		(end 124.944124 -210.160362)
		(width 0.12065)
		(layer "B.Cu")
		(net "TWI_SCL1")
	)
	(segment
		(start 124.23775 -211.43214)
		(end 124.735082 -210.934808)
		(width 0.12065)
		(layer "B.Cu")
		(net "TWI_SCL1")
	)
	(segment
		(start 323.40169 -155.511754)
		(end 328.924158 -161.034222)
		(width 0.12065)
		(layer "B.Cu")
		(net "TWI_SCL1")
	)
	(segment
		(start 328.924158 -164.814758)
		(end 329.5396 -165.4302)
		(width 0.12065)
		(layer "B.Cu")
		(net "TWI_SCL1")
	)
	(segment
		(start 118.21795 -205.83652)
		(end 118.21795 -208.816702)
		(width 0.12065)
		(layer "B.Cu")
		(net "TWI_SCL1")
	)
	(segment
		(start 321.053206 -155.511754)
		(end 323.40169 -155.511754)
		(width 0.12065)
		(layer "B.Cu")
		(net "TWI_SCL1")
	)
	(segment
		(start 116.96065 -205.680056)
		(end 117.0813 -205.559406)
		(width 0.12065)
		(layer "B.Cu")
		(net "TWI_SCL1")
	)
	(segment
		(start 118.21795 -208.816702)
		(end 120.833388 -211.43214)
		(width 0.12065)
		(layer "B.Cu")
		(net "TWI_SCL1")
	)
	(segment
		(start 328.924158 -161.034222)
		(end 328.924158 -163.878514)
		(width 0.12065)
		(layer "B.Cu")
		(net "TWI_SCL1")
	)
	(segment
		(start 117.940836 -205.559406)
		(end 118.21795 -205.83652)
		(width 0.12065)
		(layer "B.Cu")
		(net "TWI_SCL1")
	)
	(segment
		(start 124.735082 -210.934808)
		(end 124.735082 -210.369404)
		(width 0.12065)
		(layer "B.Cu")
		(net "TWI_SCL1")
	)
	(segment
		(start 117.0813 -205.559406)
		(end 117.940836 -205.559406)
		(width 0.12065)
		(layer "B.Cu")
		(net "TWI_SCL1")
	)
	(segment
		(start 219.854272 -179.560728)
		(end 219.854272 -161.838386)
		(width 0.12065)
		(layer "B.Cu")
		(net "TWI_SCL1")
	)
	(segment
		(start 226.600258 -155.0924)
		(end 320.633852 -155.0924)
		(width 0.12065)
		(layer "B.Cu")
		(net "TWI_SCL1")
	)
	(segment
		(start 320.633852 -155.0924)
		(end 321.053206 -155.511754)
		(width 0.12065)
		(layer "B.Cu")
		(net "TWI_SCL1")
	)
	(segment
		(start 328.924158 -163.878514)
		(end 328.924158 -164.814758)
		(width 0.12065)
		(layer "B.Cu")
		(net "TWI_SCL1")
	)
	(segment
		(start 266.2174 -27.559)
		(end 266.06246 -27.71394)
		(width 0.127)
		(layer "In2.Cu")
		(net "TWI_SCL1")
	)
	(segment
		(start 254.940562 -31.09722)
		(end 254.703072 -31.33471)
		(width 0.1016)
		(layer "In2.Cu")
		(net "TWI_SCL1")
	)
	(segment
		(start 262.346948 -29.394912)
		(end 261.539482 -30.202378)
		(width 0.127)
		(layer "In2.Cu")
		(net "TWI_SCL1")
	)
	(segment
		(start 250.524264 -36.464748)
		(end 250.524264 -39.075614)
		(width 0.1016)
		(layer "In2.Cu")
		(net "TWI_SCL1")
	)
	(segment
		(start 254.703072 -32.775144)
		(end 254.376682 -33.101534)
		(width 0.1016)
		(layer "In2.Cu")
		(net "TWI_SCL1")
	)
	(segment
		(start 266.06246 -27.71394)
		(end 266.06246 -28.506928)
		(width 0.127)
		(layer "In2.Cu")
		(net "TWI_SCL1")
	)
	(segment
		(start 261.387082 -30.752796)
		(end 261.042658 -31.09722)
		(width 0.1016)
		(layer "In2.Cu")
		(net "TWI_SCL1")
	)
	(segment
		(start 254.376682 -33.101534)
		(end 253.839218 -33.101534)
		(width 0.1016)
		(layer "In2.Cu")
		(net "TWI_SCL1")
	)
	(segment
		(start 266.06246 -28.506928)
		(end 265.174476 -29.394912)
		(width 0.127)
		(layer "In2.Cu")
		(net "TWI_SCL1")
	)
	(segment
		(start 254.703072 -31.33471)
		(end 254.703072 -32.775144)
		(width 0.1016)
		(layer "In2.Cu")
		(net "TWI_SCL1")
	)
	(segment
		(start 261.042658 -31.09722)
		(end 254.940562 -31.09722)
		(width 0.1016)
		(layer "In2.Cu")
		(net "TWI_SCL1")
	)
	(segment
		(start 265.174476 -29.394912)
		(end 262.346948 -29.394912)
		(width 0.127)
		(layer "In2.Cu")
		(net "TWI_SCL1")
	)
	(segment
		(start 253.839218 -33.101534)
		(end 253.698756 -33.241996)
		(width 0.1016)
		(layer "In2.Cu")
		(net "TWI_SCL1")
	)
	(segment
		(start 261.539482 -30.369764)
		(end 261.387082 -30.522164)
		(width 0.1016)
		(layer "In2.Cu")
		(net "TWI_SCL1")
	)
	(segment
		(start 261.387082 -30.522164)
		(end 261.387082 -30.752796)
		(width 0.1016)
		(layer "In2.Cu")
		(net "TWI_SCL1")
	)
	(segment
		(start 253.698756 -33.886902)
		(end 253.484126 -34.101532)
		(width 0.1016)
		(layer "In2.Cu")
		(net "TWI_SCL1")
	)
	(segment
		(start 261.539482 -30.344364)
		(end 261.539482 -30.369764)
		(width 0.1016)
		(layer "In2.Cu")
		(net "TWI_SCL1")
	)
	(segment
		(start 251.70511 -35.259518)
		(end 251.70511 -35.832288)
		(width 0.1016)
		(layer "In2.Cu")
		(net "TWI_SCL1")
	)
	(segment
		(start 251.439426 -36.097972)
		(end 250.89104 -36.097972)
		(width 0.1016)
		(layer "In2.Cu")
		(net "TWI_SCL1")
	)
	(segment
		(start 253.698756 -33.241996)
		(end 253.698756 -33.886902)
		(width 0.1016)
		(layer "In2.Cu")
		(net "TWI_SCL1")
	)
	(segment
		(start 250.524264 -39.075614)
		(end 250.09983 -39.500048)
		(width 0.1016)
		(layer "In2.Cu")
		(net "TWI_SCL1")
	)
	(segment
		(start 250.89104 -36.097972)
		(end 250.524264 -36.464748)
		(width 0.1016)
		(layer "In2.Cu")
		(net "TWI_SCL1")
	)
	(segment
		(start 261.539482 -30.202378)
		(end 261.539482 -30.344364)
		(width 0.127)
		(layer "In2.Cu")
		(net "TWI_SCL1")
	)
	(segment
		(start 252.863096 -34.101532)
		(end 251.70511 -35.259518)
		(width 0.1016)
		(layer "In2.Cu")
		(net "TWI_SCL1")
	)
	(segment
		(start 251.70511 -35.832288)
		(end 251.439426 -36.097972)
		(width 0.1016)
		(layer "In2.Cu")
		(net "TWI_SCL1")
	)
	(segment
		(start 253.484126 -34.101532)
		(end 252.863096 -34.101532)
		(width 0.1016)
		(layer "In2.Cu")
		(net "TWI_SCL1")
	)
	(segment
		(start 331.388212 -178.861212)
		(end 331.388212 -185.781188)
		(width 0.127)
		(layer "In5.Cu")
		(net "TWI_SCL1")
	)
	(segment
		(start 219.8497 -178.948588)
		(end 219.8497 -179.140612)
		(width 0.127)
		(layer "In5.Cu")
		(net "TWI_SCL1")
	)
	(segment
		(start 218.1606 -179.140612)
		(end 218.420188 -178.881024)
		(width 0.127)
		(layer "In5.Cu")
		(net "TWI_SCL1")
	)
	(segment
		(start 219.6592 -179.331112)
		(end 219.6592 -179.7558)
		(width 0.127)
		(layer "In5.Cu")
		(net "TWI_SCL1")
	)
	(segment
		(start 218.1606 -186.563)
		(end 218.1606 -179.140612)
		(width 0.127)
		(layer "In5.Cu")
		(net "TWI_SCL1")
	)
	(segment
		(start 218.420188 -178.881024)
		(end 219.782136 -178.881024)
		(width 0.127)
		(layer "In5.Cu")
		(net "TWI_SCL1")
	)
	(segment
		(start 219.782136 -178.881024)
		(end 219.8497 -178.948588)
		(width 0.127)
		(layer "In5.Cu")
		(net "TWI_SCL1")
	)
	(segment
		(start 216.0651 -188.6585)
		(end 218.1606 -186.563)
		(width 0.127)
		(layer "In5.Cu")
		(net "TWI_SCL1")
	)
	(segment
		(start 331.388212 -185.781188)
		(end 331.756512 -186.149488)
		(width 0.127)
		(layer "In5.Cu")
		(net "TWI_SCL1")
	)
	(segment
		(start 329.0697 -176.5427)
		(end 331.388212 -178.861212)
		(width 0.127)
		(layer "In5.Cu")
		(net "TWI_SCL1")
	)
	(segment
		(start 218.4146 -203.935838)
		(end 218.4146 -200.16216)
		(width 0.127)
		(layer "In5.Cu")
		(net "TWI_SCL1")
	)
	(segment
		(start 218.797124 -204.318362)
		(end 218.4146 -203.935838)
		(width 0.127)
		(layer "In5.Cu")
		(net "TWI_SCL1")
	)
	(segment
		(start 329.257152 -165.4302)
		(end 329.0697 -165.617652)
		(width 0.127)
		(layer "In5.Cu")
		(net "TWI_SCL1")
	)
	(segment
		(start 329.5396 -165.4302)
		(end 329.257152 -165.4302)
		(width 0.127)
		(layer "In5.Cu")
		(net "TWI_SCL1")
	)
	(segment
		(start 219.8497 -179.140612)
		(end 219.6592 -179.331112)
		(width 0.127)
		(layer "In5.Cu")
		(net "TWI_SCL1")
	)
	(segment
		(start 218.4146 -200.16216)
		(end 216.0651 -197.81266)
		(width 0.127)
		(layer "In5.Cu")
		(net "TWI_SCL1")
	)
	(segment
		(start 216.0651 -197.81266)
		(end 216.0651 -188.6585)
		(width 0.127)
		(layer "In5.Cu")
		(net "TWI_SCL1")
	)
	(segment
		(start 329.0697 -165.617652)
		(end 329.0697 -176.5427)
		(width 0.127)
		(layer "In5.Cu")
		(net "TWI_SCL1")
	)
	(segment
		(start 121.774204 -102.784656)
		(end 122.013472 -103.023924)
		(width 0.12065)
		(layer "F.Cu")
		(net "TWI_SCL0")
	)
	(segment
		(start 250.599956 -35.999928)
		(end 251.099828 -35.500056)
		(width 0.12065)
		(layer "F.Cu")
		(net "TWI_SCL0")
	)
	(segment
		(start 121.774204 -102.190296)
		(end 121.774204 -102.784656)
		(width 0.12065)
		(layer "F.Cu")
		(net "TWI_SCL0")
	)
	(segment
		(start 122.0978 -101.8667)
		(end 121.774204 -102.190296)
		(width 0.12065)
		(layer "F.Cu")
		(net "TWI_SCL0")
	)
	(via
		(at 122.16384 -98.796856)
		(size 0.7112)
		(drill 0.3556)
		(layers "F.Cu" "B.Cu")
		(net "TWI_SCL0")
	)
	(via
		(at 111.394494 -42.390568)
		(size 0.508)
		(drill 0.254)
		(layers "F.Cu" "B.Cu")
		(net "TWI_SCL0")
	)
	(via
		(at 251.099828 -35.500056)
		(size 0.4572)
		(drill 0.2032)
		(layers "F.Cu" "B.Cu")
		(net "TWI_SCL0")
	)
	(via
		(at 122.013472 -103.023924)
		(size 0.508)
		(drill 0.254)
		(layers "F.Cu" "B.Cu")
		(net "TWI_SCL0")
	)
	(segment
		(start 252.977142 -29.852366)
		(end 252.70206 -30.127448)
		(width 0.1016)
		(layer "B.Cu")
		(net "TWI_SCL0")
	)
	(segment
		(start 253.18847 -29.852366)
		(end 252.977142 -29.852366)
		(width 0.1016)
		(layer "B.Cu")
		(net "TWI_SCL0")
	)
	(segment
		(start 251.852176 -36.096956)
		(end 251.255276 -35.500056)
		(width 0.1016)
		(layer "B.Cu")
		(net "TWI_SCL0")
	)
	(segment
		(start 253.20625 -29.834586)
		(end 253.18847 -29.852366)
		(width 0.1016)
		(layer "B.Cu")
		(net "TWI_SCL0")
	)
	(segment
		(start 254.517398 -28.155646)
		(end 253.69647 -28.976574)
		(width 0.12065)
		(layer "B.Cu")
		(net "TWI_SCL0")
	)
	(segment
		(start 254.7874 -26.974546)
		(end 254.517398 -27.244548)
		(width 0.12065)
		(layer "B.Cu")
		(net "TWI_SCL0")
	)
	(segment
		(start 121.75617 -98.796856)
		(end 121.75617 -102.766622)
		(width 0.12065)
		(layer "B.Cu")
		(net "TWI_SCL0")
	)
	(segment
		(start 121.75617 -98.796856)
		(end 122.16384 -98.796856)
		(width 0.12065)
		(layer "B.Cu")
		(net "TWI_SCL0")
	)
	(segment
		(start 121.75617 -96.84893)
		(end 121.75617 -98.796856)
		(width 0.12065)
		(layer "B.Cu")
		(net "TWI_SCL0")
	)
	(segment
		(start 121.9708 -96.6343)
		(end 121.75617 -96.84893)
		(width 0.12065)
		(layer "B.Cu")
		(net "TWI_SCL0")
	)
	(segment
		(start 254.517398 -27.244548)
		(end 254.517398 -28.155646)
		(width 0.12065)
		(layer "B.Cu")
		(net "TWI_SCL0")
	)
	(segment
		(start 253.69647 -29.344366)
		(end 253.20625 -29.834586)
		(width 0.12065)
		(layer "B.Cu")
		(net "TWI_SCL0")
	)
	(segment
		(start 252.70206 -30.127448)
		(end 252.70206 -35.742372)
		(width 0.1016)
		(layer "B.Cu")
		(net "TWI_SCL0")
	)
	(segment
		(start 253.69647 -28.976574)
		(end 253.69647 -29.344366)
		(width 0.12065)
		(layer "B.Cu")
		(net "TWI_SCL0")
	)
	(segment
		(start 251.255276 -35.500056)
		(end 251.099828 -35.500056)
		(width 0.1016)
		(layer "B.Cu")
		(net "TWI_SCL0")
	)
	(segment
		(start 252.347476 -36.096956)
		(end 251.852176 -36.096956)
		(width 0.1016)
		(layer "B.Cu")
		(net "TWI_SCL0")
	)
	(segment
		(start 121.75617 -102.766622)
		(end 122.013472 -103.023924)
		(width 0.12065)
		(layer "B.Cu")
		(net "TWI_SCL0")
	)
	(segment
		(start 254.7874 -26.5557)
		(end 254.7874 -26.974546)
		(width 0.12065)
		(layer "B.Cu")
		(net "TWI_SCL0")
	)
	(segment
		(start 252.70206 -35.742372)
		(end 252.347476 -36.096956)
		(width 0.1016)
		(layer "B.Cu")
		(net "TWI_SCL0")
	)
	(segment
		(start 124.6632 -95.1738)
		(end 124.6632 -90.146886)
		(width 0.127)
		(layer "In2.Cu")
		(net "TWI_SCL0")
	)
	(segment
		(start 110.588044 -44.196)
		(end 111.229394 -43.55465)
		(width 0.127)
		(layer "In2.Cu")
		(net "TWI_SCL0")
	)
	(segment
		(start 121.8057 -98.0313)
		(end 124.6632 -95.1738)
		(width 0.127)
		(layer "In2.Cu")
		(net "TWI_SCL0")
	)
	(segment
		(start 110.0582 -44.196)
		(end 110.588044 -44.196)
		(width 0.127)
		(layer "In2.Cu")
		(net "TWI_SCL0")
	)
	(segment
		(start 106.581194 -72.06488)
		(end 106.581194 -47.673006)
		(width 0.127)
		(layer "In2.Cu")
		(net "TWI_SCL0")
	)
	(segment
		(start 106.581194 -47.673006)
		(end 110.0582 -44.196)
		(width 0.127)
		(layer "In2.Cu")
		(net "TWI_SCL0")
	)
	(segment
		(start 122.013472 -103.023924)
		(end 121.8057 -102.816152)
		(width 0.127)
		(layer "In2.Cu")
		(net "TWI_SCL0")
	)
	(segment
		(start 111.229394 -43.55465)
		(end 111.229394 -42.555668)
		(width 0.127)
		(layer "In2.Cu")
		(net "TWI_SCL0")
	)
	(segment
		(start 124.6632 -90.146886)
		(end 106.581194 -72.06488)
		(width 0.127)
		(layer "In2.Cu")
		(net "TWI_SCL0")
	)
	(segment
		(start 121.8057 -102.816152)
		(end 121.8057 -98.0313)
		(width 0.127)
		(layer "In2.Cu")
		(net "TWI_SCL0")
	)
	(segment
		(start 111.229394 -42.555668)
		(end 111.394494 -42.390568)
		(width 0.127)
		(layer "In2.Cu")
		(net "TWI_SCL0")
	)
	(segment
		(start 248.620534 -26.874216)
		(end 248.620534 -28.364688)
		(width 0.1016)
		(layer "In5.Cu")
		(net "TWI_SCL0")
	)
	(segment
		(start 216.643966 -6.574536)
		(end 218.33078 -6.574536)
		(width 0.127)
		(layer "In5.Cu")
		(net "TWI_SCL0")
	)
	(segment
		(start 133.657086 -3.78841)
		(end 175.704754 -3.78841)
		(width 0.127)
		(layer "In5.Cu")
		(net "TWI_SCL0")
	)
	(segment
		(start 234.864148 -8.9662)
		(end 242.236498 -8.9662)
		(width 0.127)
		(layer "In5.Cu")
		(net "TWI_SCL0")
	)
	(segment
		(start 250.139708 -33.096962)
		(end 250.253754 -33.096962)
		(width 0.1016)
		(layer "In5.Cu")
		(net "TWI_SCL0")
	)
	(segment
		(start 112.649 -40.480742)
		(end 112.649 -27.7622)
		(width 0.127)
		(layer "In5.Cu")
		(net "TWI_SCL0")
	)
	(segment
		(start 112.649 -27.7622)
		(end 125.1839 -15.2273)
		(width 0.127)
		(layer "In5.Cu")
		(net "TWI_SCL0")
	)
	(segment
		(start 224.61855 -7.9502)
		(end 233.848148 -7.9502)
		(width 0.127)
		(layer "In5.Cu")
		(net "TWI_SCL0")
	)
	(segment
		(start 249.311414 -30.102302)
		(end 249.49404 -30.284928)
		(width 0.1016)
		(layer "In5.Cu")
		(net "TWI_SCL0")
	)
	(segment
		(start 218.768676 -7.012432)
		(end 223.680782 -7.012432)
		(width 0.127)
		(layer "In5.Cu")
		(net "TWI_SCL0")
	)
	(segment
		(start 242.236498 -8.9662)
		(end 248.468134 -15.197836)
		(width 0.127)
		(layer "In5.Cu")
		(net "TWI_SCL0")
	)
	(segment
		(start 248.502932 -28.48229)
		(end 248.502932 -29.747718)
		(width 0.1016)
		(layer "In5.Cu")
		(net "TWI_SCL0")
	)
	(segment
		(start 181.623716 -9.707372)
		(end 182.044594 -9.707118)
		(width 0.127)
		(layer "In5.Cu")
		(net "TWI_SCL0")
	)
	(segment
		(start 233.848148 -7.9502)
		(end 234.864148 -8.9662)
		(width 0.127)
		(layer "In5.Cu")
		(net "TWI_SCL0")
	)
	(segment
		(start 248.468134 -26.614628)
		(end 248.468134 -26.721816)
		(width 0.1016)
		(layer "In5.Cu")
		(net "TWI_SCL0")
	)
	(segment
		(start 248.620534 -28.364688)
		(end 248.502932 -28.48229)
		(width 0.1016)
		(layer "In5.Cu")
		(net "TWI_SCL0")
	)
	(segment
		(start 249.70613 -32.663384)
		(end 250.139708 -33.096962)
		(width 0.1016)
		(layer "In5.Cu")
		(net "TWI_SCL0")
	)
	(segment
		(start 212.970872 -10.24763)
		(end 216.643966 -6.574536)
		(width 0.127)
		(layer "In5.Cu")
		(net "TWI_SCL0")
	)
	(segment
		(start 192.87998 -10.815574)
		(end 193.447924 -10.24763)
		(width 0.127)
		(layer "In5.Cu")
		(net "TWI_SCL0")
	)
	(segment
		(start 189.056264 -9.707118)
		(end 190.16472 -10.815574)
		(width 0.127)
		(layer "In5.Cu")
		(net "TWI_SCL0")
	)
	(segment
		(start 250.253754 -33.096962)
		(end 250.49353 -33.336738)
		(width 0.1016)
		(layer "In5.Cu")
		(net "TWI_SCL0")
	)
	(segment
		(start 111.394494 -42.390568)
		(end 111.241332 -42.237406)
		(width 0.127)
		(layer "In5.Cu")
		(net "TWI_SCL0")
	)
	(segment
		(start 125.1839 -15.2273)
		(end 125.1839 -12.261596)
		(width 0.127)
		(layer "In5.Cu")
		(net "TWI_SCL0")
	)
	(segment
		(start 249.49404 -30.284928)
		(end 249.49404 -31.825438)
		(width 0.1016)
		(layer "In5.Cu")
		(net "TWI_SCL0")
	)
	(segment
		(start 190.16472 -10.815574)
		(end 192.87998 -10.815574)
		(width 0.127)
		(layer "In5.Cu")
		(net "TWI_SCL0")
	)
	(segment
		(start 193.447924 -10.24763)
		(end 212.970872 -10.24763)
		(width 0.127)
		(layer "In5.Cu")
		(net "TWI_SCL0")
	)
	(segment
		(start 111.241332 -42.237406)
		(end 111.241332 -41.88841)
		(width 0.127)
		(layer "In5.Cu")
		(net "TWI_SCL0")
	)
	(segment
		(start 248.468134 -26.721816)
		(end 248.620534 -26.874216)
		(width 0.1016)
		(layer "In5.Cu")
		(net "TWI_SCL0")
	)
	(segment
		(start 250.49353 -34.893758)
		(end 251.099828 -35.500056)
		(width 0.1016)
		(layer "In5.Cu")
		(net "TWI_SCL0")
	)
	(segment
		(start 223.680782 -7.012432)
		(end 224.61855 -7.9502)
		(width 0.127)
		(layer "In5.Cu")
		(net "TWI_SCL0")
	)
	(segment
		(start 175.704754 -3.78841)
		(end 181.623716 -9.707372)
		(width 0.127)
		(layer "In5.Cu")
		(net "TWI_SCL0")
	)
	(segment
		(start 218.33078 -6.574536)
		(end 218.768676 -7.012432)
		(width 0.127)
		(layer "In5.Cu")
		(net "TWI_SCL0")
	)
	(segment
		(start 248.857516 -30.102302)
		(end 249.311414 -30.102302)
		(width 0.1016)
		(layer "In5.Cu")
		(net "TWI_SCL0")
	)
	(segment
		(start 248.502932 -29.747718)
		(end 248.857516 -30.102302)
		(width 0.1016)
		(layer "In5.Cu")
		(net "TWI_SCL0")
	)
	(segment
		(start 111.241332 -41.88841)
		(end 112.649 -40.480742)
		(width 0.127)
		(layer "In5.Cu")
		(net "TWI_SCL0")
	)
	(segment
		(start 125.1839 -12.261596)
		(end 133.657086 -3.78841)
		(width 0.127)
		(layer "In5.Cu")
		(net "TWI_SCL0")
	)
	(segment
		(start 250.49353 -33.336738)
		(end 250.49353 -34.893758)
		(width 0.1016)
		(layer "In5.Cu")
		(net "TWI_SCL0")
	)
	(segment
		(start 248.468134 -15.197836)
		(end 248.468134 -26.614628)
		(width 0.127)
		(layer "In5.Cu")
		(net "TWI_SCL0")
	)
	(segment
		(start 182.044594 -9.707118)
		(end 189.056264 -9.707118)
		(width 0.127)
		(layer "In5.Cu")
		(net "TWI_SCL0")
	)
	(segment
		(start 249.49404 -31.825438)
		(end 249.70613 -32.037528)
		(width 0.1016)
		(layer "In5.Cu")
		(net "TWI_SCL0")
	)
	(segment
		(start 249.70613 -32.037528)
		(end 249.70613 -32.663384)
		(width 0.1016)
		(layer "In5.Cu")
		(net "TWI_SCL0")
	)
	(segment
		(start 28.300934 -118.755668)
		(end 29.287724 -119.742458)
		(width 0.12065)
		(layer "F.Cu")
		(net "TP_LPC_CPU_FRAME_N")
	)
	(segment
		(start 28.2956 -118.747794)
		(end 28.2956 -117.1829)
		(width 0.12065)
		(layer "F.Cu")
		(net "TP_LPC_CPU_FRAME_N")
	)
	(segment
		(start 30.504892 -122.018044)
		(end 30.504892 -122.084846)
		(width 0.12065)
		(layer "F.Cu")
		(net "TP_LPC_CPU_FRAME_N")
	)
	(segment
		(start 29.287724 -119.742458)
		(end 29.287724 -120.800876)
		(width 0.12065)
		(layer "F.Cu")
		(net "TP_LPC_CPU_FRAME_N")
	)
	(segment
		(start 28.302458 -118.755668)
		(end 28.302458 -118.754652)
		(width 0.12065)
		(layer "F.Cu")
		(net "TP_LPC_CPU_FRAME_N")
	)
	(segment
		(start 28.300934 -118.755668)
		(end 28.302458 -118.755668)
		(width 0.12065)
		(layer "F.Cu")
		(net "TP_LPC_CPU_FRAME_N")
	)
	(segment
		(start 28.2956 -117.1829)
		(end 28.321 -117.1575)
		(width 0.12065)
		(layer "F.Cu")
		(net "TP_LPC_CPU_FRAME_N")
	)
	(segment
		(start 28.302458 -118.754652)
		(end 28.2956 -118.747794)
		(width 0.12065)
		(layer "F.Cu")
		(net "TP_LPC_CPU_FRAME_N")
	)
	(segment
		(start 29.287724 -120.800876)
		(end 30.504892 -122.018044)
		(width 0.12065)
		(layer "F.Cu")
		(net "TP_LPC_CPU_FRAME_N")
	)
	(via
		(at 28.300934 -118.755668)
		(size 0.7112)
		(drill 0.3556)
		(layers "F.Cu" "B.Cu")
		(net "TP_LPC_CPU_FRAME_N")
	)
	(segment
		(start 30.095444 -122.227848)
		(end 30.095444 -121.923048)
		(width 0.12065)
		(layer "F.Cu")
		(net "TP_LPC_CPU_CLKOUT0")
	)
	(segment
		(start 31.057342 -122.884946)
		(end 30.647894 -122.475498)
		(width 0.12065)
		(layer "F.Cu")
		(net "TP_LPC_CPU_CLKOUT0")
	)
	(segment
		(start 27.178 -117.2845)
		(end 27.305 -117.1575)
		(width 0.12065)
		(layer "F.Cu")
		(net "TP_LPC_CPU_CLKOUT0")
	)
	(segment
		(start 27.178 -118.472966)
		(end 27.178 -118.123208)
		(width 0.12065)
		(layer "F.Cu")
		(net "TP_LPC_CPU_CLKOUT0")
	)
	(segment
		(start 28.744164 -120.607582)
		(end 28.744164 -120.03913)
		(width 0.12065)
		(layer "F.Cu")
		(net "TP_LPC_CPU_CLKOUT0")
	)
	(segment
		(start 27.173682 -118.11889)
		(end 27.178 -118.114572)
		(width 0.12065)
		(layer "F.Cu")
		(net "TP_LPC_CPU_CLKOUT0")
	)
	(segment
		(start 29.86659 -121.694194)
		(end 29.830776 -121.694194)
		(width 0.12065)
		(layer "F.Cu")
		(net "TP_LPC_CPU_CLKOUT0")
	)
	(segment
		(start 29.830776 -121.694194)
		(end 28.744164 -120.607582)
		(width 0.12065)
		(layer "F.Cu")
		(net "TP_LPC_CPU_CLKOUT0")
	)
	(segment
		(start 27.178 -118.123208)
		(end 27.173682 -118.11889)
		(width 0.12065)
		(layer "F.Cu")
		(net "TP_LPC_CPU_CLKOUT0")
	)
	(segment
		(start 31.304738 -122.884946)
		(end 31.057342 -122.884946)
		(width 0.12065)
		(layer "F.Cu")
		(net "TP_LPC_CPU_CLKOUT0")
	)
	(segment
		(start 28.744164 -120.03913)
		(end 27.178 -118.472966)
		(width 0.12065)
		(layer "F.Cu")
		(net "TP_LPC_CPU_CLKOUT0")
	)
	(segment
		(start 30.095444 -121.923048)
		(end 29.86659 -121.694194)
		(width 0.12065)
		(layer "F.Cu")
		(net "TP_LPC_CPU_CLKOUT0")
	)
	(segment
		(start 30.343094 -122.475498)
		(end 30.095444 -122.227848)
		(width 0.12065)
		(layer "F.Cu")
		(net "TP_LPC_CPU_CLKOUT0")
	)
	(segment
		(start 30.647894 -122.475498)
		(end 30.343094 -122.475498)
		(width 0.12065)
		(layer "F.Cu")
		(net "TP_LPC_CPU_CLKOUT0")
	)
	(segment
		(start 27.178 -118.114572)
		(end 27.178 -117.2845)
		(width 0.12065)
		(layer "F.Cu")
		(net "TP_LPC_CPU_CLKOUT0")
	)
	(via
		(at 27.173682 -118.11889)
		(size 0.7112)
		(drill 0.3556)
		(layers "F.Cu" "B.Cu")
		(net "TP_LPC_CPU_CLKOUT0")
	)
	(segment
		(start 33.704784 -125.284992)
		(end 33.304988 -124.885196)
		(width 0.12065)
		(layer "F.Cu")
		(net "TP_IRQ_CPU_SERIAL")
	)
	(via
		(at 33.304988 -124.885196)
		(size 0.4572)
		(drill 0.2032)
		(layers "F.Cu" "B.Cu")
		(net "TP_IRQ_CPU_SERIAL")
	)
	(via
		(at 26.289 -118.116604)
		(size 0.7112)
		(drill 0.3556)
		(layers "F.Cu" "B.Cu")
		(net "TP_IRQ_CPU_SERIAL")
	)
	(segment
		(start 33.304988 -124.885196)
		(end 32.89554 -124.475748)
		(width 0.12065)
		(layer "B.Cu")
		(net "TP_IRQ_CPU_SERIAL")
	)
	(segment
		(start 32.11449 -123.942094)
		(end 26.289 -118.116604)
		(width 0.12065)
		(layer "B.Cu")
		(net "TP_IRQ_CPU_SERIAL")
	)
	(segment
		(start 26.289 -118.116604)
		(end 26.289 -117.1575)
		(width 0.12065)
		(layer "B.Cu")
		(net "TP_IRQ_CPU_SERIAL")
	)
	(segment
		(start 32.11449 -124.246894)
		(end 32.11449 -123.942094)
		(width 0.12065)
		(layer "B.Cu")
		(net "TP_IRQ_CPU_SERIAL")
	)
	(segment
		(start 32.89554 -124.475748)
		(end 32.343344 -124.475748)
		(width 0.12065)
		(layer "B.Cu")
		(net "TP_IRQ_CPU_SERIAL")
	)
	(segment
		(start 32.343344 -124.475748)
		(end 32.11449 -124.246894)
		(width 0.12065)
		(layer "B.Cu")
		(net "TP_IRQ_CPU_SERIAL")
	)
	(segment
		(start 41.704768 -125.284992)
		(end 41.304972 -124.885196)
		(width 0.12065)
		(layer "F.Cu")
		(net "TP_GPIOH7")
	)
	(via
		(at 41.304972 -124.885196)
		(size 0.4572)
		(drill 0.2032)
		(layers "F.Cu" "B.Cu")
		(net "TP_GPIOH7")
	)
	(segment
		(start 42.815002 -118.275608)
		(end 42.815002 -119.37873)
		(width 0.12065)
		(layer "B.Cu")
		(net "TP_GPIOH7")
	)
	(segment
		(start 41.6052 -122.047)
		(end 40.91432 -122.73788)
		(width 0.12065)
		(layer "B.Cu")
		(net "TP_GPIOH7")
	)
	(segment
		(start 42.926 -118.16461)
		(end 42.815002 -118.275608)
		(width 0.12065)
		(layer "B.Cu")
		(net "TP_GPIOH7")
	)
	(segment
		(start 42.815002 -119.37873)
		(end 41.6052 -120.588532)
		(width 0.12065)
		(layer "B.Cu")
		(net "TP_GPIOH7")
	)
	(segment
		(start 41.6052 -120.588532)
		(end 41.6052 -122.047)
		(width 0.12065)
		(layer "B.Cu")
		(net "TP_GPIOH7")
	)
	(segment
		(start 42.926 -117.602)
		(end 42.926 -118.16461)
		(width 0.12065)
		(layer "B.Cu")
		(net "TP_GPIOH7")
	)
	(segment
		(start 40.91432 -124.494544)
		(end 41.304972 -124.885196)
		(width 0.12065)
		(layer "B.Cu")
		(net "TP_GPIOH7")
	)
	(segment
		(start 40.91432 -122.73788)
		(end 40.91432 -124.494544)
		(width 0.12065)
		(layer "B.Cu")
		(net "TP_GPIOH7")
	)
	(segment
		(start 45.390308 -118.947692)
		(end 42.504868 -121.833132)
		(width 0.12065)
		(layer "F.Cu")
		(net "TP_GPIOH6")
	)
	(segment
		(start 42.504868 -121.833132)
		(end 42.504868 -122.084846)
		(width 0.12065)
		(layer "F.Cu")
		(net "TP_GPIOH6")
	)
	(segment
		(start 45.72 -118.364)
		(end 45.390308 -118.693692)
		(width 0.12065)
		(layer "F.Cu")
		(net "TP_GPIOH6")
	)
	(segment
		(start 45.390308 -118.693692)
		(end 45.390308 -118.947692)
		(width 0.12065)
		(layer "F.Cu")
		(net "TP_GPIOH6")
	)
	(segment
		(start 42.139616 -121.629932)
		(end 42.139616 -122.519694)
		(width 0.12065)
		(layer "F.Cu")
		(net "TP_GPIOH5")
	)
	(segment
		(start 42.139616 -122.519694)
		(end 42.504868 -122.884946)
		(width 0.12065)
		(layer "F.Cu")
		(net "TP_GPIOH5")
	)
	(segment
		(start 44.993052 -117.344952)
		(end 44.993052 -118.776496)
		(width 0.12065)
		(layer "F.Cu")
		(net "TP_GPIOH5")
	)
	(segment
		(start 45.053758 -117.284246)
		(end 44.993052 -117.344952)
		(width 0.12065)
		(layer "F.Cu")
		(net "TP_GPIOH5")
	)
	(segment
		(start 44.993052 -118.776496)
		(end 42.139616 -121.629932)
		(width 0.12065)
		(layer "F.Cu")
		(net "TP_GPIOH5")
	)
	(segment
		(start 41.704768 -124.484892)
		(end 41.304972 -124.085096)
		(width 0.12065)
		(layer "F.Cu")
		(net "TP_GPIOH4")
	)
	(via
		(at 41.304972 -124.085096)
		(size 0.4572)
		(drill 0.2032)
		(layers "F.Cu" "B.Cu")
		(net "TP_GPIOH4")
	)
	(segment
		(start 41.304972 -124.085096)
		(end 41.91 -123.480068)
		(width 0.12065)
		(layer "B.Cu")
		(net "TP_GPIOH4")
	)
	(segment
		(start 43.434 -119.521732)
		(end 43.434 -118.872)
		(width 0.12065)
		(layer "B.Cu")
		(net "TP_GPIOH4")
	)
	(segment
		(start 41.91 -123.480068)
		(end 41.91 -121.045732)
		(width 0.12065)
		(layer "B.Cu")
		(net "TP_GPIOH4")
	)
	(segment
		(start 41.91 -121.045732)
		(end 43.434 -119.521732)
		(width 0.12065)
		(layer "B.Cu")
		(net "TP_GPIOH4")
	)
	(segment
		(start 41.704768 -121.744232)
		(end 41.704768 -122.084846)
		(width 0.12065)
		(layer "F.Cu")
		(net "TP_GPIOH3")
	)
	(segment
		(start 44.45 -118.364)
		(end 44.45 -118.999)
		(width 0.12065)
		(layer "F.Cu")
		(net "TP_GPIOH3")
	)
	(segment
		(start 44.45 -118.999)
		(end 41.704768 -121.744232)
		(width 0.12065)
		(layer "F.Cu")
		(net "TP_GPIOH3")
	)
	(segment
		(start 30.895544 -121.923048)
		(end 30.895544 -122.228102)
		(width 0.12065)
		(layer "F.Cu")
		(net "TP_BMC0_LPC_LAD3")
	)
	(segment
		(start 29.337 -118.043452)
		(end 29.337 -117.1575)
		(width 0.12065)
		(layer "F.Cu")
		(net "TP_BMC0_LPC_LAD3")
	)
	(segment
		(start 29.380942 -118.087394)
		(end 29.380942 -119.068342)
		(width 0.12065)
		(layer "F.Cu")
		(net "TP_BMC0_LPC_LAD3")
	)
	(segment
		(start 29.771848 -120.799352)
		(end 30.895544 -121.923048)
		(width 0.12065)
		(layer "F.Cu")
		(net "TP_BMC0_LPC_LAD3")
	)
	(segment
		(start 31.14294 -122.475498)
		(end 31.44774 -122.475498)
		(width 0.12065)
		(layer "F.Cu")
		(net "TP_BMC0_LPC_LAD3")
	)
	(segment
		(start 31.739586 -122.767344)
		(end 31.739586 -123.31954)
		(width 0.12065)
		(layer "F.Cu")
		(net "TP_BMC0_LPC_LAD3")
	)
	(segment
		(start 31.44774 -122.475498)
		(end 31.739586 -122.767344)
		(width 0.12065)
		(layer "F.Cu")
		(net "TP_BMC0_LPC_LAD3")
	)
	(segment
		(start 31.739586 -123.31954)
		(end 32.104838 -123.684792)
		(width 0.12065)
		(layer "F.Cu")
		(net "TP_BMC0_LPC_LAD3")
	)
	(segment
		(start 29.380942 -119.068342)
		(end 29.771848 -119.459248)
		(width 0.12065)
		(layer "F.Cu")
		(net "TP_BMC0_LPC_LAD3")
	)
	(segment
		(start 29.771848 -119.459248)
		(end 29.771848 -120.799352)
		(width 0.12065)
		(layer "F.Cu")
		(net "TP_BMC0_LPC_LAD3")
	)
	(segment
		(start 30.895544 -122.228102)
		(end 31.14294 -122.475498)
		(width 0.12065)
		(layer "F.Cu")
		(net "TP_BMC0_LPC_LAD3")
	)
	(segment
		(start 29.380942 -118.087394)
		(end 29.337 -118.043452)
		(width 0.12065)
		(layer "F.Cu")
		(net "TP_BMC0_LPC_LAD3")
	)
	(via
		(at 29.380942 -118.087394)
		(size 0.7112)
		(drill 0.3556)
		(layers "F.Cu" "B.Cu")
		(net "TP_BMC0_LPC_LAD3")
	)
	(segment
		(start 32.104838 -126.084838)
		(end 32.504634 -125.685042)
		(width 0.12065)
		(layer "F.Cu")
		(net "TP_BMC0_LPC_LAD2")
	)
	(via
		(at 17.4244 -125.5776)
		(size 0.7112)
		(drill 0.3556)
		(layers "F.Cu" "B.Cu")
		(net "TP_BMC0_LPC_LAD2")
	)
	(via
		(at 32.504634 -125.685042)
		(size 0.4572)
		(drill 0.2032)
		(layers "F.Cu" "B.Cu")
		(net "TP_BMC0_LPC_LAD2")
	)
	(via
		(at 17.1958 -126.77648)
		(size 0.508)
		(drill 0.254)
		(layers "F.Cu" "B.Cu")
		(net "TP_BMC0_LPC_LAD2")
	)
	(segment
		(start 17.9832 -126.152148)
		(end 17.9705 -126.139448)
		(width 0.12065)
		(layer "B.Cu")
		(net "TP_BMC0_LPC_LAD2")
	)
	(segment
		(start 17.9832 -126.6063)
		(end 17.9832 -126.152148)
		(width 0.12065)
		(layer "B.Cu")
		(net "TP_BMC0_LPC_LAD2")
	)
	(segment
		(start 17.4244 -125.5776)
		(end 17.1958 -125.8062)
		(width 0.12065)
		(layer "B.Cu")
		(net "TP_BMC0_LPC_LAD2")
	)
	(segment
		(start 17.1958 -125.8062)
		(end 17.1958 -126.77648)
		(width 0.12065)
		(layer "B.Cu")
		(net "TP_BMC0_LPC_LAD2")
	)
	(segment
		(start 17.9705 -126.1237)
		(end 17.4244 -125.5776)
		(width 0.12065)
		(layer "B.Cu")
		(net "TP_BMC0_LPC_LAD2")
	)
	(segment
		(start 17.9705 -126.619)
		(end 17.9832 -126.6063)
		(width 0.12065)
		(layer "B.Cu")
		(net "TP_BMC0_LPC_LAD2")
	)
	(segment
		(start 17.9705 -126.139448)
		(end 17.9705 -126.1237)
		(width 0.12065)
		(layer "B.Cu")
		(net "TP_BMC0_LPC_LAD2")
	)
	(segment
		(start 27.105356 -125.291088)
		(end 32.11068 -125.291088)
		(width 0.127)
		(layer "In2.Cu")
		(net "TP_BMC0_LPC_LAD2")
	)
	(segment
		(start 26.72207 -124.907802)
		(end 27.105356 -125.291088)
		(width 0.127)
		(layer "In2.Cu")
		(net "TP_BMC0_LPC_LAD2")
	)
	(segment
		(start 22.738334 -125.291088)
		(end 23.12162 -124.907802)
		(width 0.127)
		(layer "In2.Cu")
		(net "TP_BMC0_LPC_LAD2")
	)
	(segment
		(start 17.1958 -126.77648)
		(end 18.681192 -125.291088)
		(width 0.127)
		(layer "In2.Cu")
		(net "TP_BMC0_LPC_LAD2")
	)
	(segment
		(start 32.11068 -125.291088)
		(end 32.504634 -125.685042)
		(width 0.127)
		(layer "In2.Cu")
		(net "TP_BMC0_LPC_LAD2")
	)
	(segment
		(start 18.681192 -125.291088)
		(end 22.738334 -125.291088)
		(width 0.127)
		(layer "In2.Cu")
		(net "TP_BMC0_LPC_LAD2")
	)
	(segment
		(start 23.12162 -124.907802)
		(end 26.72207 -124.907802)
		(width 0.127)
		(layer "In2.Cu")
		(net "TP_BMC0_LPC_LAD2")
	)
	(segment
		(start 25.7683 -117.1575)
		(end 25.4 -117.5258)
		(width 0.12065)
		(layer "F.Cu")
		(net "TP_BMC0_LPC_LAD1")
	)
	(segment
		(start 29.704792 -122.084846)
		(end 28.435046 -120.8151)
		(width 0.12065)
		(layer "F.Cu")
		(net "TP_BMC0_LPC_LAD1")
	)
	(segment
		(start 28.435046 -120.8151)
		(end 28.435046 -120.154446)
		(width 0.12065)
		(layer "F.Cu")
		(net "TP_BMC0_LPC_LAD1")
	)
	(segment
		(start 26.289 -117.1575)
		(end 25.7683 -117.1575)
		(width 0.12065)
		(layer "F.Cu")
		(net "TP_BMC0_LPC_LAD1")
	)
	(segment
		(start 28.435046 -120.154446)
		(end 27.190192 -118.909592)
		(width 0.12065)
		(layer "F.Cu")
		(net "TP_BMC0_LPC_LAD1")
	)
	(segment
		(start 26.915364 -118.72214)
		(end 26.176224 -117.983)
		(width 0.12065)
		(layer "F.Cu")
		(net "TP_BMC0_LPC_LAD1")
	)
	(segment
		(start 27.102562 -118.909592)
		(end 26.915364 -118.722394)
		(width 0.12065)
		(layer "F.Cu")
		(net "TP_BMC0_LPC_LAD1")
	)
	(segment
		(start 25.4 -117.7798)
		(end 25.4 -117.5258)
		(width 0.12065)
		(layer "F.Cu")
		(net "TP_BMC0_LPC_LAD1")
	)
	(segment
		(start 27.190192 -118.909592)
		(end 27.102562 -118.909592)
		(width 0.12065)
		(layer "F.Cu")
		(net "TP_BMC0_LPC_LAD1")
	)
	(segment
		(start 26.176224 -117.983)
		(end 25.6032 -117.983)
		(width 0.12065)
		(layer "F.Cu")
		(net "TP_BMC0_LPC_LAD1")
	)
	(segment
		(start 25.6032 -117.983)
		(end 25.4 -117.7798)
		(width 0.12065)
		(layer "F.Cu")
		(net "TP_BMC0_LPC_LAD1")
	)
	(segment
		(start 26.915364 -118.722394)
		(end 26.915364 -118.72214)
		(width 0.12065)
		(layer "F.Cu")
		(net "TP_BMC0_LPC_LAD1")
	)
	(via
		(at 25.4 -117.5258)
		(size 0.7112)
		(drill 0.3556)
		(layers "F.Cu" "B.Cu")
		(net "TP_BMC0_LPC_LAD1")
	)
	(segment
		(start 23.495 -119.3165)
		(end 23.495 -119.0244)
		(width 0.12065)
		(layer "F.Cu")
		(net "TP_BMC0_LPC_LAD0")
	)
	(segment
		(start 28.006548 -120.939052)
		(end 29.542994 -122.475498)
		(width 0.12065)
		(layer "F.Cu")
		(net "TP_BMC0_LPC_LAD0")
	)
	(segment
		(start 30.301946 -122.884946)
		(end 30.504892 -122.884946)
		(width 0.12065)
		(layer "F.Cu")
		(net "TP_BMC0_LPC_LAD0")
	)
	(segment
		(start 26.04516 -118.364)
		(end 26.813002 -119.131842)
		(width 0.12065)
		(layer "F.Cu")
		(net "TP_BMC0_LPC_LAD0")
	)
	(segment
		(start 24.8666 -117.856)
		(end 25.3746 -118.364)
		(width 0.12065)
		(layer "F.Cu")
		(net "TP_BMC0_LPC_LAD0")
	)
	(segment
		(start 29.892498 -122.475498)
		(end 30.301946 -122.884946)
		(width 0.12065)
		(layer "F.Cu")
		(net "TP_BMC0_LPC_LAD0")
	)
	(segment
		(start 23.701756 -118.406164)
		(end 23.701756 -118.213124)
		(width 0.12065)
		(layer "F.Cu")
		(net "TP_BMC0_LPC_LAD0")
	)
	(segment
		(start 24.05888 -117.856)
		(end 24.8666 -117.856)
		(width 0.12065)
		(layer "F.Cu")
		(net "TP_BMC0_LPC_LAD0")
	)
	(segment
		(start 23.495 -119.0244)
		(end 23.701756 -118.817644)
		(width 0.12065)
		(layer "F.Cu")
		(net "TP_BMC0_LPC_LAD0")
	)
	(segment
		(start 29.542994 -122.475498)
		(end 29.892498 -122.475498)
		(width 0.12065)
		(layer "F.Cu")
		(net "TP_BMC0_LPC_LAD0")
	)
	(segment
		(start 27.037538 -119.131842)
		(end 28.006548 -120.100852)
		(width 0.12065)
		(layer "F.Cu")
		(net "TP_BMC0_LPC_LAD0")
	)
	(segment
		(start 28.006548 -120.100852)
		(end 28.006548 -120.939052)
		(width 0.12065)
		(layer "F.Cu")
		(net "TP_BMC0_LPC_LAD0")
	)
	(segment
		(start 23.701756 -118.817644)
		(end 23.701756 -118.406164)
		(width 0.12065)
		(layer "F.Cu")
		(net "TP_BMC0_LPC_LAD0")
	)
	(segment
		(start 23.701756 -118.213124)
		(end 24.05888 -117.856)
		(width 0.12065)
		(layer "F.Cu")
		(net "TP_BMC0_LPC_LAD0")
	)
	(segment
		(start 26.813002 -119.131842)
		(end 27.037538 -119.131842)
		(width 0.12065)
		(layer "F.Cu")
		(net "TP_BMC0_LPC_LAD0")
	)
	(segment
		(start 25.3746 -118.364)
		(end 26.04516 -118.364)
		(width 0.12065)
		(layer "F.Cu")
		(net "TP_BMC0_LPC_LAD0")
	)
	(via
		(at 23.701756 -118.406164)
		(size 0.7112)
		(drill 0.3556)
		(layers "F.Cu" "B.Cu")
		(net "TP_BMC0_LPC_LAD0")
	)
	(segment
		(start 48.301656 -135.763)
		(end 46.623478 -134.084822)
		(width 0.12065)
		(layer "F.Cu")
		(net "TP_BMC_GPIOJ7")
	)
	(segment
		(start 50.292 -135.763)
		(end 48.301656 -135.763)
		(width 0.12065)
		(layer "F.Cu")
		(net "TP_BMC_GPIOJ7")
	)
	(segment
		(start 46.623478 -134.084822)
		(end 46.50486 -134.084822)
		(width 0.12065)
		(layer "F.Cu")
		(net "TP_BMC_GPIOJ7")
	)
	(segment
		(start 50.292 -134.493)
		(end 47.625 -134.493)
		(width 0.12065)
		(layer "F.Cu")
		(net "TP_BMC_GPIOJ6")
	)
	(segment
		(start 46.85157 -133.71957)
		(end 46.070012 -133.71957)
		(width 0.12065)
		(layer "F.Cu")
		(net "TP_BMC_GPIOJ6")
	)
	(segment
		(start 47.625 -134.493)
		(end 46.85157 -133.71957)
		(width 0.12065)
		(layer "F.Cu")
		(net "TP_BMC_GPIOJ6")
	)
	(segment
		(start 46.070012 -133.71957)
		(end 45.70476 -134.084822)
		(width 0.12065)
		(layer "F.Cu")
		(net "TP_BMC_GPIOJ6")
	)
	(segment
		(start 46.717204 -134.493)
		(end 46.096682 -134.493)
		(width 0.12065)
		(layer "F.Cu")
		(net "TP_BMC_GPIOJ5")
	)
	(segment
		(start 50.90795 -136.41705)
		(end 48.641254 -136.41705)
		(width 0.12065)
		(layer "F.Cu")
		(net "TP_BMC_GPIOJ5")
	)
	(segment
		(start 51.562 -135.763)
		(end 50.90795 -136.41705)
		(width 0.12065)
		(layer "F.Cu")
		(net "TP_BMC_GPIOJ5")
	)
	(segment
		(start 46.096682 -134.493)
		(end 45.70476 -134.884922)
		(width 0.12065)
		(layer "F.Cu")
		(net "TP_BMC_GPIOJ5")
	)
	(segment
		(start 48.641254 -136.41705)
		(end 46.717204 -134.493)
		(width 0.12065)
		(layer "F.Cu")
		(net "TP_BMC_GPIOJ5")
	)
	(segment
		(start 44.104814 -134.084822)
		(end 44.50461 -133.685026)
		(width 0.12065)
		(layer "F.Cu")
		(net "TP_BMC_GPIOJ4")
	)
	(via
		(at 44.50461 -133.685026)
		(size 0.4572)
		(drill 0.2032)
		(layers "F.Cu" "B.Cu")
		(net "TP_BMC_GPIOJ4")
	)
	(segment
		(start 43.2562 -133.501892)
		(end 43.463718 -133.294374)
		(width 0.12065)
		(layer "B.Cu")
		(net "TP_BMC_GPIOJ4")
	)
	(segment
		(start 43.236388 -133.501892)
		(end 43.2562 -133.501892)
		(width 0.12065)
		(layer "B.Cu")
		(net "TP_BMC_GPIOJ4")
	)
	(segment
		(start 43.463718 -133.294374)
		(end 44.113958 -133.294374)
		(width 0.12065)
		(layer "B.Cu")
		(net "TP_BMC_GPIOJ4")
	)
	(segment
		(start 42.824146 -133.914134)
		(end 43.236388 -133.501892)
		(width 0.12065)
		(layer "B.Cu")
		(net "TP_BMC_GPIOJ4")
	)
	(segment
		(start 44.113958 -133.294374)
		(end 44.50461 -133.685026)
		(width 0.12065)
		(layer "B.Cu")
		(net "TP_BMC_GPIOJ4")
	)
	(segment
		(start 256.477262 -8.713978)
		(end 256.477262 -9.616948)
		(width 0.12065)
		(layer "F.Cu")
		(net "THERM_EMIT_R")
	)
	(segment
		(start 256.477262 -9.616948)
		(end 256.711704 -9.85139)
		(width 0.12065)
		(layer "F.Cu")
		(net "THERM_EMIT_R")
	)
	(segment
		(start 256.711704 -9.85139)
		(end 256.711704 -10.544048)
		(width 0.12065)
		(layer "F.Cu")
		(net "THERM_EMIT_R")
	)
	(segment
		(start 250.599956 -36.999926)
		(end 251.099828 -36.500054)
		(width 0.1524)
		(layer "F.Cu")
		(net "THERM_EMIT")
	)
	(segment
		(start 256.978912 -12.473686)
		(end 256.978912 -11.700256)
		(width 0.1524)
		(layer "F.Cu")
		(net "THERM_EMIT")
	)
	(segment
		(start 256.978912 -11.700256)
		(end 256.711704 -11.433048)
		(width 0.1524)
		(layer "F.Cu")
		(net "THERM_EMIT")
	)
	(segment
		(start 256.161032 -12.116816)
		(end 255.703832 -12.116816)
		(width 0.1524)
		(layer "F.Cu")
		(net "THERM_EMIT")
	)
	(segment
		(start 255.703832 -12.116816)
		(end 255.21031 -12.610338)
		(width 0.1524)
		(layer "F.Cu")
		(net "THERM_EMIT")
	)
	(segment
		(start 256.161032 -11.98372)
		(end 256.161032 -12.116816)
		(width 0.1524)
		(layer "F.Cu")
		(net "THERM_EMIT")
	)
	(segment
		(start 256.711704 -11.433048)
		(end 256.161032 -11.98372)
		(width 0.1524)
		(layer "F.Cu")
		(net "THERM_EMIT")
	)
	(via
		(at 251.099828 -36.500054)
		(size 0.4572)
		(drill 0.2032)
		(layers "F.Cu" "B.Cu")
		(net "THERM_EMIT")
	)
	(via
		(at 255.21031 -12.610338)
		(size 0.7112)
		(drill 0.3556)
		(layers "F.Cu" "B.Cu")
		(net "THERM_EMIT")
	)
	(via
		(at 256.161032 -12.116816)
		(size 0.508)
		(drill 0.254)
		(layers "F.Cu" "B.Cu")
		(net "THERM_EMIT")
	)
	(segment
		(start 251.39269 -31.903162)
		(end 251.696728 -32.2072)
		(width 0.1016)
		(layer "In5.Cu")
		(net "THERM_EMIT")
	)
	(segment
		(start 250.698 -29.9466)
		(end 250.698 -31.748984)
		(width 0.1016)
		(layer "In5.Cu")
		(net "THERM_EMIT")
	)
	(segment
		(start 250.852178 -31.903162)
		(end 251.39269 -31.903162)
		(width 0.1016)
		(layer "In5.Cu")
		(net "THERM_EMIT")
	)
	(segment
		(start 251.696728 -32.2072)
		(end 251.696728 -35.747706)
		(width 0.1016)
		(layer "In5.Cu")
		(net "THERM_EMIT")
	)
	(segment
		(start 249.980196 -29.228796)
		(end 250.444 -29.6926)
		(width 0.1524)
		(layer "In5.Cu")
		(net "THERM_EMIT")
	)
	(segment
		(start 251.696728 -35.747706)
		(end 251.608844 -35.835844)
		(width 0.1016)
		(layer "In5.Cu")
		(net "THERM_EMIT")
	)
	(segment
		(start 250.357386 -26.216356)
		(end 249.980196 -26.593546)
		(width 0.1524)
		(layer "In5.Cu")
		(net "THERM_EMIT")
	)
	(segment
		(start 256.161032 -12.116816)
		(end 250.357386 -17.920462)
		(width 0.1524)
		(layer "In5.Cu")
		(net "THERM_EMIT")
	)
	(segment
		(start 251.099828 -36.34486)
		(end 251.099828 -36.500054)
		(width 0.1016)
		(layer "In5.Cu")
		(net "THERM_EMIT")
	)
	(segment
		(start 250.698 -31.748984)
		(end 250.852178 -31.903162)
		(width 0.1016)
		(layer "In5.Cu")
		(net "THERM_EMIT")
	)
	(segment
		(start 250.357386 -17.920462)
		(end 250.357386 -26.216356)
		(width 0.1524)
		(layer "In5.Cu")
		(net "THERM_EMIT")
	)
	(segment
		(start 249.980196 -26.593546)
		(end 249.980196 -29.228796)
		(width 0.1524)
		(layer "In5.Cu")
		(net "THERM_EMIT")
	)
	(segment
		(start 251.608844 -35.835844)
		(end 251.099828 -36.34486)
		(width 0.1016)
		(layer "In5.Cu")
		(net "THERM_EMIT")
	)
	(segment
		(start 250.444 -29.6926)
		(end 250.698 -29.9466)
		(width 0.1016)
		(layer "In5.Cu")
		(net "THERM_EMIT")
	)
	(segment
		(start 254.12192 -11.556238)
		(end 254.173482 -11.6078)
		(width 0.12065)
		(layer "F.Cu")
		(net "THERM_BASE_R")
	)
	(segment
		(start 254.12192 -10.620248)
		(end 254.12192 -11.556238)
		(width 0.12065)
		(layer "F.Cu")
		(net "THERM_BASE_R")
	)
	(segment
		(start 254.12192 -10.620248)
		(end 254.12192 -10.50544)
		(width 0.12065)
		(layer "F.Cu")
		(net "THERM_BASE_R")
	)
	(segment
		(start 255.842262 -9.392412)
		(end 255.842262 -8.713978)
		(width 0.12065)
		(layer "F.Cu")
		(net "THERM_BASE_R")
	)
	(segment
		(start 255.414272 -9.820402)
		(end 255.842262 -9.392412)
		(width 0.12065)
		(layer "F.Cu")
		(net "THERM_BASE_R")
	)
	(segment
		(start 254.806958 -9.820402)
		(end 255.414272 -9.820402)
		(width 0.12065)
		(layer "F.Cu")
		(net "THERM_BASE_R")
	)
	(segment
		(start 254.12192 -10.50544)
		(end 254.806958 -9.820402)
		(width 0.12065)
		(layer "F.Cu")
		(net "THERM_BASE_R")
	)
	(via
		(at 254.12192 -10.620248)
		(size 0.7112)
		(drill 0.3556)
		(layers "F.Cu" "B.Cu")
		(net "THERM_BASE_R")
	)
	(segment
		(start 254.070104 -12.600178)
		(end 254.173482 -12.4968)
		(width 0.1524)
		(layer "F.Cu")
		(net "THERM_BASE")
	)
	(segment
		(start 253.251716 -12.600178)
		(end 254.070104 -12.600178)
		(width 0.1524)
		(layer "F.Cu")
		(net "THERM_BASE")
	)
	(segment
		(start 250.599956 -37.999924)
		(end 251.099828 -37.500052)
		(width 0.1524)
		(layer "F.Cu")
		(net "THERM_BASE")
	)
	(segment
		(start 255.314704 -11.433048)
		(end 255.237234 -11.433048)
		(width 0.1524)
		(layer "F.Cu")
		(net "THERM_BASE")
	)
	(segment
		(start 255.237234 -11.433048)
		(end 254.173482 -12.4968)
		(width 0.1524)
		(layer "F.Cu")
		(net "THERM_BASE")
	)
	(segment
		(start 253.239778 -12.58824)
		(end 253.251716 -12.600178)
		(width 0.1524)
		(layer "F.Cu")
		(net "THERM_BASE")
	)
	(via
		(at 253.239778 -12.58824)
		(size 0.508)
		(drill 0.254)
		(layers "F.Cu" "B.Cu")
		(net "THERM_BASE")
	)
	(via
		(at 251.099828 -37.500052)
		(size 0.4572)
		(drill 0.2032)
		(layers "F.Cu" "B.Cu")
		(net "THERM_BASE")
	)
	(via
		(at 253.047754 -11.608054)
		(size 0.7112)
		(drill 0.3556)
		(layers "F.Cu" "B.Cu")
		(net "THERM_BASE")
	)
	(segment
		(start 253.239778 -12.684506)
		(end 253.047754 -12.492482)
		(width 0.1524)
		(layer "B.Cu")
		(net "THERM_BASE")
	)
	(segment
		(start 253.047754 -12.492482)
		(end 253.047754 -11.608054)
		(width 0.1524)
		(layer "B.Cu")
		(net "THERM_BASE")
	)
	(segment
		(start 253.239778 -12.58824)
		(end 253.239778 -12.684506)
		(width 0.1524)
		(layer "B.Cu")
		(net "THERM_BASE")
	)
	(segment
		(start 250.2916 -29.9974)
		(end 250.49353 -30.19933)
		(width 0.1016)
		(layer "In5.Cu")
		(net "THERM_BASE")
	)
	(segment
		(start 249.675396 -29.381196)
		(end 250.2916 -29.9974)
		(width 0.1524)
		(layer "In5.Cu")
		(net "THERM_BASE")
	)
	(segment
		(start 249.675396 -26.538936)
		(end 249.675396 -29.381196)
		(width 0.1524)
		(layer "In5.Cu")
		(net "THERM_BASE")
	)
	(segment
		(start 250.706128 -36.336732)
		(end 250.706128 -36.893754)
		(width 0.1016)
		(layer "In5.Cu")
		(net "THERM_BASE")
	)
	(segment
		(start 253.239778 -12.684506)
		(end 253.388368 -12.833096)
		(width 0.1524)
		(layer "In5.Cu")
		(net "THERM_BASE")
	)
	(segment
		(start 251.04725 -36.109656)
		(end 250.933204 -36.109656)
		(width 0.1016)
		(layer "In5.Cu")
		(net "THERM_BASE")
	)
	(segment
		(start 251.493528 -32.33674)
		(end 251.493528 -35.663378)
		(width 0.1016)
		(layer "In5.Cu")
		(net "THERM_BASE")
	)
	(segment
		(start 253.239778 -12.58824)
		(end 253.239778 -12.684506)
		(width 0.1524)
		(layer "In5.Cu")
		(net "THERM_BASE")
	)
	(segment
		(start 251.099828 -37.287454)
		(end 251.099828 -37.500052)
		(width 0.1016)
		(layer "In5.Cu")
		(net "THERM_BASE")
	)
	(segment
		(start 250.052586 -26.161746)
		(end 249.675396 -26.538936)
		(width 0.1524)
		(layer "In5.Cu")
		(net "THERM_BASE")
	)
	(segment
		(start 251.493528 -35.663378)
		(end 251.04725 -36.109656)
		(width 0.1016)
		(layer "In5.Cu")
		(net "THERM_BASE")
	)
	(segment
		(start 250.49353 -30.19933)
		(end 250.49353 -31.877)
		(width 0.1016)
		(layer "In5.Cu")
		(net "THERM_BASE")
	)
	(segment
		(start 251.26315 -32.106362)
		(end 251.493528 -32.33674)
		(width 0.1016)
		(layer "In5.Cu")
		(net "THERM_BASE")
	)
	(segment
		(start 253.388368 -12.833096)
		(end 253.388368 -14.073632)
		(width 0.1524)
		(layer "In5.Cu")
		(net "THERM_BASE")
	)
	(segment
		(start 250.933204 -36.109656)
		(end 250.706128 -36.336732)
		(width 0.1016)
		(layer "In5.Cu")
		(net "THERM_BASE")
	)
	(segment
		(start 253.388368 -14.073632)
		(end 250.052586 -17.409414)
		(width 0.1524)
		(layer "In5.Cu")
		(net "THERM_BASE")
	)
	(segment
		(start 250.722892 -32.106362)
		(end 251.26315 -32.106362)
		(width 0.1016)
		(layer "In5.Cu")
		(net "THERM_BASE")
	)
	(segment
		(start 250.706128 -36.893754)
		(end 251.099828 -37.287454)
		(width 0.1016)
		(layer "In5.Cu")
		(net "THERM_BASE")
	)
	(segment
		(start 250.49353 -31.877)
		(end 250.722892 -32.106362)
		(width 0.1016)
		(layer "In5.Cu")
		(net "THERM_BASE")
	)
	(segment
		(start 250.052586 -17.409414)
		(end 250.052586 -26.161746)
		(width 0.1524)
		(layer "In5.Cu")
		(net "THERM_BASE")
	)
	(segment
		(start 119.958612 -43.644566)
		(end 121.059956 -42.543222)
		(width 0.1524)
		(layer "F.Cu")
		(net "TEMP_SENSOR_DXP_R")
	)
	(segment
		(start 104.60736 -32.639)
		(end 115.612926 -43.644566)
		(width 0.1524)
		(layer "F.Cu")
		(net "TEMP_SENSOR_DXP_R")
	)
	(segment
		(start 90.187526 -31.526988)
		(end 91.299538 -32.639)
		(width 0.1524)
		(layer "F.Cu")
		(net "TEMP_SENSOR_DXP_R")
	)
	(segment
		(start 91.299538 -32.639)
		(end 104.60736 -32.639)
		(width 0.1524)
		(layer "F.Cu")
		(net "TEMP_SENSOR_DXP_R")
	)
	(segment
		(start 115.612926 -43.644566)
		(end 119.958612 -43.644566)
		(width 0.1524)
		(layer "F.Cu")
		(net "TEMP_SENSOR_DXP_R")
	)
	(via
		(at 256.121662 0.49276)
		(size 0.508)
		(drill 0.254)
		(layers "F.Cu" "B.Cu")
		(net "TEMP_SENSOR_DXP_R")
	)
	(via
		(at 90.187526 -31.526988)
		(size 0.508)
		(drill 0.254)
		(layers "F.Cu" "B.Cu")
		(net "TEMP_SENSOR_DXP_R")
	)
	(via
		(at 261.994396 -2.470912)
		(size 0.7112)
		(drill 0.3556)
		(layers "F.Cu" "B.Cu")
		(net "TEMP_SENSOR_DXP_R")
	)
	(segment
		(start 258.29133 0.147828)
		(end 256.466594 0.147828)
		(width 0.1524)
		(layer "B.Cu")
		(net "TEMP_SENSOR_DXP_R")
	)
	(segment
		(start 258.988814 -0.549656)
		(end 258.29133 0.147828)
		(width 0.1524)
		(layer "B.Cu")
		(net "TEMP_SENSOR_DXP_R")
	)
	(segment
		(start 261.994396 -2.470912)
		(end 260.38556 -2.470912)
		(width 0.1524)
		(layer "B.Cu")
		(net "TEMP_SENSOR_DXP_R")
	)
	(segment
		(start 262.527034 -2.470912)
		(end 263.10082 -1.897126)
		(width 0.1524)
		(layer "B.Cu")
		(net "TEMP_SENSOR_DXP_R")
	)
	(segment
		(start 258.988814 -1.074166)
		(end 258.988814 -0.549656)
		(width 0.1524)
		(layer "B.Cu")
		(net "TEMP_SENSOR_DXP_R")
	)
	(segment
		(start 261.994396 -2.470912)
		(end 262.527034 -2.470912)
		(width 0.1524)
		(layer "B.Cu")
		(net "TEMP_SENSOR_DXP_R")
	)
	(segment
		(start 260.38556 -2.470912)
		(end 258.988814 -1.074166)
		(width 0.1524)
		(layer "B.Cu")
		(net "TEMP_SENSOR_DXP_R")
	)
	(segment
		(start 256.466594 0.147828)
		(end 256.121662 0.49276)
		(width 0.1524)
		(layer "B.Cu")
		(net "TEMP_SENSOR_DXP_R")
	)
	(segment
		(start 256.121662 0.49276)
		(end 254.907542 1.70688)
		(width 0.1524)
		(layer "In2.Cu")
		(net "TEMP_SENSOR_DXP_R")
	)
	(segment
		(start 119.188738 -3.847592)
		(end 92.361258 -30.675072)
		(width 0.1524)
		(layer "In2.Cu")
		(net "TEMP_SENSOR_DXP_R")
	)
	(segment
		(start 128.556766 4.16179)
		(end 120.547384 -3.847592)
		(width 0.1524)
		(layer "In2.Cu")
		(net "TEMP_SENSOR_DXP_R")
	)
	(segment
		(start 245.023894 4.16179)
		(end 128.556766 4.16179)
		(width 0.1524)
		(layer "In2.Cu")
		(net "TEMP_SENSOR_DXP_R")
	)
	(segment
		(start 247.478804 1.70688)
		(end 245.023894 4.16179)
		(width 0.1524)
		(layer "In2.Cu")
		(net "TEMP_SENSOR_DXP_R")
	)
	(segment
		(start 91.039442 -30.675072)
		(end 90.187526 -31.526988)
		(width 0.1524)
		(layer "In2.Cu")
		(net "TEMP_SENSOR_DXP_R")
	)
	(segment
		(start 92.361258 -30.675072)
		(end 91.039442 -30.675072)
		(width 0.1524)
		(layer "In2.Cu")
		(net "TEMP_SENSOR_DXP_R")
	)
	(segment
		(start 254.907542 1.70688)
		(end 247.478804 1.70688)
		(width 0.1524)
		(layer "In2.Cu")
		(net "TEMP_SENSOR_DXP_R")
	)
	(segment
		(start 120.547384 -3.847592)
		(end 119.188738 -3.847592)
		(width 0.1524)
		(layer "In2.Cu")
		(net "TEMP_SENSOR_DXP_R")
	)
	(via
		(at 262.628634 -8.868156)
		(size 0.7112)
		(drill 0.3556)
		(layers "F.Cu" "B.Cu")
		(net "TEMP_SENSOR_DXP")
	)
	(segment
		(start 259.7404 -4.3688)
		(end 262.579358 -4.3688)
		(width 0.1524)
		(layer "B.Cu")
		(net "TEMP_SENSOR_DXP")
	)
	(segment
		(start 260.522466 -7.90194)
		(end 259.64134 -7.90194)
		(width 0.1524)
		(layer "B.Cu")
		(net "TEMP_SENSOR_DXP")
	)
	(segment
		(start 259.1054 -5.0038)
		(end 259.7404 -4.3688)
		(width 0.1524)
		(layer "B.Cu")
		(net "TEMP_SENSOR_DXP")
	)
	(segment
		(start 261.93496 -8.174482)
		(end 262.628634 -8.868156)
		(width 0.1524)
		(layer "B.Cu")
		(net "TEMP_SENSOR_DXP")
	)
	(segment
		(start 261.190232 -7.90194)
		(end 261.462774 -8.174482)
		(width 0.1524)
		(layer "B.Cu")
		(net "TEMP_SENSOR_DXP")
	)
	(segment
		(start 260.522466 -7.90194)
		(end 261.190232 -7.90194)
		(width 0.1524)
		(layer "B.Cu")
		(net "TEMP_SENSOR_DXP")
	)
	(segment
		(start 259.64134 -7.90194)
		(end 259.1054 -7.366)
		(width 0.1524)
		(layer "B.Cu")
		(net "TEMP_SENSOR_DXP")
	)
	(segment
		(start 263.211818 -2.897124)
		(end 263.10082 -2.786126)
		(width 0.1524)
		(layer "B.Cu")
		(net "TEMP_SENSOR_DXP")
	)
	(segment
		(start 261.462774 -8.174482)
		(end 261.93496 -8.174482)
		(width 0.1524)
		(layer "B.Cu")
		(net "TEMP_SENSOR_DXP")
	)
	(segment
		(start 259.1054 -7.366)
		(end 259.1054 -5.0038)
		(width 0.1524)
		(layer "B.Cu")
		(net "TEMP_SENSOR_DXP")
	)
	(segment
		(start 262.579358 -4.3688)
		(end 263.211818 -3.73634)
		(width 0.1524)
		(layer "B.Cu")
		(net "TEMP_SENSOR_DXP")
	)
	(segment
		(start 263.211818 -3.73634)
		(end 263.211818 -2.897124)
		(width 0.1524)
		(layer "B.Cu")
		(net "TEMP_SENSOR_DXP")
	)
	(segment
		(start 120.802146 -41.531032)
		(end 114.218212 -41.531032)
		(width 0.1524)
		(layer "F.Cu")
		(net "TEMP_SENSOR_DXN_BJT")
	)
	(segment
		(start 91.74353 -32.1056)
		(end 91.164918 -31.526988)
		(width 0.1524)
		(layer "F.Cu")
		(net "TEMP_SENSOR_DXN_BJT")
	)
	(segment
		(start 104.79278 -32.1056)
		(end 91.74353 -32.1056)
		(width 0.1524)
		(layer "F.Cu")
		(net "TEMP_SENSOR_DXN_BJT")
	)
	(segment
		(start 121.059956 -41.273222)
		(end 120.802146 -41.531032)
		(width 0.1524)
		(layer "F.Cu")
		(net "TEMP_SENSOR_DXN_BJT")
	)
	(segment
		(start 114.218212 -41.531032)
		(end 104.79278 -32.1056)
		(width 0.1524)
		(layer "F.Cu")
		(net "TEMP_SENSOR_DXN_BJT")
	)
	(via
		(at 91.164918 -31.526988)
		(size 0.508)
		(drill 0.254)
		(layers "F.Cu" "B.Cu")
		(net "TEMP_SENSOR_DXN_BJT")
	)
	(via
		(at 265.275314 0.307086)
		(size 0.7112)
		(drill 0.3556)
		(layers "F.Cu" "B.Cu")
		(net "TEMP_SENSOR_DXN_BJT")
	)
	(via
		(at 259.044186 1.941068)
		(size 0.508)
		(drill 0.254)
		(layers "F.Cu" "B.Cu")
		(net "TEMP_SENSOR_DXN_BJT")
	)
	(segment
		(start 265.6078 -0.650494)
		(end 265.6078 -0.0254)
		(width 0.1524)
		(layer "B.Cu")
		(net "TEMP_SENSOR_DXN_BJT")
	)
	(segment
		(start 259.011674 0.82423)
		(end 259.497576 0.338328)
		(width 0.1524)
		(layer "B.Cu")
		(net "TEMP_SENSOR_DXN_BJT")
	)
	(segment
		(start 265.509502 -0.748792)
		(end 265.6078 -0.650494)
		(width 0.1524)
		(layer "B.Cu")
		(net "TEMP_SENSOR_DXN_BJT")
	)
	(segment
		(start 264.349992 -1.908302)
		(end 265.509502 -0.748792)
		(width 0.1524)
		(layer "B.Cu")
		(net "TEMP_SENSOR_DXN_BJT")
	)
	(segment
		(start 261.001002 0.776732)
		(end 264.805668 0.776732)
		(width 0.1524)
		(layer "B.Cu")
		(net "TEMP_SENSOR_DXN_BJT")
	)
	(segment
		(start 260.562598 0.338328)
		(end 261.001002 0.776732)
		(width 0.1524)
		(layer "B.Cu")
		(net "TEMP_SENSOR_DXN_BJT")
	)
	(segment
		(start 264.805668 0.776732)
		(end 265.275314 0.307086)
		(width 0.1524)
		(layer "B.Cu")
		(net "TEMP_SENSOR_DXN_BJT")
	)
	(segment
		(start 259.044186 1.941068)
		(end 259.011674 1.908556)
		(width 0.1524)
		(layer "B.Cu")
		(net "TEMP_SENSOR_DXN_BJT")
	)
	(segment
		(start 259.011674 1.908556)
		(end 259.011674 0.82423)
		(width 0.1524)
		(layer "B.Cu")
		(net "TEMP_SENSOR_DXN_BJT")
	)
	(segment
		(start 265.6078 -0.0254)
		(end 265.275314 0.307086)
		(width 0.1524)
		(layer "B.Cu")
		(net "TEMP_SENSOR_DXN_BJT")
	)
	(segment
		(start 264.19556 -1.908302)
		(end 264.349992 -1.908302)
		(width 0.1524)
		(layer "B.Cu")
		(net "TEMP_SENSOR_DXN_BJT")
	)
	(segment
		(start 259.497576 0.338328)
		(end 260.562598 0.338328)
		(width 0.1524)
		(layer "B.Cu")
		(net "TEMP_SENSOR_DXN_BJT")
	)
	(segment
		(start 91.599004 -31.961074)
		(end 91.164918 -31.526988)
		(width 0.1524)
		(layer "In2.Cu")
		(net "TEMP_SENSOR_DXN_BJT")
	)
	(segment
		(start 259.091176 1.894078)
		(end 259.091176 -1.065784)
		(width 0.1524)
		(layer "In2.Cu")
		(net "TEMP_SENSOR_DXN_BJT")
	)
	(segment
		(start 92.31376 -31.961074)
		(end 91.599004 -31.961074)
		(width 0.1524)
		(layer "In2.Cu")
		(net "TEMP_SENSOR_DXN_BJT")
	)
	(segment
		(start 241.53495 3.55219)
		(end 128.881632 3.55219)
		(width 0.1524)
		(layer "In2.Cu")
		(net "TEMP_SENSOR_DXN_BJT")
	)
	(segment
		(start 247.712992 -2.625852)
		(end 241.53495 3.55219)
		(width 0.1524)
		(layer "In2.Cu")
		(net "TEMP_SENSOR_DXN_BJT")
	)
	(segment
		(start 119.548402 -4.726432)
		(end 92.31376 -31.961074)
		(width 0.1524)
		(layer "In2.Cu")
		(net "TEMP_SENSOR_DXN_BJT")
	)
	(segment
		(start 128.881632 3.55219)
		(end 120.60301 -4.726432)
		(width 0.1524)
		(layer "In2.Cu")
		(net "TEMP_SENSOR_DXN_BJT")
	)
	(segment
		(start 257.531108 -2.625852)
		(end 247.712992 -2.625852)
		(width 0.1524)
		(layer "In2.Cu")
		(net "TEMP_SENSOR_DXN_BJT")
	)
	(segment
		(start 259.091176 -1.065784)
		(end 257.531108 -2.625852)
		(width 0.1524)
		(layer "In2.Cu")
		(net "TEMP_SENSOR_DXN_BJT")
	)
	(segment
		(start 259.044186 1.941068)
		(end 259.091176 1.894078)
		(width 0.1524)
		(layer "In2.Cu")
		(net "TEMP_SENSOR_DXN_BJT")
	)
	(segment
		(start 120.60301 -4.726432)
		(end 119.548402 -4.726432)
		(width 0.1524)
		(layer "In2.Cu")
		(net "TEMP_SENSOR_DXN_BJT")
	)
	(via
		(at 263.147302 -6.938772)
		(size 0.7112)
		(drill 0.3556)
		(layers "F.Cu" "B.Cu")
		(net "TEMP_SENSOR_DXN")
	)
	(segment
		(start 263.592818 -4.24434)
		(end 263.478264 -4.24434)
		(width 0.1524)
		(layer "B.Cu")
		(net "TEMP_SENSOR_DXN")
	)
	(segment
		(start 262.935974 -7.1501)
		(end 263.147302 -6.938772)
		(width 0.1524)
		(layer "B.Cu")
		(net "TEMP_SENSOR_DXN")
	)
	(segment
		(start 262.845804 -4.8768)
		(end 260.0452 -4.8768)
		(width 0.1524)
		(layer "B.Cu")
		(net "TEMP_SENSOR_DXN")
	)
	(segment
		(start 261.343648 -7.1501)
		(end 262.935974 -7.1501)
		(width 0.1524)
		(layer "B.Cu")
		(net "TEMP_SENSOR_DXN")
	)
	(segment
		(start 259.6134 -5.3086)
		(end 259.6134 -6.8326)
		(width 0.1524)
		(layer "B.Cu")
		(net "TEMP_SENSOR_DXN")
	)
	(segment
		(start 259.6134 -6.8326)
		(end 260.0325 -7.2517)
		(width 0.1524)
		(layer "B.Cu")
		(net "TEMP_SENSOR_DXN")
	)
	(segment
		(start 264.100818 -3.73634)
		(end 264.100818 -2.892044)
		(width 0.1524)
		(layer "B.Cu")
		(net "TEMP_SENSOR_DXN")
	)
	(segment
		(start 260.522466 -7.2517)
		(end 261.242048 -7.2517)
		(width 0.1524)
		(layer "B.Cu")
		(net "TEMP_SENSOR_DXN")
	)
	(segment
		(start 264.100818 -3.73634)
		(end 263.592818 -4.24434)
		(width 0.1524)
		(layer "B.Cu")
		(net "TEMP_SENSOR_DXN")
	)
	(segment
		(start 263.478264 -4.24434)
		(end 262.845804 -4.8768)
		(width 0.1524)
		(layer "B.Cu")
		(net "TEMP_SENSOR_DXN")
	)
	(segment
		(start 264.100818 -2.892044)
		(end 264.19556 -2.797302)
		(width 0.1524)
		(layer "B.Cu")
		(net "TEMP_SENSOR_DXN")
	)
	(segment
		(start 261.242048 -7.2517)
		(end 261.343648 -7.1501)
		(width 0.1524)
		(layer "B.Cu")
		(net "TEMP_SENSOR_DXN")
	)
	(segment
		(start 260.0325 -7.2517)
		(end 260.522466 -7.2517)
		(width 0.1524)
		(layer "B.Cu")
		(net "TEMP_SENSOR_DXN")
	)
	(segment
		(start 260.0452 -4.8768)
		(end 259.6134 -5.3086)
		(width 0.1524)
		(layer "B.Cu")
		(net "TEMP_SENSOR_DXN")
	)
	(segment
		(start 104.973374 -31.478474)
		(end 92.082112 -31.478474)
		(width 0.1524)
		(layer "F.Cu")
		(net "TEMP_SENSOR_C")
	)
	(segment
		(start 119.835168 -40.003222)
		(end 118.660926 -41.177464)
		(width 0.1524)
		(layer "F.Cu")
		(net "TEMP_SENSOR_C")
	)
	(segment
		(start 113.197386 -39.702486)
		(end 104.973374 -31.478474)
		(width 0.1524)
		(layer "F.Cu")
		(net "TEMP_SENSOR_C")
	)
	(segment
		(start 114.687096 -41.177464)
		(end 113.212118 -39.702486)
		(width 0.1524)
		(layer "F.Cu")
		(net "TEMP_SENSOR_C")
	)
	(segment
		(start 121.059956 -40.003222)
		(end 119.835168 -40.003222)
		(width 0.1524)
		(layer "F.Cu")
		(net "TEMP_SENSOR_C")
	)
	(segment
		(start 113.212118 -39.702486)
		(end 113.197386 -39.702486)
		(width 0.1524)
		(layer "F.Cu")
		(net "TEMP_SENSOR_C")
	)
	(segment
		(start 118.660926 -41.177464)
		(end 114.687096 -41.177464)
		(width 0.1524)
		(layer "F.Cu")
		(net "TEMP_SENSOR_C")
	)
	(via
		(at 92.082112 -31.478474)
		(size 0.508)
		(drill 0.254)
		(layers "F.Cu" "B.Cu")
		(net "TEMP_SENSOR_C")
	)
	(via
		(at 262.972042 0.192532)
		(size 0.7112)
		(drill 0.3556)
		(layers "F.Cu" "B.Cu")
		(net "TEMP_SENSOR_C")
	)
	(via
		(at 257.092958 0.74676)
		(size 0.508)
		(drill 0.254)
		(layers "F.Cu" "B.Cu")
		(net "TEMP_SENSOR_C")
	)
	(segment
		(start 263.583674 -0.4191)
		(end 262.972042 0.192532)
		(width 0.1524)
		(layer "B.Cu")
		(net "TEMP_SENSOR_C")
	)
	(segment
		(start 260.848094 0.192532)
		(end 260.688836 0.033274)
		(width 0.1524)
		(layer "B.Cu")
		(net "TEMP_SENSOR_C")
	)
	(segment
		(start 262.972042 0.192532)
		(end 260.848094 0.192532)
		(width 0.1524)
		(layer "B.Cu")
		(net "TEMP_SENSOR_C")
	)
	(segment
		(start 259.050536 0.033274)
		(end 258.52501 0.5588)
		(width 0.1524)
		(layer "B.Cu")
		(net "TEMP_SENSOR_C")
	)
	(segment
		(start 263.610598 -0.748792)
		(end 263.583674 -0.721868)
		(width 0.1524)
		(layer "B.Cu")
		(net "TEMP_SENSOR_C")
	)
	(segment
		(start 260.688836 0.033274)
		(end 259.050536 0.033274)
		(width 0.1524)
		(layer "B.Cu")
		(net "TEMP_SENSOR_C")
	)
	(segment
		(start 263.583674 -0.721868)
		(end 263.583674 -0.4191)
		(width 0.1524)
		(layer "B.Cu")
		(net "TEMP_SENSOR_C")
	)
	(segment
		(start 258.52501 0.5588)
		(end 257.280918 0.5588)
		(width 0.1524)
		(layer "B.Cu")
		(net "TEMP_SENSOR_C")
	)
	(segment
		(start 264.620502 -0.748792)
		(end 263.610598 -0.748792)
		(width 0.1524)
		(layer "B.Cu")
		(net "TEMP_SENSOR_C")
	)
	(segment
		(start 257.280918 0.5588)
		(end 257.092958 0.74676)
		(width 0.1524)
		(layer "B.Cu")
		(net "TEMP_SENSOR_C")
	)
	(segment
		(start 120.620536 -4.277614)
		(end 120.566434 -4.277614)
		(width 0.1524)
		(layer "In2.Cu")
		(net "TEMP_SENSOR_C")
	)
	(segment
		(start 128.75514 3.85699)
		(end 120.620536 -4.277614)
		(width 0.1524)
		(layer "In2.Cu")
		(net "TEMP_SENSOR_C")
	)
	(segment
		(start 255.92151 0.01016)
		(end 254.52959 1.40208)
		(width 0.1524)
		(layer "In2.Cu")
		(net "TEMP_SENSOR_C")
	)
	(segment
		(start 247.352312 1.40208)
		(end 244.897402 3.85699)
		(width 0.1524)
		(layer "In2.Cu")
		(net "TEMP_SENSOR_C")
	)
	(segment
		(start 257.092958 0.74676)
		(end 256.356358 0.01016)
		(width 0.1524)
		(layer "In2.Cu")
		(net "TEMP_SENSOR_C")
	)
	(segment
		(start 92.082112 -31.47822)
		(end 92.082112 -31.478474)
		(width 0.1524)
		(layer "In2.Cu")
		(net "TEMP_SENSOR_C")
	)
	(segment
		(start 120.566434 -4.277614)
		(end 119.282464 -4.277868)
		(width 0.1524)
		(layer "In2.Cu")
		(net "TEMP_SENSOR_C")
	)
	(segment
		(start 119.282464 -4.277868)
		(end 92.082112 -31.47822)
		(width 0.1524)
		(layer "In2.Cu")
		(net "TEMP_SENSOR_C")
	)
	(segment
		(start 254.52959 1.40208)
		(end 247.352312 1.40208)
		(width 0.1524)
		(layer "In2.Cu")
		(net "TEMP_SENSOR_C")
	)
	(segment
		(start 244.897402 3.85699)
		(end 128.75514 3.85699)
		(width 0.1524)
		(layer "In2.Cu")
		(net "TEMP_SENSOR_C")
	)
	(segment
		(start 256.356358 0.01016)
		(end 255.92151 0.01016)
		(width 0.1524)
		(layer "In2.Cu")
		(net "TEMP_SENSOR_C")
	)
	(segment
		(start 226.48164 -78.74254)
		(end 226.48164 -80.90154)
		(width 0.12065)
		(layer "F.Cu")
		(net "TEMP_3_SDA")
	)
	(segment
		(start 226.0981 -78.5749)
		(end 226.314 -78.5749)
		(width 0.12065)
		(layer "F.Cu")
		(net "TEMP_3_SDA")
	)
	(segment
		(start 225.425 -79.248)
		(end 226.0981 -78.5749)
		(width 0.12065)
		(layer "F.Cu")
		(net "TEMP_3_SDA")
	)
	(segment
		(start 226.314 -78.5749)
		(end 226.48164 -78.74254)
		(width 0.12065)
		(layer "F.Cu")
		(net "TEMP_3_SDA")
	)
	(via
		(at 225.425 -79.248)
		(size 0.7112)
		(drill 0.3556)
		(layers "F.Cu" "B.Cu")
		(net "TEMP_3_SDA")
	)
	(segment
		(start 227.687124 -78.5749)
		(end 228.299518 -79.187294)
		(width 0.12065)
		(layer "F.Cu")
		(net "TEMP_3_SCL")
	)
	(segment
		(start 227.33 -78.5749)
		(end 227.687124 -78.5749)
		(width 0.12065)
		(layer "F.Cu")
		(net "TEMP_3_SCL")
	)
	(segment
		(start 227.13188 -80.90154)
		(end 227.13188 -78.77302)
		(width 0.12065)
		(layer "F.Cu")
		(net "TEMP_3_SCL")
	)
	(segment
		(start 227.13188 -78.77302)
		(end 227.33 -78.5749)
		(width 0.12065)
		(layer "F.Cu")
		(net "TEMP_3_SCL")
	)
	(via
		(at 228.299518 -79.187294)
		(size 0.7112)
		(drill 0.3556)
		(layers "F.Cu" "B.Cu")
		(net "TEMP_3_SCL")
	)
	(segment
		(start 227.78212 -80.19288)
		(end 227.78212 -80.90154)
		(width 0.12065)
		(layer "F.Cu")
		(net "TEMP_3_ALERT")
	)
	(segment
		(start 230.251 -80.391)
		(end 229.812088 -79.952088)
		(width 0.12065)
		(layer "F.Cu")
		(net "TEMP_3_ALERT")
	)
	(segment
		(start 229.812088 -79.952088)
		(end 228.022912 -79.952088)
		(width 0.12065)
		(layer "F.Cu")
		(net "TEMP_3_ALERT")
	)
	(segment
		(start 228.022912 -79.952088)
		(end 227.78212 -80.19288)
		(width 0.12065)
		(layer "F.Cu")
		(net "TEMP_3_ALERT")
	)
	(segment
		(start 228.43236 -85.852)
		(end 227.711 -86.57336)
		(width 0.12065)
		(layer "F.Cu")
		(net "TEMP_3_A2")
	)
	(segment
		(start 228.346 -86.7664)
		(end 228.6635 -86.7664)
		(width 0.12065)
		(layer "F.Cu")
		(net "TEMP_3_A2")
	)
	(segment
		(start 227.711 -86.57336)
		(end 227.711 -86.995)
		(width 0.12065)
		(layer "F.Cu")
		(net "TEMP_3_A2")
	)
	(segment
		(start 228.43236 -85.01126)
		(end 228.43236 -85.852)
		(width 0.12065)
		(layer "F.Cu")
		(net "TEMP_3_A2")
	)
	(segment
		(start 227.711 -86.995)
		(end 228.1174 -86.995)
		(width 0.12065)
		(layer "F.Cu")
		(net "TEMP_3_A2")
	)
	(segment
		(start 228.6635 -86.7664)
		(end 228.6635 -87.7824)
		(width 0.12065)
		(layer "F.Cu")
		(net "TEMP_3_A2")
	)
	(segment
		(start 228.1174 -86.995)
		(end 228.346 -86.7664)
		(width 0.12065)
		(layer "F.Cu")
		(net "TEMP_3_A2")
	)
	(via
		(at 227.711 -86.995)
		(size 0.7112)
		(drill 0.3556)
		(layers "F.Cu" "B.Cu")
		(net "TEMP_3_A2")
	)
	(segment
		(start 227.142548 -86.629748)
		(end 227.142548 -88.382348)
		(width 0.12065)
		(layer "F.Cu")
		(net "TEMP_3_A1")
	)
	(segment
		(start 227.78212 -85.01126)
		(end 227.78212 -85.990176)
		(width 0.12065)
		(layer "F.Cu")
		(net "TEMP_3_A1")
	)
	(segment
		(start 227.7618 -88.9)
		(end 228.6635 -88.9)
		(width 0.12065)
		(layer "F.Cu")
		(net "TEMP_3_A1")
	)
	(segment
		(start 228.6635 -88.9)
		(end 228.6635 -89.916)
		(width 0.12065)
		(layer "F.Cu")
		(net "TEMP_3_A1")
	)
	(segment
		(start 227.142548 -88.382348)
		(end 227.711 -88.9508)
		(width 0.12065)
		(layer "F.Cu")
		(net "TEMP_3_A1")
	)
	(segment
		(start 227.78212 -85.990176)
		(end 227.142548 -86.629748)
		(width 0.12065)
		(layer "F.Cu")
		(net "TEMP_3_A1")
	)
	(segment
		(start 227.711 -88.9508)
		(end 227.7618 -88.9)
		(width 0.12065)
		(layer "F.Cu")
		(net "TEMP_3_A1")
	)
	(via
		(at 227.711 -88.9508)
		(size 0.7112)
		(drill 0.3556)
		(layers "F.Cu" "B.Cu")
		(net "TEMP_3_A1")
	)
	(segment
		(start 227.6856 -91.059)
		(end 228.6635 -91.059)
		(width 0.12065)
		(layer "F.Cu")
		(net "TEMP_3_A0")
	)
	(segment
		(start 226.780598 -86.479634)
		(end 226.780598 -90.153998)
		(width 0.12065)
		(layer "F.Cu")
		(net "TEMP_3_A0")
	)
	(segment
		(start 228.6635 -91.059)
		(end 228.6635 -92.202)
		(width 0.12065)
		(layer "F.Cu")
		(net "TEMP_3_A0")
	)
	(segment
		(start 227.13188 -85.01126)
		(end 227.13188 -86.128352)
		(width 0.12065)
		(layer "F.Cu")
		(net "TEMP_3_A0")
	)
	(segment
		(start 227.13188 -86.128352)
		(end 226.780598 -86.479634)
		(width 0.12065)
		(layer "F.Cu")
		(net "TEMP_3_A0")
	)
	(segment
		(start 227.6348 -91.0082)
		(end 227.6856 -91.059)
		(width 0.12065)
		(layer "F.Cu")
		(net "TEMP_3_A0")
	)
	(segment
		(start 226.780598 -90.153998)
		(end 227.6348 -91.0082)
		(width 0.12065)
		(layer "F.Cu")
		(net "TEMP_3_A0")
	)
	(via
		(at 227.6348 -91.0082)
		(size 0.7112)
		(drill 0.3556)
		(layers "F.Cu" "B.Cu")
		(net "TEMP_3_A0")
	)
	(segment
		(start 58.258456 -149.069044)
		(end 57.121044 -149.069044)
		(width 0.12065)
		(layer "F.Cu")
		(net "TEMP_2_SDA")
	)
	(segment
		(start 58.4835 -148.844)
		(end 58.258456 -149.069044)
		(width 0.12065)
		(layer "F.Cu")
		(net "TEMP_2_SDA")
	)
	(segment
		(start 58.4835 -147.9296)
		(end 58.4835 -148.844)
		(width 0.12065)
		(layer "F.Cu")
		(net "TEMP_2_SDA")
	)
	(segment
		(start 57.121044 -149.069044)
		(end 57.06364 -149.01164)
		(width 0.12065)
		(layer "F.Cu")
		(net "TEMP_2_SDA")
	)
	(segment
		(start 57.06364 -149.01164)
		(end 56.15686 -149.01164)
		(width 0.12065)
		(layer "F.Cu")
		(net "TEMP_2_SDA")
	)
	(via
		(at 58.4835 -147.9296)
		(size 0.7112)
		(drill 0.3556)
		(layers "F.Cu" "B.Cu")
		(net "TEMP_2_SDA")
	)
	(segment
		(start 58.4835 -150.8125)
		(end 58.4835 -149.86)
		(width 0.12065)
		(layer "F.Cu")
		(net "TEMP_2_SCL")
	)
	(segment
		(start 58.194194 -149.570694)
		(end 57.109106 -149.570694)
		(width 0.12065)
		(layer "F.Cu")
		(net "TEMP_2_SCL")
	)
	(segment
		(start 57.109106 -149.570694)
		(end 57.01792 -149.66188)
		(width 0.12065)
		(layer "F.Cu")
		(net "TEMP_2_SCL")
	)
	(segment
		(start 57.01792 -149.66188)
		(end 56.15686 -149.66188)
		(width 0.12065)
		(layer "F.Cu")
		(net "TEMP_2_SCL")
	)
	(segment
		(start 58.4835 -149.86)
		(end 58.194194 -149.570694)
		(width 0.12065)
		(layer "F.Cu")
		(net "TEMP_2_SCL")
	)
	(via
		(at 58.4835 -150.8125)
		(size 0.7112)
		(drill 0.3556)
		(layers "F.Cu" "B.Cu")
		(net "TEMP_2_SCL")
	)
	(segment
		(start 57.106312 -151.21763)
		(end 57.106312 -150.395432)
		(width 0.12065)
		(layer "F.Cu")
		(net "TEMP_2_ALERT")
	)
	(segment
		(start 56.769 -151.554942)
		(end 57.106312 -151.21763)
		(width 0.12065)
		(layer "F.Cu")
		(net "TEMP_2_ALERT")
	)
	(segment
		(start 57.023 -150.31212)
		(end 56.15686 -150.31212)
		(width 0.12065)
		(layer "F.Cu")
		(net "TEMP_2_ALERT")
	)
	(segment
		(start 56.769 -152.781)
		(end 56.769 -151.554942)
		(width 0.12065)
		(layer "F.Cu")
		(net "TEMP_2_ALERT")
	)
	(segment
		(start 57.106312 -150.395432)
		(end 57.023 -150.31212)
		(width 0.12065)
		(layer "F.Cu")
		(net "TEMP_2_ALERT")
	)
	(segment
		(start 49.784 -151.8285)
		(end 50.7365 -151.8285)
		(width 0.12065)
		(layer "F.Cu")
		(net "TEMP_2_A2")
	)
	(segment
		(start 51.8414 -152.4254)
		(end 52.04714 -152.21966)
		(width 0.12065)
		(layer "F.Cu")
		(net "TEMP_2_A2")
	)
	(segment
		(start 52.04714 -152.21966)
		(end 52.04714 -150.96236)
		(width 0.12065)
		(layer "F.Cu")
		(net "TEMP_2_A2")
	)
	(segment
		(start 50.7365 -151.8285)
		(end 51.3334 -152.4254)
		(width 0.12065)
		(layer "F.Cu")
		(net "TEMP_2_A2")
	)
	(segment
		(start 49.657 -151.9555)
		(end 49.784 -151.8285)
		(width 0.12065)
		(layer "F.Cu")
		(net "TEMP_2_A2")
	)
	(segment
		(start 51.3334 -152.4254)
		(end 51.8414 -152.4254)
		(width 0.12065)
		(layer "F.Cu")
		(net "TEMP_2_A2")
	)
	(segment
		(start 49.657 -151.9555)
		(end 48.641 -151.9555)
		(width 0.12065)
		(layer "F.Cu")
		(net "TEMP_2_A2")
	)
	(via
		(at 51.8414 -152.4254)
		(size 0.7112)
		(drill 0.3556)
		(layers "F.Cu" "B.Cu")
		(net "TEMP_2_A2")
	)
	(segment
		(start 48.641 -150.9395)
		(end 48.0695 -150.9395)
		(width 0.12065)
		(layer "F.Cu")
		(net "TEMP_2_A1")
	)
	(segment
		(start 48.0695 -150.9395)
		(end 47.625 -151.384)
		(width 0.12065)
		(layer "F.Cu")
		(net "TEMP_2_A1")
	)
	(segment
		(start 50.3555 -150.9395)
		(end 50.98288 -150.31212)
		(width 0.12065)
		(layer "F.Cu")
		(net "TEMP_2_A1")
	)
	(segment
		(start 48.641 -150.9395)
		(end 49.657 -150.9395)
		(width 0.12065)
		(layer "F.Cu")
		(net "TEMP_2_A1")
	)
	(segment
		(start 50.98288 -150.31212)
		(end 52.04714 -150.31212)
		(width 0.12065)
		(layer "F.Cu")
		(net "TEMP_2_A1")
	)
	(segment
		(start 49.657 -150.9395)
		(end 50.3555 -150.9395)
		(width 0.12065)
		(layer "F.Cu")
		(net "TEMP_2_A1")
	)
	(via
		(at 47.625 -151.384)
		(size 0.7112)
		(drill 0.3556)
		(layers "F.Cu" "B.Cu")
		(net "TEMP_2_A1")
	)
	(segment
		(start 50.8635 -149.0345)
		(end 51.49088 -149.66188)
		(width 0.12065)
		(layer "F.Cu")
		(net "TEMP_2_A0")
	)
	(segment
		(start 49.657 -149.0345)
		(end 50.8635 -149.0345)
		(width 0.12065)
		(layer "F.Cu")
		(net "TEMP_2_A0")
	)
	(segment
		(start 48.641 -149.0345)
		(end 48.1965 -149.0345)
		(width 0.12065)
		(layer "F.Cu")
		(net "TEMP_2_A0")
	)
	(segment
		(start 48.1965 -149.0345)
		(end 47.6885 -148.5265)
		(width 0.12065)
		(layer "F.Cu")
		(net "TEMP_2_A0")
	)
	(segment
		(start 51.49088 -149.66188)
		(end 52.04714 -149.66188)
		(width 0.12065)
		(layer "F.Cu")
		(net "TEMP_2_A0")
	)
	(segment
		(start 48.641 -149.0345)
		(end 49.657 -149.0345)
		(width 0.12065)
		(layer "F.Cu")
		(net "TEMP_2_A0")
	)
	(via
		(at 47.6885 -148.5265)
		(size 0.7112)
		(drill 0.3556)
		(layers "F.Cu" "B.Cu")
		(net "TEMP_2_A0")
	)
	(via
		(at 255.4605 -5.026152)
		(size 0.7112)
		(drill 0.3556)
		(layers "F.Cu" "B.Cu")
		(net "TEMP_1_SDA")
	)
	(segment
		(start 255.950212 -5.99567)
		(end 255.950212 -5.515864)
		(width 0.12065)
		(layer "B.Cu")
		(net "TEMP_1_SDA")
	)
	(segment
		(start 256.210054 -6.255512)
		(end 255.950212 -5.99567)
		(width 0.12065)
		(layer "B.Cu")
		(net "TEMP_1_SDA")
	)
	(segment
		(start 257.514598 -6.60146)
		(end 257.16865 -6.255512)
		(width 0.12065)
		(layer "B.Cu")
		(net "TEMP_1_SDA")
	)
	(segment
		(start 255.950212 -5.515864)
		(end 255.4605 -5.026152)
		(width 0.12065)
		(layer "B.Cu")
		(net "TEMP_1_SDA")
	)
	(segment
		(start 257.16865 -6.255512)
		(end 256.210054 -6.255512)
		(width 0.12065)
		(layer "B.Cu")
		(net "TEMP_1_SDA")
	)
	(segment
		(start 257.830066 -6.60146)
		(end 257.514598 -6.60146)
		(width 0.12065)
		(layer "B.Cu")
		(net "TEMP_1_SDA")
	)
	(via
		(at 255.466596 -8.090916)
		(size 0.7112)
		(drill 0.3556)
		(layers "F.Cu" "B.Cu")
		(net "TEMP_1_SCL")
	)
	(segment
		(start 257.830066 -7.2517)
		(end 257.455162 -7.2517)
		(width 0.12065)
		(layer "B.Cu")
		(net "TEMP_1_SCL")
	)
	(segment
		(start 257.455162 -7.2517)
		(end 256.960624 -6.757162)
		(width 0.12065)
		(layer "B.Cu")
		(net "TEMP_1_SCL")
	)
	(segment
		(start 256.960624 -6.757162)
		(end 256.20472 -6.757162)
		(width 0.12065)
		(layer "B.Cu")
		(net "TEMP_1_SCL")
	)
	(segment
		(start 256.20472 -6.757162)
		(end 255.950212 -7.01167)
		(width 0.12065)
		(layer "B.Cu")
		(net "TEMP_1_SCL")
	)
	(segment
		(start 255.466596 -7.905242)
		(end 255.950212 -7.421626)
		(width 0.12065)
		(layer "B.Cu")
		(net "TEMP_1_SCL")
	)
	(segment
		(start 255.466596 -8.090916)
		(end 255.466596 -7.905242)
		(width 0.12065)
		(layer "B.Cu")
		(net "TEMP_1_SCL")
	)
	(segment
		(start 255.950212 -7.421626)
		(end 255.950212 -7.01167)
		(width 0.12065)
		(layer "B.Cu")
		(net "TEMP_1_SCL")
	)
	(via
		(at 263.395206 -5.665978)
		(size 0.7112)
		(drill 0.3556)
		(layers "F.Cu" "B.Cu")
		(net "TEMP_1_A1")
	)
	(segment
		(start 265.216894 -4.525772)
		(end 265.229594 -4.538472)
		(width 0.12065)
		(layer "B.Cu")
		(net "TEMP_1_A1")
	)
	(segment
		(start 260.522466 -6.60146)
		(end 262.459724 -6.60146)
		(width 0.12065)
		(layer "B.Cu")
		(net "TEMP_1_A1")
	)
	(segment
		(start 265.807952 -4.662678)
		(end 266.360148 -4.662678)
		(width 0.12065)
		(layer "B.Cu")
		(net "TEMP_1_A1")
	)
	(segment
		(start 265.216894 -4.525772)
		(end 265.204194 -4.538472)
		(width 0.12065)
		(layer "B.Cu")
		(net "TEMP_1_A1")
	)
	(segment
		(start 264.349992 -4.711192)
		(end 263.395206 -5.665978)
		(width 0.12065)
		(layer "B.Cu")
		(net "TEMP_1_A1")
	)
	(segment
		(start 265.204194 -4.538472)
		(end 264.922 -4.538472)
		(width 0.12065)
		(layer "B.Cu")
		(net "TEMP_1_A1")
	)
	(segment
		(start 265.229594 -4.538472)
		(end 265.683746 -4.538472)
		(width 0.12065)
		(layer "B.Cu")
		(net "TEMP_1_A1")
	)
	(segment
		(start 264.74928 -4.711192)
		(end 264.349992 -4.711192)
		(width 0.12065)
		(layer "B.Cu")
		(net "TEMP_1_A1")
	)
	(segment
		(start 264.922 -4.538472)
		(end 264.74928 -4.711192)
		(width 0.12065)
		(layer "B.Cu")
		(net "TEMP_1_A1")
	)
	(segment
		(start 262.459724 -6.60146)
		(end 263.395206 -5.665978)
		(width 0.12065)
		(layer "B.Cu")
		(net "TEMP_1_A1")
	)
	(segment
		(start 265.683746 -4.538472)
		(end 265.807952 -4.662678)
		(width 0.12065)
		(layer "B.Cu")
		(net "TEMP_1_A1")
	)
	(via
		(at 262.125714 -5.708142)
		(size 0.7112)
		(drill 0.3556)
		(layers "F.Cu" "B.Cu")
		(net "TEMP_1_A0")
	)
	(segment
		(start 265.904218 -2.62636)
		(end 265.956288 -2.67843)
		(width 0.12065)
		(layer "B.Cu")
		(net "TEMP_1_A0")
	)
	(segment
		(start 264.320528 -4.228592)
		(end 263.592056 -4.957064)
		(width 0.12065)
		(layer "B.Cu")
		(net "TEMP_1_A0")
	)
	(segment
		(start 260.522466 -5.95249)
		(end 261.881366 -5.95249)
		(width 0.12065)
		(layer "B.Cu")
		(net "TEMP_1_A0")
	)
	(segment
		(start 264.634472 -3.205226)
		(end 264.634472 -4.089908)
		(width 0.12065)
		(layer "B.Cu")
		(net "TEMP_1_A0")
	)
	(segment
		(start 264.495788 -4.228592)
		(end 264.320528 -4.228592)
		(width 0.12065)
		(layer "B.Cu")
		(net "TEMP_1_A0")
	)
	(segment
		(start 263.592056 -4.957064)
		(end 263.30021 -4.957064)
		(width 0.12065)
		(layer "B.Cu")
		(net "TEMP_1_A0")
	)
	(segment
		(start 265.213338 -2.62636)
		(end 264.634472 -3.205226)
		(width 0.12065)
		(layer "B.Cu")
		(net "TEMP_1_A0")
	)
	(segment
		(start 266.153646 -2.67843)
		(end 266.486894 -3.011678)
		(width 0.12065)
		(layer "B.Cu")
		(net "TEMP_1_A0")
	)
	(segment
		(start 261.881366 -5.95249)
		(end 262.125714 -5.708142)
		(width 0.12065)
		(layer "B.Cu")
		(net "TEMP_1_A0")
	)
	(segment
		(start 262.549132 -5.708142)
		(end 262.125714 -5.708142)
		(width 0.12065)
		(layer "B.Cu")
		(net "TEMP_1_A0")
	)
	(segment
		(start 264.634472 -4.089908)
		(end 264.495788 -4.228592)
		(width 0.12065)
		(layer "B.Cu")
		(net "TEMP_1_A0")
	)
	(segment
		(start 263.30021 -4.957064)
		(end 262.549132 -5.708142)
		(width 0.12065)
		(layer "B.Cu")
		(net "TEMP_1_A0")
	)
	(segment
		(start 265.213338 -2.62636)
		(end 265.904218 -2.62636)
		(width 0.12065)
		(layer "B.Cu")
		(net "TEMP_1_A0")
	)
	(segment
		(start 265.956288 -2.67843)
		(end 266.153646 -2.67843)
		(width 0.12065)
		(layer "B.Cu")
		(net "TEMP_1_A0")
	)
	(segment
		(start 330.100178 -223.804988)
		(end 330.100178 -225.54438)
		(width 0.12065)
		(layer "F.Cu")
		(net "SSD_PWREN9_R")
	)
	(segment
		(start 329.934824 -221.037404)
		(end 329.934824 -222.024448)
		(width 0.12065)
		(layer "F.Cu")
		(net "SSD_PWREN9_R")
	)
	(segment
		(start 329.9333 -207.9117)
		(end 329.9333 -221.03588)
		(width 0.12065)
		(layer "F.Cu")
		(net "SSD_PWREN9_R")
	)
	(segment
		(start 329.8952 -207.8736)
		(end 329.9333 -207.9117)
		(width 0.12065)
		(layer "F.Cu")
		(net "SSD_PWREN9_R")
	)
	(segment
		(start 329.9333 -222.025972)
		(end 329.9333 -222.53829)
		(width 0.12065)
		(layer "F.Cu")
		(net "SSD_PWREN9_R")
	)
	(segment
		(start 329.9333 -221.03588)
		(end 329.934824 -221.037404)
		(width 0.12065)
		(layer "F.Cu")
		(net "SSD_PWREN9_R")
	)
	(segment
		(start 343.281 -173.092872)
		(end 344.1319 -173.943772)
		(width 0.12065)
		(layer "F.Cu")
		(net "SSD_PWREN9_R")
	)
	(segment
		(start 338.868512 -171.987718)
		(end 338.868512 -171.196)
		(width 0.12065)
		(layer "F.Cu")
		(net "SSD_PWREN9_R")
	)
	(segment
		(start 344.1319 -173.943772)
		(end 344.1319 -184.475374)
		(width 0.12065)
		(layer "F.Cu")
		(net "SSD_PWREN9_R")
	)
	(segment
		(start 344.1319 -184.475374)
		(end 340.520274 -188.087)
		(width 0.12065)
		(layer "F.Cu")
		(net "SSD_PWREN9_R")
	)
	(segment
		(start 340.520274 -188.087)
		(end 340.334854 -188.087)
		(width 0.12065)
		(layer "F.Cu")
		(net "SSD_PWREN9_R")
	)
	(segment
		(start 329.9333 -222.53829)
		(end 329.819 -222.65259)
		(width 0.12065)
		(layer "F.Cu")
		(net "SSD_PWREN9_R")
	)
	(segment
		(start 329.819 -222.65259)
		(end 329.819 -223.52381)
		(width 0.12065)
		(layer "F.Cu")
		(net "SSD_PWREN9_R")
	)
	(segment
		(start 329.934824 -222.024448)
		(end 329.9333 -222.025972)
		(width 0.12065)
		(layer "F.Cu")
		(net "SSD_PWREN9_R")
	)
	(segment
		(start 329.819 -223.52381)
		(end 330.100178 -223.804988)
		(width 0.12065)
		(layer "F.Cu")
		(net "SSD_PWREN9_R")
	)
	(segment
		(start 340.334854 -188.087)
		(end 329.8952 -198.526654)
		(width 0.12065)
		(layer "F.Cu")
		(net "SSD_PWREN9_R")
	)
	(segment
		(start 343.281 -171.45)
		(end 343.281 -173.092872)
		(width 0.12065)
		(layer "F.Cu")
		(net "SSD_PWREN9_R")
	)
	(segment
		(start 329.8952 -198.526654)
		(end 329.8952 -207.8736)
		(width 0.12065)
		(layer "F.Cu")
		(net "SSD_PWREN9_R")
	)
	(via
		(at 338.868512 -171.196)
		(size 0.508)
		(drill 0.254)
		(layers "F.Cu" "B.Cu")
		(net "SSD_PWREN9_R")
	)
	(via
		(at 343.281 -170.4848)
		(size 0.7112)
		(drill 0.3556)
		(layers "F.Cu" "B.Cu")
		(net "SSD_PWREN9_R")
	)
	(via
		(at 343.281 -171.45)
		(size 0.508)
		(drill 0.254)
		(layers "F.Cu" "B.Cu")
		(net "SSD_PWREN9_R")
	)
	(segment
		(start 343.281 -170.4848)
		(end 343.281 -171.45)
		(width 0.12065)
		(layer "B.Cu")
		(net "SSD_PWREN9_R")
	)
	(segment
		(start 339.344 -170.688)
		(end 338.868512 -171.163488)
		(width 0.127)
		(layer "In2.Cu")
		(net "SSD_PWREN9_R")
	)
	(segment
		(start 338.868512 -171.163488)
		(end 338.868512 -171.196)
		(width 0.127)
		(layer "In2.Cu")
		(net "SSD_PWREN9_R")
	)
	(segment
		(start 342.519 -170.688)
		(end 339.344 -170.688)
		(width 0.127)
		(layer "In2.Cu")
		(net "SSD_PWREN9_R")
	)
	(segment
		(start 343.281 -171.45)
		(end 342.519 -170.688)
		(width 0.127)
		(layer "In2.Cu")
		(net "SSD_PWREN9_R")
	)
	(segment
		(start 338.335874 -174.24908)
		(end 338.595208 -174.24908)
		(width 0.12065)
		(layer "F.Cu")
		(net "SSD_PWREN9")
	)
	(segment
		(start 337.461352 -175.962818)
		(end 337.461352 -175.123602)
		(width 0.12065)
		(layer "F.Cu")
		(net "SSD_PWREN9")
	)
	(segment
		(start 338.868512 -173.975776)
		(end 338.595208 -174.24908)
		(width 0.12065)
		(layer "F.Cu")
		(net "SSD_PWREN9")
	)
	(segment
		(start 338.868512 -172.876718)
		(end 338.868512 -173.975776)
		(width 0.12065)
		(layer "F.Cu")
		(net "SSD_PWREN9")
	)
	(segment
		(start 337.461352 -175.123602)
		(end 338.335874 -174.24908)
		(width 0.12065)
		(layer "F.Cu")
		(net "SSD_PWREN9")
	)
	(via
		(at 338.595208 -174.24908)
		(size 0.7112)
		(drill 0.3556)
		(layers "F.Cu" "B.Cu")
		(net "SSD_PWREN9")
	)
	(segment
		(start 225.9584 -183.5404)
		(end 225.9584 -187.9092)
		(width 0.12065)
		(layer "F.Cu")
		(net "SSD_PWREN8_R")
	)
	(segment
		(start 225.6536 -183.2356)
		(end 225.9584 -183.5404)
		(width 0.12065)
		(layer "F.Cu")
		(net "SSD_PWREN8_R")
	)
	(segment
		(start 225.9584 -187.9092)
		(end 225.909124 -187.958476)
		(width 0.12065)
		(layer "F.Cu")
		(net "SSD_PWREN8_R")
	)
	(segment
		(start 225.909124 -187.958476)
		(end 225.909124 -190.156592)
		(width 0.12065)
		(layer "F.Cu")
		(net "SSD_PWREN8_R")
	)
	(via
		(at 225.6536 -183.2356)
		(size 0.508)
		(drill 0.254)
		(layers "F.Cu" "B.Cu")
		(net "SSD_PWREN8_R")
	)
	(via
		(at 225.6917 -178.308)
		(size 0.7112)
		(drill 0.3556)
		(layers "F.Cu" "B.Cu")
		(net "SSD_PWREN8_R")
	)
	(segment
		(start 255.369314 -157.70225)
		(end 228.369622 -157.70225)
		(width 0.12065)
		(layer "B.Cu")
		(net "SSD_PWREN8_R")
	)
	(segment
		(start 260.3373 -172.564298)
		(end 260.337554 -172.564044)
		(width 0.12065)
		(layer "B.Cu")
		(net "SSD_PWREN8_R")
	)
	(segment
		(start 268.598142 -222.069914)
		(end 268.598142 -219.203778)
		(width 0.12065)
		(layer "B.Cu")
		(net "SSD_PWREN8_R")
	)
	(segment
		(start 260.3373 -162.670236)
		(end 255.369314 -157.70225)
		(width 0.12065)
		(layer "B.Cu")
		(net "SSD_PWREN8_R")
	)
	(segment
		(start 260.3373 -210.942936)
		(end 260.3373 -172.564298)
		(width 0.12065)
		(layer "B.Cu")
		(net "SSD_PWREN8_R")
	)
	(segment
		(start 268.458442 -222.209614)
		(end 268.598142 -222.069914)
		(width 0.12065)
		(layer "B.Cu")
		(net "SSD_PWREN8_R")
	)
	(segment
		(start 269.300198 -225.92538)
		(end 269.300198 -224.10674)
		(width 0.12065)
		(layer "B.Cu")
		(net "SSD_PWREN8_R")
	)
	(segment
		(start 225.6536 -183.2356)
		(end 225.6917 -183.1975)
		(width 0.12065)
		(layer "B.Cu")
		(net "SSD_PWREN8_R")
	)
	(segment
		(start 260.337554 -172.264324)
		(end 260.3373 -172.26407)
		(width 0.12065)
		(layer "B.Cu")
		(net "SSD_PWREN8_R")
	)
	(segment
		(start 225.6917 -183.1975)
		(end 225.6917 -178.308)
		(width 0.12065)
		(layer "B.Cu")
		(net "SSD_PWREN8_R")
	)
	(segment
		(start 268.598142 -219.203778)
		(end 260.3373 -210.942936)
		(width 0.12065)
		(layer "B.Cu")
		(net "SSD_PWREN8_R")
	)
	(segment
		(start 228.369622 -157.70225)
		(end 225.6917 -160.380172)
		(width 0.12065)
		(layer "B.Cu")
		(net "SSD_PWREN8_R")
	)
	(segment
		(start 260.337554 -172.564044)
		(end 260.337554 -172.264324)
		(width 0.12065)
		(layer "B.Cu")
		(net "SSD_PWREN8_R")
	)
	(segment
		(start 260.3373 -172.26407)
		(end 260.3373 -162.670236)
		(width 0.12065)
		(layer "B.Cu")
		(net "SSD_PWREN8_R")
	)
	(segment
		(start 268.458442 -223.264984)
		(end 268.458442 -222.209614)
		(width 0.12065)
		(layer "B.Cu")
		(net "SSD_PWREN8_R")
	)
	(segment
		(start 269.300198 -224.10674)
		(end 268.458442 -223.264984)
		(width 0.12065)
		(layer "B.Cu")
		(net "SSD_PWREN8_R")
	)
	(segment
		(start 225.6917 -160.380172)
		(end 225.6917 -178.308)
		(width 0.12065)
		(layer "B.Cu")
		(net "SSD_PWREN8_R")
	)
	(segment
		(start 225.834956 -192.288414)
		(end 225.574098 -192.549272)
		(width 0.12065)
		(layer "F.Cu")
		(net "SSD_PWREN8")
	)
	(segment
		(start 225.909124 -191.381634)
		(end 225.834956 -191.455802)
		(width 0.12065)
		(layer "F.Cu")
		(net "SSD_PWREN8")
	)
	(segment
		(start 225.21799 -192.836038)
		(end 225.287332 -192.836038)
		(width 0.12065)
		(layer "F.Cu")
		(net "SSD_PWREN8")
	)
	(segment
		(start 225.909124 -191.045592)
		(end 225.909124 -191.381634)
		(width 0.12065)
		(layer "F.Cu")
		(net "SSD_PWREN8")
	)
	(segment
		(start 224.501964 -193.552064)
		(end 225.21799 -192.836038)
		(width 0.12065)
		(layer "F.Cu")
		(net "SSD_PWREN8")
	)
	(segment
		(start 224.501964 -194.131692)
		(end 224.501964 -193.552064)
		(width 0.12065)
		(layer "F.Cu")
		(net "SSD_PWREN8")
	)
	(segment
		(start 225.834956 -191.455802)
		(end 225.834956 -192.288414)
		(width 0.12065)
		(layer "F.Cu")
		(net "SSD_PWREN8")
	)
	(segment
		(start 225.287332 -192.836038)
		(end 225.574098 -192.549272)
		(width 0.12065)
		(layer "F.Cu")
		(net "SSD_PWREN8")
	)
	(via
		(at 225.574098 -192.549272)
		(size 0.7112)
		(drill 0.3556)
		(layers "F.Cu" "B.Cu")
		(net "SSD_PWREN8")
	)
	(segment
		(start 128.6256 -209.8675)
		(end 128.538224 -209.8675)
		(width 0.12065)
		(layer "F.Cu")
		(net "SSD_PWREN7_R")
	)
	(segment
		(start 129.159 -209.3341)
		(end 128.6256 -209.8675)
		(width 0.12065)
		(layer "F.Cu")
		(net "SSD_PWREN7_R")
	)
	(segment
		(start 128.538224 -209.8675)
		(end 127.204978 -211.200746)
		(width 0.12065)
		(layer "F.Cu")
		(net "SSD_PWREN7_R")
	)
	(via
		(at 127.204978 -211.200746)
		(size 0.508)
		(drill 0.254)
		(layers "F.Cu" "B.Cu")
		(net "SSD_PWREN7_R")
	)
	(via
		(at 176.542446 -206.082646)
		(size 0.7112)
		(drill 0.3556)
		(layers "F.Cu" "B.Cu")
		(net "SSD_PWREN7_R")
	)
	(segment
		(start 176.542446 -206.082646)
		(end 178.054 -207.5942)
		(width 0.12065)
		(layer "B.Cu")
		(net "SSD_PWREN7_R")
	)
	(segment
		(start 135.67029 -211.661502)
		(end 127.665734 -211.661502)
		(width 0.12065)
		(layer "B.Cu")
		(net "SSD_PWREN7_R")
	)
	(segment
		(start 178.054 -207.5942)
		(end 184.0103 -213.5505)
		(width 0.12065)
		(layer "B.Cu")
		(net "SSD_PWREN7_R")
	)
	(segment
		(start 184.083452 -223.256348)
		(end 183.300116 -224.039684)
		(width 0.12065)
		(layer "B.Cu")
		(net "SSD_PWREN7_R")
	)
	(segment
		(start 167.325548 -196.865748)
		(end 150.466044 -196.865748)
		(width 0.12065)
		(layer "B.Cu")
		(net "SSD_PWREN7_R")
	)
	(segment
		(start 150.466044 -196.865748)
		(end 135.67029 -211.661502)
		(width 0.12065)
		(layer "B.Cu")
		(net "SSD_PWREN7_R")
	)
	(segment
		(start 184.083452 -221.484952)
		(end 184.083452 -223.256348)
		(width 0.12065)
		(layer "B.Cu")
		(net "SSD_PWREN7_R")
	)
	(segment
		(start 176.542446 -206.082646)
		(end 167.325548 -196.865748)
		(width 0.12065)
		(layer "B.Cu")
		(net "SSD_PWREN7_R")
	)
	(segment
		(start 183.300116 -224.039684)
		(end 183.300116 -225.92538)
		(width 0.12065)
		(layer "B.Cu")
		(net "SSD_PWREN7_R")
	)
	(segment
		(start 184.0103 -213.5505)
		(end 184.0103 -221.4118)
		(width 0.12065)
		(layer "B.Cu")
		(net "SSD_PWREN7_R")
	)
	(segment
		(start 184.0103 -221.4118)
		(end 184.083452 -221.484952)
		(width 0.12065)
		(layer "B.Cu")
		(net "SSD_PWREN7_R")
	)
	(segment
		(start 127.665734 -211.661502)
		(end 127.204978 -211.200746)
		(width 0.12065)
		(layer "B.Cu")
		(net "SSD_PWREN7_R")
	)
	(segment
		(start 128.601724 -208.129378)
		(end 128.595882 -208.129378)
		(width 0.12065)
		(layer "F.Cu")
		(net "SSD_PWREN7")
	)
	(segment
		(start 127.955802 -206.563468)
		(end 127.955802 -207.178656)
		(width 0.12065)
		(layer "F.Cu")
		(net "SSD_PWREN7")
	)
	(segment
		(start 128.595882 -208.129378)
		(end 127.95123 -207.484726)
		(width 0.12065)
		(layer "F.Cu")
		(net "SSD_PWREN7")
	)
	(segment
		(start 127.95123 -207.484726)
		(end 127.95123 -207.183228)
		(width 0.12065)
		(layer "F.Cu")
		(net "SSD_PWREN7")
	)
	(segment
		(start 129.159 -208.4451)
		(end 128.917446 -208.4451)
		(width 0.12065)
		(layer "F.Cu")
		(net "SSD_PWREN7")
	)
	(segment
		(start 128.048004 -206.471266)
		(end 127.955802 -206.563468)
		(width 0.12065)
		(layer "F.Cu")
		(net "SSD_PWREN7")
	)
	(segment
		(start 128.917446 -208.4451)
		(end 128.601724 -208.129378)
		(width 0.12065)
		(layer "F.Cu")
		(net "SSD_PWREN7")
	)
	(segment
		(start 128.048004 -205.612492)
		(end 128.048004 -206.471266)
		(width 0.12065)
		(layer "F.Cu")
		(net "SSD_PWREN7")
	)
	(segment
		(start 127.955802 -207.178656)
		(end 127.95123 -207.183228)
		(width 0.12065)
		(layer "F.Cu")
		(net "SSD_PWREN7")
	)
	(via
		(at 127.95123 -207.183228)
		(size 0.7112)
		(drill 0.3556)
		(layers "F.Cu" "B.Cu")
		(net "SSD_PWREN7")
	)
	(segment
		(start 135.2931 -223.871028)
		(end 135.2931 -213.219284)
		(width 0.12065)
		(layer "F.Cu")
		(net "SSD_PWREN6_R")
	)
	(segment
		(start 135.183118 -213.109302)
		(end 134.825994 -212.752178)
		(width 0.12065)
		(layer "F.Cu")
		(net "SSD_PWREN6_R")
	)
	(segment
		(start 133.0198 -210.7438)
		(end 133.0198 -209.639916)
		(width 0.12065)
		(layer "F.Cu")
		(net "SSD_PWREN6_R")
	)
	(segment
		(start 134.825994 -212.752178)
		(end 134.825994 -212.549994)
		(width 0.12065)
		(layer "F.Cu")
		(net "SSD_PWREN6_R")
	)
	(segment
		(start 133.0198 -209.639916)
		(end 133.326124 -209.333592)
		(width 0.12065)
		(layer "F.Cu")
		(net "SSD_PWREN6_R")
	)
	(segment
		(start 135.2931 -213.219284)
		(end 135.183118 -213.109302)
		(width 0.12065)
		(layer "F.Cu")
		(net "SSD_PWREN6_R")
	)
	(segment
		(start 135.300212 -225.54438)
		(end 135.300212 -223.87814)
		(width 0.12065)
		(layer "F.Cu")
		(net "SSD_PWREN6_R")
	)
	(segment
		(start 134.825994 -212.549994)
		(end 133.0198 -210.7438)
		(width 0.12065)
		(layer "F.Cu")
		(net "SSD_PWREN6_R")
	)
	(segment
		(start 135.300212 -223.87814)
		(end 135.2931 -223.871028)
		(width 0.12065)
		(layer "F.Cu")
		(net "SSD_PWREN6_R")
	)
	(via
		(at 135.183118 -213.109302)
		(size 0.7112)
		(drill 0.3556)
		(layers "F.Cu" "B.Cu")
		(net "SSD_PWREN6_R")
	)
	(segment
		(start 132.583428 -207.945228)
		(end 132.583428 -207.686656)
		(width 0.12065)
		(layer "F.Cu")
		(net "SSD_PWREN6")
	)
	(segment
		(start 130.648964 -206.493618)
		(end 131.162806 -207.00746)
		(width 0.12065)
		(layer "F.Cu")
		(net "SSD_PWREN6")
	)
	(segment
		(start 131.904232 -207.00746)
		(end 132.278374 -207.381602)
		(width 0.12065)
		(layer "F.Cu")
		(net "SSD_PWREN6")
	)
	(segment
		(start 131.162806 -207.00746)
		(end 131.904232 -207.00746)
		(width 0.12065)
		(layer "F.Cu")
		(net "SSD_PWREN6")
	)
	(segment
		(start 132.583428 -207.686656)
		(end 132.278374 -207.381602)
		(width 0.12065)
		(layer "F.Cu")
		(net "SSD_PWREN6")
	)
	(segment
		(start 133.082792 -208.444592)
		(end 132.583428 -207.945228)
		(width 0.12065)
		(layer "F.Cu")
		(net "SSD_PWREN6")
	)
	(segment
		(start 130.648964 -205.612492)
		(end 130.648964 -206.493618)
		(width 0.12065)
		(layer "F.Cu")
		(net "SSD_PWREN6")
	)
	(segment
		(start 133.326124 -208.444592)
		(end 133.082792 -208.444592)
		(width 0.12065)
		(layer "F.Cu")
		(net "SSD_PWREN6")
	)
	(via
		(at 132.278374 -207.381602)
		(size 0.7112)
		(drill 0.3556)
		(layers "F.Cu" "B.Cu")
		(net "SSD_PWREN6")
	)
	(segment
		(start 77.827124 -180.973476)
		(end 77.827124 -182.790592)
		(width 0.12065)
		(layer "F.Cu")
		(net "SSD_PWREN5_R")
	)
	(segment
		(start 77.851 -179.35575)
		(end 77.851 -180.9496)
		(width 0.12065)
		(layer "F.Cu")
		(net "SSD_PWREN5_R")
	)
	(segment
		(start 77.851 -180.9496)
		(end 77.827124 -180.973476)
		(width 0.12065)
		(layer "F.Cu")
		(net "SSD_PWREN5_R")
	)
	(segment
		(start 77.827124 -179.331874)
		(end 77.851 -179.35575)
		(width 0.12065)
		(layer "F.Cu")
		(net "SSD_PWREN5_R")
	)
	(via
		(at 63.448438 -178.232562)
		(size 0.7112)
		(drill 0.3556)
		(layers "F.Cu" "B.Cu")
		(net "SSD_PWREN5_R")
	)
	(via
		(at 77.827124 -179.331874)
		(size 0.508)
		(drill 0.254)
		(layers "F.Cu" "B.Cu")
		(net "SSD_PWREN5_R")
	)
	(segment
		(start 62.099952 -225.92538)
		(end 62.099952 -223.57588)
		(width 0.12065)
		(layer "B.Cu")
		(net "SSD_PWREN5_R")
	)
	(segment
		(start 62.061598 -179.619402)
		(end 63.448438 -178.232562)
		(width 0.12065)
		(layer "B.Cu")
		(net "SSD_PWREN5_R")
	)
	(segment
		(start 62.099952 -223.57588)
		(end 62.061598 -223.537526)
		(width 0.12065)
		(layer "B.Cu")
		(net "SSD_PWREN5_R")
	)
	(segment
		(start 76.349098 -177.853848)
		(end 63.827152 -177.853848)
		(width 0.12065)
		(layer "B.Cu")
		(net "SSD_PWREN5_R")
	)
	(segment
		(start 77.827124 -179.331874)
		(end 76.349098 -177.853848)
		(width 0.12065)
		(layer "B.Cu")
		(net "SSD_PWREN5_R")
	)
	(segment
		(start 62.061598 -223.537526)
		(end 62.061598 -179.619402)
		(width 0.12065)
		(layer "B.Cu")
		(net "SSD_PWREN5_R")
	)
	(segment
		(start 63.827152 -177.853848)
		(end 63.448438 -178.232562)
		(width 0.12065)
		(layer "B.Cu")
		(net "SSD_PWREN5_R")
	)
	(segment
		(start 77.827124 -183.679592)
		(end 77.343 -184.163716)
		(width 0.12065)
		(layer "F.Cu")
		(net "SSD_PWREN5")
	)
	(segment
		(start 76.419964 -186.765692)
		(end 76.419964 -185.990992)
		(width 0.12065)
		(layer "F.Cu")
		(net "SSD_PWREN5")
	)
	(segment
		(start 77.343 -185.067956)
		(end 77.321664 -185.089292)
		(width 0.12065)
		(layer "F.Cu")
		(net "SSD_PWREN5")
	)
	(segment
		(start 77.343 -184.163716)
		(end 77.343 -185.067956)
		(width 0.12065)
		(layer "F.Cu")
		(net "SSD_PWREN5")
	)
	(segment
		(start 76.419964 -185.990992)
		(end 77.321664 -185.089292)
		(width 0.12065)
		(layer "F.Cu")
		(net "SSD_PWREN5")
	)
	(via
		(at 77.321664 -185.089292)
		(size 0.7112)
		(drill 0.3556)
		(layers "F.Cu" "B.Cu")
		(net "SSD_PWREN5")
	)
	(segment
		(start 334.804512 -171.459398)
		(end 334.906112 -171.357798)
		(width 0.12065)
		(layer "F.Cu")
		(net "SSD_PWREN4_R")
	)
	(segment
		(start 334.804512 -171.987718)
		(end 334.804512 -171.459398)
		(width 0.12065)
		(layer "F.Cu")
		(net "SSD_PWREN4_R")
	)
	(segment
		(start 334.906112 -169.042334)
		(end 334.519778 -168.656)
		(width 0.12065)
		(layer "F.Cu")
		(net "SSD_PWREN4_R")
	)
	(segment
		(start 334.906112 -171.357798)
		(end 334.906112 -169.042334)
		(width 0.12065)
		(layer "F.Cu")
		(net "SSD_PWREN4_R")
	)
	(via
		(at 334.519778 -168.656)
		(size 0.508)
		(drill 0.254)
		(layers "F.Cu" "B.Cu")
		(net "SSD_PWREN4_R")
	)
	(via
		(at 296.826178 -211.963)
		(size 0.7112)
		(drill 0.3556)
		(layers "F.Cu" "B.Cu")
		(net "SSD_PWREN4_R")
	)
	(segment
		(start 296.826178 -221.599252)
		(end 296.826178 -211.963)
		(width 0.12065)
		(layer "B.Cu")
		(net "SSD_PWREN4_R")
	)
	(segment
		(start 296.8752 -208.395062)
		(end 296.826178 -208.444084)
		(width 0.12065)
		(layer "B.Cu")
		(net "SSD_PWREN4_R")
	)
	(segment
		(start 297.300142 -225.92538)
		(end 297.300142 -222.073216)
		(width 0.12065)
		(layer "B.Cu")
		(net "SSD_PWREN4_R")
	)
	(segment
		(start 333.329026 -167.465248)
		(end 327.788016 -167.465248)
		(width 0.12065)
		(layer "B.Cu")
		(net "SSD_PWREN4_R")
	)
	(segment
		(start 296.826178 -209.04454)
		(end 296.826178 -211.963)
		(width 0.12065)
		(layer "B.Cu")
		(net "SSD_PWREN4_R")
	)
	(segment
		(start 327.187814 -167.464994)
		(end 296.8752 -197.777608)
		(width 0.12065)
		(layer "B.Cu")
		(net "SSD_PWREN4_R")
	)
	(segment
		(start 334.519778 -168.656)
		(end 333.329026 -167.465248)
		(width 0.12065)
		(layer "B.Cu")
		(net "SSD_PWREN4_R")
	)
	(segment
		(start 296.8752 -197.777608)
		(end 296.8752 -208.395062)
		(width 0.12065)
		(layer "B.Cu")
		(net "SSD_PWREN4_R")
	)
	(segment
		(start 327.788016 -167.465248)
		(end 327.787762 -167.464994)
		(width 0.12065)
		(layer "B.Cu")
		(net "SSD_PWREN4_R")
	)
	(segment
		(start 327.787762 -167.464994)
		(end 327.187814 -167.464994)
		(width 0.12065)
		(layer "B.Cu")
		(net "SSD_PWREN4_R")
	)
	(segment
		(start 296.826178 -208.444084)
		(end 296.826178 -209.04454)
		(width 0.12065)
		(layer "B.Cu")
		(net "SSD_PWREN4_R")
	)
	(segment
		(start 297.300142 -222.073216)
		(end 296.826178 -221.599252)
		(width 0.12065)
		(layer "B.Cu")
		(net "SSD_PWREN4_R")
	)
	(segment
		(start 334.318864 -171.588684)
		(end 334.318864 -171.020232)
		(width 0.12065)
		(layer "F.Cu")
		(net "SSD_PWREN4")
	)
	(segment
		(start 334.804512 -172.876718)
		(end 334.804512 -172.82414)
		(width 0.12065)
		(layer "F.Cu")
		(net "SSD_PWREN4")
	)
	(segment
		(start 334.33766 -172.357288)
		(end 334.33766 -171.60748)
		(width 0.12065)
		(layer "F.Cu")
		(net "SSD_PWREN4")
	)
	(segment
		(start 334.860392 -174.586138)
		(end 334.860392 -175.962818)
		(width 0.12065)
		(layer "F.Cu")
		(net "SSD_PWREN4")
	)
	(segment
		(start 334.804512 -172.82414)
		(end 334.33766 -172.357288)
		(width 0.12065)
		(layer "F.Cu")
		(net "SSD_PWREN4")
	)
	(segment
		(start 334.33766 -171.60748)
		(end 334.318864 -171.588684)
		(width 0.12065)
		(layer "F.Cu")
		(net "SSD_PWREN4")
	)
	(segment
		(start 334.432148 -173.249082)
		(end 334.432148 -174.157894)
		(width 0.12065)
		(layer "F.Cu")
		(net "SSD_PWREN4")
	)
	(segment
		(start 334.804512 -172.876718)
		(end 334.432148 -173.249082)
		(width 0.12065)
		(layer "F.Cu")
		(net "SSD_PWREN4")
	)
	(segment
		(start 334.432148 -174.157894)
		(end 334.860392 -174.586138)
		(width 0.12065)
		(layer "F.Cu")
		(net "SSD_PWREN4")
	)
	(via
		(at 334.318864 -171.020232)
		(size 0.7112)
		(drill 0.3556)
		(layers "F.Cu" "B.Cu")
		(net "SSD_PWREN4")
	)
	(segment
		(start 209.9564 -193.5226)
		(end 210.412076 -193.066924)
		(width 0.12065)
		(layer "F.Cu")
		(net "SSD_PWREN3_R")
	)
	(segment
		(start 210.500214 -224.165414)
		(end 209.9564 -223.6216)
		(width 0.12065)
		(layer "F.Cu")
		(net "SSD_PWREN3_R")
	)
	(segment
		(start 214.376 -189.103)
		(end 210.412076 -193.066924)
		(width 0.12065)
		(layer "F.Cu")
		(net "SSD_PWREN3_R")
	)
	(segment
		(start 221.831408 -188.3283)
		(end 221.831408 -189.31128)
		(width 0.12065)
		(layer "F.Cu")
		(net "SSD_PWREN3_R")
	)
	(segment
		(start 214.376 -186.817)
		(end 214.376 -189.103)
		(width 0.12065)
		(layer "F.Cu")
		(net "SSD_PWREN3_R")
	)
	(segment
		(start 209.9564 -223.6216)
		(end 209.9564 -193.5226)
		(width 0.12065)
		(layer "F.Cu")
		(net "SSD_PWREN3_R")
	)
	(segment
		(start 221.831408 -189.31128)
		(end 221.835218 -189.31509)
		(width 0.12065)
		(layer "F.Cu")
		(net "SSD_PWREN3_R")
	)
	(segment
		(start 221.845124 -189.324996)
		(end 221.835218 -189.31509)
		(width 0.12065)
		(layer "F.Cu")
		(net "SSD_PWREN3_R")
	)
	(segment
		(start 221.845124 -190.137796)
		(end 221.845124 -189.324996)
		(width 0.12065)
		(layer "F.Cu")
		(net "SSD_PWREN3_R")
	)
	(segment
		(start 210.500214 -225.54438)
		(end 210.500214 -224.165414)
		(width 0.12065)
		(layer "F.Cu")
		(net "SSD_PWREN3_R")
	)
	(via
		(at 214.376 -186.817)
		(size 0.508)
		(drill 0.254)
		(layers "F.Cu" "B.Cu")
		(net "SSD_PWREN3_R")
	)
	(via
		(at 210.412076 -193.066924)
		(size 0.7112)
		(drill 0.3556)
		(layers "F.Cu" "B.Cu")
		(net "SSD_PWREN3_R")
	)
	(via
		(at 221.835218 -189.31509)
		(size 0.508)
		(drill 0.254)
		(layers "F.Cu" "B.Cu")
		(net "SSD_PWREN3_R")
	)
	(segment
		(start 215.197182 -187.2869)
		(end 214.727282 -186.817)
		(width 0.127)
		(layer "In2.Cu")
		(net "SSD_PWREN3_R")
	)
	(segment
		(start 221.835218 -189.31509)
		(end 221.835218 -189.371986)
		(width 0.127)
		(layer "In2.Cu")
		(net "SSD_PWREN3_R")
	)
	(segment
		(start 221.835218 -189.371986)
		(end 219.750132 -187.2869)
		(width 0.127)
		(layer "In2.Cu")
		(net "SSD_PWREN3_R")
	)
	(segment
		(start 214.727282 -186.817)
		(end 214.376 -186.817)
		(width 0.127)
		(layer "In2.Cu")
		(net "SSD_PWREN3_R")
	)
	(segment
		(start 219.750132 -187.2869)
		(end 215.197182 -187.2869)
		(width 0.127)
		(layer "In2.Cu")
		(net "SSD_PWREN3_R")
	)
	(segment
		(start 221.733364 -193.232532)
		(end 221.733364 -192.501774)
		(width 0.12065)
		(layer "F.Cu")
		(net "SSD_PWREN3")
	)
	(segment
		(start 221.901004 -194.131692)
		(end 221.901004 -193.400172)
		(width 0.12065)
		(layer "F.Cu")
		(net "SSD_PWREN3")
	)
	(segment
		(start 221.901004 -193.400172)
		(end 221.733364 -193.232532)
		(width 0.12065)
		(layer "F.Cu")
		(net "SSD_PWREN3")
	)
	(segment
		(start 221.845124 -191.662304)
		(end 221.549976 -191.957452)
		(width 0.12065)
		(layer "F.Cu")
		(net "SSD_PWREN3")
	)
	(segment
		(start 221.733364 -192.501774)
		(end 221.549976 -192.318386)
		(width 0.12065)
		(layer "F.Cu")
		(net "SSD_PWREN3")
	)
	(segment
		(start 221.549976 -192.318386)
		(end 221.549976 -191.957452)
		(width 0.12065)
		(layer "F.Cu")
		(net "SSD_PWREN3")
	)
	(segment
		(start 221.845124 -191.026796)
		(end 221.845124 -191.662304)
		(width 0.12065)
		(layer "F.Cu")
		(net "SSD_PWREN3")
	)
	(via
		(at 221.549976 -191.957452)
		(size 0.7112)
		(drill 0.3556)
		(layers "F.Cu" "B.Cu")
		(net "SSD_PWREN3")
	)
	(segment
		(start 132.4864 -195.568316)
		(end 132.4864 -194.714876)
		(width 0.12065)
		(layer "F.Cu")
		(net "SSD_PWREN2_R")
	)
	(segment
		(start 132.4864 -194.714876)
		(end 132.056124 -194.2846)
		(width 0.12065)
		(layer "F.Cu")
		(net "SSD_PWREN2_R")
	)
	(segment
		(start 132.056124 -195.998592)
		(end 132.4864 -195.568316)
		(width 0.12065)
		(layer "F.Cu")
		(net "SSD_PWREN2_R")
	)
	(segment
		(start 138.1252 -192.4558)
		(end 149.6314 -192.4558)
		(width 0.12065)
		(layer "F.Cu")
		(net "SSD_PWREN2_R")
	)
	(segment
		(start 164.0586 -206.883)
		(end 164.398452 -207.222852)
		(width 0.12065)
		(layer "F.Cu")
		(net "SSD_PWREN2_R")
	)
	(segment
		(start 164.084 -222.377)
		(end 164.900102 -223.193102)
		(width 0.12065)
		(layer "F.Cu")
		(net "SSD_PWREN2_R")
	)
	(segment
		(start 164.900102 -223.193102)
		(end 164.900102 -225.54438)
		(width 0.12065)
		(layer "F.Cu")
		(net "SSD_PWREN2_R")
	)
	(segment
		(start 164.084 -219.2274)
		(end 164.084 -222.377)
		(width 0.12065)
		(layer "F.Cu")
		(net "SSD_PWREN2_R")
	)
	(segment
		(start 164.398452 -218.912948)
		(end 164.084 -219.2274)
		(width 0.12065)
		(layer "F.Cu")
		(net "SSD_PWREN2_R")
	)
	(segment
		(start 149.6314 -192.4558)
		(end 162.17138 -204.99578)
		(width 0.12065)
		(layer "F.Cu")
		(net "SSD_PWREN2_R")
	)
	(segment
		(start 162.17138 -204.99578)
		(end 164.0586 -206.883)
		(width 0.12065)
		(layer "F.Cu")
		(net "SSD_PWREN2_R")
	)
	(segment
		(start 137.287 -193.294)
		(end 138.1252 -192.4558)
		(width 0.12065)
		(layer "F.Cu")
		(net "SSD_PWREN2_R")
	)
	(segment
		(start 164.398452 -207.222852)
		(end 164.398452 -218.912948)
		(width 0.12065)
		(layer "F.Cu")
		(net "SSD_PWREN2_R")
	)
	(via
		(at 162.17138 -204.99578)
		(size 0.7112)
		(drill 0.3556)
		(layers "F.Cu" "B.Cu")
		(net "SSD_PWREN2_R")
	)
	(via
		(at 132.056124 -194.2846)
		(size 0.508)
		(drill 0.254)
		(layers "F.Cu" "B.Cu")
		(net "SSD_PWREN2_R")
	)
	(via
		(at 137.287 -193.294)
		(size 0.508)
		(drill 0.254)
		(layers "F.Cu" "B.Cu")
		(net "SSD_PWREN2_R")
	)
	(segment
		(start 132.653024 -194.2846)
		(end 133.389624 -193.548)
		(width 0.127)
		(layer "In2.Cu")
		(net "SSD_PWREN2_R")
	)
	(segment
		(start 132.056124 -194.2846)
		(end 132.653024 -194.2846)
		(width 0.127)
		(layer "In2.Cu")
		(net "SSD_PWREN2_R")
	)
	(segment
		(start 137.033 -193.548)
		(end 137.287 -193.294)
		(width 0.127)
		(layer "In2.Cu")
		(net "SSD_PWREN2_R")
	)
	(segment
		(start 133.389624 -193.548)
		(end 137.033 -193.548)
		(width 0.127)
		(layer "In2.Cu")
		(net "SSD_PWREN2_R")
	)
	(segment
		(start 132.056124 -196.887592)
		(end 132.056124 -197.814946)
		(width 0.12065)
		(layer "F.Cu")
		(net "SSD_PWREN2")
	)
	(segment
		(start 130.648964 -199.336152)
		(end 131.942332 -198.042784)
		(width 0.12065)
		(layer "F.Cu")
		(net "SSD_PWREN2")
	)
	(segment
		(start 132.056124 -197.814946)
		(end 131.942332 -197.928738)
		(width 0.12065)
		(layer "F.Cu")
		(net "SSD_PWREN2")
	)
	(segment
		(start 131.942332 -198.042784)
		(end 131.942332 -197.928738)
		(width 0.12065)
		(layer "F.Cu")
		(net "SSD_PWREN2")
	)
	(segment
		(start 130.648964 -199.973692)
		(end 130.648964 -199.336152)
		(width 0.12065)
		(layer "F.Cu")
		(net "SSD_PWREN2")
	)
	(via
		(at 131.942332 -197.928738)
		(size 0.7112)
		(drill 0.3556)
		(layers "F.Cu" "B.Cu")
		(net "SSD_PWREN2")
	)
	(segment
		(start 337.852512 -185.322718)
		(end 337.852512 -186.097418)
		(width 0.12065)
		(layer "F.Cu")
		(net "SSD_PWREN14_R")
	)
	(via
		(at 340.487 -190.881)
		(size 0.7112)
		(drill 0.3556)
		(layers "F.Cu" "B.Cu")
		(net "SSD_PWREN14_R")
	)
	(via
		(at 337.852512 -186.097418)
		(size 0.508)
		(drill 0.254)
		(layers "F.Cu" "B.Cu")
		(net "SSD_PWREN14_R")
	)
	(segment
		(start 338.2137 -186.458606)
		(end 338.2137 -188.103764)
		(width 0.12065)
		(layer "B.Cu")
		(net "SSD_PWREN14_R")
	)
	(segment
		(start 342.41105 -214.860886)
		(end 344.54465 -212.727286)
		(width 0.12065)
		(layer "B.Cu")
		(net "SSD_PWREN14_R")
	)
	(segment
		(start 337.743292 -201.981308)
		(end 344.08745 -195.63715)
		(width 0.12065)
		(layer "B.Cu")
		(net "SSD_PWREN14_R")
	)
	(segment
		(start 342.41105 -222.069914)
		(end 342.41105 -214.860886)
		(width 0.12065)
		(layer "B.Cu")
		(net "SSD_PWREN14_R")
	)
	(segment
		(start 342.55075 -222.209614)
		(end 342.41105 -222.069914)
		(width 0.12065)
		(layer "B.Cu")
		(net "SSD_PWREN14_R")
	)
	(segment
		(start 344.08745 -195.63715)
		(end 344.08745 -193.977514)
		(width 0.12065)
		(layer "B.Cu")
		(net "SSD_PWREN14_R")
	)
	(segment
		(start 337.7438 -207.6196)
		(end 337.693 -207.5688)
		(width 0.12065)
		(layer "B.Cu")
		(net "SSD_PWREN14_R")
	)
	(segment
		(start 342.9 -225.92538)
		(end 342.9 -223.885252)
		(width 0.12065)
		(layer "B.Cu")
		(net "SSD_PWREN14_R")
	)
	(segment
		(start 341.909908 -207.696308)
		(end 338.226908 -207.696308)
		(width 0.12065)
		(layer "B.Cu")
		(net "SSD_PWREN14_R")
	)
	(segment
		(start 340.738968 -190.629032)
		(end 340.487 -190.881)
		(width 0.12065)
		(layer "B.Cu")
		(net "SSD_PWREN14_R")
	)
	(segment
		(start 337.693 -207.000348)
		(end 337.743292 -206.950056)
		(width 0.12065)
		(layer "B.Cu")
		(net "SSD_PWREN14_R")
	)
	(segment
		(start 344.57386 -212.16493)
		(end 344.57386 -210.36026)
		(width 0.12065)
		(layer "B.Cu")
		(net "SSD_PWREN14_R")
	)
	(segment
		(start 338.226908 -207.696308)
		(end 338.1502 -207.6196)
		(width 0.12065)
		(layer "B.Cu")
		(net "SSD_PWREN14_R")
	)
	(segment
		(start 342.9 -223.885252)
		(end 342.55075 -223.536002)
		(width 0.12065)
		(layer "B.Cu")
		(net "SSD_PWREN14_R")
	)
	(segment
		(start 344.57386 -210.36026)
		(end 341.909908 -207.696308)
		(width 0.12065)
		(layer "B.Cu")
		(net "SSD_PWREN14_R")
	)
	(segment
		(start 338.2137 -188.103764)
		(end 340.738968 -190.629032)
		(width 0.12065)
		(layer "B.Cu")
		(net "SSD_PWREN14_R")
	)
	(segment
		(start 337.743292 -206.950056)
		(end 337.743292 -201.981308)
		(width 0.12065)
		(layer "B.Cu")
		(net "SSD_PWREN14_R")
	)
	(segment
		(start 337.852512 -186.097418)
		(end 338.2137 -186.458606)
		(width 0.12065)
		(layer "B.Cu")
		(net "SSD_PWREN14_R")
	)
	(segment
		(start 338.1502 -207.6196)
		(end 337.7438 -207.6196)
		(width 0.12065)
		(layer "B.Cu")
		(net "SSD_PWREN14_R")
	)
	(segment
		(start 337.693 -207.5688)
		(end 337.693 -207.000348)
		(width 0.12065)
		(layer "B.Cu")
		(net "SSD_PWREN14_R")
	)
	(segment
		(start 344.08745 -193.977514)
		(end 340.738968 -190.629032)
		(width 0.12065)
		(layer "B.Cu")
		(net "SSD_PWREN14_R")
	)
	(segment
		(start 342.55075 -223.536002)
		(end 342.55075 -222.209614)
		(width 0.12065)
		(layer "B.Cu")
		(net "SSD_PWREN14_R")
	)
	(segment
		(start 344.54465 -212.19414)
		(end 344.57386 -212.16493)
		(width 0.12065)
		(layer "B.Cu")
		(net "SSD_PWREN14_R")
	)
	(segment
		(start 344.54465 -212.727286)
		(end 344.54465 -212.19414)
		(width 0.12065)
		(layer "B.Cu")
		(net "SSD_PWREN14_R")
	)
	(segment
		(start 337.461352 -181.601618)
		(end 337.461352 -183.029352)
		(width 0.12065)
		(layer "F.Cu")
		(net "SSD_PWREN14")
	)
	(segment
		(start 337.852512 -183.420512)
		(end 337.693 -183.261)
		(width 0.12065)
		(layer "F.Cu")
		(net "SSD_PWREN14")
	)
	(segment
		(start 337.461352 -183.029352)
		(end 337.693 -183.261)
		(width 0.12065)
		(layer "F.Cu")
		(net "SSD_PWREN14")
	)
	(segment
		(start 337.852512 -184.433718)
		(end 337.852512 -183.420512)
		(width 0.12065)
		(layer "F.Cu")
		(net "SSD_PWREN14")
	)
	(via
		(at 337.693 -183.261)
		(size 0.7112)
		(drill 0.3556)
		(layers "F.Cu" "B.Cu")
		(net "SSD_PWREN14")
	)
	(segment
		(start 229.409498 -205.812898)
		(end 230.147368 -206.550768)
		(width 0.12065)
		(layer "F.Cu")
		(net "SSD_PWREN13_R")
	)
	(segment
		(start 230.147368 -206.550768)
		(end 230.147368 -206.676498)
		(width 0.12065)
		(layer "F.Cu")
		(net "SSD_PWREN13_R")
	)
	(segment
		(start 297.32605 -207.02905)
		(end 297.32605 -223.682814)
		(width 0.12065)
		(layer "F.Cu")
		(net "SSD_PWREN13_R")
	)
	(segment
		(start 221.9579 -206.0194)
		(end 222.14078 -206.20228)
		(width 0.12065)
		(layer "F.Cu")
		(net "SSD_PWREN13_R")
	)
	(segment
		(start 233.888026 -152.056846)
		(end 229.409498 -156.535374)
		(width 0.12065)
		(layer "F.Cu")
		(net "SSD_PWREN13_R")
	)
	(segment
		(start 297.300142 -176.667414)
		(end 297.300142 -176.330102)
		(width 0.12065)
		(layer "F.Cu")
		(net "SSD_PWREN13_R")
	)
	(segment
		(start 297.32605 -223.682814)
		(end 297.300142 -223.708722)
		(width 0.12065)
		(layer "F.Cu")
		(net "SSD_PWREN13_R")
	)
	(segment
		(start 297.300142 -223.708722)
		(end 297.300142 -225.54438)
		(width 0.12065)
		(layer "F.Cu")
		(net "SSD_PWREN13_R")
	)
	(segment
		(start 234.187746 -152.056846)
		(end 233.888026 -152.056846)
		(width 0.12065)
		(layer "F.Cu")
		(net "SSD_PWREN13_R")
	)
	(segment
		(start 297.1038 -206.8068)
		(end 297.32605 -207.02905)
		(width 0.12065)
		(layer "F.Cu")
		(net "SSD_PWREN13_R")
	)
	(segment
		(start 297.815 -188.595)
		(end 297.815 -206.0956)
		(width 0.12065)
		(layer "F.Cu")
		(net "SSD_PWREN13_R")
	)
	(segment
		(start 273.02714 -152.0571)
		(end 234.187746 -152.056846)
		(width 0.12065)
		(layer "F.Cu")
		(net "SSD_PWREN13_R")
	)
	(segment
		(start 297.300142 -176.330102)
		(end 273.02714 -152.0571)
		(width 0.12065)
		(layer "F.Cu")
		(net "SSD_PWREN13_R")
	)
	(segment
		(start 221.9579 -203.4921)
		(end 221.9579 -206.0194)
		(width 0.12065)
		(layer "F.Cu")
		(net "SSD_PWREN13_R")
	)
	(segment
		(start 297.815 -188.595)
		(end 297.815 -177.182272)
		(width 0.12065)
		(layer "F.Cu")
		(net "SSD_PWREN13_R")
	)
	(segment
		(start 229.409498 -156.535374)
		(end 229.409498 -205.812898)
		(width 0.12065)
		(layer "F.Cu")
		(net "SSD_PWREN13_R")
	)
	(segment
		(start 297.815 -206.0956)
		(end 297.1038 -206.8068)
		(width 0.12065)
		(layer "F.Cu")
		(net "SSD_PWREN13_R")
	)
	(segment
		(start 297.815 -177.182272)
		(end 297.300142 -176.667414)
		(width 0.12065)
		(layer "F.Cu")
		(net "SSD_PWREN13_R")
	)
	(via
		(at 222.14078 -206.20228)
		(size 0.508)
		(drill 0.254)
		(layers "F.Cu" "B.Cu")
		(net "SSD_PWREN13_R")
	)
	(via
		(at 230.147368 -206.676498)
		(size 0.508)
		(drill 0.254)
		(layers "F.Cu" "B.Cu")
		(net "SSD_PWREN13_R")
	)
	(via
		(at 297.815 -188.595)
		(size 0.7112)
		(drill 0.3556)
		(layers "F.Cu" "B.Cu")
		(net "SSD_PWREN13_R")
	)
	(segment
		(start 222.14078 -206.20228)
		(end 229.67315 -206.20228)
		(width 0.127)
		(layer "In2.Cu")
		(net "SSD_PWREN13_R")
	)
	(segment
		(start 229.67315 -206.20228)
		(end 230.147368 -206.676498)
		(width 0.127)
		(layer "In2.Cu")
		(net "SSD_PWREN13_R")
	)
	(segment
		(start 221.901004 -199.770492)
		(end 221.901004 -201.174604)
		(width 0.12065)
		(layer "F.Cu")
		(net "SSD_PWREN13")
	)
	(segment
		(start 221.9579 -201.2315)
		(end 221.9198 -201.1934)
		(width 0.12065)
		(layer "F.Cu")
		(net "SSD_PWREN13")
	)
	(segment
		(start 221.901004 -201.174604)
		(end 221.9198 -201.1934)
		(width 0.12065)
		(layer "F.Cu")
		(net "SSD_PWREN13")
	)
	(segment
		(start 221.9579 -202.6031)
		(end 221.9579 -201.2315)
		(width 0.12065)
		(layer "F.Cu")
		(net "SSD_PWREN13")
	)
	(via
		(at 221.9198 -201.1934)
		(size 0.7112)
		(drill 0.3556)
		(layers "F.Cu" "B.Cu")
		(net "SSD_PWREN13")
	)
	(segment
		(start 226.1108 -208.0768)
		(end 226.1108 -206.622904)
		(width 0.12065)
		(layer "F.Cu")
		(net "SSD_PWREN12_R")
	)
	(segment
		(start 226.348798 -206.384906)
		(end 226.62134 -206.112364)
		(width 0.12065)
		(layer "F.Cu")
		(net "SSD_PWREN12_R")
	)
	(segment
		(start 226.1108 -206.622904)
		(end 226.348798 -206.384906)
		(width 0.12065)
		(layer "F.Cu")
		(net "SSD_PWREN12_R")
	)
	(segment
		(start 226.62134 -203.949808)
		(end 226.163124 -203.491592)
		(width 0.12065)
		(layer "F.Cu")
		(net "SSD_PWREN12_R")
	)
	(segment
		(start 226.62134 -206.112364)
		(end 226.62134 -203.949808)
		(width 0.12065)
		(layer "F.Cu")
		(net "SSD_PWREN12_R")
	)
	(via
		(at 214.757 -208.407)
		(size 0.7112)
		(drill 0.3556)
		(layers "F.Cu" "B.Cu")
		(net "SSD_PWREN12_R")
	)
	(via
		(at 226.1108 -208.0768)
		(size 0.508)
		(drill 0.254)
		(layers "F.Cu" "B.Cu")
		(net "SSD_PWREN12_R")
	)
	(segment
		(start 225.7806 -208.407)
		(end 214.757 -208.407)
		(width 0.12065)
		(layer "B.Cu")
		(net "SSD_PWREN12_R")
	)
	(segment
		(start 212.882734 -208.407)
		(end 214.757 -208.407)
		(width 0.12065)
		(layer "B.Cu")
		(net "SSD_PWREN12_R")
	)
	(segment
		(start 208.900014 -212.38972)
		(end 212.882734 -208.407)
		(width 0.12065)
		(layer "B.Cu")
		(net "SSD_PWREN12_R")
	)
	(segment
		(start 226.1108 -208.0768)
		(end 225.7806 -208.407)
		(width 0.12065)
		(layer "B.Cu")
		(net "SSD_PWREN12_R")
	)
	(segment
		(start 208.900014 -225.92538)
		(end 208.900014 -212.38972)
		(width 0.12065)
		(layer "B.Cu")
		(net "SSD_PWREN12_R")
	)
	(segment
		(start 224.501964 -199.770492)
		(end 224.501964 -200.504298)
		(width 0.12065)
		(layer "F.Cu")
		(net "SSD_PWREN12")
	)
	(segment
		(start 224.87636 -200.878694)
		(end 225.19386 -200.878694)
		(width 0.12065)
		(layer "F.Cu")
		(net "SSD_PWREN12")
	)
	(segment
		(start 226.163124 -201.567542)
		(end 226.072446 -201.476864)
		(width 0.12065)
		(layer "F.Cu")
		(net "SSD_PWREN12")
	)
	(segment
		(start 226.163124 -202.602592)
		(end 226.163124 -201.567542)
		(width 0.12065)
		(layer "F.Cu")
		(net "SSD_PWREN12")
	)
	(segment
		(start 225.19386 -200.878694)
		(end 225.39706 -201.081894)
		(width 0.12065)
		(layer "F.Cu")
		(net "SSD_PWREN12")
	)
	(segment
		(start 224.501964 -200.504298)
		(end 224.87636 -200.878694)
		(width 0.12065)
		(layer "F.Cu")
		(net "SSD_PWREN12")
	)
	(segment
		(start 225.677476 -201.081894)
		(end 226.072446 -201.476864)
		(width 0.12065)
		(layer "F.Cu")
		(net "SSD_PWREN12")
	)
	(segment
		(start 225.39706 -201.081894)
		(end 225.677476 -201.081894)
		(width 0.12065)
		(layer "F.Cu")
		(net "SSD_PWREN12")
	)
	(via
		(at 226.072446 -201.476864)
		(size 0.7112)
		(drill 0.3556)
		(layers "F.Cu" "B.Cu")
		(net "SSD_PWREN12")
	)
	(segment
		(start 160.1216 -199.0598)
		(end 151.4602 -190.3984)
		(width 0.12065)
		(layer "F.Cu")
		(net "SSD_PWREN11_R")
	)
	(segment
		(start 111.47806 -190.3984)
		(end 97.31756 -176.2379)
		(width 0.12065)
		(layer "F.Cu")
		(net "SSD_PWREN11_R")
	)
	(segment
		(start 74.3458 -198.5772)
		(end 74.3458 -197.4088)
		(width 0.12065)
		(layer "F.Cu")
		(net "SSD_PWREN11_R")
	)
	(segment
		(start 66.162936 -199.4916)
		(end 73.4314 -199.4916)
		(width 0.12065)
		(layer "F.Cu")
		(net "SSD_PWREN11_R")
	)
	(segment
		(start 97.31756 -176.2379)
		(end 69.53504 -176.2379)
		(width 0.12065)
		(layer "F.Cu")
		(net "SSD_PWREN11_R")
	)
	(segment
		(start 73.914 -196.977)
		(end 73.914 -196.1261)
		(width 0.12065)
		(layer "F.Cu")
		(net "SSD_PWREN11_R")
	)
	(segment
		(start 73.4314 -199.4916)
		(end 74.3458 -198.5772)
		(width 0.12065)
		(layer "F.Cu")
		(net "SSD_PWREN11_R")
	)
	(segment
		(start 69.53504 -176.2379)
		(end 64.56045 -181.21249)
		(width 0.12065)
		(layer "F.Cu")
		(net "SSD_PWREN11_R")
	)
	(segment
		(start 64.56045 -181.21249)
		(end 64.56045 -197.889114)
		(width 0.12065)
		(layer "F.Cu")
		(net "SSD_PWREN11_R")
	)
	(segment
		(start 64.56045 -197.889114)
		(end 66.162936 -199.4916)
		(width 0.12065)
		(layer "F.Cu")
		(net "SSD_PWREN11_R")
	)
	(segment
		(start 163.9824 -199.0598)
		(end 160.1216 -199.0598)
		(width 0.12065)
		(layer "F.Cu")
		(net "SSD_PWREN11_R")
	)
	(segment
		(start 151.4602 -190.3984)
		(end 111.47806 -190.3984)
		(width 0.12065)
		(layer "F.Cu")
		(net "SSD_PWREN11_R")
	)
	(segment
		(start 164.0332 -199.1106)
		(end 163.9824 -199.0598)
		(width 0.12065)
		(layer "F.Cu")
		(net "SSD_PWREN11_R")
	)
	(segment
		(start 74.3458 -197.4088)
		(end 73.914 -196.977)
		(width 0.12065)
		(layer "F.Cu")
		(net "SSD_PWREN11_R")
	)
	(via
		(at 164.0332 -199.1106)
		(size 0.508)
		(drill 0.254)
		(layers "F.Cu" "B.Cu")
		(net "SSD_PWREN11_R")
	)
	(via
		(at 164.2872 -206.121)
		(size 0.7112)
		(drill 0.3556)
		(layers "F.Cu" "B.Cu")
		(net "SSD_PWREN11_R")
	)
	(segment
		(start 162.687 -220.983556)
		(end 163.300156 -220.3704)
		(width 0.12065)
		(layer "B.Cu")
		(net "SSD_PWREN11_R")
	)
	(segment
		(start 163.300156 -225.92538)
		(end 163.300156 -224.082356)
		(width 0.12065)
		(layer "B.Cu")
		(net "SSD_PWREN11_R")
	)
	(segment
		(start 162.687 -222.794068)
		(end 162.687 -220.983556)
		(width 0.12065)
		(layer "B.Cu")
		(net "SSD_PWREN11_R")
	)
	(segment
		(start 164.0332 -199.1106)
		(end 164.2872 -199.3646)
		(width 0.12065)
		(layer "B.Cu")
		(net "SSD_PWREN11_R")
	)
	(segment
		(start 162.677348 -223.459548)
		(end 162.677348 -222.80372)
		(width 0.12065)
		(layer "B.Cu")
		(net "SSD_PWREN11_R")
	)
	(segment
		(start 163.300156 -220.3704)
		(end 163.300156 -216.869772)
		(width 0.12065)
		(layer "B.Cu")
		(net "SSD_PWREN11_R")
	)
	(segment
		(start 164.2872 -199.3646)
		(end 164.2872 -200.2028)
		(width 0.12065)
		(layer "B.Cu")
		(net "SSD_PWREN11_R")
	)
	(segment
		(start 163.300156 -224.082356)
		(end 162.677348 -223.459548)
		(width 0.12065)
		(layer "B.Cu")
		(net "SSD_PWREN11_R")
	)
	(segment
		(start 164.2872 -215.882728)
		(end 164.2872 -206.121)
		(width 0.12065)
		(layer "B.Cu")
		(net "SSD_PWREN11_R")
	)
	(segment
		(start 164.2872 -200.2028)
		(end 164.2872 -206.121)
		(width 0.12065)
		(layer "B.Cu")
		(net "SSD_PWREN11_R")
	)
	(segment
		(start 162.677348 -222.80372)
		(end 162.687 -222.794068)
		(width 0.12065)
		(layer "B.Cu")
		(net "SSD_PWREN11_R")
	)
	(segment
		(start 163.300156 -216.869772)
		(end 164.2872 -215.882728)
		(width 0.12065)
		(layer "B.Cu")
		(net "SSD_PWREN11_R")
	)
	(segment
		(start 73.914 -194.125088)
		(end 73.7616 -193.972688)
		(width 0.12065)
		(layer "F.Cu")
		(net "SSD_PWREN11")
	)
	(segment
		(start 73.819004 -193.915284)
		(end 73.7616 -193.972688)
		(width 0.12065)
		(layer "F.Cu")
		(net "SSD_PWREN11")
	)
	(segment
		(start 73.914 -195.2371)
		(end 73.914 -194.125088)
		(width 0.12065)
		(layer "F.Cu")
		(net "SSD_PWREN11")
	)
	(segment
		(start 73.819004 -192.404492)
		(end 73.819004 -193.915284)
		(width 0.12065)
		(layer "F.Cu")
		(net "SSD_PWREN11")
	)
	(via
		(at 73.7616 -193.972688)
		(size 0.7112)
		(drill 0.3556)
		(layers "F.Cu" "B.Cu")
		(net "SSD_PWREN11")
	)
	(segment
		(start 78.081124 -196.125592)
		(end 78.081124 -196.900292)
		(width 0.12065)
		(layer "F.Cu")
		(net "SSD_PWREN10_R")
	)
	(via
		(at 78.081124 -196.900292)
		(size 0.508)
		(drill 0.254)
		(layers "F.Cu" "B.Cu")
		(net "SSD_PWREN10_R")
	)
	(via
		(at 91.644978 -203.150978)
		(size 0.7112)
		(drill 0.3556)
		(layers "F.Cu" "B.Cu")
		(net "SSD_PWREN10_R")
	)
	(segment
		(start 78.5876 -196.74967)
		(end 79.265272 -196.071998)
		(width 0.12065)
		(layer "B.Cu")
		(net "SSD_PWREN10_R")
	)
	(segment
		(start 85.323934 -196.829934)
		(end 91.644978 -203.150978)
		(width 0.12065)
		(layer "B.Cu")
		(net "SSD_PWREN10_R")
	)
	(segment
		(start 78.105 -196.924168)
		(end 78.105 -198.1454)
		(width 0.12065)
		(layer "B.Cu")
		(net "SSD_PWREN10_R")
	)
	(segment
		(start 78.081124 -196.900292)
		(end 78.105 -196.924168)
		(width 0.12065)
		(layer "B.Cu")
		(net "SSD_PWREN10_R")
	)
	(segment
		(start 81.214468 -196.829934)
		(end 85.323934 -196.829934)
		(width 0.12065)
		(layer "B.Cu")
		(net "SSD_PWREN10_R")
	)
	(segment
		(start 78.105 -198.1454)
		(end 78.5876 -197.6628)
		(width 0.12065)
		(layer "B.Cu")
		(net "SSD_PWREN10_R")
	)
	(segment
		(start 94.937834 -222.011494)
		(end 94.937834 -206.443834)
		(width 0.12065)
		(layer "B.Cu")
		(net "SSD_PWREN10_R")
	)
	(segment
		(start 94.899988 -225.92538)
		(end 94.899988 -222.04934)
		(width 0.12065)
		(layer "B.Cu")
		(net "SSD_PWREN10_R")
	)
	(segment
		(start 79.265272 -196.071998)
		(end 80.456532 -196.071998)
		(width 0.12065)
		(layer "B.Cu")
		(net "SSD_PWREN10_R")
	)
	(segment
		(start 94.937834 -206.443834)
		(end 91.644978 -203.150978)
		(width 0.12065)
		(layer "B.Cu")
		(net "SSD_PWREN10_R")
	)
	(segment
		(start 80.456532 -196.071998)
		(end 81.214468 -196.829934)
		(width 0.12065)
		(layer "B.Cu")
		(net "SSD_PWREN10_R")
	)
	(segment
		(start 94.899988 -222.04934)
		(end 94.937834 -222.011494)
		(width 0.12065)
		(layer "B.Cu")
		(net "SSD_PWREN10_R")
	)
	(segment
		(start 78.5876 -197.6628)
		(end 78.5876 -196.74967)
		(width 0.12065)
		(layer "B.Cu")
		(net "SSD_PWREN10_R")
	)
	(segment
		(start 78.081124 -194.159124)
		(end 77.978 -194.056)
		(width 0.12065)
		(layer "F.Cu")
		(net "SSD_PWREN10")
	)
	(segment
		(start 77.076046 -193.9417)
		(end 77.8637 -193.9417)
		(width 0.12065)
		(layer "F.Cu")
		(net "SSD_PWREN10")
	)
	(segment
		(start 77.8637 -193.9417)
		(end 77.978 -194.056)
		(width 0.12065)
		(layer "F.Cu")
		(net "SSD_PWREN10")
	)
	(segment
		(start 78.081124 -195.236592)
		(end 78.081124 -194.159124)
		(width 0.12065)
		(layer "F.Cu")
		(net "SSD_PWREN10")
	)
	(segment
		(start 76.419964 -192.404492)
		(end 76.419964 -193.285618)
		(width 0.12065)
		(layer "F.Cu")
		(net "SSD_PWREN10")
	)
	(segment
		(start 76.419964 -193.285618)
		(end 77.076046 -193.9417)
		(width 0.12065)
		(layer "F.Cu")
		(net "SSD_PWREN10")
	)
	(via
		(at 77.978 -194.056)
		(size 0.7112)
		(drill 0.3556)
		(layers "F.Cu" "B.Cu")
		(net "SSD_PWREN10")
	)
	(segment
		(start 127.992124 -195.998592)
		(end 127.992124 -195.223892)
		(width 0.12065)
		(layer "F.Cu")
		(net "SSD_PWREN1_R")
	)
	(segment
		(start 88.9127 -185.3565)
		(end 88.9127 -182.5371)
		(width 0.12065)
		(layer "F.Cu")
		(net "SSD_PWREN1_R")
	)
	(segment
		(start 94.7293 -223.413828)
		(end 94.7293 -205.632812)
		(width 0.12065)
		(layer "F.Cu")
		(net "SSD_PWREN1_R")
	)
	(segment
		(start 88.9127 -199.816212)
		(end 88.9127 -185.9407)
		(width 0.12065)
		(layer "F.Cu")
		(net "SSD_PWREN1_R")
	)
	(segment
		(start 88.6206 -185.6486)
		(end 88.9127 -185.3565)
		(width 0.12065)
		(layer "F.Cu")
		(net "SSD_PWREN1_R")
	)
	(segment
		(start 92.329 -179.1208)
		(end 92.329 -178.816)
		(width 0.12065)
		(layer "F.Cu")
		(net "SSD_PWREN1_R")
	)
	(segment
		(start 94.899988 -223.584516)
		(end 94.7293 -223.413828)
		(width 0.12065)
		(layer "F.Cu")
		(net "SSD_PWREN1_R")
	)
	(segment
		(start 94.899988 -225.54438)
		(end 94.899988 -223.584516)
		(width 0.12065)
		(layer "F.Cu")
		(net "SSD_PWREN1_R")
	)
	(segment
		(start 88.9127 -185.9407)
		(end 88.6206 -185.6486)
		(width 0.12065)
		(layer "F.Cu")
		(net "SSD_PWREN1_R")
	)
	(segment
		(start 94.7293 -205.632812)
		(end 88.9127 -199.816212)
		(width 0.12065)
		(layer "F.Cu")
		(net "SSD_PWREN1_R")
	)
	(segment
		(start 88.9127 -182.5371)
		(end 92.329 -179.1208)
		(width 0.12065)
		(layer "F.Cu")
		(net "SSD_PWREN1_R")
	)
	(via
		(at 123.886976 -191.118744)
		(size 0.7112)
		(drill 0.3556)
		(layers "F.Cu" "B.Cu")
		(net "SSD_PWREN1_R")
	)
	(via
		(at 92.329 -178.816)
		(size 0.508)
		(drill 0.254)
		(layers "F.Cu" "B.Cu")
		(net "SSD_PWREN1_R")
	)
	(via
		(at 127.992124 -195.223892)
		(size 0.508)
		(drill 0.254)
		(layers "F.Cu" "B.Cu")
		(net "SSD_PWREN1_R")
	)
	(segment
		(start 111.114332 -178.3461)
		(end 123.886976 -191.118744)
		(width 0.12065)
		(layer "B.Cu")
		(net "SSD_PWREN1_R")
	)
	(segment
		(start 127.992124 -195.223892)
		(end 123.886976 -191.118744)
		(width 0.12065)
		(layer "B.Cu")
		(net "SSD_PWREN1_R")
	)
	(segment
		(start 92.329 -178.816)
		(end 92.7989 -178.3461)
		(width 0.12065)
		(layer "B.Cu")
		(net "SSD_PWREN1_R")
	)
	(segment
		(start 92.7989 -178.3461)
		(end 111.114332 -178.3461)
		(width 0.12065)
		(layer "B.Cu")
		(net "SSD_PWREN1_R")
	)
	(segment
		(start 127.992124 -196.887592)
		(end 127.992124 -196.835014)
		(width 0.12065)
		(layer "F.Cu")
		(net "SSD_PWREN1")
	)
	(segment
		(start 127.61976 -197.259956)
		(end 127.61976 -198.168768)
		(width 0.12065)
		(layer "F.Cu")
		(net "SSD_PWREN1")
	)
	(segment
		(start 127.525272 -196.368162)
		(end 127.525272 -194.482974)
		(width 0.12065)
		(layer "F.Cu")
		(net "SSD_PWREN1")
	)
	(segment
		(start 127.992124 -196.835014)
		(end 127.525272 -196.368162)
		(width 0.12065)
		(layer "F.Cu")
		(net "SSD_PWREN1")
	)
	(segment
		(start 127.61976 -198.168768)
		(end 128.048004 -198.597012)
		(width 0.12065)
		(layer "F.Cu")
		(net "SSD_PWREN1")
	)
	(segment
		(start 128.048004 -198.597012)
		(end 128.048004 -199.973692)
		(width 0.12065)
		(layer "F.Cu")
		(net "SSD_PWREN1")
	)
	(segment
		(start 127.992124 -196.887592)
		(end 127.61976 -197.259956)
		(width 0.12065)
		(layer "F.Cu")
		(net "SSD_PWREN1")
	)
	(segment
		(start 127.519176 -194.476878)
		(end 127.519176 -194.34429)
		(width 0.12065)
		(layer "F.Cu")
		(net "SSD_PWREN1")
	)
	(segment
		(start 127.525272 -194.482974)
		(end 127.519176 -194.476878)
		(width 0.12065)
		(layer "F.Cu")
		(net "SSD_PWREN1")
	)
	(via
		(at 127.519176 -194.34429)
		(size 0.7112)
		(drill 0.3556)
		(layers "F.Cu" "B.Cu")
		(net "SSD_PWREN1")
	)
	(segment
		(start 73.745852 -181.8132)
		(end 73.745852 -180.959252)
		(width 0.12065)
		(layer "F.Cu")
		(net "SSD_PWREN0_R")
	)
	(segment
		(start 62.099952 -225.54438)
		(end 62.099952 -192.6082)
		(width 0.12065)
		(layer "F.Cu")
		(net "SSD_PWREN0_R")
	)
	(segment
		(start 62.099952 -192.6082)
		(end 62.484 -192.224152)
		(width 0.12065)
		(layer "F.Cu")
		(net "SSD_PWREN0_R")
	)
	(segment
		(start 62.484 -183.515)
		(end 62.484 -189.357)
		(width 0.12065)
		(layer "F.Cu")
		(net "SSD_PWREN0_R")
	)
	(segment
		(start 62.484 -192.224152)
		(end 62.484 -189.357)
		(width 0.12065)
		(layer "F.Cu")
		(net "SSD_PWREN0_R")
	)
	(segment
		(start 73.7108 -180.9242)
		(end 73.279 -181.356)
		(width 0.12065)
		(layer "F.Cu")
		(net "SSD_PWREN0_R")
	)
	(segment
		(start 73.279 -182.306468)
		(end 73.763124 -182.790592)
		(width 0.12065)
		(layer "F.Cu")
		(net "SSD_PWREN0_R")
	)
	(segment
		(start 61.341 -182.372)
		(end 62.484 -183.515)
		(width 0.12065)
		(layer "F.Cu")
		(net "SSD_PWREN0_R")
	)
	(segment
		(start 73.745852 -180.959252)
		(end 73.7108 -180.9242)
		(width 0.12065)
		(layer "F.Cu")
		(net "SSD_PWREN0_R")
	)
	(segment
		(start 73.279 -181.356)
		(end 73.279 -182.306468)
		(width 0.12065)
		(layer "F.Cu")
		(net "SSD_PWREN0_R")
	)
	(segment
		(start 61.214 -182.372)
		(end 61.341 -182.372)
		(width 0.12065)
		(layer "F.Cu")
		(net "SSD_PWREN0_R")
	)
	(via
		(at 73.745852 -181.8132)
		(size 0.508)
		(drill 0.254)
		(layers "F.Cu" "B.Cu")
		(net "SSD_PWREN0_R")
	)
	(via
		(at 61.214 -182.372)
		(size 0.508)
		(drill 0.254)
		(layers "F.Cu" "B.Cu")
		(net "SSD_PWREN0_R")
	)
	(via
		(at 62.484 -189.357)
		(size 0.7112)
		(drill 0.3556)
		(layers "F.Cu" "B.Cu")
		(net "SSD_PWREN0_R")
	)
	(segment
		(start 63.373 -180.213)
		(end 61.214 -182.372)
		(width 0.127)
		(layer "In5.Cu")
		(net "SSD_PWREN0_R")
	)
	(segment
		(start 73.745852 -181.8132)
		(end 73.745852 -181.608476)
		(width 0.127)
		(layer "In5.Cu")
		(net "SSD_PWREN0_R")
	)
	(segment
		(start 72.350376 -180.213)
		(end 63.373 -180.213)
		(width 0.127)
		(layer "In5.Cu")
		(net "SSD_PWREN0_R")
	)
	(segment
		(start 73.745852 -181.608476)
		(end 72.350376 -180.213)
		(width 0.127)
		(layer "In5.Cu")
		(net "SSD_PWREN0_R")
	)
	(segment
		(start 73.763124 -183.679592)
		(end 73.376028 -184.066688)
		(width 0.12065)
		(layer "F.Cu")
		(net "SSD_PWREN0")
	)
	(segment
		(start 74.379074 -185.34253)
		(end 74.379074 -185.291476)
		(width 0.12065)
		(layer "F.Cu")
		(net "SSD_PWREN0")
	)
	(segment
		(start 74.174858 -185.08726)
		(end 74.379074 -185.291476)
		(width 0.12065)
		(layer "F.Cu")
		(net "SSD_PWREN0")
	)
	(segment
		(start 73.781412 -185.08726)
		(end 74.174858 -185.08726)
		(width 0.12065)
		(layer "F.Cu")
		(net "SSD_PWREN0")
	)
	(segment
		(start 73.819004 -185.9026)
		(end 74.379074 -185.34253)
		(width 0.12065)
		(layer "F.Cu")
		(net "SSD_PWREN0")
	)
	(segment
		(start 73.376028 -184.681876)
		(end 73.781412 -185.08726)
		(width 0.12065)
		(layer "F.Cu")
		(net "SSD_PWREN0")
	)
	(segment
		(start 73.376028 -184.066688)
		(end 73.376028 -184.681876)
		(width 0.12065)
		(layer "F.Cu")
		(net "SSD_PWREN0")
	)
	(segment
		(start 73.819004 -186.765692)
		(end 73.819004 -185.9026)
		(width 0.12065)
		(layer "F.Cu")
		(net "SSD_PWREN0")
	)
	(via
		(at 74.379074 -185.291476)
		(size 0.7112)
		(drill 0.3556)
		(layers "F.Cu" "B.Cu")
		(net "SSD_PWREN0")
	)
	(segment
		(start 329.073256 -222.37446)
		(end 329.2094 -222.238062)
		(width 0.12065)
		(layer "F.Cu")
		(net "SSD_PRSNT#9_R")
	)
	(segment
		(start 329.2094 -210.874864)
		(end 328.964798 -210.630262)
		(width 0.12065)
		(layer "F.Cu")
		(net "SSD_PRSNT#9_R")
	)
	(segment
		(start 329.210924 -221.72422)
		(end 329.210924 -221.337632)
		(width 0.12065)
		(layer "F.Cu")
		(net "SSD_PRSNT#9_R")
	)
	(segment
		(start 329.2094 -221.336108)
		(end 329.2094 -210.874864)
		(width 0.12065)
		(layer "F.Cu")
		(net "SSD_PRSNT#9_R")
	)
	(segment
		(start 342.1888 -179.457858)
		(end 341.993474 -179.262532)
		(width 0.12065)
		(layer "F.Cu")
		(net "SSD_PRSNT#9_R")
	)
	(segment
		(start 329.2094 -221.725744)
		(end 329.210924 -221.72422)
		(width 0.12065)
		(layer "F.Cu")
		(net "SSD_PRSNT#9_R")
	)
	(segment
		(start 342.052148 -180.908706)
		(end 342.1888 -180.772054)
		(width 0.12065)
		(layer "F.Cu")
		(net "SSD_PRSNT#9_R")
	)
	(segment
		(start 342.1888 -185.394346)
		(end 342.1888 -181.431946)
		(width 0.12065)
		(layer "F.Cu")
		(net "SSD_PRSNT#9_R")
	)
	(segment
		(start 341.993474 -179.262532)
		(end 341.993474 -178.791616)
		(width 0.12065)
		(layer "F.Cu")
		(net "SSD_PRSNT#9_R")
	)
	(segment
		(start 341.993474 -178.791616)
		(end 342.401652 -178.383438)
		(width 0.12065)
		(layer "F.Cu")
		(net "SSD_PRSNT#9_R")
	)
	(segment
		(start 342.401652 -178.383438)
		(end 342.401652 -171.664122)
		(width 0.12065)
		(layer "F.Cu")
		(net "SSD_PRSNT#9_R")
	)
	(segment
		(start 336.836512 -171.987718)
		(end 336.836512 -171.196)
		(width 0.12065)
		(layer "F.Cu")
		(net "SSD_PRSNT#9_R")
	)
	(segment
		(start 342.401652 -171.664122)
		(end 342.076278 -171.338748)
		(width 0.12065)
		(layer "F.Cu")
		(net "SSD_PRSNT#9_R")
	)
	(segment
		(start 328.500232 -224.0026)
		(end 329.073256 -223.429576)
		(width 0.12065)
		(layer "F.Cu")
		(net "SSD_PRSNT#9_R")
	)
	(segment
		(start 340.18728 -187.210446)
		(end 340.3727 -187.210446)
		(width 0.12065)
		(layer "F.Cu")
		(net "SSD_PRSNT#9_R")
	)
	(segment
		(start 342.1888 -180.772054)
		(end 342.1888 -179.457858)
		(width 0.12065)
		(layer "F.Cu")
		(net "SSD_PRSNT#9_R")
	)
	(segment
		(start 340.3727 -187.210446)
		(end 342.1888 -185.394346)
		(width 0.12065)
		(layer "F.Cu")
		(net "SSD_PRSNT#9_R")
	)
	(segment
		(start 342.052148 -181.295294)
		(end 342.052148 -180.908706)
		(width 0.12065)
		(layer "F.Cu")
		(net "SSD_PRSNT#9_R")
	)
	(segment
		(start 329.210924 -221.337632)
		(end 329.2094 -221.336108)
		(width 0.12065)
		(layer "F.Cu")
		(net "SSD_PRSNT#9_R")
	)
	(segment
		(start 342.076278 -171.338748)
		(end 340.502748 -171.338748)
		(width 0.12065)
		(layer "F.Cu")
		(net "SSD_PRSNT#9_R")
	)
	(segment
		(start 328.964798 -198.432928)
		(end 340.18728 -187.210446)
		(width 0.12065)
		(layer "F.Cu")
		(net "SSD_PRSNT#9_R")
	)
	(segment
		(start 328.964798 -210.630262)
		(end 328.964798 -198.432928)
		(width 0.12065)
		(layer "F.Cu")
		(net "SSD_PRSNT#9_R")
	)
	(segment
		(start 340.502748 -171.338748)
		(end 340.36 -171.196)
		(width 0.12065)
		(layer "F.Cu")
		(net "SSD_PRSNT#9_R")
	)
	(segment
		(start 329.2094 -222.238062)
		(end 329.2094 -221.725744)
		(width 0.12065)
		(layer "F.Cu")
		(net "SSD_PRSNT#9_R")
	)
	(segment
		(start 329.073256 -223.429576)
		(end 329.073256 -222.37446)
		(width 0.12065)
		(layer "F.Cu")
		(net "SSD_PRSNT#9_R")
	)
	(segment
		(start 342.1888 -181.431946)
		(end 342.052148 -181.295294)
		(width 0.12065)
		(layer "F.Cu")
		(net "SSD_PRSNT#9_R")
	)
	(segment
		(start 328.500232 -225.54438)
		(end 328.500232 -224.0026)
		(width 0.12065)
		(layer "F.Cu")
		(net "SSD_PRSNT#9_R")
	)
	(via
		(at 336.836512 -171.196)
		(size 0.508)
		(drill 0.254)
		(layers "F.Cu" "B.Cu")
		(net "SSD_PRSNT#9_R")
	)
	(via
		(at 340.36 -171.196)
		(size 0.508)
		(drill 0.254)
		(layers "F.Cu" "B.Cu")
		(net "SSD_PRSNT#9_R")
	)
	(via
		(at 337.82 -170.729148)
		(size 0.7112)
		(drill 0.3556)
		(layers "F.Cu" "B.Cu")
		(net "SSD_PRSNT#9_R")
	)
	(segment
		(start 336.836512 -171.196)
		(end 337.303364 -170.729148)
		(width 0.12065)
		(layer "B.Cu")
		(net "SSD_PRSNT#9_R")
	)
	(segment
		(start 339.893148 -170.729148)
		(end 337.82 -170.729148)
		(width 0.12065)
		(layer "B.Cu")
		(net "SSD_PRSNT#9_R")
	)
	(segment
		(start 337.303364 -170.729148)
		(end 337.82 -170.729148)
		(width 0.12065)
		(layer "B.Cu")
		(net "SSD_PRSNT#9_R")
	)
	(segment
		(start 340.36 -171.196)
		(end 339.893148 -170.729148)
		(width 0.12065)
		(layer "B.Cu")
		(net "SSD_PRSNT#9_R")
	)
	(segment
		(start 336.996532 -173.036738)
		(end 336.836512 -172.876718)
		(width 0.12065)
		(layer "F.Cu")
		(net "SSD_PRSNT#9")
	)
	(segment
		(start 336.160872 -175.251872)
		(end 336.996532 -174.416212)
		(width 0.12065)
		(layer "F.Cu")
		(net "SSD_PRSNT#9")
	)
	(segment
		(start 337.303364 -171.180252)
		(end 337.691984 -170.791632)
		(width 0.12065)
		(layer "F.Cu")
		(net "SSD_PRSNT#9")
	)
	(segment
		(start 336.836512 -172.876718)
		(end 336.836512 -172.864018)
		(width 0.12065)
		(layer "F.Cu")
		(net "SSD_PRSNT#9")
	)
	(segment
		(start 337.691984 -170.791632)
		(end 337.713066 -170.791632)
		(width 0.12065)
		(layer "F.Cu")
		(net "SSD_PRSNT#9")
	)
	(segment
		(start 336.836512 -172.864018)
		(end 337.303364 -172.397166)
		(width 0.12065)
		(layer "F.Cu")
		(net "SSD_PRSNT#9")
	)
	(segment
		(start 336.996532 -174.416212)
		(end 336.996532 -173.036738)
		(width 0.12065)
		(layer "F.Cu")
		(net "SSD_PRSNT#9")
	)
	(segment
		(start 337.303364 -172.397166)
		(end 337.303364 -171.180252)
		(width 0.12065)
		(layer "F.Cu")
		(net "SSD_PRSNT#9")
	)
	(segment
		(start 336.160872 -175.962818)
		(end 336.160872 -175.251872)
		(width 0.12065)
		(layer "F.Cu")
		(net "SSD_PRSNT#9")
	)
	(via
		(at 337.713066 -170.791632)
		(size 0.7112)
		(drill 0.3556)
		(layers "F.Cu" "B.Cu")
		(net "SSD_PRSNT#9")
	)
	(via
		(at 336.996532 -174.416212)
		(size 0.508)
		(drill 0.254)
		(layers "F.Cu" "B.Cu")
		(net "SSD_PRSNT#9")
	)
	(segment
		(start 336.836512 -173.98746)
		(end 336.996532 -174.14748)
		(width 0.12065)
		(layer "B.Cu")
		(net "SSD_PRSNT#9")
	)
	(segment
		(start 336.996532 -174.14748)
		(end 336.996532 -174.416212)
		(width 0.12065)
		(layer "B.Cu")
		(net "SSD_PRSNT#9")
	)
	(segment
		(start 336.836512 -172.876718)
		(end 336.836512 -173.98746)
		(width 0.12065)
		(layer "B.Cu")
		(net "SSD_PRSNT#9")
	)
	(segment
		(start 223.043496 -188.35116)
		(end 223.043496 -188.33211)
		(width 0.12065)
		(layer "F.Cu")
		(net "SSD_PRSNT#8_R")
	)
	(segment
		(start 223.043496 -188.33211)
		(end 223.028256 -188.31687)
		(width 0.12065)
		(layer "F.Cu")
		(net "SSD_PRSNT#8_R")
	)
	(segment
		(start 223.877124 -190.156592)
		(end 223.877124 -189.184788)
		(width 0.12065)
		(layer "F.Cu")
		(net "SSD_PRSNT#8_R")
	)
	(segment
		(start 223.028256 -188.31687)
		(end 223.028256 -186.970924)
		(width 0.12065)
		(layer "F.Cu")
		(net "SSD_PRSNT#8_R")
	)
	(segment
		(start 223.8248 -186.17438)
		(end 223.8248 -183.2102)
		(width 0.12065)
		(layer "F.Cu")
		(net "SSD_PRSNT#8_R")
	)
	(segment
		(start 223.028256 -186.970924)
		(end 223.8248 -186.17438)
		(width 0.12065)
		(layer "F.Cu")
		(net "SSD_PRSNT#8_R")
	)
	(segment
		(start 223.877124 -189.184788)
		(end 223.043496 -188.35116)
		(width 0.12065)
		(layer "F.Cu")
		(net "SSD_PRSNT#8_R")
	)
	(via
		(at 223.8248 -183.2102)
		(size 0.508)
		(drill 0.254)
		(layers "F.Cu" "B.Cu")
		(net "SSD_PRSNT#8_R")
	)
	(via
		(at 223.8248 -181.229)
		(size 0.7112)
		(drill 0.3556)
		(layers "F.Cu" "B.Cu")
		(net "SSD_PRSNT#8_R")
	)
	(segment
		(start 255.669542 -156.97835)
		(end 228.069394 -156.97835)
		(width 0.12065)
		(layer "B.Cu")
		(net "SSD_PRSNT#8_R")
	)
	(segment
		(start 271.290796 -223.231456)
		(end 271.290796 -220.872304)
		(width 0.12065)
		(layer "B.Cu")
		(net "SSD_PRSNT#8_R")
	)
	(segment
		(start 223.8248 -161.222944)
		(end 223.8248 -181.229)
		(width 0.12065)
		(layer "B.Cu")
		(net "SSD_PRSNT#8_R")
	)
	(segment
		(start 270.900144 -225.92538)
		(end 270.900144 -223.622108)
		(width 0.12065)
		(layer "B.Cu")
		(net "SSD_PRSNT#8_R")
	)
	(segment
		(start 223.8248 -183.2102)
		(end 223.8248 -181.229)
		(width 0.12065)
		(layer "B.Cu")
		(net "SSD_PRSNT#8_R")
	)
	(segment
		(start 271.290796 -220.872304)
		(end 261.0866 -210.668108)
		(width 0.12065)
		(layer "B.Cu")
		(net "SSD_PRSNT#8_R")
	)
	(segment
		(start 228.069394 -156.97835)
		(end 223.8248 -161.222944)
		(width 0.12065)
		(layer "B.Cu")
		(net "SSD_PRSNT#8_R")
	)
	(segment
		(start 261.0866 -162.395408)
		(end 255.669542 -156.97835)
		(width 0.12065)
		(layer "B.Cu")
		(net "SSD_PRSNT#8_R")
	)
	(segment
		(start 270.900144 -223.622108)
		(end 271.290796 -223.231456)
		(width 0.12065)
		(layer "B.Cu")
		(net "SSD_PRSNT#8_R")
	)
	(segment
		(start 261.0866 -210.668108)
		(end 261.0866 -162.395408)
		(width 0.12065)
		(layer "B.Cu")
		(net "SSD_PRSNT#8_R")
	)
	(segment
		(start 223.473264 -191.449452)
		(end 223.473264 -191.992758)
		(width 0.12065)
		(layer "F.Cu")
		(net "SSD_PRSNT#8")
	)
	(segment
		(start 223.877124 -191.045592)
		(end 223.473264 -191.449452)
		(width 0.12065)
		(layer "F.Cu")
		(net "SSD_PRSNT#8")
	)
	(segment
		(start 223.88449 -192.945258)
		(end 224.085658 -192.74409)
		(width 0.12065)
		(layer "F.Cu")
		(net "SSD_PRSNT#8")
	)
	(segment
		(start 223.41713 -192.945258)
		(end 223.88449 -192.945258)
		(width 0.12065)
		(layer "F.Cu")
		(net "SSD_PRSNT#8")
	)
	(segment
		(start 223.473264 -192.131696)
		(end 223.473264 -191.992758)
		(width 0.12065)
		(layer "F.Cu")
		(net "SSD_PRSNT#8")
	)
	(segment
		(start 223.201484 -193.160904)
		(end 223.41713 -192.945258)
		(width 0.12065)
		(layer "F.Cu")
		(net "SSD_PRSNT#8")
	)
	(segment
		(start 224.085658 -192.74409)
		(end 223.473264 -192.131696)
		(width 0.12065)
		(layer "F.Cu")
		(net "SSD_PRSNT#8")
	)
	(segment
		(start 223.201484 -194.131692)
		(end 223.201484 -193.160904)
		(width 0.12065)
		(layer "F.Cu")
		(net "SSD_PRSNT#8")
	)
	(via
		(at 223.473264 -191.992758)
		(size 0.7112)
		(drill 0.3556)
		(layers "F.Cu" "B.Cu")
		(net "SSD_PRSNT#8")
	)
	(via
		(at 224.085658 -192.74409)
		(size 0.508)
		(drill 0.254)
		(layers "F.Cu" "B.Cu")
		(net "SSD_PRSNT#8")
	)
	(segment
		(start 224.21215 -191.935608)
		(end 224.21215 -192.58915)
		(width 0.12065)
		(layer "B.Cu")
		(net "SSD_PRSNT#8")
	)
	(segment
		(start 224.867724 -191.280034)
		(end 224.21215 -191.935608)
		(width 0.12065)
		(layer "B.Cu")
		(net "SSD_PRSNT#8")
	)
	(segment
		(start 224.086166 -192.74409)
		(end 224.085658 -192.74409)
		(width 0.12065)
		(layer "B.Cu")
		(net "SSD_PRSNT#8")
	)
	(segment
		(start 224.086166 -192.715134)
		(end 224.086166 -192.74409)
		(width 0.12065)
		(layer "B.Cu")
		(net "SSD_PRSNT#8")
	)
	(segment
		(start 224.867724 -191.045592)
		(end 224.867724 -191.280034)
		(width 0.12065)
		(layer "B.Cu")
		(net "SSD_PRSNT#8")
	)
	(segment
		(start 224.21215 -192.58915)
		(end 224.086166 -192.715134)
		(width 0.12065)
		(layer "B.Cu")
		(net "SSD_PRSNT#8")
	)
	(segment
		(start 178.973226 -209.981038)
		(end 180.97373 -207.980534)
		(width 0.12065)
		(layer "F.Cu")
		(net "SSD_PRSNT#7_R")
	)
	(segment
		(start 178.500024 -225.54438)
		(end 178.500024 -224.097088)
		(width 0.12065)
		(layer "F.Cu")
		(net "SSD_PRSNT#7_R")
	)
	(segment
		(start 178.973226 -218.673426)
		(end 178.973226 -209.981038)
		(width 0.12065)
		(layer "F.Cu")
		(net "SSD_PRSNT#7_R")
	)
	(segment
		(start 178.500024 -224.097088)
		(end 178.071272 -223.668336)
		(width 0.12065)
		(layer "F.Cu")
		(net "SSD_PRSNT#7_R")
	)
	(segment
		(start 179.3494 -220.9038)
		(end 179.3494 -219.0496)
		(width 0.12065)
		(layer "F.Cu")
		(net "SSD_PRSNT#7_R")
	)
	(segment
		(start 178.071272 -223.668336)
		(end 178.071272 -222.181928)
		(width 0.12065)
		(layer "F.Cu")
		(net "SSD_PRSNT#7_R")
	)
	(segment
		(start 131.084066 -209.3214)
		(end 130.220466 -210.185)
		(width 0.12065)
		(layer "F.Cu")
		(net "SSD_PRSNT#7_R")
	)
	(segment
		(start 180.97373 -207.980534)
		(end 180.97373 -207.31353)
		(width 0.12065)
		(layer "F.Cu")
		(net "SSD_PRSNT#7_R")
	)
	(segment
		(start 178.071272 -222.181928)
		(end 179.3494 -220.9038)
		(width 0.12065)
		(layer "F.Cu")
		(net "SSD_PRSNT#7_R")
	)
	(segment
		(start 131.236466 -209.3214)
		(end 131.084066 -209.3214)
		(width 0.12065)
		(layer "F.Cu")
		(net "SSD_PRSNT#7_R")
	)
	(segment
		(start 179.3494 -219.0496)
		(end 178.973226 -218.673426)
		(width 0.12065)
		(layer "F.Cu")
		(net "SSD_PRSNT#7_R")
	)
	(via
		(at 174.805848 -201.145648)
		(size 0.7112)
		(drill 0.3556)
		(layers "F.Cu" "B.Cu")
		(net "SSD_PRSNT#7_R")
	)
	(via
		(at 180.97373 -207.31353)
		(size 0.508)
		(drill 0.254)
		(layers "F.Cu" "B.Cu")
		(net "SSD_PRSNT#7_R")
	)
	(via
		(at 130.220466 -210.185)
		(size 0.508)
		(drill 0.254)
		(layers "F.Cu" "B.Cu")
		(net "SSD_PRSNT#7_R")
	)
	(segment
		(start 135.050276 -210.575652)
		(end 130.611118 -210.575652)
		(width 0.12065)
		(layer "B.Cu")
		(net "SSD_PRSNT#7_R")
	)
	(segment
		(start 168.503346 -194.843146)
		(end 150.782782 -194.843146)
		(width 0.12065)
		(layer "B.Cu")
		(net "SSD_PRSNT#7_R")
	)
	(segment
		(start 150.782782 -194.843146)
		(end 135.050276 -210.575652)
		(width 0.12065)
		(layer "B.Cu")
		(net "SSD_PRSNT#7_R")
	)
	(segment
		(start 180.97373 -207.31353)
		(end 174.805848 -201.145648)
		(width 0.12065)
		(layer "B.Cu")
		(net "SSD_PRSNT#7_R")
	)
	(segment
		(start 174.805848 -201.145648)
		(end 168.503346 -194.843146)
		(width 0.12065)
		(layer "B.Cu")
		(net "SSD_PRSNT#7_R")
	)
	(segment
		(start 130.611118 -210.575652)
		(end 130.220466 -210.185)
		(width 0.12065)
		(layer "B.Cu")
		(net "SSD_PRSNT#7_R")
	)
	(segment
		(start 131.006088 -208.4324)
		(end 130.551936 -207.978248)
		(width 0.12065)
		(layer "F.Cu")
		(net "SSD_PRSNT#7")
	)
	(segment
		(start 130.543554 -207.978248)
		(end 130.229864 -207.664558)
		(width 0.12065)
		(layer "F.Cu")
		(net "SSD_PRSNT#7")
	)
	(segment
		(start 129.348484 -205.612492)
		(end 129.348484 -206.854806)
		(width 0.12065)
		(layer "F.Cu")
		(net "SSD_PRSNT#7")
	)
	(segment
		(start 129.348484 -206.854806)
		(end 129.50317 -207.009492)
		(width 0.12065)
		(layer "F.Cu")
		(net "SSD_PRSNT#7")
	)
	(segment
		(start 130.14706 -207.653382)
		(end 129.50317 -207.009492)
		(width 0.12065)
		(layer "F.Cu")
		(net "SSD_PRSNT#7")
	)
	(segment
		(start 131.236466 -208.4324)
		(end 131.006088 -208.4324)
		(width 0.12065)
		(layer "F.Cu")
		(net "SSD_PRSNT#7")
	)
	(segment
		(start 130.229864 -207.66532)
		(end 130.217926 -207.653382)
		(width 0.12065)
		(layer "F.Cu")
		(net "SSD_PRSNT#7")
	)
	(segment
		(start 130.229864 -207.664558)
		(end 130.229864 -207.66532)
		(width 0.12065)
		(layer "F.Cu")
		(net "SSD_PRSNT#7")
	)
	(segment
		(start 130.229864 -207.664558)
		(end 130.229864 -207.6577)
		(width 0.12065)
		(layer "F.Cu")
		(net "SSD_PRSNT#7")
	)
	(segment
		(start 130.551936 -207.978248)
		(end 130.543554 -207.978248)
		(width 0.12065)
		(layer "F.Cu")
		(net "SSD_PRSNT#7")
	)
	(segment
		(start 130.217926 -207.653382)
		(end 130.14706 -207.653382)
		(width 0.12065)
		(layer "F.Cu")
		(net "SSD_PRSNT#7")
	)
	(via
		(at 129.50317 -207.009492)
		(size 0.7112)
		(drill 0.3556)
		(layers "F.Cu" "B.Cu")
		(net "SSD_PRSNT#7")
	)
	(via
		(at 130.229864 -207.6577)
		(size 0.508)
		(drill 0.254)
		(layers "F.Cu" "B.Cu")
		(net "SSD_PRSNT#7")
	)
	(segment
		(start 130.220466 -207.792066)
		(end 130.218688 -207.790288)
		(width 0.12065)
		(layer "B.Cu")
		(net "SSD_PRSNT#7")
	)
	(segment
		(start 130.218688 -207.676496)
		(end 130.229864 -207.66532)
		(width 0.12065)
		(layer "B.Cu")
		(net "SSD_PRSNT#7")
	)
	(segment
		(start 130.229864 -207.66532)
		(end 130.229864 -207.6577)
		(width 0.12065)
		(layer "B.Cu")
		(net "SSD_PRSNT#7")
	)
	(segment
		(start 130.220466 -208.4324)
		(end 130.220466 -207.792066)
		(width 0.12065)
		(layer "B.Cu")
		(net "SSD_PRSNT#7")
	)
	(segment
		(start 130.218688 -207.790288)
		(end 130.218688 -207.676496)
		(width 0.12065)
		(layer "B.Cu")
		(net "SSD_PRSNT#7")
	)
	(segment
		(start 137.2108 -210.4136)
		(end 137.2108 -212.6488)
		(width 0.12065)
		(layer "F.Cu")
		(net "SSD_PRSNT#6_R")
	)
	(segment
		(start 136.02716 -221.373954)
		(end 137.2108 -220.190314)
		(width 0.12065)
		(layer "F.Cu")
		(net "SSD_PRSNT#6_R")
	)
	(segment
		(start 137.2108 -220.190314)
		(end 137.2108 -212.6488)
		(width 0.12065)
		(layer "F.Cu")
		(net "SSD_PRSNT#6_R")
	)
	(segment
		(start 136.130792 -209.333592)
		(end 137.2108 -210.4136)
		(width 0.12065)
		(layer "F.Cu")
		(net "SSD_PRSNT#6_R")
	)
	(segment
		(start 136.900158 -225.54438)
		(end 136.900158 -224.453958)
		(width 0.12065)
		(layer "F.Cu")
		(net "SSD_PRSNT#6_R")
	)
	(segment
		(start 136.02716 -223.58096)
		(end 136.02716 -221.373954)
		(width 0.12065)
		(layer "F.Cu")
		(net "SSD_PRSNT#6_R")
	)
	(segment
		(start 135.358124 -209.333592)
		(end 136.130792 -209.333592)
		(width 0.12065)
		(layer "F.Cu")
		(net "SSD_PRSNT#6_R")
	)
	(segment
		(start 136.900158 -224.453958)
		(end 136.02716 -223.58096)
		(width 0.12065)
		(layer "F.Cu")
		(net "SSD_PRSNT#6_R")
	)
	(via
		(at 137.2108 -212.6488)
		(size 0.7112)
		(drill 0.3556)
		(layers "F.Cu" "B.Cu")
		(net "SSD_PRSNT#6_R")
	)
	(segment
		(start 135.358124 -208.444592)
		(end 135.116824 -208.444592)
		(width 0.12065)
		(layer "F.Cu")
		(net "SSD_PRSNT#6")
	)
	(segment
		(start 131.949444 -205.612492)
		(end 132.181092 -205.612492)
		(width 0.12065)
		(layer "F.Cu")
		(net "SSD_PRSNT#6")
	)
	(segment
		(start 134.1374 -207.5688)
		(end 134.138924 -207.5688)
		(width 0.12065)
		(layer "F.Cu")
		(net "SSD_PRSNT#6")
	)
	(segment
		(start 132.181092 -205.612492)
		(end 134.1374 -207.5688)
		(width 0.12065)
		(layer "F.Cu")
		(net "SSD_PRSNT#6")
	)
	(segment
		(start 134.240016 -207.669892)
		(end 134.342124 -207.669892)
		(width 0.12065)
		(layer "F.Cu")
		(net "SSD_PRSNT#6")
	)
	(segment
		(start 134.138924 -207.5688)
		(end 134.240016 -207.669892)
		(width 0.12065)
		(layer "F.Cu")
		(net "SSD_PRSNT#6")
	)
	(segment
		(start 135.116824 -208.444592)
		(end 134.342124 -207.669892)
		(width 0.12065)
		(layer "F.Cu")
		(net "SSD_PRSNT#6")
	)
	(via
		(at 135.256524 -208.28)
		(size 0.7112)
		(drill 0.3556)
		(layers "F.Cu" "B.Cu")
		(net "SSD_PRSNT#6")
	)
	(via
		(at 134.342124 -207.669892)
		(size 0.508)
		(drill 0.254)
		(layers "F.Cu" "B.Cu")
		(net "SSD_PRSNT#6")
	)
	(segment
		(start 134.367016 -207.645)
		(end 135.128 -207.645)
		(width 0.12065)
		(layer "B.Cu")
		(net "SSD_PRSNT#6")
	)
	(segment
		(start 135.128 -207.645)
		(end 135.256524 -207.773524)
		(width 0.12065)
		(layer "B.Cu")
		(net "SSD_PRSNT#6")
	)
	(segment
		(start 135.091932 -208.444592)
		(end 135.256524 -208.28)
		(width 0.12065)
		(layer "B.Cu")
		(net "SSD_PRSNT#6")
	)
	(segment
		(start 135.256524 -207.773524)
		(end 135.256524 -208.28)
		(width 0.12065)
		(layer "B.Cu")
		(net "SSD_PRSNT#6")
	)
	(segment
		(start 134.342124 -207.669892)
		(end 134.367016 -207.645)
		(width 0.12065)
		(layer "B.Cu")
		(net "SSD_PRSNT#6")
	)
	(segment
		(start 134.342124 -208.444592)
		(end 135.091932 -208.444592)
		(width 0.12065)
		(layer "B.Cu")
		(net "SSD_PRSNT#6")
	)
	(segment
		(start 75.795124 -182.790592)
		(end 75.795124 -179.324)
		(width 0.12065)
		(layer "F.Cu")
		(net "SSD_PRSNT#5_R")
	)
	(via
		(at 65.015872 -179.332128)
		(size 0.7112)
		(drill 0.3556)
		(layers "F.Cu" "B.Cu")
		(net "SSD_PRSNT#5_R")
	)
	(via
		(at 75.795124 -179.324)
		(size 0.508)
		(drill 0.254)
		(layers "F.Cu" "B.Cu")
		(net "SSD_PRSNT#5_R")
	)
	(segment
		(start 75.048872 -178.577748)
		(end 65.770252 -178.577748)
		(width 0.12065)
		(layer "B.Cu")
		(net "SSD_PRSNT#5_R")
	)
	(segment
		(start 62.785498 -181.562502)
		(end 65.015872 -179.332128)
		(width 0.12065)
		(layer "B.Cu")
		(net "SSD_PRSNT#5_R")
	)
	(segment
		(start 62.785498 -223.237298)
		(end 62.785498 -181.562502)
		(width 0.12065)
		(layer "B.Cu")
		(net "SSD_PRSNT#5_R")
	)
	(segment
		(start 75.795124 -179.324)
		(end 75.048872 -178.577748)
		(width 0.12065)
		(layer "B.Cu")
		(net "SSD_PRSNT#5_R")
	)
	(segment
		(start 63.700152 -225.92538)
		(end 63.700152 -224.151952)
		(width 0.12065)
		(layer "B.Cu")
		(net "SSD_PRSNT#5_R")
	)
	(segment
		(start 63.700152 -224.151952)
		(end 62.785498 -223.237298)
		(width 0.12065)
		(layer "B.Cu")
		(net "SSD_PRSNT#5_R")
	)
	(segment
		(start 65.770252 -178.577748)
		(end 65.015872 -179.332128)
		(width 0.12065)
		(layer "B.Cu")
		(net "SSD_PRSNT#5_R")
	)
	(segment
		(start 75.795124 -185.009028)
		(end 75.84948 -185.063384)
		(width 0.12065)
		(layer "F.Cu")
		(net "SSD_PRSNT#5")
	)
	(segment
		(start 75.84948 -185.32475)
		(end 75.84948 -185.063384)
		(width 0.12065)
		(layer "F.Cu")
		(net "SSD_PRSNT#5")
	)
	(segment
		(start 75.795124 -183.679592)
		(end 75.795124 -185.009028)
		(width 0.12065)
		(layer "F.Cu")
		(net "SSD_PRSNT#5")
	)
	(segment
		(start 75.119484 -186.765692)
		(end 75.119484 -186.054746)
		(width 0.12065)
		(layer "F.Cu")
		(net "SSD_PRSNT#5")
	)
	(segment
		(start 75.119484 -186.054746)
		(end 75.84948 -185.32475)
		(width 0.12065)
		(layer "F.Cu")
		(net "SSD_PRSNT#5")
	)
	(via
		(at 76.708 -185.547)
		(size 0.7112)
		(drill 0.3556)
		(layers "F.Cu" "B.Cu")
		(net "SSD_PRSNT#5")
	)
	(via
		(at 75.84948 -185.063384)
		(size 0.508)
		(drill 0.254)
		(layers "F.Cu" "B.Cu")
		(net "SSD_PRSNT#5")
	)
	(segment
		(start 75.832716 -185.04662)
		(end 75.84948 -185.063384)
		(width 0.12065)
		(layer "B.Cu")
		(net "SSD_PRSNT#5")
	)
	(segment
		(start 75.832716 -183.683402)
		(end 75.832716 -185.04662)
		(width 0.12065)
		(layer "B.Cu")
		(net "SSD_PRSNT#5")
	)
	(segment
		(start 76.333096 -185.547)
		(end 76.708 -185.547)
		(width 0.12065)
		(layer "B.Cu")
		(net "SSD_PRSNT#5")
	)
	(segment
		(start 75.84948 -185.063384)
		(end 76.333096 -185.547)
		(width 0.12065)
		(layer "B.Cu")
		(net "SSD_PRSNT#5")
	)
	(segment
		(start 332.360524 -171.58843)
		(end 332.360524 -169.088054)
		(width 0.12065)
		(layer "F.Cu")
		(net "SSD_PRSNT#4_R")
	)
	(segment
		(start 332.772512 -171.987718)
		(end 332.759812 -171.987718)
		(width 0.12065)
		(layer "F.Cu")
		(net "SSD_PRSNT#4_R")
	)
	(segment
		(start 332.360524 -169.088054)
		(end 332.792578 -168.656)
		(width 0.12065)
		(layer "F.Cu")
		(net "SSD_PRSNT#4_R")
	)
	(segment
		(start 332.759812 -171.987718)
		(end 332.360524 -171.58843)
		(width 0.12065)
		(layer "F.Cu")
		(net "SSD_PRSNT#4_R")
	)
	(via
		(at 298.891452 -204.851)
		(size 0.7112)
		(drill 0.3556)
		(layers "F.Cu" "B.Cu")
		(net "SSD_PRSNT#4_R")
	)
	(via
		(at 332.792578 -168.656)
		(size 0.508)
		(drill 0.254)
		(layers "F.Cu" "B.Cu")
		(net "SSD_PRSNT#4_R")
	)
	(segment
		(start 332.325726 -168.189148)
		(end 327.487788 -168.189148)
		(width 0.12065)
		(layer "B.Cu")
		(net "SSD_PRSNT#4_R")
	)
	(segment
		(start 297.985688 -208.947258)
		(end 298.891452 -208.041494)
		(width 0.12065)
		(layer "B.Cu")
		(net "SSD_PRSNT#4_R")
	)
	(segment
		(start 298.900088 -216.459816)
		(end 297.985688 -215.545416)
		(width 0.12065)
		(layer "B.Cu")
		(net "SSD_PRSNT#4_R")
	)
	(segment
		(start 298.891452 -208.041494)
		(end 298.891452 -204.851)
		(width 0.12065)
		(layer "B.Cu")
		(net "SSD_PRSNT#4_R")
	)
	(segment
		(start 297.985688 -215.545416)
		(end 297.985688 -208.947258)
		(width 0.12065)
		(layer "B.Cu")
		(net "SSD_PRSNT#4_R")
	)
	(segment
		(start 298.900088 -225.92538)
		(end 298.900088 -216.459816)
		(width 0.12065)
		(layer "B.Cu")
		(net "SSD_PRSNT#4_R")
	)
	(segment
		(start 298.891452 -196.785484)
		(end 298.891452 -204.851)
		(width 0.12065)
		(layer "B.Cu")
		(net "SSD_PRSNT#4_R")
	)
	(segment
		(start 332.792578 -168.656)
		(end 332.325726 -168.189148)
		(width 0.12065)
		(layer "B.Cu")
		(net "SSD_PRSNT#4_R")
	)
	(segment
		(start 327.487788 -168.189148)
		(end 298.891452 -196.785484)
		(width 0.12065)
		(layer "B.Cu")
		(net "SSD_PRSNT#4_R")
	)
	(segment
		(start 333.239364 -172.43044)
		(end 333.239364 -171.20489)
		(width 0.12065)
		(layer "F.Cu")
		(net "SSD_PRSNT#4")
	)
	(segment
		(start 333.559912 -175.962818)
		(end 333.559912 -174.588678)
		(width 0.12065)
		(layer "F.Cu")
		(net "SSD_PRSNT#4")
	)
	(segment
		(start 332.772512 -172.876718)
		(end 332.793086 -172.876718)
		(width 0.12065)
		(layer "F.Cu")
		(net "SSD_PRSNT#4")
	)
	(segment
		(start 333.239364 -171.20489)
		(end 332.998318 -170.963844)
		(width 0.12065)
		(layer "F.Cu")
		(net "SSD_PRSNT#4")
	)
	(segment
		(start 333.281528 -173.810422)
		(end 332.772512 -173.301406)
		(width 0.12065)
		(layer "F.Cu")
		(net "SSD_PRSNT#4")
	)
	(segment
		(start 333.559912 -174.588678)
		(end 333.281528 -174.310294)
		(width 0.12065)
		(layer "F.Cu")
		(net "SSD_PRSNT#4")
	)
	(segment
		(start 332.793086 -172.876718)
		(end 333.239364 -172.43044)
		(width 0.12065)
		(layer "F.Cu")
		(net "SSD_PRSNT#4")
	)
	(segment
		(start 332.772512 -173.301406)
		(end 332.772512 -172.876718)
		(width 0.12065)
		(layer "F.Cu")
		(net "SSD_PRSNT#4")
	)
	(segment
		(start 333.281528 -174.310294)
		(end 333.281528 -173.810422)
		(width 0.12065)
		(layer "F.Cu")
		(net "SSD_PRSNT#4")
	)
	(via
		(at 332.998318 -170.963844)
		(size 0.7112)
		(drill 0.3556)
		(layers "F.Cu" "B.Cu")
		(net "SSD_PRSNT#4")
	)
	(via
		(at 333.281528 -173.810422)
		(size 0.508)
		(drill 0.254)
		(layers "F.Cu" "B.Cu")
		(net "SSD_PRSNT#4")
	)
	(segment
		(start 332.772512 -173.387512)
		(end 333.195422 -173.810422)
		(width 0.12065)
		(layer "B.Cu")
		(net "SSD_PRSNT#4")
	)
	(segment
		(start 332.772512 -172.876718)
		(end 332.772512 -173.387512)
		(width 0.12065)
		(layer "B.Cu")
		(net "SSD_PRSNT#4")
	)
	(segment
		(start 333.195422 -173.810422)
		(end 333.281528 -173.810422)
		(width 0.12065)
		(layer "B.Cu")
		(net "SSD_PRSNT#4")
	)
	(segment
		(start 208.900014 -191.439038)
		(end 211.603844 -188.735208)
		(width 0.12065)
		(layer "F.Cu")
		(net "SSD_PRSNT#3_R")
	)
	(segment
		(start 219.813124 -190.156592)
		(end 219.813124 -189.381892)
		(width 0.12065)
		(layer "F.Cu")
		(net "SSD_PRSNT#3_R")
	)
	(segment
		(start 212.598 -186.817)
		(end 212.598 -187.741052)
		(width 0.12065)
		(layer "F.Cu")
		(net "SSD_PRSNT#3_R")
	)
	(segment
		(start 212.598 -187.741052)
		(end 211.603844 -188.735208)
		(width 0.12065)
		(layer "F.Cu")
		(net "SSD_PRSNT#3_R")
	)
	(segment
		(start 208.900014 -225.54438)
		(end 208.900014 -191.439038)
		(width 0.12065)
		(layer "F.Cu")
		(net "SSD_PRSNT#3_R")
	)
	(via
		(at 212.598 -186.817)
		(size 0.508)
		(drill 0.254)
		(layers "F.Cu" "B.Cu")
		(net "SSD_PRSNT#3_R")
	)
	(via
		(at 219.813124 -189.381892)
		(size 0.508)
		(drill 0.254)
		(layers "F.Cu" "B.Cu")
		(net "SSD_PRSNT#3_R")
	)
	(via
		(at 211.603844 -188.735208)
		(size 0.7112)
		(drill 0.3556)
		(layers "F.Cu" "B.Cu")
		(net "SSD_PRSNT#3_R")
	)
	(segment
		(start 212.598 -186.944)
		(end 212.598 -186.817)
		(width 0.127)
		(layer "In2.Cu")
		(net "SSD_PRSNT#3_R")
	)
	(segment
		(start 219.813124 -189.381892)
		(end 218.480132 -188.0489)
		(width 0.127)
		(layer "In2.Cu")
		(net "SSD_PRSNT#3_R")
	)
	(segment
		(start 213.7029 -188.0489)
		(end 212.598 -186.944)
		(width 0.127)
		(layer "In2.Cu")
		(net "SSD_PRSNT#3_R")
	)
	(segment
		(start 218.480132 -188.0489)
		(end 213.7029 -188.0489)
		(width 0.127)
		(layer "In2.Cu")
		(net "SSD_PRSNT#3_R")
	)
	(segment
		(start 220.600524 -194.131692)
		(end 220.600524 -193.521838)
		(width 0.12065)
		(layer "F.Cu")
		(net "SSD_PRSNT#3")
	)
	(segment
		(start 220.600524 -193.521838)
		(end 220.224096 -193.14541)
		(width 0.12065)
		(layer "F.Cu")
		(net "SSD_PRSNT#3")
	)
	(segment
		(start 220.224096 -193.14541)
		(end 220.224096 -192.07734)
		(width 0.12065)
		(layer "F.Cu")
		(net "SSD_PRSNT#3")
	)
	(segment
		(start 220.224096 -192.07734)
		(end 220.32214 -191.979296)
		(width 0.12065)
		(layer "F.Cu")
		(net "SSD_PRSNT#3")
	)
	(segment
		(start 219.813124 -191.302386)
		(end 220.32214 -191.811402)
		(width 0.12065)
		(layer "F.Cu")
		(net "SSD_PRSNT#3")
	)
	(segment
		(start 220.32214 -191.811402)
		(end 220.32214 -191.979296)
		(width 0.12065)
		(layer "F.Cu")
		(net "SSD_PRSNT#3")
	)
	(segment
		(start 219.813124 -191.045592)
		(end 219.813124 -191.302386)
		(width 0.12065)
		(layer "F.Cu")
		(net "SSD_PRSNT#3")
	)
	(via
		(at 219.548964 -192.5574)
		(size 0.7112)
		(drill 0.3556)
		(layers "F.Cu" "B.Cu")
		(net "SSD_PRSNT#3")
	)
	(via
		(at 220.32214 -191.979296)
		(size 0.508)
		(drill 0.254)
		(layers "F.Cu" "B.Cu")
		(net "SSD_PRSNT#3")
	)
	(segment
		(start 220.32214 -191.979296)
		(end 219.744036 -192.5574)
		(width 0.12065)
		(layer "B.Cu")
		(net "SSD_PRSNT#3")
	)
	(segment
		(start 219.548964 -191.182752)
		(end 219.548964 -192.5574)
		(width 0.12065)
		(layer "B.Cu")
		(net "SSD_PRSNT#3")
	)
	(segment
		(start 219.686124 -191.045592)
		(end 219.548964 -191.182752)
		(width 0.12065)
		(layer "B.Cu")
		(net "SSD_PRSNT#3")
	)
	(segment
		(start 219.744036 -192.5574)
		(end 219.548964 -192.5574)
		(width 0.12065)
		(layer "B.Cu")
		(net "SSD_PRSNT#3")
	)
	(segment
		(start 139.03833 -193.344292)
		(end 139.044172 -193.33845)
		(width 0.12065)
		(layer "F.Cu")
		(net "SSD_PRSNT#2_R")
	)
	(segment
		(start 130.024124 -195.998592)
		(end 130.546348 -195.476368)
		(width 0.12065)
		(layer "F.Cu")
		(net "SSD_PRSNT#2_R")
	)
	(segment
		(start 163.674552 -210.943952)
		(end 156.068776 -203.338176)
		(width 0.12065)
		(layer "F.Cu")
		(net "SSD_PRSNT#2_R")
	)
	(segment
		(start 130.9751 -194.515486)
		(end 130.9751 -194.183)
		(width 0.12065)
		(layer "F.Cu")
		(net "SSD_PRSNT#2_R")
	)
	(segment
		(start 163.3601 -218.927172)
		(end 163.674552 -218.61272)
		(width 0.12065)
		(layer "F.Cu")
		(net "SSD_PRSNT#2_R")
	)
	(segment
		(start 139.044172 -193.33845)
		(end 146.06905 -193.33845)
		(width 0.12065)
		(layer "F.Cu")
		(net "SSD_PRSNT#2_R")
	)
	(segment
		(start 163.300156 -225.54438)
		(end 163.300156 -223.642174)
		(width 0.12065)
		(layer "F.Cu")
		(net "SSD_PRSNT#2_R")
	)
	(segment
		(start 130.546348 -194.944238)
		(end 130.9751 -194.515486)
		(width 0.12065)
		(layer "F.Cu")
		(net "SSD_PRSNT#2_R")
	)
	(segment
		(start 163.674552 -223.267778)
		(end 163.674552 -222.756222)
		(width 0.12065)
		(layer "F.Cu")
		(net "SSD_PRSNT#2_R")
	)
	(segment
		(start 163.3601 -222.44177)
		(end 163.3601 -218.927172)
		(width 0.12065)
		(layer "F.Cu")
		(net "SSD_PRSNT#2_R")
	)
	(segment
		(start 163.674552 -218.61272)
		(end 163.674552 -210.943952)
		(width 0.12065)
		(layer "F.Cu")
		(net "SSD_PRSNT#2_R")
	)
	(segment
		(start 163.300156 -223.642174)
		(end 163.674552 -223.267778)
		(width 0.12065)
		(layer "F.Cu")
		(net "SSD_PRSNT#2_R")
	)
	(segment
		(start 163.674552 -222.756222)
		(end 163.3601 -222.44177)
		(width 0.12065)
		(layer "F.Cu")
		(net "SSD_PRSNT#2_R")
	)
	(segment
		(start 146.06905 -193.33845)
		(end 156.068776 -203.338176)
		(width 0.12065)
		(layer "F.Cu")
		(net "SSD_PRSNT#2_R")
	)
	(segment
		(start 130.546348 -195.476368)
		(end 130.546348 -194.944238)
		(width 0.12065)
		(layer "F.Cu")
		(net "SSD_PRSNT#2_R")
	)
	(via
		(at 156.068776 -203.338176)
		(size 0.7112)
		(drill 0.3556)
		(layers "F.Cu" "B.Cu")
		(net "SSD_PRSNT#2_R")
	)
	(via
		(at 130.9751 -194.183)
		(size 0.508)
		(drill 0.254)
		(layers "F.Cu" "B.Cu")
		(net "SSD_PRSNT#2_R")
	)
	(via
		(at 139.03833 -193.344292)
		(size 0.508)
		(drill 0.254)
		(layers "F.Cu" "B.Cu")
		(net "SSD_PRSNT#2_R")
	)
	(segment
		(start 131.8133 -195.6435)
		(end 132.3721 -195.6435)
		(width 0.127)
		(layer "In2.Cu")
		(net "SSD_PRSNT#2_R")
	)
	(segment
		(start 138.43 -194.31)
		(end 139.03833 -193.70167)
		(width 0.127)
		(layer "In2.Cu")
		(net "SSD_PRSNT#2_R")
	)
	(segment
		(start 131.546092 -195.376292)
		(end 131.8133 -195.6435)
		(width 0.127)
		(layer "In2.Cu")
		(net "SSD_PRSNT#2_R")
	)
	(segment
		(start 130.9751 -194.183)
		(end 131.546092 -194.753992)
		(width 0.127)
		(layer "In2.Cu")
		(net "SSD_PRSNT#2_R")
	)
	(segment
		(start 132.3721 -195.6435)
		(end 133.7056 -194.31)
		(width 0.127)
		(layer "In2.Cu")
		(net "SSD_PRSNT#2_R")
	)
	(segment
		(start 133.7056 -194.31)
		(end 138.43 -194.31)
		(width 0.127)
		(layer "In2.Cu")
		(net "SSD_PRSNT#2_R")
	)
	(segment
		(start 139.03833 -193.70167)
		(end 139.03833 -193.344292)
		(width 0.127)
		(layer "In2.Cu")
		(net "SSD_PRSNT#2_R")
	)
	(segment
		(start 131.546092 -194.753992)
		(end 131.546092 -195.376292)
		(width 0.127)
		(layer "In2.Cu")
		(net "SSD_PRSNT#2_R")
	)
	(segment
		(start 129.916936 -197.74281)
		(end 129.748788 -197.910958)
		(width 0.12065)
		(layer "F.Cu")
		(net "SSD_PRSNT#2")
	)
	(segment
		(start 130.024124 -197.635622)
		(end 129.916936 -197.74281)
		(width 0.12065)
		(layer "F.Cu")
		(net "SSD_PRSNT#2")
	)
	(segment
		(start 129.348484 -198.485506)
		(end 129.348484 -198.5518)
		(width 0.12065)
		(layer "F.Cu")
		(net "SSD_PRSNT#2")
	)
	(segment
		(start 129.748788 -198.085202)
		(end 129.348484 -198.485506)
		(width 0.12065)
		(layer "F.Cu")
		(net "SSD_PRSNT#2")
	)
	(segment
		(start 130.024124 -196.887592)
		(end 130.024124 -197.635622)
		(width 0.12065)
		(layer "F.Cu")
		(net "SSD_PRSNT#2")
	)
	(segment
		(start 129.748788 -197.910958)
		(end 129.748788 -198.085202)
		(width 0.12065)
		(layer "F.Cu")
		(net "SSD_PRSNT#2")
	)
	(segment
		(start 129.348484 -199.973692)
		(end 129.348484 -198.5518)
		(width 0.12065)
		(layer "F.Cu")
		(net "SSD_PRSNT#2")
	)
	(via
		(at 129.916936 -197.74281)
		(size 0.508)
		(drill 0.254)
		(layers "F.Cu" "B.Cu")
		(net "SSD_PRSNT#2")
	)
	(via
		(at 129.348484 -198.5518)
		(size 0.7112)
		(drill 0.3556)
		(layers "F.Cu" "B.Cu")
		(net "SSD_PRSNT#2")
	)
	(segment
		(start 130.301746 -197.358)
		(end 129.916936 -197.74281)
		(width 0.12065)
		(layer "B.Cu")
		(net "SSD_PRSNT#2")
	)
	(segment
		(start 131.4323 -196.8373)
		(end 130.9116 -197.358)
		(width 0.12065)
		(layer "B.Cu")
		(net "SSD_PRSNT#2")
	)
	(segment
		(start 130.9116 -197.358)
		(end 130.301746 -197.358)
		(width 0.12065)
		(layer "B.Cu")
		(net "SSD_PRSNT#2")
	)
	(segment
		(start 131.5212 -196.8373)
		(end 131.4323 -196.8373)
		(width 0.12065)
		(layer "B.Cu")
		(net "SSD_PRSNT#2")
	)
	(segment
		(start 330.900024 -223.94037)
		(end 330.190348 -223.230694)
		(width 0.12065)
		(layer "F.Cu")
		(net "SSD_PRSNT#14_R")
	)
	(segment
		(start 330.850748 -198.231252)
		(end 340.487 -188.595)
		(width 0.12065)
		(layer "F.Cu")
		(net "SSD_PRSNT#14_R")
	)
	(segment
		(start 330.327 -210.667854)
		(end 331.987652 -209.006948)
		(width 0.12065)
		(layer "F.Cu")
		(net "SSD_PRSNT#14_R")
	)
	(segment
		(start 330.850748 -203.012548)
		(end 330.850748 -198.231252)
		(width 0.12065)
		(layer "F.Cu")
		(net "SSD_PRSNT#14_R")
	)
	(segment
		(start 330.190348 -222.844106)
		(end 330.322682 -222.711772)
		(width 0.12065)
		(layer "F.Cu")
		(net "SSD_PRSNT#14_R")
	)
	(segment
		(start 330.322682 -222.711772)
		(end 330.322682 -210.68919)
		(width 0.12065)
		(layer "F.Cu")
		(net "SSD_PRSNT#14_R")
	)
	(segment
		(start 330.322682 -210.68919)
		(end 330.327 -210.667854)
		(width 0.12065)
		(layer "F.Cu")
		(net "SSD_PRSNT#14_R")
	)
	(segment
		(start 330.190348 -223.230694)
		(end 330.190348 -222.844106)
		(width 0.12065)
		(layer "F.Cu")
		(net "SSD_PRSNT#14_R")
	)
	(segment
		(start 330.900024 -225.54438)
		(end 330.900024 -223.94037)
		(width 0.12065)
		(layer "F.Cu")
		(net "SSD_PRSNT#14_R")
	)
	(segment
		(start 331.987652 -209.006948)
		(end 331.987652 -204.149452)
		(width 0.12065)
		(layer "F.Cu")
		(net "SSD_PRSNT#14_R")
	)
	(segment
		(start 339.884512 -185.322718)
		(end 339.884512 -186.149488)
		(width 0.12065)
		(layer "F.Cu")
		(net "SSD_PRSNT#14_R")
	)
	(segment
		(start 331.987652 -204.149452)
		(end 330.850748 -203.012548)
		(width 0.12065)
		(layer "F.Cu")
		(net "SSD_PRSNT#14_R")
	)
	(via
		(at 339.884512 -186.149488)
		(size 0.508)
		(drill 0.254)
		(layers "F.Cu" "B.Cu")
		(net "SSD_PRSNT#14_R")
	)
	(via
		(at 340.487 -188.595)
		(size 0.508)
		(drill 0.254)
		(layers "F.Cu" "B.Cu")
		(net "SSD_PRSNT#14_R")
	)
	(via
		(at 339.884512 -187.452)
		(size 0.7112)
		(drill 0.3556)
		(layers "F.Cu" "B.Cu")
		(net "SSD_PRSNT#14_R")
	)
	(segment
		(start 339.884512 -187.992512)
		(end 339.884512 -187.452)
		(width 0.12065)
		(layer "B.Cu")
		(net "SSD_PRSNT#14_R")
	)
	(segment
		(start 339.884512 -187.452)
		(end 339.884512 -186.149488)
		(width 0.12065)
		(layer "B.Cu")
		(net "SSD_PRSNT#14_R")
	)
	(segment
		(start 340.487 -188.595)
		(end 339.884512 -187.992512)
		(width 0.12065)
		(layer "B.Cu")
		(net "SSD_PRSNT#14_R")
	)
	(segment
		(start 339.884512 -184.433718)
		(end 339.884512 -183.801512)
		(width 0.12065)
		(layer "F.Cu")
		(net "SSD_PRSNT#14")
	)
	(segment
		(start 339.884512 -183.801512)
		(end 339.725 -183.642)
		(width 0.12065)
		(layer "F.Cu")
		(net "SSD_PRSNT#14")
	)
	(segment
		(start 338.761832 -181.601618)
		(end 338.761832 -182.780686)
		(width 0.12065)
		(layer "F.Cu")
		(net "SSD_PRSNT#14")
	)
	(segment
		(start 338.761832 -182.780686)
		(end 339.623146 -183.642)
		(width 0.12065)
		(layer "F.Cu")
		(net "SSD_PRSNT#14")
	)
	(segment
		(start 339.623146 -183.642)
		(end 339.725 -183.642)
		(width 0.12065)
		(layer "F.Cu")
		(net "SSD_PRSNT#14")
	)
	(via
		(at 339.725 -183.642)
		(size 0.508)
		(drill 0.254)
		(layers "F.Cu" "B.Cu")
		(net "SSD_PRSNT#14")
	)
	(via
		(at 340.868 -184.531)
		(size 0.7112)
		(drill 0.3556)
		(layers "F.Cu" "B.Cu")
		(net "SSD_PRSNT#14")
	)
	(segment
		(start 340.868 -184.023)
		(end 340.868 -184.531)
		(width 0.12065)
		(layer "B.Cu")
		(net "SSD_PRSNT#14")
	)
	(segment
		(start 339.725 -183.642)
		(end 339.873082 -183.642)
		(width 0.12065)
		(layer "B.Cu")
		(net "SSD_PRSNT#14")
	)
	(segment
		(start 339.884512 -184.433718)
		(end 339.981794 -184.531)
		(width 0.12065)
		(layer "B.Cu")
		(net "SSD_PRSNT#14")
	)
	(segment
		(start 339.981794 -184.531)
		(end 340.868 -184.531)
		(width 0.12065)
		(layer "B.Cu")
		(net "SSD_PRSNT#14")
	)
	(segment
		(start 339.873082 -183.642)
		(end 339.981032 -183.74995)
		(width 0.12065)
		(layer "B.Cu")
		(net "SSD_PRSNT#14")
	)
	(segment
		(start 340.59495 -183.74995)
		(end 340.868 -184.023)
		(width 0.12065)
		(layer "B.Cu")
		(net "SSD_PRSNT#14")
	)
	(segment
		(start 339.981032 -183.74995)
		(end 340.59495 -183.74995)
		(width 0.12065)
		(layer "B.Cu")
		(net "SSD_PRSNT#14")
	)
	(segment
		(start 230.2383 -156.7307)
		(end 234.188 -152.781)
		(width 0.12065)
		(layer "F.Cu")
		(net "SSD_PRSNT#13_R")
	)
	(segment
		(start 224.040446 -204.1525)
		(end 224.040446 -204.993494)
		(width 0.12065)
		(layer "F.Cu")
		(net "SSD_PRSNT#13_R")
	)
	(segment
		(start 272.393664 -152.781)
		(end 296.00525 -176.392586)
		(width 0.12065)
		(layer "F.Cu")
		(net "SSD_PRSNT#13_R")
	)
	(segment
		(start 295.700196 -224.142046)
		(end 296.566844 -223.275398)
		(width 0.12065)
		(layer "F.Cu")
		(net "SSD_PRSNT#13_R")
	)
	(segment
		(start 296.00525 -208.887314)
		(end 296.00525 -192.278)
		(width 0.12065)
		(layer "F.Cu")
		(net "SSD_PRSNT#13_R")
	)
	(segment
		(start 224.040446 -204.993494)
		(end 223.95688 -205.07706)
		(width 0.12065)
		(layer "F.Cu")
		(net "SSD_PRSNT#13_R")
	)
	(segment
		(start 230.2383 -204.9526)
		(end 230.2383 -156.7307)
		(width 0.12065)
		(layer "F.Cu")
		(net "SSD_PRSNT#13_R")
	)
	(segment
		(start 296.00525 -176.392586)
		(end 296.00525 -192.278)
		(width 0.12065)
		(layer "F.Cu")
		(net "SSD_PRSNT#13_R")
	)
	(segment
		(start 296.566844 -223.275398)
		(end 296.566844 -209.448908)
		(width 0.12065)
		(layer "F.Cu")
		(net "SSD_PRSNT#13_R")
	)
	(segment
		(start 295.700196 -225.54438)
		(end 295.700196 -224.142046)
		(width 0.12065)
		(layer "F.Cu")
		(net "SSD_PRSNT#13_R")
	)
	(segment
		(start 296.566844 -209.448908)
		(end 296.00525 -208.887314)
		(width 0.12065)
		(layer "F.Cu")
		(net "SSD_PRSNT#13_R")
	)
	(segment
		(start 234.188 -152.781)
		(end 272.393664 -152.781)
		(width 0.12065)
		(layer "F.Cu")
		(net "SSD_PRSNT#13_R")
	)
	(via
		(at 223.95688 -205.07706)
		(size 0.508)
		(drill 0.254)
		(layers "F.Cu" "B.Cu")
		(net "SSD_PRSNT#13_R")
	)
	(via
		(at 230.2383 -204.9526)
		(size 0.508)
		(drill 0.254)
		(layers "F.Cu" "B.Cu")
		(net "SSD_PRSNT#13_R")
	)
	(via
		(at 296.00525 -192.278)
		(size 0.7112)
		(drill 0.3556)
		(layers "F.Cu" "B.Cu")
		(net "SSD_PRSNT#13_R")
	)
	(segment
		(start 223.95688 -205.07706)
		(end 230.11384 -205.07706)
		(width 0.127)
		(layer "In2.Cu")
		(net "SSD_PRSNT#13_R")
	)
	(segment
		(start 230.11384 -205.07706)
		(end 230.2383 -204.9526)
		(width 0.127)
		(layer "In2.Cu")
		(net "SSD_PRSNT#13_R")
	)
	(segment
		(start 223.442784 -201.209656)
		(end 224.10166 -201.868532)
		(width 0.12065)
		(layer "F.Cu")
		(net "SSD_PRSNT#13")
	)
	(segment
		(start 224.040446 -202.440794)
		(end 224.040446 -203.2635)
		(width 0.12065)
		(layer "F.Cu")
		(net "SSD_PRSNT#13")
	)
	(segment
		(start 224.10166 -202.37958)
		(end 224.040446 -202.440794)
		(width 0.12065)
		(layer "F.Cu")
		(net "SSD_PRSNT#13")
	)
	(segment
		(start 223.201484 -199.770492)
		(end 223.201484 -200.968356)
		(width 0.12065)
		(layer "F.Cu")
		(net "SSD_PRSNT#13")
	)
	(segment
		(start 223.201484 -200.968356)
		(end 223.442784 -201.209656)
		(width 0.12065)
		(layer "F.Cu")
		(net "SSD_PRSNT#13")
	)
	(segment
		(start 224.10166 -201.868532)
		(end 224.10166 -202.37958)
		(width 0.12065)
		(layer "F.Cu")
		(net "SSD_PRSNT#13")
	)
	(via
		(at 223.442784 -201.209656)
		(size 0.7112)
		(drill 0.3556)
		(layers "F.Cu" "B.Cu")
		(net "SSD_PRSNT#13")
	)
	(via
		(at 224.10166 -202.37958)
		(size 0.508)
		(drill 0.254)
		(layers "F.Cu" "B.Cu")
		(net "SSD_PRSNT#13")
	)
	(segment
		(start 224.040446 -202.440794)
		(end 224.040446 -203.25334)
		(width 0.12065)
		(layer "B.Cu")
		(net "SSD_PRSNT#13")
	)
	(segment
		(start 224.10166 -202.37958)
		(end 224.040446 -202.440794)
		(width 0.12065)
		(layer "B.Cu")
		(net "SSD_PRSNT#13")
	)
	(segment
		(start 228.195124 -207.189324)
		(end 228.2698 -207.264)
		(width 0.12065)
		(layer "F.Cu")
		(net "SSD_PRSNT#12_R")
	)
	(segment
		(start 228.195124 -203.491592)
		(end 228.195124 -207.189324)
		(width 0.12065)
		(layer "F.Cu")
		(net "SSD_PRSNT#12_R")
	)
	(via
		(at 228.2698 -207.264)
		(size 0.508)
		(drill 0.254)
		(layers "F.Cu" "B.Cu")
		(net "SSD_PRSNT#12_R")
	)
	(via
		(at 219.456 -206.883)
		(size 0.7112)
		(drill 0.3556)
		(layers "F.Cu" "B.Cu")
		(net "SSD_PRSNT#12_R")
	)
	(segment
		(start 227.36048 -206.35468)
		(end 228.2698 -207.264)
		(width 0.12065)
		(layer "B.Cu")
		(net "SSD_PRSNT#12_R")
	)
	(segment
		(start 207.300068 -212.815932)
		(end 213.233 -206.883)
		(width 0.12065)
		(layer "B.Cu")
		(net "SSD_PRSNT#12_R")
	)
	(segment
		(start 224.32772 -206.35468)
		(end 227.36048 -206.35468)
		(width 0.12065)
		(layer "B.Cu")
		(net "SSD_PRSNT#12_R")
	)
	(segment
		(start 207.300068 -225.92538)
		(end 207.300068 -212.815932)
		(width 0.12065)
		(layer "B.Cu")
		(net "SSD_PRSNT#12_R")
	)
	(segment
		(start 213.233 -206.883)
		(end 219.456 -206.883)
		(width 0.12065)
		(layer "B.Cu")
		(net "SSD_PRSNT#12_R")
	)
	(segment
		(start 219.456 -206.883)
		(end 223.7994 -206.883)
		(width 0.12065)
		(layer "B.Cu")
		(net "SSD_PRSNT#12_R")
	)
	(segment
		(start 223.7994 -206.883)
		(end 224.32772 -206.35468)
		(width 0.12065)
		(layer "B.Cu")
		(net "SSD_PRSNT#12_R")
	)
	(segment
		(start 228.195124 -202.602592)
		(end 228.195124 -201.801476)
		(width 0.12065)
		(layer "F.Cu")
		(net "SSD_PRSNT#12")
	)
	(segment
		(start 227.812092 -199.770492)
		(end 228.2698 -200.2282)
		(width 0.12065)
		(layer "F.Cu")
		(net "SSD_PRSNT#12")
	)
	(segment
		(start 225.802444 -199.770492)
		(end 227.812092 -199.770492)
		(width 0.12065)
		(layer "F.Cu")
		(net "SSD_PRSNT#12")
	)
	(segment
		(start 228.2698 -201.7268)
		(end 228.2698 -200.2282)
		(width 0.12065)
		(layer "F.Cu")
		(net "SSD_PRSNT#12")
	)
	(segment
		(start 228.195124 -201.801476)
		(end 228.2698 -201.7268)
		(width 0.12065)
		(layer "F.Cu")
		(net "SSD_PRSNT#12")
	)
	(via
		(at 228.2698 -201.7268)
		(size 0.508)
		(drill 0.254)
		(layers "F.Cu" "B.Cu")
		(net "SSD_PRSNT#12")
	)
	(via
		(at 228.2698 -200.2282)
		(size 0.7112)
		(drill 0.3556)
		(layers "F.Cu" "B.Cu")
		(net "SSD_PRSNT#12")
	)
	(segment
		(start 228.195124 -201.801476)
		(end 228.2698 -201.7268)
		(width 0.12065)
		(layer "B.Cu")
		(net "SSD_PRSNT#12")
	)
	(segment
		(start 228.195124 -202.602592)
		(end 228.195124 -201.801476)
		(width 0.12065)
		(layer "B.Cu")
		(net "SSD_PRSNT#12")
	)
	(segment
		(start 97.8154 -175.514)
		(end 69.0372 -175.514)
		(width 0.12065)
		(layer "F.Cu")
		(net "SSD_PRSNT#11_R")
	)
	(segment
		(start 75.312016 -196.571362)
		(end 75.705208 -196.17817)
		(width 0.12065)
		(layer "F.Cu")
		(net "SSD_PRSNT#11_R")
	)
	(segment
		(start 69.0372 -175.514)
		(end 63.836296 -180.714904)
		(width 0.12065)
		(layer "F.Cu")
		(net "SSD_PRSNT#11_R")
	)
	(segment
		(start 75.311 -198.83374)
		(end 75.311 -198.734934)
		(width 0.12065)
		(layer "F.Cu")
		(net "SSD_PRSNT#11_R")
	)
	(segment
		(start 75.311 -198.734934)
		(end 75.312016 -198.733918)
		(width 0.12065)
		(layer "F.Cu")
		(net "SSD_PRSNT#11_R")
	)
	(segment
		(start 63.836296 -180.714904)
		(end 63.836296 -198.189088)
		(width 0.12065)
		(layer "F.Cu")
		(net "SSD_PRSNT#11_R")
	)
	(segment
		(start 73.78954 -200.3552)
		(end 75.311 -198.83374)
		(width 0.12065)
		(layer "F.Cu")
		(net "SSD_PRSNT#11_R")
	)
	(segment
		(start 111.8362 -189.5348)
		(end 97.8154 -175.514)
		(width 0.12065)
		(layer "F.Cu")
		(net "SSD_PRSNT#11_R")
	)
	(segment
		(start 63.836296 -198.189088)
		(end 66.002408 -200.3552)
		(width 0.12065)
		(layer "F.Cu")
		(net "SSD_PRSNT#11_R")
	)
	(segment
		(start 75.312016 -198.733918)
		(end 75.312016 -196.571362)
		(width 0.12065)
		(layer "F.Cu")
		(net "SSD_PRSNT#11_R")
	)
	(segment
		(start 75.705208 -196.17817)
		(end 75.983592 -196.17817)
		(width 0.12065)
		(layer "F.Cu")
		(net "SSD_PRSNT#11_R")
	)
	(segment
		(start 159.9946 -197.3326)
		(end 152.1968 -189.5348)
		(width 0.12065)
		(layer "F.Cu")
		(net "SSD_PRSNT#11_R")
	)
	(segment
		(start 152.1968 -189.5348)
		(end 111.8362 -189.5348)
		(width 0.12065)
		(layer "F.Cu")
		(net "SSD_PRSNT#11_R")
	)
	(segment
		(start 164.0332 -197.3326)
		(end 159.9946 -197.3326)
		(width 0.12065)
		(layer "F.Cu")
		(net "SSD_PRSNT#11_R")
	)
	(segment
		(start 66.002408 -200.3552)
		(end 73.78954 -200.3552)
		(width 0.12065)
		(layer "F.Cu")
		(net "SSD_PRSNT#11_R")
	)
	(via
		(at 164.0332 -197.3326)
		(size 0.508)
		(drill 0.254)
		(layers "F.Cu" "B.Cu")
		(net "SSD_PRSNT#11_R")
	)
	(via
		(at 162.814 -207.391)
		(size 0.7112)
		(drill 0.3556)
		(layers "F.Cu" "B.Cu")
		(net "SSD_PRSNT#11_R")
	)
	(segment
		(start 162.814 -198.5518)
		(end 162.814 -207.391)
		(width 0.12065)
		(layer "B.Cu")
		(net "SSD_PRSNT#11_R")
	)
	(segment
		(start 161.70021 -225.92538)
		(end 161.70021 -217.44559)
		(width 0.12065)
		(layer "B.Cu")
		(net "SSD_PRSNT#11_R")
	)
	(segment
		(start 161.70021 -217.44559)
		(end 162.814 -216.3318)
		(width 0.12065)
		(layer "B.Cu")
		(net "SSD_PRSNT#11_R")
	)
	(segment
		(start 164.0332 -197.3326)
		(end 162.814 -198.5518)
		(width 0.12065)
		(layer "B.Cu")
		(net "SSD_PRSNT#11_R")
	)
	(segment
		(start 162.814 -216.3318)
		(end 162.814 -207.391)
		(width 0.12065)
		(layer "B.Cu")
		(net "SSD_PRSNT#11_R")
	)
	(segment
		(start 75.119484 -193.610484)
		(end 75.311 -193.802)
		(width 0.12065)
		(layer "F.Cu")
		(net "SSD_PRSNT#11")
	)
	(segment
		(start 75.119484 -192.404492)
		(end 75.119484 -193.610484)
		(width 0.12065)
		(layer "F.Cu")
		(net "SSD_PRSNT#11")
	)
	(segment
		(start 75.983592 -195.28917)
		(end 75.983592 -194.494658)
		(width 0.12065)
		(layer "F.Cu")
		(net "SSD_PRSNT#11")
	)
	(segment
		(start 75.992736 -194.485514)
		(end 75.311 -193.803778)
		(width 0.12065)
		(layer "F.Cu")
		(net "SSD_PRSNT#11")
	)
	(segment
		(start 75.983592 -194.494658)
		(end 75.992736 -194.485514)
		(width 0.12065)
		(layer "F.Cu")
		(net "SSD_PRSNT#11")
	)
	(segment
		(start 75.311 -193.803778)
		(end 75.311 -193.802)
		(width 0.12065)
		(layer "F.Cu")
		(net "SSD_PRSNT#11")
	)
	(via
		(at 75.992736 -194.485514)
		(size 0.508)
		(drill 0.254)
		(layers "F.Cu" "B.Cu")
		(net "SSD_PRSNT#11")
	)
	(via
		(at 75.311 -193.802)
		(size 0.7112)
		(drill 0.3556)
		(layers "F.Cu" "B.Cu")
		(net "SSD_PRSNT#11")
	)
	(segment
		(start 75.987656 -194.490594)
		(end 75.992736 -194.485514)
		(width 0.12065)
		(layer "B.Cu")
		(net "SSD_PRSNT#11")
	)
	(segment
		(start 75.987656 -195.285614)
		(end 75.987656 -194.490594)
		(width 0.12065)
		(layer "B.Cu")
		(net "SSD_PRSNT#11")
	)
	(segment
		(start 80.113124 -196.125592)
		(end 80.113124 -196.9008)
		(width 0.12065)
		(layer "F.Cu")
		(net "SSD_PRSNT#10_R")
	)
	(via
		(at 80.113124 -196.9008)
		(size 0.508)
		(drill 0.254)
		(layers "F.Cu" "B.Cu")
		(net "SSD_PRSNT#10_R")
	)
	(via
		(at 92.648786 -207.202786)
		(size 0.7112)
		(drill 0.3556)
		(layers "F.Cu" "B.Cu")
		(net "SSD_PRSNT#10_R")
	)
	(segment
		(start 93.300042 -222.625158)
		(end 94.213934 -221.711266)
		(width 0.12065)
		(layer "B.Cu")
		(net "SSD_PRSNT#10_R")
	)
	(segment
		(start 94.213934 -221.711266)
		(end 94.213934 -208.767934)
		(width 0.12065)
		(layer "B.Cu")
		(net "SSD_PRSNT#10_R")
	)
	(segment
		(start 93.300042 -225.92538)
		(end 93.300042 -222.625158)
		(width 0.12065)
		(layer "B.Cu")
		(net "SSD_PRSNT#10_R")
	)
	(segment
		(start 94.213934 -208.767934)
		(end 92.648786 -207.202786)
		(width 0.12065)
		(layer "B.Cu")
		(net "SSD_PRSNT#10_R")
	)
	(segment
		(start 80.113124 -196.9008)
		(end 81.23301 -198.020686)
		(width 0.12065)
		(layer "B.Cu")
		(net "SSD_PRSNT#10_R")
	)
	(segment
		(start 81.23301 -198.020686)
		(end 83.466686 -198.020686)
		(width 0.12065)
		(layer "B.Cu")
		(net "SSD_PRSNT#10_R")
	)
	(segment
		(start 83.466686 -198.020686)
		(end 92.648786 -207.202786)
		(width 0.12065)
		(layer "B.Cu")
		(net "SSD_PRSNT#10_R")
	)
	(segment
		(start 80.113124 -195.236592)
		(end 80.113124 -194.461892)
		(width 0.12065)
		(layer "F.Cu")
		(net "SSD_PRSNT#10")
	)
	(segment
		(start 78.171548 -192.404492)
		(end 78.507082 -192.068958)
		(width 0.12065)
		(layer "F.Cu")
		(net "SSD_PRSNT#10")
	)
	(segment
		(start 77.720444 -192.404492)
		(end 78.171548 -192.404492)
		(width 0.12065)
		(layer "F.Cu")
		(net "SSD_PRSNT#10")
	)
	(segment
		(start 80.113124 -193.078608)
		(end 80.113124 -194.461892)
		(width 0.12065)
		(layer "F.Cu")
		(net "SSD_PRSNT#10")
	)
	(segment
		(start 78.507082 -192.068958)
		(end 79.103474 -192.068958)
		(width 0.12065)
		(layer "F.Cu")
		(net "SSD_PRSNT#10")
	)
	(segment
		(start 79.103474 -192.068958)
		(end 80.113124 -193.078608)
		(width 0.12065)
		(layer "F.Cu")
		(net "SSD_PRSNT#10")
	)
	(via
		(at 80.113124 -194.461892)
		(size 0.508)
		(drill 0.254)
		(layers "F.Cu" "B.Cu")
		(net "SSD_PRSNT#10")
	)
	(via
		(at 83.152742 -194.503294)
		(size 0.7112)
		(drill 0.3556)
		(layers "F.Cu" "B.Cu")
		(net "SSD_PRSNT#10")
	)
	(segment
		(start 80.736694 -194.564)
		(end 80.772254 -194.52844)
		(width 0.12065)
		(layer "B.Cu")
		(net "SSD_PRSNT#10")
	)
	(segment
		(start 81.98993 -194.29095)
		(end 82.0293 -194.29095)
		(width 0.12065)
		(layer "B.Cu")
		(net "SSD_PRSNT#10")
	)
	(segment
		(start 82.90687 -194.056)
		(end 83.152742 -194.301872)
		(width 0.12065)
		(layer "B.Cu")
		(net "SSD_PRSNT#10")
	)
	(segment
		(start 82.26425 -194.056)
		(end 82.90687 -194.056)
		(width 0.12065)
		(layer "B.Cu")
		(net "SSD_PRSNT#10")
	)
	(segment
		(start 82.145124 -194.982592)
		(end 82.926174 -194.982592)
		(width 0.12065)
		(layer "B.Cu")
		(net "SSD_PRSNT#10")
	)
	(segment
		(start 82.926174 -194.982592)
		(end 83.152742 -194.756024)
		(width 0.12065)
		(layer "B.Cu")
		(net "SSD_PRSNT#10")
	)
	(segment
		(start 80.215232 -194.564)
		(end 80.736694 -194.564)
		(width 0.12065)
		(layer "B.Cu")
		(net "SSD_PRSNT#10")
	)
	(segment
		(start 80.113124 -194.461892)
		(end 80.215232 -194.564)
		(width 0.12065)
		(layer "B.Cu")
		(net "SSD_PRSNT#10")
	)
	(segment
		(start 80.772254 -194.52844)
		(end 81.75244 -194.52844)
		(width 0.12065)
		(layer "B.Cu")
		(net "SSD_PRSNT#10")
	)
	(segment
		(start 82.0293 -194.29095)
		(end 82.26425 -194.056)
		(width 0.12065)
		(layer "B.Cu")
		(net "SSD_PRSNT#10")
	)
	(segment
		(start 83.152742 -194.301872)
		(end 83.152742 -194.503294)
		(width 0.12065)
		(layer "B.Cu")
		(net "SSD_PRSNT#10")
	)
	(segment
		(start 83.152742 -194.756024)
		(end 83.152742 -194.503294)
		(width 0.12065)
		(layer "B.Cu")
		(net "SSD_PRSNT#10")
	)
	(segment
		(start 81.75244 -194.52844)
		(end 81.98993 -194.29095)
		(width 0.12065)
		(layer "B.Cu")
		(net "SSD_PRSNT#10")
	)
	(segment
		(start 96.500188 -225.54438)
		(end 96.500188 -224.160588)
		(width 0.12065)
		(layer "F.Cu")
		(net "SSD_PRSNT#1_R")
	)
	(segment
		(start 94.107 -180.2384)
		(end 94.107 -179.197)
		(width 0.12065)
		(layer "F.Cu")
		(net "SSD_PRSNT#1_R")
	)
	(segment
		(start 96.500188 -224.160588)
		(end 95.4532 -223.1136)
		(width 0.12065)
		(layer "F.Cu")
		(net "SSD_PRSNT#1_R")
	)
	(segment
		(start 95.4532 -205.332584)
		(end 89.6366 -199.515984)
		(width 0.12065)
		(layer "F.Cu")
		(net "SSD_PRSNT#1_R")
	)
	(segment
		(start 95.4532 -223.1136)
		(end 95.4532 -205.332584)
		(width 0.12065)
		(layer "F.Cu")
		(net "SSD_PRSNT#1_R")
	)
	(segment
		(start 89.6366 -184.7088)
		(end 94.107 -180.2384)
		(width 0.12065)
		(layer "F.Cu")
		(net "SSD_PRSNT#1_R")
	)
	(segment
		(start 125.960124 -195.998592)
		(end 125.960124 -195.223892)
		(width 0.12065)
		(layer "F.Cu")
		(net "SSD_PRSNT#1_R")
	)
	(segment
		(start 89.6366 -199.515984)
		(end 89.6366 -184.7088)
		(width 0.12065)
		(layer "F.Cu")
		(net "SSD_PRSNT#1_R")
	)
	(via
		(at 123.939046 -193.202814)
		(size 0.7112)
		(drill 0.3556)
		(layers "F.Cu" "B.Cu")
		(net "SSD_PRSNT#1_R")
	)
	(via
		(at 125.960124 -195.223892)
		(size 0.508)
		(drill 0.254)
		(layers "F.Cu" "B.Cu")
		(net "SSD_PRSNT#1_R")
	)
	(via
		(at 94.107 -179.197)
		(size 0.508)
		(drill 0.254)
		(layers "F.Cu" "B.Cu")
		(net "SSD_PRSNT#1_R")
	)
	(segment
		(start 123.939046 -193.202814)
		(end 125.960124 -195.223892)
		(width 0.12065)
		(layer "B.Cu")
		(net "SSD_PRSNT#1_R")
	)
	(segment
		(start 94.107 -179.197)
		(end 94.234 -179.07)
		(width 0.12065)
		(layer "B.Cu")
		(net "SSD_PRSNT#1_R")
	)
	(segment
		(start 109.806232 -179.07)
		(end 123.939046 -193.202814)
		(width 0.12065)
		(layer "B.Cu")
		(net "SSD_PRSNT#1_R")
	)
	(segment
		(start 94.234 -179.07)
		(end 109.806232 -179.07)
		(width 0.12065)
		(layer "B.Cu")
		(net "SSD_PRSNT#1_R")
	)
	(segment
		(start 126.747524 -199.973692)
		(end 126.747524 -198.599552)
		(width 0.12065)
		(layer "F.Cu")
		(net "SSD_PRSNT#1")
	)
	(segment
		(start 126.46914 -198.321168)
		(end 126.46914 -197.821296)
		(width 0.12065)
		(layer "F.Cu")
		(net "SSD_PRSNT#1")
	)
	(segment
		(start 125.34773 -197.8406)
		(end 125.325632 -197.818502)
		(width 0.12065)
		(layer "F.Cu")
		(net "SSD_PRSNT#1")
	)
	(segment
		(start 125.325632 -197.522084)
		(end 125.325632 -197.818502)
		(width 0.12065)
		(layer "F.Cu")
		(net "SSD_PRSNT#1")
	)
	(segment
		(start 126.46914 -197.821296)
		(end 126.449836 -197.8406)
		(width 0.12065)
		(layer "F.Cu")
		(net "SSD_PRSNT#1")
	)
	(segment
		(start 125.960124 -196.887592)
		(end 125.325632 -197.522084)
		(width 0.12065)
		(layer "F.Cu")
		(net "SSD_PRSNT#1")
	)
	(segment
		(start 126.449836 -197.8406)
		(end 125.34773 -197.8406)
		(width 0.12065)
		(layer "F.Cu")
		(net "SSD_PRSNT#1")
	)
	(segment
		(start 126.747524 -198.599552)
		(end 126.46914 -198.321168)
		(width 0.12065)
		(layer "F.Cu")
		(net "SSD_PRSNT#1")
	)
	(via
		(at 126.46914 -197.821296)
		(size 0.508)
		(drill 0.254)
		(layers "F.Cu" "B.Cu")
		(net "SSD_PRSNT#1")
	)
	(via
		(at 125.325632 -197.818502)
		(size 0.7112)
		(drill 0.3556)
		(layers "F.Cu" "B.Cu")
		(net "SSD_PRSNT#1")
	)
	(segment
		(start 125.960124 -197.31228)
		(end 126.46914 -197.821296)
		(width 0.12065)
		(layer "B.Cu")
		(net "SSD_PRSNT#1")
	)
	(segment
		(start 125.960124 -196.887592)
		(end 125.960124 -197.31228)
		(width 0.12065)
		(layer "B.Cu")
		(net "SSD_PRSNT#1")
	)
	(segment
		(start 71.731124 -182.790592)
		(end 71.731124 -182.015892)
		(width 0.12065)
		(layer "F.Cu")
		(net "SSD_PRSNT#0_R")
	)
	(segment
		(start 61.214 -184.277)
		(end 61.02985 -184.46115)
		(width 0.12065)
		(layer "F.Cu")
		(net "SSD_PRSNT#0_R")
	)
	(segment
		(start 61.02985 -222.066866)
		(end 61.02985 -185.674)
		(width 0.12065)
		(layer "F.Cu")
		(net "SSD_PRSNT#0_R")
	)
	(segment
		(start 61.366908 -222.403924)
		(end 61.02985 -222.066866)
		(width 0.12065)
		(layer "F.Cu")
		(net "SSD_PRSNT#0_R")
	)
	(segment
		(start 60.500006 -225.54438)
		(end 60.500006 -224.1423)
		(width 0.12065)
		(layer "F.Cu")
		(net "SSD_PRSNT#0_R")
	)
	(segment
		(start 61.366908 -223.275398)
		(end 61.366908 -222.403924)
		(width 0.12065)
		(layer "F.Cu")
		(net "SSD_PRSNT#0_R")
	)
	(segment
		(start 60.500006 -224.1423)
		(end 61.366908 -223.275398)
		(width 0.12065)
		(layer "F.Cu")
		(net "SSD_PRSNT#0_R")
	)
	(segment
		(start 61.02985 -184.46115)
		(end 61.02985 -185.674)
		(width 0.12065)
		(layer "F.Cu")
		(net "SSD_PRSNT#0_R")
	)
	(via
		(at 61.214 -184.277)
		(size 0.508)
		(drill 0.254)
		(layers "F.Cu" "B.Cu")
		(net "SSD_PRSNT#0_R")
	)
	(via
		(at 61.02985 -185.674)
		(size 0.7112)
		(drill 0.3556)
		(layers "F.Cu" "B.Cu")
		(net "SSD_PRSNT#0_R")
	)
	(via
		(at 71.731124 -182.015892)
		(size 0.508)
		(drill 0.254)
		(layers "F.Cu" "B.Cu")
		(net "SSD_PRSNT#0_R")
	)
	(segment
		(start 70.993 -181.229)
		(end 71.731124 -181.967124)
		(width 0.127)
		(layer "In5.Cu")
		(net "SSD_PRSNT#0_R")
	)
	(segment
		(start 61.214 -184.277)
		(end 64.262 -181.229)
		(width 0.127)
		(layer "In5.Cu")
		(net "SSD_PRSNT#0_R")
	)
	(segment
		(start 64.262 -181.229)
		(end 70.993 -181.229)
		(width 0.127)
		(layer "In5.Cu")
		(net "SSD_PRSNT#0_R")
	)
	(segment
		(start 71.731124 -181.967124)
		(end 71.731124 -182.015892)
		(width 0.127)
		(layer "In5.Cu")
		(net "SSD_PRSNT#0_R")
	)
	(segment
		(start 72.518524 -185.353706)
		(end 72.421496 -185.256678)
		(width 0.12065)
		(layer "F.Cu")
		(net "SSD_PRSNT#0")
	)
	(segment
		(start 71.246492 -184.608724)
		(end 72.331072 -184.608724)
		(width 0.12065)
		(layer "F.Cu")
		(net "SSD_PRSNT#0")
	)
	(segment
		(start 72.421496 -184.5183)
		(end 72.474582 -184.465214)
		(width 0.12065)
		(layer "F.Cu")
		(net "SSD_PRSNT#0")
	)
	(segment
		(start 71.731124 -183.679592)
		(end 71.246492 -184.164224)
		(width 0.12065)
		(layer "F.Cu")
		(net "SSD_PRSNT#0")
	)
	(segment
		(start 72.331072 -184.608724)
		(end 72.421496 -184.5183)
		(width 0.12065)
		(layer "F.Cu")
		(net "SSD_PRSNT#0")
	)
	(segment
		(start 72.518524 -186.765692)
		(end 72.518524 -185.353706)
		(width 0.12065)
		(layer "F.Cu")
		(net "SSD_PRSNT#0")
	)
	(segment
		(start 71.246492 -184.164224)
		(end 71.246492 -184.608724)
		(width 0.12065)
		(layer "F.Cu")
		(net "SSD_PRSNT#0")
	)
	(segment
		(start 72.421496 -185.256678)
		(end 72.421496 -184.5183)
		(width 0.12065)
		(layer "F.Cu")
		(net "SSD_PRSNT#0")
	)
	(via
		(at 71.246492 -184.608724)
		(size 0.7112)
		(drill 0.3556)
		(layers "F.Cu" "B.Cu")
		(net "SSD_PRSNT#0")
	)
	(via
		(at 72.474582 -184.465214)
		(size 0.508)
		(drill 0.254)
		(layers "F.Cu" "B.Cu")
		(net "SSD_PRSNT#0")
	)
	(segment
		(start 71.731124 -183.721756)
		(end 72.474582 -184.465214)
		(width 0.12065)
		(layer "B.Cu")
		(net "SSD_PRSNT#0")
	)
	(segment
		(start 71.731124 -183.679592)
		(end 71.731124 -183.721756)
		(width 0.12065)
		(layer "B.Cu")
		(net "SSD_PRSNT#0")
	)
	(segment
		(start 306.20335 -220.012514)
		(end 306.20335 -215.940386)
		(width 0.12065)
		(layer "F.Cu")
		(net "SSD_PERST#9_R")
	)
	(segment
		(start 339.41766 -173.220888)
		(end 339.522562 -173.32579)
		(width 0.12065)
		(layer "F.Cu")
		(net "SSD_PERST#9_R")
	)
	(segment
		(start 305.47945 -169.28465)
		(end 307.34 -167.4241)
		(width 0.12065)
		(layer "F.Cu")
		(net "SSD_PERST#9_R")
	)
	(segment
		(start 339.54593 -172.3263)
		(end 339.54593 -172.397166)
		(width 0.12065)
		(layer "F.Cu")
		(net "SSD_PERST#9_R")
	)
	(segment
		(start 305.300126 -225.54438)
		(end 305.300126 -224.197926)
		(width 0.12065)
		(layer "F.Cu")
		(net "SSD_PERST#9_R")
	)
	(segment
		(start 339.54593 -173.408086)
		(end 339.54593 -174.025814)
		(width 0.12065)
		(layer "F.Cu")
		(net "SSD_PERST#9_R")
	)
	(segment
		(start 304.433224 -223.331024)
		(end 304.433224 -221.78264)
		(width 0.12065)
		(layer "F.Cu")
		(net "SSD_PERST#9_R")
	)
	(segment
		(start 339.522562 -173.32579)
		(end 339.522562 -173.384718)
		(width 0.12065)
		(layer "F.Cu")
		(net "SSD_PERST#9_R")
	)
	(segment
		(start 306.20335 -215.940386)
		(end 305.47945 -215.216486)
		(width 0.12065)
		(layer "F.Cu")
		(net "SSD_PERST#9_R")
	)
	(segment
		(start 305.300126 -224.197926)
		(end 304.433224 -223.331024)
		(width 0.12065)
		(layer "F.Cu")
		(net "SSD_PERST#9_R")
	)
	(segment
		(start 339.884512 -171.987718)
		(end 339.54593 -172.3263)
		(width 0.12065)
		(layer "F.Cu")
		(net "SSD_PERST#9_R")
	)
	(segment
		(start 304.433224 -221.78264)
		(end 306.20335 -220.012514)
		(width 0.12065)
		(layer "F.Cu")
		(net "SSD_PERST#9_R")
	)
	(segment
		(start 337.3501 -167.4241)
		(end 338.074 -168.148)
		(width 0.12065)
		(layer "F.Cu")
		(net "SSD_PERST#9_R")
	)
	(segment
		(start 305.47945 -215.216486)
		(end 305.47945 -169.28465)
		(width 0.12065)
		(layer "F.Cu")
		(net "SSD_PERST#9_R")
	)
	(segment
		(start 339.522562 -173.384718)
		(end 339.54593 -173.408086)
		(width 0.12065)
		(layer "F.Cu")
		(net "SSD_PERST#9_R")
	)
	(segment
		(start 307.34 -167.4241)
		(end 337.3501 -167.4241)
		(width 0.12065)
		(layer "F.Cu")
		(net "SSD_PERST#9_R")
	)
	(segment
		(start 339.54593 -172.397166)
		(end 339.41766 -172.525436)
		(width 0.12065)
		(layer "F.Cu")
		(net "SSD_PERST#9_R")
	)
	(segment
		(start 339.41766 -172.525436)
		(end 339.41766 -173.220888)
		(width 0.12065)
		(layer "F.Cu")
		(net "SSD_PERST#9_R")
	)
	(via
		(at 339.54593 -174.025814)
		(size 0.508)
		(drill 0.254)
		(layers "F.Cu" "B.Cu")
		(net "SSD_PERST#9_R")
	)
	(via
		(at 338.074 -168.148)
		(size 0.508)
		(drill 0.254)
		(layers "F.Cu" "B.Cu")
		(net "SSD_PERST#9_R")
	)
	(via
		(at 338.074 -167.1828)
		(size 0.7112)
		(drill 0.3556)
		(layers "F.Cu" "B.Cu")
		(net "SSD_PERST#9_R")
	)
	(segment
		(start 337.9216 -175.2981)
		(end 338.6709 -175.2981)
		(width 0.12065)
		(layer "B.Cu")
		(net "SSD_PERST#9_R")
	)
	(segment
		(start 339.54593 -174.139606)
		(end 339.54593 -174.025814)
		(width 0.12065)
		(layer "B.Cu")
		(net "SSD_PERST#9_R")
	)
	(segment
		(start 339.073998 -174.611538)
		(end 339.54593 -174.139606)
		(width 0.12065)
		(layer "B.Cu")
		(net "SSD_PERST#9_R")
	)
	(segment
		(start 338.6709 -175.2981)
		(end 339.073998 -174.895002)
		(width 0.12065)
		(layer "B.Cu")
		(net "SSD_PERST#9_R")
	)
	(segment
		(start 339.073998 -174.895002)
		(end 339.073998 -174.611538)
		(width 0.12065)
		(layer "B.Cu")
		(net "SSD_PERST#9_R")
	)
	(segment
		(start 338.074 -167.1828)
		(end 338.074 -168.148)
		(width 0.12065)
		(layer "B.Cu")
		(net "SSD_PERST#9_R")
	)
	(segment
		(start 338.074 -172.635418)
		(end 338.074 -168.148)
		(width 0.127)
		(layer "In2.Cu")
		(net "SSD_PERST#9_R")
	)
	(segment
		(start 339.442552 -174.00397)
		(end 338.074 -172.635418)
		(width 0.127)
		(layer "In2.Cu")
		(net "SSD_PERST#9_R")
	)
	(segment
		(start 339.524086 -174.00397)
		(end 339.442552 -174.00397)
		(width 0.127)
		(layer "In2.Cu")
		(net "SSD_PERST#9_R")
	)
	(segment
		(start 339.54593 -174.025814)
		(end 339.524086 -174.00397)
		(width 0.127)
		(layer "In2.Cu")
		(net "SSD_PERST#9_R")
	)
	(segment
		(start 340.343236 -174.133764)
		(end 340.343236 -173.693328)
		(width 0.12065)
		(layer "F.Cu")
		(net "SSD_PERST#9")
	)
	(segment
		(start 338.136484 -175.340518)
		(end 338.471002 -175.006)
		(width 0.12065)
		(layer "F.Cu")
		(net "SSD_PERST#9")
	)
	(segment
		(start 339.884512 -173.234604)
		(end 340.343236 -173.693328)
		(width 0.12065)
		(layer "F.Cu")
		(net "SSD_PERST#9")
	)
	(segment
		(start 339.445854 -175.006)
		(end 339.709506 -174.742348)
		(width 0.12065)
		(layer "F.Cu")
		(net "SSD_PERST#9")
	)
	(segment
		(start 340.9442 -172.7835)
		(end 340.850982 -172.876718)
		(width 0.12065)
		(layer "F.Cu")
		(net "SSD_PERST#9")
	)
	(segment
		(start 339.734652 -174.742348)
		(end 340.343236 -174.133764)
		(width 0.12065)
		(layer "F.Cu")
		(net "SSD_PERST#9")
	)
	(segment
		(start 338.111592 -175.352964)
		(end 338.124038 -175.340518)
		(width 0.12065)
		(layer "F.Cu")
		(net "SSD_PERST#9")
	)
	(segment
		(start 339.884512 -172.876718)
		(end 339.884512 -173.234604)
		(width 0.12065)
		(layer "F.Cu")
		(net "SSD_PERST#9")
	)
	(segment
		(start 339.709506 -174.742348)
		(end 339.734652 -174.742348)
		(width 0.12065)
		(layer "F.Cu")
		(net "SSD_PERST#9")
	)
	(segment
		(start 338.124038 -175.340518)
		(end 338.136484 -175.340518)
		(width 0.12065)
		(layer "F.Cu")
		(net "SSD_PERST#9")
	)
	(segment
		(start 340.850982 -172.876718)
		(end 339.884512 -172.876718)
		(width 0.12065)
		(layer "F.Cu")
		(net "SSD_PERST#9")
	)
	(segment
		(start 338.111592 -175.962818)
		(end 338.111592 -175.352964)
		(width 0.12065)
		(layer "F.Cu")
		(net "SSD_PERST#9")
	)
	(segment
		(start 338.471002 -175.006)
		(end 339.445854 -175.006)
		(width 0.12065)
		(layer "F.Cu")
		(net "SSD_PERST#9")
	)
	(via
		(at 341.122 -172.974)
		(size 0.7112)
		(drill 0.3556)
		(layers "F.Cu" "B.Cu")
		(net "SSD_PERST#9")
	)
	(via
		(at 340.343236 -173.693328)
		(size 0.508)
		(drill 0.254)
		(layers "F.Cu" "B.Cu")
		(net "SSD_PERST#9")
	)
	(segment
		(start 339.435948 -175.015906)
		(end 339.709506 -174.742348)
		(width 0.12065)
		(layer "B.Cu")
		(net "SSD_PERST#9")
	)
	(segment
		(start 341.12327 -173.60773)
		(end 341.12327 -172.97527)
		(width 0.12065)
		(layer "B.Cu")
		(net "SSD_PERST#9")
	)
	(segment
		(start 341.024718 -172.876718)
		(end 341.122 -172.974)
		(width 0.12065)
		(layer "B.Cu")
		(net "SSD_PERST#9")
	)
	(segment
		(start 339.175852 -180.64226)
		(end 339.175852 -179.959)
		(width 0.12065)
		(layer "B.Cu")
		(net "SSD_PERST#9")
	)
	(segment
		(start 339.435948 -175.402494)
		(end 339.435948 -175.015906)
		(width 0.12065)
		(layer "B.Cu")
		(net "SSD_PERST#9")
	)
	(segment
		(start 339.598 -181.906672)
		(end 339.113622 -181.422294)
		(width 0.12065)
		(layer "B.Cu")
		(net "SSD_PERST#9")
	)
	(segment
		(start 339.598 -182.197248)
		(end 339.598 -181.906672)
		(width 0.12065)
		(layer "B.Cu")
		(net "SSD_PERST#9")
	)
	(segment
		(start 339.53704 -176.579276)
		(end 339.53704 -175.503586)
		(width 0.12065)
		(layer "B.Cu")
		(net "SSD_PERST#9")
	)
	(segment
		(start 339.344 -182.451248)
		(end 339.598 -182.197248)
		(width 0.12065)
		(layer "B.Cu")
		(net "SSD_PERST#9")
	)
	(segment
		(start 341.12327 -172.97527)
		(end 341.122 -172.974)
		(width 0.12065)
		(layer "B.Cu")
		(net "SSD_PERST#9")
	)
	(segment
		(start 340.343236 -173.693328)
		(end 341.037672 -173.693328)
		(width 0.12065)
		(layer "B.Cu")
		(net "SSD_PERST#9")
	)
	(segment
		(start 340.159848 -174.317152)
		(end 340.159848 -174.242222)
		(width 0.12065)
		(layer "B.Cu")
		(net "SSD_PERST#9")
	)
	(segment
		(start 340.159848 -174.242222)
		(end 340.343236 -174.058834)
		(width 0.12065)
		(layer "B.Cu")
		(net "SSD_PERST#9")
	)
	(segment
		(start 339.113622 -181.422294)
		(end 339.113622 -180.70449)
		(width 0.12065)
		(layer "B.Cu")
		(net "SSD_PERST#9")
	)
	(segment
		(start 339.884512 -172.876718)
		(end 341.024718 -172.876718)
		(width 0.12065)
		(layer "B.Cu")
		(net "SSD_PERST#9")
	)
	(segment
		(start 339.113622 -180.70449)
		(end 339.175852 -180.64226)
		(width 0.12065)
		(layer "B.Cu")
		(net "SSD_PERST#9")
	)
	(segment
		(start 338.470748 -179.253896)
		(end 338.470748 -177.645568)
		(width 0.12065)
		(layer "B.Cu")
		(net "SSD_PERST#9")
	)
	(segment
		(start 339.709506 -174.742348)
		(end 339.734652 -174.742348)
		(width 0.12065)
		(layer "B.Cu")
		(net "SSD_PERST#9")
	)
	(segment
		(start 337.7946 -182.2831)
		(end 338.074 -182.2831)
		(width 0.12065)
		(layer "B.Cu")
		(net "SSD_PERST#9")
	)
	(segment
		(start 339.734652 -174.742348)
		(end 340.159848 -174.317152)
		(width 0.12065)
		(layer "B.Cu")
		(net "SSD_PERST#9")
	)
	(segment
		(start 338.242148 -182.451248)
		(end 339.344 -182.451248)
		(width 0.12065)
		(layer "B.Cu")
		(net "SSD_PERST#9")
	)
	(segment
		(start 339.175852 -179.959)
		(end 338.470748 -179.253896)
		(width 0.12065)
		(layer "B.Cu")
		(net "SSD_PERST#9")
	)
	(segment
		(start 339.53704 -175.503586)
		(end 339.435948 -175.402494)
		(width 0.12065)
		(layer "B.Cu")
		(net "SSD_PERST#9")
	)
	(segment
		(start 338.470748 -177.645568)
		(end 339.53704 -176.579276)
		(width 0.12065)
		(layer "B.Cu")
		(net "SSD_PERST#9")
	)
	(segment
		(start 340.343236 -174.058834)
		(end 340.343236 -173.693328)
		(width 0.12065)
		(layer "B.Cu")
		(net "SSD_PERST#9")
	)
	(segment
		(start 341.037672 -173.693328)
		(end 341.12327 -173.60773)
		(width 0.12065)
		(layer "B.Cu")
		(net "SSD_PERST#9")
	)
	(segment
		(start 338.074 -182.2831)
		(end 338.242148 -182.451248)
		(width 0.12065)
		(layer "B.Cu")
		(net "SSD_PERST#9")
	)
	(segment
		(start 226.44862 -189.680088)
		(end 226.925124 -190.156592)
		(width 0.12065)
		(layer "F.Cu")
		(net "SSD_PERST#8_R")
	)
	(segment
		(start 226.5934 -183.1594)
		(end 226.5934 -188.299852)
		(width 0.12065)
		(layer "F.Cu")
		(net "SSD_PERST#8_R")
	)
	(segment
		(start 226.328224 -191.932814)
		(end 226.458272 -191.802766)
		(width 0.12065)
		(layer "F.Cu")
		(net "SSD_PERST#8_R")
	)
	(segment
		(start 226.458272 -191.802766)
		(end 226.458272 -190.623444)
		(width 0.12065)
		(layer "F.Cu")
		(net "SSD_PERST#8_R")
	)
	(segment
		(start 226.5934 -188.299852)
		(end 226.44862 -188.444632)
		(width 0.12065)
		(layer "F.Cu")
		(net "SSD_PERST#8_R")
	)
	(segment
		(start 226.44862 -188.444632)
		(end 226.44862 -189.680088)
		(width 0.12065)
		(layer "F.Cu")
		(net "SSD_PERST#8_R")
	)
	(segment
		(start 226.458272 -190.623444)
		(end 226.925124 -190.156592)
		(width 0.12065)
		(layer "F.Cu")
		(net "SSD_PERST#8_R")
	)
	(via
		(at 226.5934 -183.1594)
		(size 0.508)
		(drill 0.254)
		(layers "F.Cu" "B.Cu")
		(net "SSD_PERST#8_R")
	)
	(via
		(at 226.5934 -176.276)
		(size 0.7112)
		(drill 0.3556)
		(layers "F.Cu" "B.Cu")
		(net "SSD_PERST#8_R")
	)
	(via
		(at 226.328224 -191.932814)
		(size 0.508)
		(drill 0.254)
		(layers "F.Cu" "B.Cu")
		(net "SSD_PERST#8_R")
	)
	(segment
		(start 224.079562 -193.61023)
		(end 225.35388 -193.61023)
		(width 0.12065)
		(layer "B.Cu")
		(net "SSD_PERST#8_R")
	)
	(segment
		(start 225.815652 -192.445386)
		(end 226.328224 -191.932814)
		(width 0.12065)
		(layer "B.Cu")
		(net "SSD_PERST#8_R")
	)
	(segment
		(start 268.236192 -219.353892)
		(end 259.97535 -211.09305)
		(width 0.12065)
		(layer "B.Cu")
		(net "SSD_PERST#8_R")
	)
	(segment
		(start 268.236192 -223.357186)
		(end 268.236192 -219.353892)
		(width 0.12065)
		(layer "B.Cu")
		(net "SSD_PERST#8_R")
	)
	(segment
		(start 255.2192 -158.0642)
		(end 228.519736 -158.0642)
		(width 0.12065)
		(layer "B.Cu")
		(net "SSD_PERST#8_R")
	)
	(segment
		(start 228.519736 -158.0642)
		(end 226.5934 -159.990536)
		(width 0.12065)
		(layer "B.Cu")
		(net "SSD_PERST#8_R")
	)
	(segment
		(start 259.97535 -162.82035)
		(end 255.2192 -158.0642)
		(width 0.12065)
		(layer "B.Cu")
		(net "SSD_PERST#8_R")
	)
	(segment
		(start 226.5934 -159.990536)
		(end 226.5934 -176.276)
		(width 0.12065)
		(layer "B.Cu")
		(net "SSD_PERST#8_R")
	)
	(segment
		(start 259.97535 -211.09305)
		(end 259.97535 -162.82035)
		(width 0.12065)
		(layer "B.Cu")
		(net "SSD_PERST#8_R")
	)
	(segment
		(start 268.500098 -225.92538)
		(end 268.500098 -223.621092)
		(width 0.12065)
		(layer "B.Cu")
		(net "SSD_PERST#8_R")
	)
	(segment
		(start 268.500098 -223.621092)
		(end 268.236192 -223.357186)
		(width 0.12065)
		(layer "B.Cu")
		(net "SSD_PERST#8_R")
	)
	(segment
		(start 226.5934 -176.276)
		(end 226.5934 -183.1594)
		(width 0.12065)
		(layer "B.Cu")
		(net "SSD_PERST#8_R")
	)
	(segment
		(start 225.815652 -193.148458)
		(end 225.815652 -192.445386)
		(width 0.12065)
		(layer "B.Cu")
		(net "SSD_PERST#8_R")
	)
	(segment
		(start 225.35388 -193.61023)
		(end 225.815652 -193.148458)
		(width 0.12065)
		(layer "B.Cu")
		(net "SSD_PERST#8_R")
	)
	(segment
		(start 227.965508 -191.045592)
		(end 226.925124 -191.045592)
		(width 0.12065)
		(layer "F.Cu")
		(net "SSD_PERST#8")
	)
	(segment
		(start 227.9904 -191.0207)
		(end 227.965508 -191.045592)
		(width 0.12065)
		(layer "F.Cu")
		(net "SSD_PERST#8")
	)
	(segment
		(start 225.492818 -193.167)
		(end 226.237546 -193.167)
		(width 0.12065)
		(layer "F.Cu")
		(net "SSD_PERST#8")
	)
	(segment
		(start 226.237546 -193.167)
		(end 227.19411 -192.210436)
		(width 0.12065)
		(layer "F.Cu")
		(net "SSD_PERST#8")
	)
	(segment
		(start 225.152204 -193.507614)
		(end 225.492818 -193.167)
		(width 0.12065)
		(layer "F.Cu")
		(net "SSD_PERST#8")
	)
	(segment
		(start 225.152204 -194.131692)
		(end 225.152204 -193.507614)
		(width 0.12065)
		(layer "F.Cu")
		(net "SSD_PERST#8")
	)
	(segment
		(start 227.19411 -191.314578)
		(end 226.925124 -191.045592)
		(width 0.12065)
		(layer "F.Cu")
		(net "SSD_PERST#8")
	)
	(segment
		(start 227.19411 -191.897254)
		(end 227.19411 -191.314578)
		(width 0.12065)
		(layer "F.Cu")
		(net "SSD_PERST#8")
	)
	(segment
		(start 227.19411 -192.210436)
		(end 227.19411 -191.897254)
		(width 0.12065)
		(layer "F.Cu")
		(net "SSD_PERST#8")
	)
	(via
		(at 228.5492 -191.262)
		(size 0.7112)
		(drill 0.3556)
		(layers "F.Cu" "B.Cu")
		(net "SSD_PERST#8")
	)
	(via
		(at 227.19411 -191.897254)
		(size 0.508)
		(drill 0.254)
		(layers "F.Cu" "B.Cu")
		(net "SSD_PERST#8")
	)
	(segment
		(start 225.478848 -195.248022)
		(end 225.377248 -195.349622)
		(width 0.12065)
		(layer "B.Cu")
		(net "SSD_PERST#8")
	)
	(segment
		(start 228.332792 -191.045592)
		(end 228.5492 -191.262)
		(width 0.12065)
		(layer "B.Cu")
		(net "SSD_PERST#8")
	)
	(segment
		(start 226.177602 -192.913762)
		(end 226.177602 -193.298572)
		(width 0.12065)
		(layer "B.Cu")
		(net "SSD_PERST#8")
	)
	(segment
		(start 225.377248 -196.966332)
		(end 224.869248 -197.474332)
		(width 0.12065)
		(layer "B.Cu")
		(net "SSD_PERST#8")
	)
	(segment
		(start 226.925124 -191.188086)
		(end 227.19411 -191.457072)
		(width 0.12065)
		(layer "B.Cu")
		(net "SSD_PERST#8")
	)
	(segment
		(start 224.869248 -197.474332)
		(end 224.869248 -200.547732)
		(width 0.12065)
		(layer "B.Cu")
		(net "SSD_PERST#8")
	)
	(segment
		(start 225.933 -193.543174)
		(end 225.933 -194.364356)
		(width 0.12065)
		(layer "B.Cu")
		(net "SSD_PERST#8")
	)
	(segment
		(start 226.925124 -191.045592)
		(end 226.925124 -191.188086)
		(width 0.12065)
		(layer "B.Cu")
		(net "SSD_PERST#8")
	)
	(segment
		(start 227.19411 -191.457072)
		(end 227.19411 -191.897254)
		(width 0.12065)
		(layer "B.Cu")
		(net "SSD_PERST#8")
	)
	(segment
		(start 227.19411 -191.897254)
		(end 226.177602 -192.913762)
		(width 0.12065)
		(layer "B.Cu")
		(net "SSD_PERST#8")
	)
	(segment
		(start 225.377248 -195.349622)
		(end 225.377248 -196.966332)
		(width 0.12065)
		(layer "B.Cu")
		(net "SSD_PERST#8")
	)
	(segment
		(start 226.925124 -191.045592)
		(end 228.332792 -191.045592)
		(width 0.12065)
		(layer "B.Cu")
		(net "SSD_PERST#8")
	)
	(segment
		(start 225.478848 -194.818508)
		(end 225.478848 -195.248022)
		(width 0.12065)
		(layer "B.Cu")
		(net "SSD_PERST#8")
	)
	(segment
		(start 225.933 -194.364356)
		(end 225.478848 -194.818508)
		(width 0.12065)
		(layer "B.Cu")
		(net "SSD_PERST#8")
	)
	(segment
		(start 224.869248 -200.547732)
		(end 224.01784 -201.39914)
		(width 0.12065)
		(layer "B.Cu")
		(net "SSD_PERST#8")
	)
	(segment
		(start 226.177602 -193.298572)
		(end 225.933 -193.543174)
		(width 0.12065)
		(layer "B.Cu")
		(net "SSD_PERST#8")
	)
	(segment
		(start 128.119124 -209.396076)
		(end 127.1778 -210.3374)
		(width 0.12065)
		(layer "F.Cu")
		(net "SSD_PERST#7_R")
	)
	(segment
		(start 128.119124 -209.333592)
		(end 128.119124 -209.396076)
		(width 0.12065)
		(layer "F.Cu")
		(net "SSD_PERST#7_R")
	)
	(via
		(at 127.1778 -210.3374)
		(size 0.508)
		(drill 0.254)
		(layers "F.Cu" "B.Cu")
		(net "SSD_PERST#7_R")
	)
	(via
		(at 176.083722 -204.455522)
		(size 0.7112)
		(drill 0.3556)
		(layers "F.Cu" "B.Cu")
		(net "SSD_PERST#7_R")
	)
	(via
		(at 119.126 -199.136)
		(size 0.508)
		(drill 0.254)
		(layers "F.Cu" "B.Cu")
		(net "SSD_PERST#7_R")
	)
	(segment
		(start 184.7088 -213.0806)
		(end 176.083722 -204.455522)
		(width 0.12065)
		(layer "B.Cu")
		(net "SSD_PERST#7_R")
	)
	(segment
		(start 176.083722 -204.455522)
		(end 167.1955 -195.5673)
		(width 0.12065)
		(layer "B.Cu")
		(net "SSD_PERST#7_R")
	)
	(segment
		(start 123.979178 -198.796148)
		(end 123.928378 -198.745348)
		(width 0.12065)
		(layer "B.Cu")
		(net "SSD_PERST#7_R")
	)
	(segment
		(start 184.100216 -223.554036)
		(end 184.37225 -223.282002)
		(width 0.12065)
		(layer "B.Cu")
		(net "SSD_PERST#7_R")
	)
	(segment
		(start 124.31141 -199.011286)
		(end 124.295408 -199.011286)
		(width 0.12065)
		(layer "B.Cu")
		(net "SSD_PERST#7_R")
	)
	(segment
		(start 123.928378 -198.745348)
		(end 122.578622 -198.745348)
		(width 0.12065)
		(layer "B.Cu")
		(net "SSD_PERST#7_R")
	)
	(segment
		(start 167.1955 -195.5673)
		(end 151.252428 -195.5673)
		(width 0.12065)
		(layer "B.Cu")
		(net "SSD_PERST#7_R")
	)
	(segment
		(start 121.02973 -198.75627)
		(end 120.65 -199.136)
		(width 0.12065)
		(layer "B.Cu")
		(net "SSD_PERST#7_R")
	)
	(segment
		(start 128.139952 -211.299552)
		(end 127.1778 -210.3374)
		(width 0.12065)
		(layer "B.Cu")
		(net "SSD_PERST#7_R")
	)
	(segment
		(start 120.65 -199.136)
		(end 119.126 -199.136)
		(width 0.12065)
		(layer "B.Cu")
		(net "SSD_PERST#7_R")
	)
	(segment
		(start 184.100216 -225.92538)
		(end 184.100216 -223.554036)
		(width 0.12065)
		(layer "B.Cu")
		(net "SSD_PERST#7_R")
	)
	(segment
		(start 135.520176 -211.299552)
		(end 128.139952 -211.299552)
		(width 0.12065)
		(layer "B.Cu")
		(net "SSD_PERST#7_R")
	)
	(segment
		(start 124.295408 -199.011286)
		(end 124.08027 -198.796148)
		(width 0.12065)
		(layer "B.Cu")
		(net "SSD_PERST#7_R")
	)
	(segment
		(start 124.601224 -199.3011)
		(end 124.31141 -199.011286)
		(width 0.12065)
		(layer "B.Cu")
		(net "SSD_PERST#7_R")
	)
	(segment
		(start 124.08027 -198.796148)
		(end 123.979178 -198.796148)
		(width 0.12065)
		(layer "B.Cu")
		(net "SSD_PERST#7_R")
	)
	(segment
		(start 122.5677 -198.75627)
		(end 121.02973 -198.75627)
		(width 0.12065)
		(layer "B.Cu")
		(net "SSD_PERST#7_R")
	)
	(segment
		(start 124.9426 -199.3011)
		(end 124.601224 -199.3011)
		(width 0.12065)
		(layer "B.Cu")
		(net "SSD_PERST#7_R")
	)
	(segment
		(start 122.578622 -198.745348)
		(end 122.5677 -198.75627)
		(width 0.12065)
		(layer "B.Cu")
		(net "SSD_PERST#7_R")
	)
	(segment
		(start 184.37225 -223.282002)
		(end 184.37225 -222.30715)
		(width 0.12065)
		(layer "B.Cu")
		(net "SSD_PERST#7_R")
	)
	(segment
		(start 184.7088 -221.9706)
		(end 184.7088 -213.0806)
		(width 0.12065)
		(layer "B.Cu")
		(net "SSD_PERST#7_R")
	)
	(segment
		(start 151.252428 -195.5673)
		(end 135.520176 -211.299552)
		(width 0.12065)
		(layer "B.Cu")
		(net "SSD_PERST#7_R")
	)
	(segment
		(start 184.37225 -222.30715)
		(end 184.7088 -221.9706)
		(width 0.12065)
		(layer "B.Cu")
		(net "SSD_PERST#7_R")
	)
	(segment
		(start 119.126 -199.136)
		(end 119.38 -199.39)
		(width 0.127)
		(layer "In2.Cu")
		(net "SSD_PERST#7_R")
	)
	(segment
		(start 119.38 -199.39)
		(end 119.38 -208.407)
		(width 0.127)
		(layer "In2.Cu")
		(net "SSD_PERST#7_R")
	)
	(segment
		(start 120.396 -209.423)
		(end 126.873 -209.423)
		(width 0.127)
		(layer "In2.Cu")
		(net "SSD_PERST#7_R")
	)
	(segment
		(start 119.38 -208.407)
		(end 120.396 -209.423)
		(width 0.127)
		(layer "In2.Cu")
		(net "SSD_PERST#7_R")
	)
	(segment
		(start 126.873 -209.423)
		(end 127.1778 -209.7278)
		(width 0.127)
		(layer "In2.Cu")
		(net "SSD_PERST#7_R")
	)
	(segment
		(start 127.1778 -209.7278)
		(end 127.1778 -210.3374)
		(width 0.127)
		(layer "In2.Cu")
		(net "SSD_PERST#7_R")
	)
	(segment
		(start 127.397764 -206.4766)
		(end 127.10541 -206.768954)
		(width 0.12065)
		(layer "F.Cu")
		(net "SSD_PERST#7")
	)
	(segment
		(start 127.0254 -208.4451)
		(end 127.0254 -207.825086)
		(width 0.12065)
		(layer "F.Cu")
		(net "SSD_PERST#7")
	)
	(segment
		(start 128.119124 -208.444592)
		(end 127.025908 -208.444592)
		(width 0.12065)
		(layer "F.Cu")
		(net "SSD_PERST#7")
	)
	(segment
		(start 127.10541 -206.768954)
		(end 127.10541 -207.653128)
		(width 0.12065)
		(layer "F.Cu")
		(net "SSD_PERST#7")
	)
	(segment
		(start 127.397764 -205.612492)
		(end 127.397764 -204.359764)
		(width 0.12065)
		(layer "F.Cu")
		(net "SSD_PERST#7")
	)
	(segment
		(start 124.988828 -203.581)
		(end 123.698 -203.581)
		(width 0.12065)
		(layer "F.Cu")
		(net "SSD_PERST#7")
	)
	(segment
		(start 127.025908 -208.444592)
		(end 127.0254 -208.4451)
		(width 0.12065)
		(layer "F.Cu")
		(net "SSD_PERST#7")
	)
	(segment
		(start 127.254 -204.216)
		(end 125.623828 -204.216)
		(width 0.12065)
		(layer "F.Cu")
		(net "SSD_PERST#7")
	)
	(segment
		(start 127.0254 -207.825086)
		(end 127.10541 -207.745076)
		(width 0.12065)
		(layer "F.Cu")
		(net "SSD_PERST#7")
	)
	(segment
		(start 127.397764 -204.359764)
		(end 127.254 -204.216)
		(width 0.12065)
		(layer "F.Cu")
		(net "SSD_PERST#7")
	)
	(segment
		(start 125.623828 -204.216)
		(end 124.988828 -203.581)
		(width 0.12065)
		(layer "F.Cu")
		(net "SSD_PERST#7")
	)
	(segment
		(start 127.10541 -207.745076)
		(end 127.10541 -207.653128)
		(width 0.12065)
		(layer "F.Cu")
		(net "SSD_PERST#7")
	)
	(segment
		(start 127.397764 -205.612492)
		(end 127.397764 -206.4766)
		(width 0.12065)
		(layer "F.Cu")
		(net "SSD_PERST#7")
	)
	(via
		(at 125.623828 -204.216)
		(size 0.508)
		(drill 0.254)
		(layers "F.Cu" "B.Cu")
		(net "SSD_PERST#7")
	)
	(via
		(at 123.698 -203.581)
		(size 0.7112)
		(drill 0.3556)
		(layers "F.Cu" "B.Cu")
		(net "SSD_PERST#7")
	)
	(via
		(at 127.10541 -207.653128)
		(size 0.508)
		(drill 0.254)
		(layers "F.Cu" "B.Cu")
		(net "SSD_PERST#7")
	)
	(segment
		(start 125.095 -206.1845)
		(end 125.4125 -206.1845)
		(width 0.12065)
		(layer "B.Cu")
		(net "SSD_PERST#7")
	)
	(segment
		(start 125.623828 -205.973172)
		(end 125.623828 -204.216)
		(width 0.12065)
		(layer "B.Cu")
		(net "SSD_PERST#7")
	)
	(segment
		(start 127.103124 -208.444592)
		(end 127.103124 -207.747362)
		(width 0.12065)
		(layer "B.Cu")
		(net "SSD_PERST#7")
	)
	(segment
		(start 127.10541 -207.745076)
		(end 127.10541 -207.653128)
		(width 0.12065)
		(layer "B.Cu")
		(net "SSD_PERST#7")
	)
	(segment
		(start 125.4125 -206.1845)
		(end 125.623828 -205.973172)
		(width 0.12065)
		(layer "B.Cu")
		(net "SSD_PERST#7")
	)
	(segment
		(start 127.103124 -207.747362)
		(end 127.10541 -207.745076)
		(width 0.12065)
		(layer "B.Cu")
		(net "SSD_PERST#7")
	)
	(segment
		(start 131.8768 -211.3534)
		(end 132.9182 -212.3948)
		(width 0.12065)
		(layer "F.Cu")
		(net "SSD_PERST#6_R")
	)
	(segment
		(start 132.9182 -212.3948)
		(end 133.985 -212.3948)
		(width 0.12065)
		(layer "F.Cu")
		(net "SSD_PERST#6_R")
	)
	(segment
		(start 132.310124 -209.333592)
		(end 131.8768 -209.766916)
		(width 0.12065)
		(layer "F.Cu")
		(net "SSD_PERST#6_R")
	)
	(segment
		(start 131.8768 -209.766916)
		(end 131.8768 -211.3534)
		(width 0.12065)
		(layer "F.Cu")
		(net "SSD_PERST#6_R")
	)
	(via
		(at 133.985 -212.3948)
		(size 0.508)
		(drill 0.254)
		(layers "F.Cu" "B.Cu")
		(net "SSD_PERST#6_R")
	)
	(via
		(at 137.287 -198.374)
		(size 0.508)
		(drill 0.254)
		(layers "F.Cu" "B.Cu")
		(net "SSD_PERST#6_R")
	)
	(via
		(at 138.557 -199.009)
		(size 0.7112)
		(drill 0.3556)
		(layers "F.Cu" "B.Cu")
		(net "SSD_PERST#6_R")
	)
	(segment
		(start 138.303 -198.374)
		(end 138.557 -198.628)
		(width 0.12065)
		(layer "B.Cu")
		(net "SSD_PERST#6_R")
	)
	(segment
		(start 138.257026 -199.308974)
		(end 138.557 -199.009)
		(width 0.12065)
		(layer "B.Cu")
		(net "SSD_PERST#6_R")
	)
	(segment
		(start 135.300212 -213.710012)
		(end 133.985 -212.3948)
		(width 0.12065)
		(layer "B.Cu")
		(net "SSD_PERST#6_R")
	)
	(segment
		(start 137.287 -198.374)
		(end 138.303 -198.374)
		(width 0.12065)
		(layer "B.Cu")
		(net "SSD_PERST#6_R")
	)
	(segment
		(start 137.332212 -199.308974)
		(end 138.257026 -199.308974)
		(width 0.12065)
		(layer "B.Cu")
		(net "SSD_PERST#6_R")
	)
	(segment
		(start 138.557 -198.628)
		(end 138.557 -199.009)
		(width 0.12065)
		(layer "B.Cu")
		(net "SSD_PERST#6_R")
	)
	(segment
		(start 135.300212 -225.92538)
		(end 135.300212 -213.710012)
		(width 0.12065)
		(layer "B.Cu")
		(net "SSD_PERST#6_R")
	)
	(segment
		(start 137.795 -208.6356)
		(end 134.0358 -212.3948)
		(width 0.127)
		(layer "In2.Cu")
		(net "SSD_PERST#6_R")
	)
	(segment
		(start 134.0358 -212.3948)
		(end 133.985 -212.3948)
		(width 0.127)
		(layer "In2.Cu")
		(net "SSD_PERST#6_R")
	)
	(segment
		(start 137.287 -198.374)
		(end 137.795 -198.882)
		(width 0.127)
		(layer "In2.Cu")
		(net "SSD_PERST#6_R")
	)
	(segment
		(start 137.795 -204.059282)
		(end 138.2649 -204.529182)
		(width 0.127)
		(layer "In2.Cu")
		(net "SSD_PERST#6_R")
	)
	(segment
		(start 138.2649 -204.529182)
		(end 138.2649 -204.918818)
		(width 0.127)
		(layer "In2.Cu")
		(net "SSD_PERST#6_R")
	)
	(segment
		(start 137.795 -205.388718)
		(end 137.795 -208.6356)
		(width 0.127)
		(layer "In2.Cu")
		(net "SSD_PERST#6_R")
	)
	(segment
		(start 138.2649 -204.918818)
		(end 137.795 -205.388718)
		(width 0.127)
		(layer "In2.Cu")
		(net "SSD_PERST#6_R")
	)
	(segment
		(start 137.795 -198.882)
		(end 137.795 -204.059282)
		(width 0.127)
		(layer "In2.Cu")
		(net "SSD_PERST#6_R")
	)
	(segment
		(start 131.21894 -207.619854)
		(end 131.303522 -207.619854)
		(width 0.12065)
		(layer "F.Cu")
		(net "SSD_PERST#6")
	)
	(segment
		(start 132.12826 -208.444592)
		(end 131.303522 -207.619854)
		(width 0.12065)
		(layer "F.Cu")
		(net "SSD_PERST#6")
	)
	(segment
		(start 129.998724 -205.612492)
		(end 129.998724 -206.399638)
		(width 0.12065)
		(layer "F.Cu")
		(net "SSD_PERST#6")
	)
	(segment
		(start 129.998724 -206.399638)
		(end 131.21894 -207.619854)
		(width 0.12065)
		(layer "F.Cu")
		(net "SSD_PERST#6")
	)
	(segment
		(start 132.310124 -208.444592)
		(end 132.12826 -208.444592)
		(width 0.12065)
		(layer "F.Cu")
		(net "SSD_PERST#6")
	)
	(via
		(at 136.525 -207.518)
		(size 0.7112)
		(drill 0.3556)
		(layers "F.Cu" "B.Cu")
		(net "SSD_PERST#6")
	)
	(via
		(at 131.303522 -207.619854)
		(size 0.508)
		(drill 0.254)
		(layers "F.Cu" "B.Cu")
		(net "SSD_PERST#6")
	)
	(segment
		(start 131.745228 -207.178148)
		(end 135.255 -207.178148)
		(width 0.12065)
		(layer "B.Cu")
		(net "SSD_PERST#6")
	)
	(segment
		(start 131.294124 -207.629252)
		(end 131.303522 -207.619854)
		(width 0.12065)
		(layer "B.Cu")
		(net "SSD_PERST#6")
	)
	(segment
		(start 136.824212 -207.218788)
		(end 136.824212 -206.293974)
		(width 0.12065)
		(layer "B.Cu")
		(net "SSD_PERST#6")
	)
	(segment
		(start 131.294124 -208.444592)
		(end 131.294124 -207.629252)
		(width 0.12065)
		(layer "B.Cu")
		(net "SSD_PERST#6")
	)
	(segment
		(start 137.8712 -206.3877)
		(end 137.777474 -206.293974)
		(width 0.12065)
		(layer "B.Cu")
		(net "SSD_PERST#6")
	)
	(segment
		(start 131.303522 -207.619854)
		(end 131.745228 -207.178148)
		(width 0.12065)
		(layer "B.Cu")
		(net "SSD_PERST#6")
	)
	(segment
		(start 137.777474 -206.293974)
		(end 136.824212 -206.293974)
		(width 0.12065)
		(layer "B.Cu")
		(net "SSD_PERST#6")
	)
	(segment
		(start 135.255 -207.178148)
		(end 135.594852 -207.518)
		(width 0.12065)
		(layer "B.Cu")
		(net "SSD_PERST#6")
	)
	(segment
		(start 135.594852 -207.518)
		(end 136.525 -207.518)
		(width 0.12065)
		(layer "B.Cu")
		(net "SSD_PERST#6")
	)
	(segment
		(start 136.525 -207.518)
		(end 136.824212 -207.218788)
		(width 0.12065)
		(layer "B.Cu")
		(net "SSD_PERST#6")
	)
	(segment
		(start 78.376272 -184.084214)
		(end 78.048612 -184.411874)
		(width 0.12065)
		(layer "F.Cu")
		(net "SSD_PERST#5_R")
	)
	(segment
		(start 78.376272 -183.257444)
		(end 78.376272 -184.084214)
		(width 0.12065)
		(layer "F.Cu")
		(net "SSD_PERST#5_R")
	)
	(segment
		(start 78.048612 -184.411874)
		(end 78.048612 -184.454292)
		(width 0.12065)
		(layer "F.Cu")
		(net "SSD_PERST#5_R")
	)
	(segment
		(start 78.843124 -182.790592)
		(end 78.376272 -183.257444)
		(width 0.12065)
		(layer "F.Cu")
		(net "SSD_PERST#5_R")
	)
	(via
		(at 61.214 -180.975)
		(size 0.508)
		(drill 0.254)
		(layers "F.Cu" "B.Cu")
		(net "SSD_PERST#5_R")
	)
	(via
		(at 78.048612 -184.454292)
		(size 0.508)
		(drill 0.254)
		(layers "F.Cu" "B.Cu")
		(net "SSD_PERST#5_R")
	)
	(via
		(at 43.13936 -212.51164)
		(size 0.7112)
		(drill 0.3556)
		(layers "F.Cu" "B.Cu")
		(net "SSD_PERST#5_R")
	)
	(segment
		(start 60.579 -181.61)
		(end 60.579 -201.295)
		(width 0.12065)
		(layer "B.Cu")
		(net "SSD_PERST#5_R")
	)
	(segment
		(start 43.700192 -225.92538)
		(end 43.700192 -222.820992)
		(width 0.12065)
		(layer "B.Cu")
		(net "SSD_PERST#5_R")
	)
	(segment
		(start 54.61 -207.264)
		(end 48.387 -207.264)
		(width 0.12065)
		(layer "B.Cu")
		(net "SSD_PERST#5_R")
	)
	(segment
		(start 42.799 -212.852)
		(end 43.13936 -212.51164)
		(width 0.12065)
		(layer "B.Cu")
		(net "SSD_PERST#5_R")
	)
	(segment
		(start 43.700192 -222.820992)
		(end 42.799 -221.9198)
		(width 0.12065)
		(layer "B.Cu")
		(net "SSD_PERST#5_R")
	)
	(segment
		(start 79.541878 -185.067702)
		(end 78.928468 -184.454292)
		(width 0.12065)
		(layer "B.Cu")
		(net "SSD_PERST#5_R")
	)
	(segment
		(start 48.387 -207.264)
		(end 43.13936 -212.51164)
		(width 0.12065)
		(layer "B.Cu")
		(net "SSD_PERST#5_R")
	)
	(segment
		(start 79.541878 -185.725308)
		(end 79.541878 -185.067702)
		(width 0.12065)
		(layer "B.Cu")
		(net "SSD_PERST#5_R")
	)
	(segment
		(start 78.928468 -184.454292)
		(end 78.048612 -184.454292)
		(width 0.12065)
		(layer "B.Cu")
		(net "SSD_PERST#5_R")
	)
	(segment
		(start 60.579 -201.295)
		(end 54.61 -207.264)
		(width 0.12065)
		(layer "B.Cu")
		(net "SSD_PERST#5_R")
	)
	(segment
		(start 61.214 -180.975)
		(end 60.579 -181.61)
		(width 0.12065)
		(layer "B.Cu")
		(net "SSD_PERST#5_R")
	)
	(segment
		(start 42.799 -221.9198)
		(end 42.799 -212.852)
		(width 0.12065)
		(layer "B.Cu")
		(net "SSD_PERST#5_R")
	)
	(segment
		(start 79.166212 -186.100974)
		(end 79.541878 -185.725308)
		(width 0.12065)
		(layer "B.Cu")
		(net "SSD_PERST#5_R")
	)
	(segment
		(start 78.048612 -184.272428)
		(end 73.608184 -179.832)
		(width 0.127)
		(layer "In5.Cu")
		(net "SSD_PERST#5_R")
	)
	(segment
		(start 62.357 -179.832)
		(end 61.214 -180.975)
		(width 0.127)
		(layer "In5.Cu")
		(net "SSD_PERST#5_R")
	)
	(segment
		(start 73.608184 -179.832)
		(end 62.357 -179.832)
		(width 0.127)
		(layer "In5.Cu")
		(net "SSD_PERST#5_R")
	)
	(segment
		(start 78.048612 -184.454292)
		(end 78.048612 -184.272428)
		(width 0.127)
		(layer "In5.Cu")
		(net "SSD_PERST#5_R")
	)
	(segment
		(start 78.843124 -183.859932)
		(end 79.514446 -184.531254)
		(width 0.12065)
		(layer "F.Cu")
		(net "SSD_PERST#5")
	)
	(segment
		(start 77.070204 -186.765692)
		(end 77.070204 -186.168284)
		(width 0.12065)
		(layer "F.Cu")
		(net "SSD_PERST#5")
	)
	(segment
		(start 77.070204 -186.168284)
		(end 78.356714 -184.881774)
		(width 0.12065)
		(layer "F.Cu")
		(net "SSD_PERST#5")
	)
	(segment
		(start 78.356714 -184.881774)
		(end 79.869792 -184.881774)
		(width 0.12065)
		(layer "F.Cu")
		(net "SSD_PERST#5")
	)
	(segment
		(start 79.514446 -184.531254)
		(end 79.866744 -184.531254)
		(width 0.12065)
		(layer "F.Cu")
		(net "SSD_PERST#5")
	)
	(segment
		(start 79.883 -183.7055)
		(end 79.857092 -183.679592)
		(width 0.12065)
		(layer "F.Cu")
		(net "SSD_PERST#5")
	)
	(segment
		(start 79.869792 -184.881774)
		(end 80.043528 -184.708038)
		(width 0.12065)
		(layer "F.Cu")
		(net "SSD_PERST#5")
	)
	(segment
		(start 79.866744 -184.531254)
		(end 80.043528 -184.708038)
		(width 0.12065)
		(layer "F.Cu")
		(net "SSD_PERST#5")
	)
	(segment
		(start 79.857092 -183.679592)
		(end 78.843124 -183.679592)
		(width 0.12065)
		(layer "F.Cu")
		(net "SSD_PERST#5")
	)
	(segment
		(start 78.843124 -183.679592)
		(end 78.843124 -183.859932)
		(width 0.12065)
		(layer "F.Cu")
		(net "SSD_PERST#5")
	)
	(via
		(at 80.043528 -184.708038)
		(size 0.508)
		(drill 0.254)
		(layers "F.Cu" "B.Cu")
		(net "SSD_PERST#5")
	)
	(via
		(at 80.813148 -185.407046)
		(size 0.7112)
		(drill 0.3556)
		(layers "F.Cu" "B.Cu")
		(net "SSD_PERST#5")
	)
	(segment
		(start 80.08366 -191.311276)
		(end 80.08366 -191.28613)
		(width 0.12065)
		(layer "B.Cu")
		(net "SSD_PERST#5")
	)
	(segment
		(start 79.962248 -187.627768)
		(end 81.065624 -186.524392)
		(width 0.12065)
		(layer "B.Cu")
		(net "SSD_PERST#5")
	)
	(segment
		(start 79.962248 -191.164718)
		(end 79.962248 -187.627768)
		(width 0.12065)
		(layer "B.Cu")
		(net "SSD_PERST#5")
	)
	(segment
		(start 79.039212 -193.085974)
		(end 80.132936 -193.085974)
		(width 0.12065)
		(layer "B.Cu")
		(net "SSD_PERST#5")
	)
	(segment
		(start 81.065624 -186.524392)
		(end 81.065624 -185.659522)
		(width 0.12065)
		(layer "B.Cu")
		(net "SSD_PERST#5")
	)
	(segment
		(start 80.603852 -192.615058)
		(end 80.603852 -192.144142)
		(width 0.12065)
		(layer "B.Cu")
		(net "SSD_PERST#5")
	)
	(segment
		(start 79.866744 -184.531254)
		(end 80.043528 -184.708038)
		(width 0.12065)
		(layer "B.Cu")
		(net "SSD_PERST#5")
	)
	(segment
		(start 80.253586 -191.793876)
		(end 80.253586 -191.481202)
		(width 0.12065)
		(layer "B.Cu")
		(net "SSD_PERST#5")
	)
	(segment
		(start 80.253586 -191.481202)
		(end 80.08366 -191.311276)
		(width 0.12065)
		(layer "B.Cu")
		(net "SSD_PERST#5")
	)
	(segment
		(start 80.603852 -192.144142)
		(end 80.253586 -191.793876)
		(width 0.12065)
		(layer "B.Cu")
		(net "SSD_PERST#5")
	)
	(segment
		(start 78.843124 -183.679592)
		(end 78.843124 -183.768746)
		(width 0.12065)
		(layer "B.Cu")
		(net "SSD_PERST#5")
	)
	(segment
		(start 81.065624 -185.659522)
		(end 80.813148 -185.407046)
		(width 0.12065)
		(layer "B.Cu")
		(net "SSD_PERST#5")
	)
	(segment
		(start 80.043528 -184.708038)
		(end 80.11414 -184.708038)
		(width 0.12065)
		(layer "B.Cu")
		(net "SSD_PERST#5")
	)
	(segment
		(start 78.843124 -183.768746)
		(end 79.605632 -184.531254)
		(width 0.12065)
		(layer "B.Cu")
		(net "SSD_PERST#5")
	)
	(segment
		(start 79.605632 -184.531254)
		(end 79.866744 -184.531254)
		(width 0.12065)
		(layer "B.Cu")
		(net "SSD_PERST#5")
	)
	(segment
		(start 80.11414 -184.708038)
		(end 80.813148 -185.407046)
		(width 0.12065)
		(layer "B.Cu")
		(net "SSD_PERST#5")
	)
	(segment
		(start 80.132936 -193.085974)
		(end 80.603852 -192.615058)
		(width 0.12065)
		(layer "B.Cu")
		(net "SSD_PERST#5")
	)
	(segment
		(start 80.08366 -191.28613)
		(end 79.962248 -191.164718)
		(width 0.12065)
		(layer "B.Cu")
		(net "SSD_PERST#5")
	)
	(segment
		(start 335.35366 -172.45457)
		(end 335.35366 -173.450758)
		(width 0.12065)
		(layer "F.Cu")
		(net "SSD_PERST#4_R")
	)
	(segment
		(start 335.820512 -171.987718)
		(end 335.35366 -172.45457)
		(width 0.12065)
		(layer "F.Cu")
		(net "SSD_PERST#4_R")
	)
	(segment
		(start 335.820512 -171.939712)
		(end 335.268062 -171.387262)
		(width 0.12065)
		(layer "F.Cu")
		(net "SSD_PERST#4_R")
	)
	(segment
		(start 335.268062 -171.387262)
		(end 335.268062 -168.517062)
		(width 0.12065)
		(layer "F.Cu")
		(net "SSD_PERST#4_R")
	)
	(segment
		(start 334.899 -168.148)
		(end 330.073 -168.148)
		(width 0.12065)
		(layer "F.Cu")
		(net "SSD_PERST#4_R")
	)
	(segment
		(start 335.820512 -171.987718)
		(end 335.820512 -171.939712)
		(width 0.12065)
		(layer "F.Cu")
		(net "SSD_PERST#4_R")
	)
	(segment
		(start 330.073 -168.148)
		(end 329.565 -168.656)
		(width 0.12065)
		(layer "F.Cu")
		(net "SSD_PERST#4_R")
	)
	(segment
		(start 335.35366 -173.450758)
		(end 334.899 -173.905418)
		(width 0.12065)
		(layer "F.Cu")
		(net "SSD_PERST#4_R")
	)
	(segment
		(start 335.268062 -168.517062)
		(end 334.899 -168.148)
		(width 0.12065)
		(layer "F.Cu")
		(net "SSD_PERST#4_R")
	)
	(via
		(at 328.168 -169.418)
		(size 0.7112)
		(drill 0.3556)
		(layers "F.Cu" "B.Cu")
		(net "SSD_PERST#4_R")
	)
	(via
		(at 329.565 -168.656)
		(size 0.508)
		(drill 0.254)
		(layers "F.Cu" "B.Cu")
		(net "SSD_PERST#4_R")
	)
	(via
		(at 334.899 -173.905418)
		(size 0.508)
		(drill 0.254)
		(layers "F.Cu" "B.Cu")
		(net "SSD_PERST#4_R")
	)
	(segment
		(start 309.74157 -223.349058)
		(end 310.114696 -222.975932)
		(width 0.12065)
		(layer "B.Cu")
		(net "SSD_PERST#4_R")
	)
	(segment
		(start 333.4766 -175.2981)
		(end 333.743046 -175.2981)
		(width 0.12065)
		(layer "B.Cu")
		(net "SSD_PERST#4_R")
	)
	(segment
		(start 334.476852 -174.327566)
		(end 334.899 -173.905418)
		(width 0.12065)
		(layer "B.Cu")
		(net "SSD_PERST#4_R")
	)
	(segment
		(start 309.74157 -223.86163)
		(end 309.74157 -223.349058)
		(width 0.12065)
		(layer "B.Cu")
		(net "SSD_PERST#4_R")
	)
	(segment
		(start 309.300118 -224.303082)
		(end 309.74157 -223.86163)
		(width 0.12065)
		(layer "B.Cu")
		(net "SSD_PERST#4_R")
	)
	(segment
		(start 309.300118 -225.92538)
		(end 309.300118 -224.303082)
		(width 0.12065)
		(layer "B.Cu")
		(net "SSD_PERST#4_R")
	)
	(segment
		(start 329.565 -168.656)
		(end 328.803 -169.418)
		(width 0.12065)
		(layer "B.Cu")
		(net "SSD_PERST#4_R")
	)
	(segment
		(start 327.228454 -169.418)
		(end 328.168 -169.418)
		(width 0.12065)
		(layer "B.Cu")
		(net "SSD_PERST#4_R")
	)
	(segment
		(start 333.743046 -175.2981)
		(end 334.476852 -174.564294)
		(width 0.12065)
		(layer "B.Cu")
		(net "SSD_PERST#4_R")
	)
	(segment
		(start 308.823868 -219.923868)
		(end 308.823868 -187.822586)
		(width 0.12065)
		(layer "B.Cu")
		(net "SSD_PERST#4_R")
	)
	(segment
		(start 334.476852 -174.564294)
		(end 334.476852 -174.327566)
		(width 0.12065)
		(layer "B.Cu")
		(net "SSD_PERST#4_R")
	)
	(segment
		(start 308.823868 -187.822586)
		(end 327.228454 -169.418)
		(width 0.12065)
		(layer "B.Cu")
		(net "SSD_PERST#4_R")
	)
	(segment
		(start 310.114696 -221.214696)
		(end 308.823868 -219.923868)
		(width 0.12065)
		(layer "B.Cu")
		(net "SSD_PERST#4_R")
	)
	(segment
		(start 310.114696 -222.975932)
		(end 310.114696 -221.214696)
		(width 0.12065)
		(layer "B.Cu")
		(net "SSD_PERST#4_R")
	)
	(segment
		(start 328.803 -169.418)
		(end 328.168 -169.418)
		(width 0.12065)
		(layer "B.Cu")
		(net "SSD_PERST#4_R")
	)
	(segment
		(start 335.510632 -175.962818)
		(end 335.510632 -174.267368)
		(width 0.12065)
		(layer "F.Cu")
		(net "SSD_PERST#4")
	)
	(segment
		(start 336.3214 -172.3898)
		(end 335.834482 -172.876718)
		(width 0.12065)
		(layer "F.Cu")
		(net "SSD_PERST#4")
	)
	(segment
		(start 335.510632 -174.267368)
		(end 335.769712 -174.008288)
		(width 0.12065)
		(layer "F.Cu")
		(net "SSD_PERST#4")
	)
	(segment
		(start 335.834482 -172.876718)
		(end 335.820512 -172.876718)
		(width 0.12065)
		(layer "F.Cu")
		(net "SSD_PERST#4")
	)
	(segment
		(start 335.8896 -170.9547)
		(end 336.3214 -171.3865)
		(width 0.12065)
		(layer "F.Cu")
		(net "SSD_PERST#4")
	)
	(segment
		(start 336.3214 -171.3865)
		(end 336.3214 -172.3898)
		(width 0.12065)
		(layer "F.Cu")
		(net "SSD_PERST#4")
	)
	(segment
		(start 335.820512 -173.633892)
		(end 335.769712 -173.684692)
		(width 0.12065)
		(layer "F.Cu")
		(net "SSD_PERST#4")
	)
	(segment
		(start 335.769712 -174.008288)
		(end 335.769712 -173.684692)
		(width 0.12065)
		(layer "F.Cu")
		(net "SSD_PERST#4")
	)
	(segment
		(start 335.820512 -172.876718)
		(end 335.820512 -173.633892)
		(width 0.12065)
		(layer "F.Cu")
		(net "SSD_PERST#4")
	)
	(via
		(at 335.769712 -173.684692)
		(size 0.508)
		(drill 0.254)
		(layers "F.Cu" "B.Cu")
		(net "SSD_PERST#4")
	)
	(via
		(at 335.153 -175.26)
		(size 0.7112)
		(drill 0.3556)
		(layers "F.Cu" "B.Cu")
		(net "SSD_PERST#4")
	)
	(segment
		(start 335.343754 -177.00244)
		(end 335.343754 -175.450754)
		(width 0.12065)
		(layer "B.Cu")
		(net "SSD_PERST#4")
	)
	(segment
		(start 335.820512 -173.633892)
		(end 335.769712 -173.684692)
		(width 0.12065)
		(layer "B.Cu")
		(net "SSD_PERST#4")
	)
	(segment
		(start 334.615536 -180.019706)
		(end 334.518 -179.92217)
		(width 0.12065)
		(layer "B.Cu")
		(net "SSD_PERST#4")
	)
	(segment
		(start 332.9686 -182.1561)
		(end 334.3529 -182.1561)
		(width 0.12065)
		(layer "B.Cu")
		(net "SSD_PERST#4")
	)
	(segment
		(start 334.518 -177.828194)
		(end 335.343754 -177.00244)
		(width 0.12065)
		(layer "B.Cu")
		(net "SSD_PERST#4")
	)
	(segment
		(start 335.769712 -173.684692)
		(end 335.343754 -174.11065)
		(width 0.12065)
		(layer "B.Cu")
		(net "SSD_PERST#4")
	)
	(segment
		(start 334.518 -179.92217)
		(end 334.518 -177.828194)
		(width 0.12065)
		(layer "B.Cu")
		(net "SSD_PERST#4")
	)
	(segment
		(start 335.343754 -174.11065)
		(end 335.343754 -175.069246)
		(width 0.12065)
		(layer "B.Cu")
		(net "SSD_PERST#4")
	)
	(segment
		(start 334.615536 -181.893464)
		(end 334.615536 -180.019706)
		(width 0.12065)
		(layer "B.Cu")
		(net "SSD_PERST#4")
	)
	(segment
		(start 335.820512 -172.876718)
		(end 335.820512 -173.633892)
		(width 0.12065)
		(layer "B.Cu")
		(net "SSD_PERST#4")
	)
	(segment
		(start 334.3529 -182.1561)
		(end 334.615536 -181.893464)
		(width 0.12065)
		(layer "B.Cu")
		(net "SSD_PERST#4")
	)
	(segment
		(start 335.343754 -175.450754)
		(end 335.153 -175.26)
		(width 0.12065)
		(layer "B.Cu")
		(net "SSD_PERST#4")
	)
	(segment
		(start 335.343754 -175.069246)
		(end 335.153 -175.26)
		(width 0.12065)
		(layer "B.Cu")
		(net "SSD_PERST#4")
	)
	(segment
		(start 210.3882 -194.9958)
		(end 215.392 -189.992)
		(width 0.12065)
		(layer "F.Cu")
		(net "SSD_PERST#3_R")
	)
	(segment
		(start 211.30006 -225.54438)
		(end 211.30006 -224.43186)
		(width 0.12065)
		(layer "F.Cu")
		(net "SSD_PERST#3_R")
	)
	(segment
		(start 210.3882 -223.52)
		(end 210.3882 -194.9958)
		(width 0.12065)
		(layer "F.Cu")
		(net "SSD_PERST#3_R")
	)
	(segment
		(start 215.392 -189.992)
		(end 215.392 -186.817)
		(width 0.12065)
		(layer "F.Cu")
		(net "SSD_PERST#3_R")
	)
	(segment
		(start 211.30006 -224.43186)
		(end 210.3882 -223.52)
		(width 0.12065)
		(layer "F.Cu")
		(net "SSD_PERST#3_R")
	)
	(segment
		(start 222.861124 -189.333124)
		(end 222.758 -189.23)
		(width 0.12065)
		(layer "F.Cu")
		(net "SSD_PERST#3_R")
	)
	(segment
		(start 222.861124 -190.156592)
		(end 222.861124 -189.333124)
		(width 0.12065)
		(layer "F.Cu")
		(net "SSD_PERST#3_R")
	)
	(via
		(at 223.47301 -188.543184)
		(size 0.7112)
		(drill 0.3556)
		(layers "F.Cu" "B.Cu")
		(net "SSD_PERST#3_R")
	)
	(via
		(at 222.758 -189.23)
		(size 0.508)
		(drill 0.254)
		(layers "F.Cu" "B.Cu")
		(net "SSD_PERST#3_R")
	)
	(via
		(at 215.392 -186.817)
		(size 0.508)
		(drill 0.254)
		(layers "F.Cu" "B.Cu")
		(net "SSD_PERST#3_R")
	)
	(segment
		(start 221.0181 -194.5132)
		(end 221.0181 -193.49593)
		(width 0.12065)
		(layer "B.Cu")
		(net "SSD_PERST#3_R")
	)
	(segment
		(start 223.444816 -188.543184)
		(end 223.47301 -188.543184)
		(width 0.12065)
		(layer "B.Cu")
		(net "SSD_PERST#3_R")
	)
	(segment
		(start 222.758 -189.23)
		(end 223.444816 -188.543184)
		(width 0.12065)
		(layer "B.Cu")
		(net "SSD_PERST#3_R")
	)
	(segment
		(start 222.253048 -190.850266)
		(end 222.253048 -189.734952)
		(width 0.12065)
		(layer "B.Cu")
		(net "SSD_PERST#3_R")
	)
	(segment
		(start 221.9198 -191.183514)
		(end 222.253048 -190.850266)
		(width 0.12065)
		(layer "B.Cu")
		(net "SSD_PERST#3_R")
	)
	(segment
		(start 221.339918 -193.174112)
		(end 221.339918 -191.461898)
		(width 0.12065)
		(layer "B.Cu")
		(net "SSD_PERST#3_R")
	)
	(segment
		(start 221.339918 -191.461898)
		(end 221.618302 -191.183514)
		(width 0.12065)
		(layer "B.Cu")
		(net "SSD_PERST#3_R")
	)
	(segment
		(start 221.0181 -193.49593)
		(end 221.339918 -193.174112)
		(width 0.12065)
		(layer "B.Cu")
		(net "SSD_PERST#3_R")
	)
	(segment
		(start 222.253048 -189.734952)
		(end 222.758 -189.23)
		(width 0.12065)
		(layer "B.Cu")
		(net "SSD_PERST#3_R")
	)
	(segment
		(start 221.618302 -191.183514)
		(end 221.9198 -191.183514)
		(width 0.12065)
		(layer "B.Cu")
		(net "SSD_PERST#3_R")
	)
	(segment
		(start 222.758 -189.23)
		(end 220.345 -186.817)
		(width 0.127)
		(layer "In2.Cu")
		(net "SSD_PERST#3_R")
	)
	(segment
		(start 220.345 -186.817)
		(end 215.392 -186.817)
		(width 0.127)
		(layer "In2.Cu")
		(net "SSD_PERST#3_R")
	)
	(segment
		(start 222.693992 -192.073022)
		(end 222.513144 -191.892174)
		(width 0.12065)
		(layer "F.Cu")
		(net "SSD_PERST#3")
	)
	(segment
		(start 222.693992 -193.325496)
		(end 222.693992 -192.073022)
		(width 0.12065)
		(layer "F.Cu")
		(net "SSD_PERST#3")
	)
	(segment
		(start 222.810324 -191.096392)
		(end 222.810324 -191.594994)
		(width 0.12065)
		(layer "F.Cu")
		(net "SSD_PERST#3")
	)
	(segment
		(start 222.810324 -191.594994)
		(end 222.513144 -191.892174)
		(width 0.12065)
		(layer "F.Cu")
		(net "SSD_PERST#3")
	)
	(segment
		(start 222.551244 -194.131692)
		(end 222.551244 -193.468244)
		(width 0.12065)
		(layer "F.Cu")
		(net "SSD_PERST#3")
	)
	(segment
		(start 222.551244 -193.468244)
		(end 222.693992 -193.325496)
		(width 0.12065)
		(layer "F.Cu")
		(net "SSD_PERST#3")
	)
	(segment
		(start 222.861124 -191.045592)
		(end 222.810324 -191.096392)
		(width 0.12065)
		(layer "F.Cu")
		(net "SSD_PERST#3")
	)
	(via
		(at 223.158812 -193.3067)
		(size 0.7112)
		(drill 0.3556)
		(layers "F.Cu" "B.Cu")
		(net "SSD_PERST#3")
	)
	(via
		(at 222.513144 -191.892174)
		(size 0.508)
		(drill 0.254)
		(layers "F.Cu" "B.Cu")
		(net "SSD_PERST#3")
	)
	(segment
		(start 223.851724 -191.78397)
		(end 223.8502 -191.785494)
		(width 0.12065)
		(layer "B.Cu")
		(net "SSD_PERST#3")
	)
	(segment
		(start 220.4974 -199.92086)
		(end 220.4974 -199.009)
		(width 0.12065)
		(layer "B.Cu")
		(net "SSD_PERST#3")
	)
	(segment
		(start 222.870014 -192.249044)
		(end 222.870014 -193.017902)
		(width 0.12065)
		(layer "B.Cu")
		(net "SSD_PERST#3")
	)
	(segment
		(start 221.497906 -193.531744)
		(end 221.716854 -193.312796)
		(width 0.12065)
		(layer "B.Cu")
		(net "SSD_PERST#3")
	)
	(segment
		(start 221.440248 -196.777102)
		(end 221.440248 -195.273422)
		(width 0.12065)
		(layer "B.Cu")
		(net "SSD_PERST#3")
	)
	(segment
		(start 221.716854 -192.06337)
		(end 221.865698 -191.914526)
		(width 0.12065)
		(layer "B.Cu")
		(net "SSD_PERST#3")
	)
	(segment
		(start 220.04274 -200.37552)
		(end 220.4974 -199.92086)
		(width 0.12065)
		(layer "B.Cu")
		(net "SSD_PERST#3")
	)
	(segment
		(start 222.513144 -191.892174)
		(end 222.870014 -192.249044)
		(width 0.12065)
		(layer "B.Cu")
		(net "SSD_PERST#3")
	)
	(segment
		(start 221.865698 -191.914526)
		(end 222.490792 -191.914526)
		(width 0.12065)
		(layer "B.Cu")
		(net "SSD_PERST#3")
	)
	(segment
		(start 221.700852 -197.037706)
		(end 221.440248 -196.777102)
		(width 0.12065)
		(layer "B.Cu")
		(net "SSD_PERST#3")
	)
	(segment
		(start 222.810324 -191.022224)
		(end 222.810324 -191.594994)
		(width 0.12065)
		(layer "B.Cu")
		(net "SSD_PERST#3")
	)
	(segment
		(start 223.851724 -191.045592)
		(end 223.851724 -191.78397)
		(width 0.12065)
		(layer "B.Cu")
		(net "SSD_PERST#3")
	)
	(segment
		(start 223.8502 -191.785494)
		(end 223.8502 -191.991234)
		(width 0.12065)
		(layer "B.Cu")
		(net "SSD_PERST#3")
	)
	(segment
		(start 223.557592 -192.90792)
		(end 223.158812 -193.3067)
		(width 0.12065)
		(layer "B.Cu")
		(net "SSD_PERST#3")
	)
	(segment
		(start 221.440248 -195.273422)
		(end 221.497906 -195.215764)
		(width 0.12065)
		(layer "B.Cu")
		(net "SSD_PERST#3")
	)
	(segment
		(start 222.490792 -191.914526)
		(end 222.513144 -191.892174)
		(width 0.12065)
		(layer "B.Cu")
		(net "SSD_PERST#3")
	)
	(segment
		(start 221.497906 -195.215764)
		(end 221.497906 -193.531744)
		(width 0.12065)
		(layer "B.Cu")
		(net "SSD_PERST#3")
	)
	(segment
		(start 220.4974 -199.009)
		(end 221.700852 -197.805548)
		(width 0.12065)
		(layer "B.Cu")
		(net "SSD_PERST#3")
	)
	(segment
		(start 221.700852 -197.805548)
		(end 221.700852 -197.037706)
		(width 0.12065)
		(layer "B.Cu")
		(net "SSD_PERST#3")
	)
	(segment
		(start 223.557592 -192.283842)
		(end 223.557592 -192.90792)
		(width 0.12065)
		(layer "B.Cu")
		(net "SSD_PERST#3")
	)
	(segment
		(start 223.8502 -191.991234)
		(end 223.557592 -192.283842)
		(width 0.12065)
		(layer "B.Cu")
		(net "SSD_PERST#3")
	)
	(segment
		(start 222.870014 -193.017902)
		(end 223.158812 -193.3067)
		(width 0.12065)
		(layer "B.Cu")
		(net "SSD_PERST#3")
	)
	(segment
		(start 222.810324 -191.594994)
		(end 222.513144 -191.892174)
		(width 0.12065)
		(layer "B.Cu")
		(net "SSD_PERST#3")
	)
	(segment
		(start 222.8088 -191.0207)
		(end 222.810324 -191.022224)
		(width 0.12065)
		(layer "B.Cu")
		(net "SSD_PERST#3")
	)
	(segment
		(start 221.716854 -193.312796)
		(end 221.716854 -192.06337)
		(width 0.12065)
		(layer "B.Cu")
		(net "SSD_PERST#3")
	)
	(segment
		(start 133.119876 -197.746366)
		(end 133.29793 -197.746366)
		(width 0.12065)
		(layer "F.Cu")
		(net "SSD_PERST#2_R")
	)
	(segment
		(start 133.072124 -195.998592)
		(end 132.605272 -196.465444)
		(width 0.12065)
		(layer "F.Cu")
		(net "SSD_PERST#2_R")
	)
	(segment
		(start 132.605272 -196.465444)
		(end 132.605272 -197.231762)
		(width 0.12065)
		(layer "F.Cu")
		(net "SSD_PERST#2_R")
	)
	(segment
		(start 132.605272 -197.231762)
		(end 133.119876 -197.746366)
		(width 0.12065)
		(layer "F.Cu")
		(net "SSD_PERST#2_R")
	)
	(via
		(at 133.29793 -197.746366)
		(size 0.508)
		(drill 0.254)
		(layers "F.Cu" "B.Cu")
		(net "SSD_PERST#2_R")
	)
	(via
		(at 225.425 -185.801)
		(size 0.7112)
		(drill 0.3556)
		(layers "F.Cu" "B.Cu")
		(net "SSD_PERST#2_R")
	)
	(via
		(at 89.9922 -176.784)
		(size 0.508)
		(drill 0.254)
		(layers "F.Cu" "B.Cu")
		(net "SSD_PERST#2_R")
	)
	(via
		(at 89.9922 -178.943)
		(size 0.508)
		(drill 0.254)
		(layers "F.Cu" "B.Cu")
		(net "SSD_PERST#2_R")
	)
	(segment
		(start 216.535 -221.633034)
		(end 216.899998 -221.268036)
		(width 0.12065)
		(layer "B.Cu")
		(net "SSD_PERST#2_R")
	)
	(segment
		(start 225.425 -185.801)
		(end 128.629664 -185.801)
		(width 0.12065)
		(layer "B.Cu")
		(net "SSD_PERST#2_R")
	)
	(segment
		(start 91.948 -177.6222)
		(end 90.6272 -178.943)
		(width 0.12065)
		(layer "B.Cu")
		(net "SSD_PERST#2_R")
	)
	(segment
		(start 133.270752 -199.16521)
		(end 133.270752 -198.866252)
		(width 0.12065)
		(layer "B.Cu")
		(net "SSD_PERST#2_R")
	)
	(segment
		(start 216.899998 -221.268036)
		(end 216.899998 -214.163402)
		(width 0.12065)
		(layer "B.Cu")
		(net "SSD_PERST#2_R")
	)
	(segment
		(start 133.2738 -194.0814)
		(end 131.0894 -191.897)
		(width 0.12065)
		(layer "B.Cu")
		(net "SSD_PERST#2_R")
	)
	(segment
		(start 216.899998 -214.163402)
		(end 221.3102 -209.7532)
		(width 0.12065)
		(layer "B.Cu")
		(net "SSD_PERST#2_R")
	)
	(segment
		(start 133.2738 -197.722236)
		(end 133.2738 -194.0814)
		(width 0.12065)
		(layer "B.Cu")
		(net "SSD_PERST#2_R")
	)
	(segment
		(start 90.6272 -178.943)
		(end 89.9922 -178.943)
		(width 0.12065)
		(layer "B.Cu")
		(net "SSD_PERST#2_R")
	)
	(segment
		(start 230.2002 -185.801)
		(end 225.425 -185.801)
		(width 0.12065)
		(layer "B.Cu")
		(net "SSD_PERST#2_R")
	)
	(segment
		(start 90.964004 -175.812196)
		(end 89.9922 -176.784)
		(width 0.12065)
		(layer "B.Cu")
		(net "SSD_PERST#2_R")
	)
	(segment
		(start 216.535 -223.9518)
		(end 216.535 -221.633034)
		(width 0.12065)
		(layer "B.Cu")
		(net "SSD_PERST#2_R")
	)
	(segment
		(start 133.29793 -197.746366)
		(end 133.2738 -197.722236)
		(width 0.12065)
		(layer "B.Cu")
		(net "SSD_PERST#2_R")
	)
	(segment
		(start 216.899998 -224.316798)
		(end 216.535 -223.9518)
		(width 0.12065)
		(layer "B.Cu")
		(net "SSD_PERST#2_R")
	)
	(segment
		(start 133.270752 -198.866252)
		(end 133.271006 -198.865998)
		(width 0.12065)
		(layer "B.Cu")
		(net "SSD_PERST#2_R")
	)
	(segment
		(start 95.284544 -175.812196)
		(end 90.964004 -175.812196)
		(width 0.12065)
		(layer "B.Cu")
		(net "SSD_PERST#2_R")
	)
	(segment
		(start 129.406396 -191.897)
		(end 115.131596 -177.6222)
		(width 0.12065)
		(layer "B.Cu")
		(net "SSD_PERST#2_R")
	)
	(segment
		(start 118.641114 -175.81245)
		(end 95.284798 -175.81245)
		(width 0.12065)
		(layer "B.Cu")
		(net "SSD_PERST#2_R")
	)
	(segment
		(start 216.899998 -225.92538)
		(end 216.899998 -224.316798)
		(width 0.12065)
		(layer "B.Cu")
		(net "SSD_PERST#2_R")
	)
	(segment
		(start 128.629664 -185.801)
		(end 118.641114 -175.81245)
		(width 0.12065)
		(layer "B.Cu")
		(net "SSD_PERST#2_R")
	)
	(segment
		(start 133.268212 -199.16775)
		(end 133.270752 -199.16521)
		(width 0.12065)
		(layer "B.Cu")
		(net "SSD_PERST#2_R")
	)
	(segment
		(start 115.131596 -177.6222)
		(end 91.948 -177.6222)
		(width 0.12065)
		(layer "B.Cu")
		(net "SSD_PERST#2_R")
	)
	(segment
		(start 133.271006 -197.77329)
		(end 133.29793 -197.746366)
		(width 0.12065)
		(layer "B.Cu")
		(net "SSD_PERST#2_R")
	)
	(segment
		(start 131.0894 -191.897)
		(end 129.406396 -191.897)
		(width 0.12065)
		(layer "B.Cu")
		(net "SSD_PERST#2_R")
	)
	(segment
		(start 230.9876 -206.8068)
		(end 230.9876 -186.5884)
		(width 0.12065)
		(layer "B.Cu")
		(net "SSD_PERST#2_R")
	)
	(segment
		(start 221.3102 -209.7532)
		(end 228.0412 -209.7532)
		(width 0.12065)
		(layer "B.Cu")
		(net "SSD_PERST#2_R")
	)
	(segment
		(start 228.0412 -209.7532)
		(end 230.9876 -206.8068)
		(width 0.12065)
		(layer "B.Cu")
		(net "SSD_PERST#2_R")
	)
	(segment
		(start 133.268212 -199.308974)
		(end 133.268212 -199.16775)
		(width 0.12065)
		(layer "B.Cu")
		(net "SSD_PERST#2_R")
	)
	(segment
		(start 133.271006 -198.865998)
		(end 133.271006 -197.77329)
		(width 0.12065)
		(layer "B.Cu")
		(net "SSD_PERST#2_R")
	)
	(segment
		(start 230.9876 -186.5884)
		(end 230.2002 -185.801)
		(width 0.12065)
		(layer "B.Cu")
		(net "SSD_PERST#2_R")
	)
	(segment
		(start 95.284798 -175.81245)
		(end 95.284544 -175.812196)
		(width 0.12065)
		(layer "B.Cu")
		(net "SSD_PERST#2_R")
	)
	(segment
		(start 89.9922 -176.784)
		(end 89.9922 -178.943)
		(width 0.127)
		(layer "In2.Cu")
		(net "SSD_PERST#2_R")
	)
	(segment
		(start 131.299204 -199.376284)
		(end 132.515356 -198.160132)
		(width 0.12065)
		(layer "F.Cu")
		(net "SSD_PERST#2")
	)
	(segment
		(start 133.660388 -198.76897)
		(end 134.157466 -198.76897)
		(width 0.12065)
		(layer "F.Cu")
		(net "SSD_PERST#2")
	)
	(segment
		(start 134.1374 -197.82409)
		(end 134.157466 -197.844156)
		(width 0.12065)
		(layer "F.Cu")
		(net "SSD_PERST#2")
	)
	(segment
		(start 133.072124 -196.887592)
		(end 134.112508 -196.887592)
		(width 0.12065)
		(layer "F.Cu")
		(net "SSD_PERST#2")
	)
	(segment
		(start 134.112508 -196.887592)
		(end 134.1374 -196.8627)
		(width 0.12065)
		(layer "F.Cu")
		(net "SSD_PERST#2")
	)
	(segment
		(start 133.05155 -198.160132)
		(end 133.660388 -198.76897)
		(width 0.12065)
		(layer "F.Cu")
		(net "SSD_PERST#2")
	)
	(segment
		(start 134.157466 -197.844156)
		(end 134.157466 -198.76897)
		(width 0.12065)
		(layer "F.Cu")
		(net "SSD_PERST#2")
	)
	(segment
		(start 134.1374 -196.8627)
		(end 134.1374 -197.82409)
		(width 0.12065)
		(layer "F.Cu")
		(net "SSD_PERST#2")
	)
	(segment
		(start 132.515356 -198.160132)
		(end 133.05155 -198.160132)
		(width 0.12065)
		(layer "F.Cu")
		(net "SSD_PERST#2")
	)
	(segment
		(start 131.299204 -199.973692)
		(end 131.299204 -199.376284)
		(width 0.12065)
		(layer "F.Cu")
		(net "SSD_PERST#2")
	)
	(via
		(at 135.001 -197.7644)
		(size 0.7112)
		(drill 0.3556)
		(layers "F.Cu" "B.Cu")
		(net "SSD_PERST#2")
	)
	(via
		(at 134.157466 -198.76897)
		(size 0.508)
		(drill 0.254)
		(layers "F.Cu" "B.Cu")
		(net "SSD_PERST#2")
	)
	(segment
		(start 133.743192 -201.43089)
		(end 134.318248 -200.855834)
		(width 0.12065)
		(layer "B.Cu")
		(net "SSD_PERST#2")
	)
	(segment
		(start 134.157466 -198.76897)
		(end 134.439406 -198.48703)
		(width 0.12065)
		(layer "B.Cu")
		(net "SSD_PERST#2")
	)
	(segment
		(start 134.439406 -198.48703)
		(end 134.439406 -198.094854)
		(width 0.12065)
		(layer "B.Cu")
		(net "SSD_PERST#2")
	)
	(segment
		(start 134.794752 -206.454248)
		(end 135.1026 -206.1464)
		(width 0.12065)
		(layer "B.Cu")
		(net "SSD_PERST#2")
	)
	(segment
		(start 133.141212 -206.293974)
		(end 133.319774 -206.293974)
		(width 0.12065)
		(layer "B.Cu")
		(net "SSD_PERST#2")
	)
	(segment
		(start 134.76986 -197.7644)
		(end 135.001 -197.7644)
		(width 0.12065)
		(layer "B.Cu")
		(net "SSD_PERST#2")
	)
	(segment
		(start 133.858 -198.469504)
		(end 134.157466 -198.76897)
		(width 0.12065)
		(layer "B.Cu")
		(net "SSD_PERST#2")
	)
	(segment
		(start 135.1026 -206.1464)
		(end 135.1026 -205.3336)
		(width 0.12065)
		(layer "B.Cu")
		(net "SSD_PERST#2")
	)
	(segment
		(start 135.288528 -200.058528)
		(end 135.288528 -198.051928)
		(width 0.12065)
		(layer "B.Cu")
		(net "SSD_PERST#2")
	)
	(segment
		(start 135.1026 -205.3336)
		(end 133.743192 -203.974192)
		(width 0.12065)
		(layer "B.Cu")
		(net "SSD_PERST#2")
	)
	(segment
		(start 133.858 -196.8373)
		(end 133.858 -198.469504)
		(width 0.12065)
		(layer "B.Cu")
		(net "SSD_PERST#2")
	)
	(segment
		(start 134.491222 -200.855834)
		(end 135.288528 -200.058528)
		(width 0.12065)
		(layer "B.Cu")
		(net "SSD_PERST#2")
	)
	(segment
		(start 134.439406 -198.094854)
		(end 134.76986 -197.7644)
		(width 0.12065)
		(layer "B.Cu")
		(net "SSD_PERST#2")
	)
	(segment
		(start 133.743192 -203.974192)
		(end 133.743192 -201.43089)
		(width 0.12065)
		(layer "B.Cu")
		(net "SSD_PERST#2")
	)
	(segment
		(start 135.288528 -198.051928)
		(end 135.001 -197.7644)
		(width 0.12065)
		(layer "B.Cu")
		(net "SSD_PERST#2")
	)
	(segment
		(start 134.318248 -200.855834)
		(end 134.491222 -200.855834)
		(width 0.12065)
		(layer "B.Cu")
		(net "SSD_PERST#2")
	)
	(segment
		(start 133.480048 -206.454248)
		(end 134.794752 -206.454248)
		(width 0.12065)
		(layer "B.Cu")
		(net "SSD_PERST#2")
	)
	(segment
		(start 133.319774 -206.293974)
		(end 133.480048 -206.454248)
		(width 0.12065)
		(layer "B.Cu")
		(net "SSD_PERST#2")
	)
	(segment
		(start 336.836512 -185.322718)
		(end 336.836512 -185.528712)
		(width 0.12065)
		(layer "F.Cu")
		(net "SSD_PERST#14_R")
	)
	(segment
		(start 337.784948 -186.69)
		(end 340.233 -186.69)
		(width 0.12065)
		(layer "F.Cu")
		(net "SSD_PERST#14_R")
	)
	(segment
		(start 340.233 -186.69)
		(end 340.868 -186.055)
		(width 0.12065)
		(layer "F.Cu")
		(net "SSD_PERST#14_R")
	)
	(segment
		(start 336.836512 -185.528712)
		(end 337.38566 -186.07786)
		(width 0.12065)
		(layer "F.Cu")
		(net "SSD_PERST#14_R")
	)
	(segment
		(start 337.38566 -186.07786)
		(end 337.38566 -186.290712)
		(width 0.12065)
		(layer "F.Cu")
		(net "SSD_PERST#14_R")
	)
	(segment
		(start 337.38566 -186.290712)
		(end 337.784948 -186.69)
		(width 0.12065)
		(layer "F.Cu")
		(net "SSD_PERST#14_R")
	)
	(segment
		(start 326.8472 -170.4594)
		(end 329.52055 -167.78605)
		(width 0.12065)
		(layer "F.Cu")
		(net "SSD_PERST#14_R")
	)
	(segment
		(start 336.79765 -167.78605)
		(end 337.1088 -168.0972)
		(width 0.12065)
		(layer "F.Cu")
		(net "SSD_PERST#14_R")
	)
	(segment
		(start 329.52055 -167.78605)
		(end 336.79765 -167.78605)
		(width 0.12065)
		(layer "F.Cu")
		(net "SSD_PERST#14_R")
	)
	(via
		(at 326.8472 -170.4594)
		(size 0.508)
		(drill 0.254)
		(layers "F.Cu" "B.Cu")
		(net "SSD_PERST#14_R")
	)
	(via
		(at 344.17 -181.864)
		(size 0.7112)
		(drill 0.3556)
		(layers "F.Cu" "B.Cu")
		(net "SSD_PERST#14_R")
	)
	(via
		(at 340.868 -186.055)
		(size 0.508)
		(drill 0.254)
		(layers "F.Cu" "B.Cu")
		(net "SSD_PERST#14_R")
	)
	(via
		(at 337.1088 -168.0972)
		(size 0.508)
		(drill 0.254)
		(layers "F.Cu" "B.Cu")
		(net "SSD_PERST#14_R")
	)
	(segment
		(start 340.233 -169.926)
		(end 341.4268 -171.1198)
		(width 0.12065)
		(layer "B.Cu")
		(net "SSD_PERST#14_R")
	)
	(segment
		(start 340.868 -186.055)
		(end 344.17 -182.753)
		(width 0.12065)
		(layer "B.Cu")
		(net "SSD_PERST#14_R")
	)
	(segment
		(start 343.3191 -175.2981)
		(end 344.17 -176.149)
		(width 0.12065)
		(layer "B.Cu")
		(net "SSD_PERST#14_R")
	)
	(segment
		(start 338.4296 -169.926)
		(end 340.233 -169.926)
		(width 0.12065)
		(layer "B.Cu")
		(net "SSD_PERST#14_R")
	)
	(segment
		(start 342.338152 -172.031152)
		(end 342.3666 -172.0596)
		(width 0.12065)
		(layer "B.Cu")
		(net "SSD_PERST#14_R")
	)
	(segment
		(start 344.17 -182.753)
		(end 344.17 -181.864)
		(width 0.12065)
		(layer "B.Cu")
		(net "SSD_PERST#14_R")
	)
	(segment
		(start 337.2358 -168.7322)
		(end 338.4296 -169.926)
		(width 0.12065)
		(layer "B.Cu")
		(net "SSD_PERST#14_R")
	)
	(segment
		(start 310.476646 -221.064582)
		(end 309.185818 -219.773754)
		(width 0.12065)
		(layer "B.Cu")
		(net "SSD_PERST#14_R")
	)
	(segment
		(start 337.2358 -168.2242)
		(end 337.2358 -168.7322)
		(width 0.12065)
		(layer "B.Cu")
		(net "SSD_PERST#14_R")
	)
	(segment
		(start 310.100218 -223.455484)
		(end 310.476646 -223.079056)
		(width 0.12065)
		(layer "B.Cu")
		(net "SSD_PERST#14_R")
	)
	(segment
		(start 310.476646 -223.079056)
		(end 310.476646 -221.064582)
		(width 0.12065)
		(layer "B.Cu")
		(net "SSD_PERST#14_R")
	)
	(segment
		(start 342.3666 -172.0596)
		(end 342.3666 -175.0441)
		(width 0.12065)
		(layer "B.Cu")
		(net "SSD_PERST#14_R")
	)
	(segment
		(start 342.1126 -175.2981)
		(end 343.3191 -175.2981)
		(width 0.12065)
		(layer "B.Cu")
		(net "SSD_PERST#14_R")
	)
	(segment
		(start 309.185818 -188.120782)
		(end 326.8472 -170.4594)
		(width 0.12065)
		(layer "B.Cu")
		(net "SSD_PERST#14_R")
	)
	(segment
		(start 344.17 -176.149)
		(end 344.17 -181.864)
		(width 0.12065)
		(layer "B.Cu")
		(net "SSD_PERST#14_R")
	)
	(segment
		(start 309.185818 -219.773754)
		(end 309.185818 -188.120782)
		(width 0.12065)
		(layer "B.Cu")
		(net "SSD_PERST#14_R")
	)
	(segment
		(start 342.3666 -175.0441)
		(end 342.1126 -175.2981)
		(width 0.12065)
		(layer "B.Cu")
		(net "SSD_PERST#14_R")
	)
	(segment
		(start 337.1088 -168.0972)
		(end 337.2358 -168.2242)
		(width 0.12065)
		(layer "B.Cu")
		(net "SSD_PERST#14_R")
	)
	(segment
		(start 310.100218 -225.92538)
		(end 310.100218 -223.455484)
		(width 0.12065)
		(layer "B.Cu")
		(net "SSD_PERST#14_R")
	)
	(segment
		(start 342.338152 -171.690538)
		(end 342.338152 -172.031152)
		(width 0.12065)
		(layer "B.Cu")
		(net "SSD_PERST#14_R")
	)
	(segment
		(start 341.767414 -171.1198)
		(end 342.338152 -171.690538)
		(width 0.12065)
		(layer "B.Cu")
		(net "SSD_PERST#14_R")
	)
	(segment
		(start 341.4268 -171.1198)
		(end 341.767414 -171.1198)
		(width 0.12065)
		(layer "B.Cu")
		(net "SSD_PERST#14_R")
	)
	(segment
		(start 336.811112 -183.529986)
		(end 336.7024 -183.638698)
		(width 0.12065)
		(layer "F.Cu")
		(net "SSD_PERST#14")
	)
	(segment
		(start 336.811112 -181.601618)
		(end 336.811112 -183.529986)
		(width 0.12065)
		(layer "F.Cu")
		(net "SSD_PERST#14")
	)
	(segment
		(start 336.8294 -186.4741)
		(end 336.36966 -186.01436)
		(width 0.12065)
		(layer "F.Cu")
		(net "SSD_PERST#14")
	)
	(segment
		(start 336.836512 -184.433718)
		(end 336.836512 -183.77281)
		(width 0.12065)
		(layer "F.Cu")
		(net "SSD_PERST#14")
	)
	(segment
		(start 336.36966 -186.01436)
		(end 336.36966 -184.953148)
		(width 0.12065)
		(layer "F.Cu")
		(net "SSD_PERST#14")
	)
	(segment
		(start 336.836512 -183.77281)
		(end 336.7024 -183.638698)
		(width 0.12065)
		(layer "F.Cu")
		(net "SSD_PERST#14")
	)
	(segment
		(start 336.836512 -184.486296)
		(end 336.836512 -184.433718)
		(width 0.12065)
		(layer "F.Cu")
		(net "SSD_PERST#14")
	)
	(segment
		(start 336.36966 -184.953148)
		(end 336.836512 -184.486296)
		(width 0.12065)
		(layer "F.Cu")
		(net "SSD_PERST#14")
	)
	(via
		(at 341.436198 -183.345582)
		(size 0.7112)
		(drill 0.3556)
		(layers "F.Cu" "B.Cu")
		(net "SSD_PERST#14")
	)
	(via
		(at 336.7024 -183.638698)
		(size 0.508)
		(drill 0.254)
		(layers "F.Cu" "B.Cu")
		(net "SSD_PERST#14")
	)
	(segment
		(start 341.39378 -183.388)
		(end 341.436198 -183.345582)
		(width 0.12065)
		(layer "B.Cu")
		(net "SSD_PERST#14")
	)
	(segment
		(start 341.6046 -182.2831)
		(end 341.6046 -183.17718)
		(width 0.12065)
		(layer "B.Cu")
		(net "SSD_PERST#14")
	)
	(segment
		(start 340.131146 -183.388)
		(end 341.39378 -183.388)
		(width 0.12065)
		(layer "B.Cu")
		(net "SSD_PERST#14")
	)
	(segment
		(start 341.6046 -183.17718)
		(end 341.436198 -183.345582)
		(width 0.12065)
		(layer "B.Cu")
		(net "SSD_PERST#14")
	)
	(segment
		(start 337.16595 -183.175148)
		(end 339.918294 -183.175148)
		(width 0.12065)
		(layer "B.Cu")
		(net "SSD_PERST#14")
	)
	(segment
		(start 336.677 -183.664098)
		(end 336.7024 -183.638698)
		(width 0.12065)
		(layer "B.Cu")
		(net "SSD_PERST#14")
	)
	(segment
		(start 336.677 -184.4675)
		(end 336.677 -183.664098)
		(width 0.12065)
		(layer "B.Cu")
		(net "SSD_PERST#14")
	)
	(segment
		(start 339.918294 -183.175148)
		(end 340.131146 -183.388)
		(width 0.12065)
		(layer "B.Cu")
		(net "SSD_PERST#14")
	)
	(segment
		(start 336.7024 -183.638698)
		(end 337.16595 -183.175148)
		(width 0.12065)
		(layer "B.Cu")
		(net "SSD_PERST#14")
	)
	(segment
		(start 220.918024 -204.049376)
		(end 219.6084 -205.359)
		(width 0.12065)
		(layer "F.Cu")
		(net "SSD_PERST#13_R")
	)
	(segment
		(start 305.8414 -219.8624)
		(end 305.8414 -216.0905)
		(width 0.12065)
		(layer "F.Cu")
		(net "SSD_PERST#13_R")
	)
	(segment
		(start 233.737912 -151.694896)
		(end 227.965 -157.467808)
		(width 0.12065)
		(layer "F.Cu")
		(net "SSD_PERST#13_R")
	)
	(segment
		(start 236.643164 -151.694896)
		(end 233.737912 -151.694896)
		(width 0.12065)
		(layer "F.Cu")
		(net "SSD_PERST#13_R")
	)
	(segment
		(start 305.1175 -215.3666)
		(end 305.1175 -209.3976)
		(width 0.12065)
		(layer "F.Cu")
		(net "SSD_PERST#13_R")
	)
	(segment
		(start 227.965 -157.467808)
		(end 227.965 -186.182)
		(width 0.12065)
		(layer "F.Cu")
		(net "SSD_PERST#13_R")
	)
	(segment
		(start 220.918024 -203.491592)
		(end 220.918024 -204.049376)
		(width 0.12065)
		(layer "F.Cu")
		(net "SSD_PERST#13_R")
	)
	(segment
		(start 304.071274 -221.632526)
		(end 305.8414 -219.8624)
		(width 0.12065)
		(layer "F.Cu")
		(net "SSD_PERST#13_R")
	)
	(segment
		(start 301.116746 -205.396846)
		(end 301.116746 -179.450746)
		(width 0.12065)
		(layer "F.Cu")
		(net "SSD_PERST#13_R")
	)
	(segment
		(start 304.071274 -223.629474)
		(end 304.071274 -221.632526)
		(width 0.12065)
		(layer "F.Cu")
		(net "SSD_PERST#13_R")
	)
	(segment
		(start 215.392 -205.359)
		(end 212.852 -202.819)
		(width 0.12065)
		(layer "F.Cu")
		(net "SSD_PERST#13_R")
	)
	(segment
		(start 212.852 -194.183)
		(end 214.503 -192.532)
		(width 0.12065)
		(layer "F.Cu")
		(net "SSD_PERST#13_R")
	)
	(segment
		(start 273.36115 -151.69515)
		(end 236.643164 -151.694896)
		(width 0.12065)
		(layer "F.Cu")
		(net "SSD_PERST#13_R")
	)
	(segment
		(start 227.965 -186.182)
		(end 227.711 -186.436)
		(width 0.12065)
		(layer "F.Cu")
		(net "SSD_PERST#13_R")
	)
	(segment
		(start 304.500026 -225.54438)
		(end 304.500026 -224.058226)
		(width 0.12065)
		(layer "F.Cu")
		(net "SSD_PERST#13_R")
	)
	(segment
		(start 304.500026 -224.058226)
		(end 304.071274 -223.629474)
		(width 0.12065)
		(layer "F.Cu")
		(net "SSD_PERST#13_R")
	)
	(segment
		(start 219.6084 -205.359)
		(end 215.392 -205.359)
		(width 0.12065)
		(layer "F.Cu")
		(net "SSD_PERST#13_R")
	)
	(segment
		(start 305.1175 -209.3976)
		(end 301.116746 -205.396846)
		(width 0.12065)
		(layer "F.Cu")
		(net "SSD_PERST#13_R")
	)
	(segment
		(start 305.8414 -216.0905)
		(end 305.1175 -215.3666)
		(width 0.12065)
		(layer "F.Cu")
		(net "SSD_PERST#13_R")
	)
	(segment
		(start 301.116746 -179.450746)
		(end 273.36115 -151.69515)
		(width 0.12065)
		(layer "F.Cu")
		(net "SSD_PERST#13_R")
	)
	(segment
		(start 212.852 -202.819)
		(end 212.852 -194.183)
		(width 0.12065)
		(layer "F.Cu")
		(net "SSD_PERST#13_R")
	)
	(via
		(at 227.711 -186.436)
		(size 0.508)
		(drill 0.254)
		(layers "F.Cu" "B.Cu")
		(net "SSD_PERST#13_R")
	)
	(via
		(at 214.503 -190.5)
		(size 0.7112)
		(drill 0.3556)
		(layers "F.Cu" "B.Cu")
		(net "SSD_PERST#13_R")
	)
	(via
		(at 214.503 -192.532)
		(size 0.508)
		(drill 0.254)
		(layers "F.Cu" "B.Cu")
		(net "SSD_PERST#13_R")
	)
	(segment
		(start 214.503 -192.532)
		(end 214.503 -190.5)
		(width 0.12065)
		(layer "B.Cu")
		(net "SSD_PERST#13_R")
	)
	(segment
		(start 215.773 -192.405)
		(end 214.63 -192.405)
		(width 0.12065)
		(layer "B.Cu")
		(net "SSD_PERST#13_R")
	)
	(segment
		(start 214.503 -188.849)
		(end 214.503 -190.5)
		(width 0.12065)
		(layer "B.Cu")
		(net "SSD_PERST#13_R")
	)
	(segment
		(start 216.5096 -193.5861)
		(end 216.5096 -193.1416)
		(width 0.12065)
		(layer "B.Cu")
		(net "SSD_PERST#13_R")
	)
	(segment
		(start 216.916 -186.436)
		(end 214.503 -188.849)
		(width 0.12065)
		(layer "B.Cu")
		(net "SSD_PERST#13_R")
	)
	(segment
		(start 216.5096 -193.1416)
		(end 215.773 -192.405)
		(width 0.12065)
		(layer "B.Cu")
		(net "SSD_PERST#13_R")
	)
	(segment
		(start 227.711 -186.436)
		(end 216.916 -186.436)
		(width 0.12065)
		(layer "B.Cu")
		(net "SSD_PERST#13_R")
	)
	(segment
		(start 214.63 -192.405)
		(end 214.503 -192.532)
		(width 0.12065)
		(layer "B.Cu")
		(net "SSD_PERST#13_R")
	)
	(segment
		(start 221.250764 -201.610722)
		(end 221.050612 -201.810874)
		(width 0.12065)
		(layer "F.Cu")
		(net "SSD_PERST#13")
	)
	(segment
		(start 220.918024 -201.943462)
		(end 221.050612 -201.810874)
		(width 0.12065)
		(layer "F.Cu")
		(net "SSD_PERST#13")
	)
	(segment
		(start 220.918024 -202.602592)
		(end 220.918024 -201.943462)
		(width 0.12065)
		(layer "F.Cu")
		(net "SSD_PERST#13")
	)
	(segment
		(start 221.2086 -204.5589)
		(end 221.4372 -204.3303)
		(width 0.12065)
		(layer "F.Cu")
		(net "SSD_PERST#13")
	)
	(segment
		(start 215.42502 -200.46442)
		(end 217.13444 -198.755)
		(width 0.12065)
		(layer "F.Cu")
		(net "SSD_PERST#13")
	)
	(segment
		(start 213.35746 -200.46442)
		(end 215.42502 -200.46442)
		(width 0.12065)
		(layer "F.Cu")
		(net "SSD_PERST#13")
	)
	(segment
		(start 220.918024 -202.65517)
		(end 220.918024 -202.602592)
		(width 0.12065)
		(layer "F.Cu")
		(net "SSD_PERST#13")
	)
	(segment
		(start 217.13444 -198.755)
		(end 217.244168 -198.755)
		(width 0.12065)
		(layer "F.Cu")
		(net "SSD_PERST#13")
	)
	(segment
		(start 217.498168 -198.501)
		(end 217.244168 -198.755)
		(width 0.12065)
		(layer "F.Cu")
		(net "SSD_PERST#13")
	)
	(segment
		(start 221.107 -198.501)
		(end 217.498168 -198.501)
		(width 0.12065)
		(layer "F.Cu")
		(net "SSD_PERST#13")
	)
	(segment
		(start 221.250764 -199.770492)
		(end 221.250764 -201.610722)
		(width 0.12065)
		(layer "F.Cu")
		(net "SSD_PERST#13")
	)
	(segment
		(start 221.4372 -203.174346)
		(end 220.918024 -202.65517)
		(width 0.12065)
		(layer "F.Cu")
		(net "SSD_PERST#13")
	)
	(segment
		(start 221.250764 -199.770492)
		(end 221.250764 -198.644764)
		(width 0.12065)
		(layer "F.Cu")
		(net "SSD_PERST#13")
	)
	(segment
		(start 221.250764 -198.644764)
		(end 221.107 -198.501)
		(width 0.12065)
		(layer "F.Cu")
		(net "SSD_PERST#13")
	)
	(segment
		(start 221.4372 -204.3303)
		(end 221.4372 -203.174346)
		(width 0.12065)
		(layer "F.Cu")
		(net "SSD_PERST#13")
	)
	(via
		(at 217.244168 -198.755)
		(size 0.7112)
		(drill 0.3556)
		(layers "F.Cu" "B.Cu")
		(net "SSD_PERST#13")
	)
	(via
		(at 221.050612 -201.810874)
		(size 0.508)
		(drill 0.254)
		(layers "F.Cu" "B.Cu")
		(net "SSD_PERST#13")
	)
	(via
		(at 213.35746 -200.46442)
		(size 0.508)
		(drill 0.254)
		(layers "F.Cu" "B.Cu")
		(net "SSD_PERST#13")
	)
	(segment
		(start 214.5538 -200.46442)
		(end 214.58174 -200.49236)
		(width 0.12065)
		(layer "B.Cu")
		(net "SSD_PERST#13")
	)
	(segment
		(start 220.956124 -202.602592)
		(end 220.956124 -201.905362)
		(width 0.12065)
		(layer "B.Cu")
		(net "SSD_PERST#13")
	)
	(segment
		(start 213.35746 -200.46442)
		(end 214.5538 -200.46442)
		(width 0.12065)
		(layer "B.Cu")
		(net "SSD_PERST#13")
	)
	(segment
		(start 220.956124 -201.905362)
		(end 221.050612 -201.810874)
		(width 0.12065)
		(layer "B.Cu")
		(net "SSD_PERST#13")
	)
	(segment
		(start 224.339404 -207.889856)
		(end 224.33915 -207.889856)
		(width 0.12065)
		(layer "F.Cu")
		(net "SSD_PERST#12_R")
	)
	(segment
		(start 224.540318 -204.738478)
		(end 225.114104 -204.164692)
		(width 0.12065)
		(layer "F.Cu")
		(net "SSD_PERST#12_R")
	)
	(segment
		(start 224.33915 -207.889856)
		(end 224.2185 -207.769206)
		(width 0.12065)
		(layer "F.Cu")
		(net "SSD_PERST#12_R")
	)
	(segment
		(start 224.540318 -205.253082)
		(end 224.540318 -204.738478)
		(width 0.12065)
		(layer "F.Cu")
		(net "SSD_PERST#12_R")
	)
	(segment
		(start 224.2185 -207.769206)
		(end 224.2185 -205.5749)
		(width 0.12065)
		(layer "F.Cu")
		(net "SSD_PERST#12_R")
	)
	(segment
		(start 225.5774 -209.127852)
		(end 224.339404 -207.889856)
		(width 0.12065)
		(layer "F.Cu")
		(net "SSD_PERST#12_R")
	)
	(segment
		(start 224.2185 -205.5749)
		(end 224.540318 -205.253082)
		(width 0.12065)
		(layer "F.Cu")
		(net "SSD_PERST#12_R")
	)
	(via
		(at 219.329 -209.127852)
		(size 0.7112)
		(drill 0.3556)
		(layers "F.Cu" "B.Cu")
		(net "SSD_PERST#12_R")
	)
	(via
		(at 225.5774 -209.127852)
		(size 0.508)
		(drill 0.254)
		(layers "F.Cu" "B.Cu")
		(net "SSD_PERST#12_R")
	)
	(segment
		(start 229.2604 -204.1906)
		(end 229.2604 -207.3402)
		(width 0.12065)
		(layer "B.Cu")
		(net "SSD_PERST#12_R")
	)
	(segment
		(start 229.997 -203.454)
		(end 229.2604 -204.1906)
		(width 0.12065)
		(layer "B.Cu")
		(net "SSD_PERST#12_R")
	)
	(segment
		(start 225.663252 -209.042)
		(end 225.5774 -209.127852)
		(width 0.12065)
		(layer "B.Cu")
		(net "SSD_PERST#12_R")
	)
	(segment
		(start 209.700114 -225.92538)
		(end 209.700114 -212.101684)
		(width 0.12065)
		(layer "B.Cu")
		(net "SSD_PERST#12_R")
	)
	(segment
		(start 227.5586 -209.042)
		(end 225.663252 -209.042)
		(width 0.12065)
		(layer "B.Cu")
		(net "SSD_PERST#12_R")
	)
	(segment
		(start 212.673946 -209.127852)
		(end 219.329 -209.127852)
		(width 0.12065)
		(layer "B.Cu")
		(net "SSD_PERST#12_R")
	)
	(segment
		(start 229.2604 -207.3402)
		(end 227.5586 -209.042)
		(width 0.12065)
		(layer "B.Cu")
		(net "SSD_PERST#12_R")
	)
	(segment
		(start 228.6127 -194.4116)
		(end 229.997 -195.7959)
		(width 0.12065)
		(layer "B.Cu")
		(net "SSD_PERST#12_R")
	)
	(segment
		(start 229.997 -195.7959)
		(end 229.997 -203.454)
		(width 0.12065)
		(layer "B.Cu")
		(net "SSD_PERST#12_R")
	)
	(segment
		(start 225.5774 -209.127852)
		(end 219.329 -209.127852)
		(width 0.12065)
		(layer "B.Cu")
		(net "SSD_PERST#12_R")
	)
	(segment
		(start 209.700114 -212.101684)
		(end 212.673946 -209.127852)
		(width 0.12065)
		(layer "B.Cu")
		(net "SSD_PERST#12_R")
	)
	(segment
		(start 226.03968 -205.29042)
		(end 226.041204 -205.078584)
		(width 0.12065)
		(layer "F.Cu")
		(net "SSD_PERST#12")
	)
	(segment
		(start 225.117152 -201.770488)
		(end 225.117152 -203.272644)
		(width 0.12065)
		(layer "F.Cu")
		(net "SSD_PERST#12")
	)
	(segment
		(start 223.851724 -199.770492)
		(end 223.851724 -200.661524)
		(width 0.12065)
		(layer "F.Cu")
		(net "SSD_PERST#12")
	)
	(segment
		(start 223.851724 -200.661524)
		(end 224.51187 -201.32167)
		(width 0.12065)
		(layer "F.Cu")
		(net "SSD_PERST#12")
	)
	(segment
		(start 225.117152 -203.272644)
		(end 225.114104 -203.275692)
		(width 0.12065)
		(layer "F.Cu")
		(net "SSD_PERST#12")
	)
	(segment
		(start 225.117152 -201.71029)
		(end 225.117152 -201.770488)
		(width 0.12065)
		(layer "F.Cu")
		(net "SSD_PERST#12")
	)
	(segment
		(start 224.51187 -201.32167)
		(end 224.728532 -201.32167)
		(width 0.12065)
		(layer "F.Cu")
		(net "SSD_PERST#12")
	)
	(segment
		(start 226.041204 -205.078584)
		(end 225.622612 -204.659992)
		(width 0.12065)
		(layer "F.Cu")
		(net "SSD_PERST#12")
	)
	(segment
		(start 225.622612 -203.7842)
		(end 225.114104 -203.275692)
		(width 0.12065)
		(layer "F.Cu")
		(net "SSD_PERST#12")
	)
	(segment
		(start 224.728532 -201.32167)
		(end 225.117152 -201.71029)
		(width 0.12065)
		(layer "F.Cu")
		(net "SSD_PERST#12")
	)
	(segment
		(start 225.622612 -204.659992)
		(end 225.622612 -203.7842)
		(width 0.12065)
		(layer "F.Cu")
		(net "SSD_PERST#12")
	)
	(via
		(at 226.187 -202.346052)
		(size 0.7112)
		(drill 0.3556)
		(layers "F.Cu" "B.Cu")
		(net "SSD_PERST#12")
	)
	(via
		(at 225.117152 -201.770488)
		(size 0.508)
		(drill 0.254)
		(layers "F.Cu" "B.Cu")
		(net "SSD_PERST#12")
	)
	(segment
		(start 225.06686 -201.82078)
		(end 225.06686 -203.218288)
		(width 0.12065)
		(layer "B.Cu")
		(net "SSD_PERST#12")
	)
	(segment
		(start 227.629212 -200.451974)
		(end 227.17506 -200.906126)
		(width 0.12065)
		(layer "B.Cu")
		(net "SSD_PERST#12")
	)
	(segment
		(start 226.187 -203.144882)
		(end 226.06635 -203.265532)
		(width 0.12065)
		(layer "B.Cu")
		(net "SSD_PERST#12")
	)
	(segment
		(start 226.06635 -203.265532)
		(end 225.114104 -203.265532)
		(width 0.12065)
		(layer "B.Cu")
		(net "SSD_PERST#12")
	)
	(segment
		(start 226.187 -201.656188)
		(end 226.187 -202.346052)
		(width 0.12065)
		(layer "B.Cu")
		(net "SSD_PERST#12")
	)
	(segment
		(start 226.937062 -200.906126)
		(end 226.187 -201.656188)
		(width 0.12065)
		(layer "B.Cu")
		(net "SSD_PERST#12")
	)
	(segment
		(start 225.06686 -203.218288)
		(end 225.114104 -203.265532)
		(width 0.12065)
		(layer "B.Cu")
		(net "SSD_PERST#12")
	)
	(segment
		(start 225.117152 -201.770488)
		(end 225.06686 -201.82078)
		(width 0.12065)
		(layer "B.Cu")
		(net "SSD_PERST#12")
	)
	(segment
		(start 226.187 -202.346052)
		(end 226.187 -203.144882)
		(width 0.12065)
		(layer "B.Cu")
		(net "SSD_PERST#12")
	)
	(segment
		(start 227.17506 -200.906126)
		(end 226.937062 -200.906126)
		(width 0.12065)
		(layer "B.Cu")
		(net "SSD_PERST#12")
	)
	(segment
		(start 72.771 -198.0565)
		(end 71.9709 -198.8566)
		(width 0.12065)
		(layer "F.Cu")
		(net "SSD_PERST#11_R")
	)
	(segment
		(start 64.9224 -197.739)
		(end 64.9224 -185.0644)
		(width 0.12065)
		(layer "F.Cu")
		(net "SSD_PERST#11_R")
	)
	(segment
		(start 69.699632 -177.056796)
		(end 87.230204 -177.056796)
		(width 0.12065)
		(layer "F.Cu")
		(net "SSD_PERST#11_R")
	)
	(segment
		(start 65.405 -184.277)
		(end 65.405 -181.351428)
		(width 0.12065)
		(layer "F.Cu")
		(net "SSD_PERST#11_R")
	)
	(segment
		(start 64.9224 -185.0644)
		(end 65.5574 -184.4294)
		(width 0.12065)
		(layer "F.Cu")
		(net "SSD_PERST#11_R")
	)
	(segment
		(start 65.5574 -184.4294)
		(end 65.405 -184.277)
		(width 0.12065)
		(layer "F.Cu")
		(net "SSD_PERST#11_R")
	)
	(segment
		(start 65.405 -181.351428)
		(end 69.699632 -177.056796)
		(width 0.12065)
		(layer "F.Cu")
		(net "SSD_PERST#11_R")
	)
	(segment
		(start 66.04 -198.8566)
		(end 64.9224 -197.739)
		(width 0.12065)
		(layer "F.Cu")
		(net "SSD_PERST#11_R")
	)
	(segment
		(start 87.230204 -177.056796)
		(end 87.4268 -176.8602)
		(width 0.12065)
		(layer "F.Cu")
		(net "SSD_PERST#11_R")
	)
	(segment
		(start 71.9709 -198.8566)
		(end 66.04 -198.8566)
		(width 0.12065)
		(layer "F.Cu")
		(net "SSD_PERST#11_R")
	)
	(via
		(at 221.615 -185.039)
		(size 0.7112)
		(drill 0.3556)
		(layers "F.Cu" "B.Cu")
		(net "SSD_PERST#11_R")
	)
	(via
		(at 65.5574 -184.4294)
		(size 0.508)
		(drill 0.254)
		(layers "F.Cu" "B.Cu")
		(net "SSD_PERST#11_R")
	)
	(via
		(at 87.4268 -176.8602)
		(size 0.508)
		(drill 0.254)
		(layers "F.Cu" "B.Cu")
		(net "SSD_PERST#11_R")
	)
	(segment
		(start 118.791228 -175.4505)
		(end 128.379728 -185.039)
		(width 0.12065)
		(layer "B.Cu")
		(net "SSD_PERST#11_R")
	)
	(segment
		(start 66.665348 -185.537348)
		(end 65.5574 -184.4294)
		(width 0.12065)
		(layer "B.Cu")
		(net "SSD_PERST#11_R")
	)
	(segment
		(start 217.700098 -224.481898)
		(end 216.916 -223.6978)
		(width 0.12065)
		(layer "B.Cu")
		(net "SSD_PERST#11_R")
	)
	(segment
		(start 70.6247 -185.84545)
		(end 70.316598 -185.537348)
		(width 0.12065)
		(layer "B.Cu")
		(net "SSD_PERST#11_R")
	)
	(segment
		(start 217.700098 -213.875366)
		(end 221.460314 -210.11515)
		(width 0.12065)
		(layer "B.Cu")
		(net "SSD_PERST#11_R")
	)
	(segment
		(start 228.191314 -210.11515)
		(end 231.3686 -206.937864)
		(width 0.12065)
		(layer "B.Cu")
		(net "SSD_PERST#11_R")
	)
	(segment
		(start 90.81389 -175.450246)
		(end 95.434658 -175.450246)
		(width 0.12065)
		(layer "B.Cu")
		(net "SSD_PERST#11_R")
	)
	(segment
		(start 216.916 -221.764098)
		(end 217.700098 -220.98)
		(width 0.12065)
		(layer "B.Cu")
		(net "SSD_PERST#11_R")
	)
	(segment
		(start 70.6247 -186.249818)
		(end 70.6247 -185.84545)
		(width 0.12065)
		(layer "B.Cu")
		(net "SSD_PERST#11_R")
	)
	(segment
		(start 90.254836 -176.0093)
		(end 90.81389 -175.450246)
		(width 0.12065)
		(layer "B.Cu")
		(net "SSD_PERST#11_R")
	)
	(segment
		(start 230.0986 -185.039)
		(end 221.615 -185.039)
		(width 0.12065)
		(layer "B.Cu")
		(net "SSD_PERST#11_R")
	)
	(segment
		(start 217.700098 -220.98)
		(end 217.700098 -213.875366)
		(width 0.12065)
		(layer "B.Cu")
		(net "SSD_PERST#11_R")
	)
	(segment
		(start 70.316598 -185.537348)
		(end 66.665348 -185.537348)
		(width 0.12065)
		(layer "B.Cu")
		(net "SSD_PERST#11_R")
	)
	(segment
		(start 216.916 -223.6978)
		(end 216.916 -221.764098)
		(width 0.12065)
		(layer "B.Cu")
		(net "SSD_PERST#11_R")
	)
	(segment
		(start 217.700098 -225.92538)
		(end 217.700098 -224.481898)
		(width 0.12065)
		(layer "B.Cu")
		(net "SSD_PERST#11_R")
	)
	(segment
		(start 87.4268 -176.8602)
		(end 88.2777 -176.0093)
		(width 0.12065)
		(layer "B.Cu")
		(net "SSD_PERST#11_R")
	)
	(segment
		(start 221.460314 -210.11515)
		(end 228.191314 -210.11515)
		(width 0.12065)
		(layer "B.Cu")
		(net "SSD_PERST#11_R")
	)
	(segment
		(start 231.3686 -206.937864)
		(end 231.3686 -186.309)
		(width 0.12065)
		(layer "B.Cu")
		(net "SSD_PERST#11_R")
	)
	(segment
		(start 95.434658 -175.450246)
		(end 95.434912 -175.4505)
		(width 0.12065)
		(layer "B.Cu")
		(net "SSD_PERST#11_R")
	)
	(segment
		(start 95.434912 -175.4505)
		(end 118.791228 -175.4505)
		(width 0.12065)
		(layer "B.Cu")
		(net "SSD_PERST#11_R")
	)
	(segment
		(start 128.379728 -185.039)
		(end 221.615 -185.039)
		(width 0.12065)
		(layer "B.Cu")
		(net "SSD_PERST#11_R")
	)
	(segment
		(start 231.3686 -186.309)
		(end 230.0986 -185.039)
		(width 0.12065)
		(layer "B.Cu")
		(net "SSD_PERST#11_R")
	)
	(segment
		(start 88.2777 -176.0093)
		(end 90.254836 -176.0093)
		(width 0.12065)
		(layer "B.Cu")
		(net "SSD_PERST#11_R")
	)
	(segment
		(start 72.968612 -193.443352)
		(end 72.968612 -194.416934)
		(width 0.12065)
		(layer "F.Cu")
		(net "SSD_PERST#11")
	)
	(segment
		(start 73.168764 -192.404492)
		(end 73.168764 -191.151764)
		(width 0.12065)
		(layer "F.Cu")
		(net "SSD_PERST#11")
	)
	(segment
		(start 73.025 -191.008)
		(end 71.501 -191.008)
		(width 0.12065)
		(layer "F.Cu")
		(net "SSD_PERST#11")
	)
	(segment
		(start 73.237852 -195.665852)
		(end 73.237852 -196.700648)
		(width 0.12065)
		(layer "F.Cu")
		(net "SSD_PERST#11")
	)
	(segment
		(start 73.237852 -196.700648)
		(end 72.771 -197.1675)
		(width 0.12065)
		(layer "F.Cu")
		(net "SSD_PERST#11")
	)
	(segment
		(start 72.771 -194.614546)
		(end 72.771 -195.2625)
		(width 0.12065)
		(layer "F.Cu")
		(net "SSD_PERST#11")
	)
	(segment
		(start 73.168764 -193.2432)
		(end 72.968612 -193.443352)
		(width 0.12065)
		(layer "F.Cu")
		(net "SSD_PERST#11")
	)
	(segment
		(start 72.968612 -194.416934)
		(end 72.92721 -194.458336)
		(width 0.12065)
		(layer "F.Cu")
		(net "SSD_PERST#11")
	)
	(segment
		(start 69.5198 -191.008)
		(end 71.501 -191.008)
		(width 0.12065)
		(layer "F.Cu")
		(net "SSD_PERST#11")
	)
	(segment
		(start 72.92721 -194.458336)
		(end 72.771 -194.614546)
		(width 0.12065)
		(layer "F.Cu")
		(net "SSD_PERST#11")
	)
	(segment
		(start 73.168764 -191.151764)
		(end 73.025 -191.008)
		(width 0.12065)
		(layer "F.Cu")
		(net "SSD_PERST#11")
	)
	(segment
		(start 73.168764 -192.404492)
		(end 73.168764 -193.2432)
		(width 0.12065)
		(layer "F.Cu")
		(net "SSD_PERST#11")
	)
	(segment
		(start 72.771 -195.2625)
		(end 72.8345 -195.2625)
		(width 0.12065)
		(layer "F.Cu")
		(net "SSD_PERST#11")
	)
	(segment
		(start 72.8345 -195.2625)
		(end 73.237852 -195.665852)
		(width 0.12065)
		(layer "F.Cu")
		(net "SSD_PERST#11")
	)
	(via
		(at 71.501 -191.008)
		(size 0.508)
		(drill 0.254)
		(layers "F.Cu" "B.Cu")
		(net "SSD_PERST#11")
	)
	(via
		(at 72.92721 -194.458336)
		(size 0.508)
		(drill 0.254)
		(layers "F.Cu" "B.Cu")
		(net "SSD_PERST#11")
	)
	(via
		(at 69.5198 -191.008)
		(size 0.7112)
		(drill 0.3556)
		(layers "F.Cu" "B.Cu")
		(net "SSD_PERST#11")
	)
	(segment
		(start 72.874124 -195.236592)
		(end 72.874124 -194.539362)
		(width 0.12065)
		(layer "B.Cu")
		(net "SSD_PERST#11")
	)
	(segment
		(start 71.501 -192.4685)
		(end 71.501 -191.008)
		(width 0.12065)
		(layer "B.Cu")
		(net "SSD_PERST#11")
	)
	(segment
		(start 72.874124 -194.539362)
		(end 72.92721 -194.486276)
		(width 0.12065)
		(layer "B.Cu")
		(net "SSD_PERST#11")
	)
	(segment
		(start 70.993 -192.9765)
		(end 71.501 -192.4685)
		(width 0.12065)
		(layer "B.Cu")
		(net "SSD_PERST#11")
	)
	(segment
		(start 72.92721 -194.486276)
		(end 72.92721 -194.458336)
		(width 0.12065)
		(layer "B.Cu")
		(net "SSD_PERST#11")
	)
	(segment
		(start 82.677 -185.293)
		(end 82.804 -185.166)
		(width 0.12065)
		(layer "F.Cu")
		(net "SSD_PERST#10_R")
	)
	(segment
		(start 77.4573 -197.866)
		(end 82.804 -197.866)
		(width 0.12065)
		(layer "F.Cu")
		(net "SSD_PERST#10_R")
	)
	(segment
		(start 83.82 -193.784474)
		(end 82.677 -192.641474)
		(width 0.12065)
		(layer "F.Cu")
		(net "SSD_PERST#10_R")
	)
	(segment
		(start 77.216 -198.1073)
		(end 77.4573 -197.866)
		(width 0.12065)
		(layer "F.Cu")
		(net "SSD_PERST#10_R")
	)
	(segment
		(start 82.677 -192.641474)
		(end 82.677 -185.293)
		(width 0.12065)
		(layer "F.Cu")
		(net "SSD_PERST#10_R")
	)
	(segment
		(start 83.82 -196.85)
		(end 83.82 -193.784474)
		(width 0.12065)
		(layer "F.Cu")
		(net "SSD_PERST#10_R")
	)
	(segment
		(start 82.804 -197.866)
		(end 83.82 -196.85)
		(width 0.12065)
		(layer "F.Cu")
		(net "SSD_PERST#10_R")
	)
	(via
		(at 106.168952 -206.524352)
		(size 0.7112)
		(drill 0.3556)
		(layers "F.Cu" "B.Cu")
		(net "SSD_PERST#10_R")
	)
	(via
		(at 82.804 -185.166)
		(size 0.508)
		(drill 0.254)
		(layers "F.Cu" "B.Cu")
		(net "SSD_PERST#10_R")
	)
	(segment
		(start 82.804 -185.293)
		(end 82.804 -185.166)
		(width 0.12065)
		(layer "B.Cu")
		(net "SSD_PERST#10_R")
	)
	(segment
		(start 83.230212 -185.719212)
		(end 82.804 -185.293)
		(width 0.12065)
		(layer "B.Cu")
		(net "SSD_PERST#10_R")
	)
	(segment
		(start 109.4994 -209.8548)
		(end 106.168952 -206.524352)
		(width 0.12065)
		(layer "B.Cu")
		(net "SSD_PERST#10_R")
	)
	(segment
		(start 83.230212 -186.100974)
		(end 83.230212 -185.719212)
		(width 0.12065)
		(layer "B.Cu")
		(net "SSD_PERST#10_R")
	)
	(segment
		(start 106.168952 -206.524352)
		(end 85.745574 -186.100974)
		(width 0.12065)
		(layer "B.Cu")
		(net "SSD_PERST#10_R")
	)
	(segment
		(start 108.500164 -225.92538)
		(end 108.500164 -220.861636)
		(width 0.12065)
		(layer "B.Cu")
		(net "SSD_PERST#10_R")
	)
	(segment
		(start 109.4994 -219.8624)
		(end 109.4994 -209.8548)
		(width 0.12065)
		(layer "B.Cu")
		(net "SSD_PERST#10_R")
	)
	(segment
		(start 85.745574 -186.100974)
		(end 83.230212 -186.100974)
		(width 0.12065)
		(layer "B.Cu")
		(net "SSD_PERST#10_R")
	)
	(segment
		(start 108.500164 -220.861636)
		(end 109.4994 -219.8624)
		(width 0.12065)
		(layer "B.Cu")
		(net "SSD_PERST#10_R")
	)
	(segment
		(start 75.769724 -192.404492)
		(end 75.769724 -193.295524)
		(width 0.12065)
		(layer "F.Cu")
		(net "SSD_PERST#10")
	)
	(segment
		(start 77.0382 -194.564)
		(end 77.0382 -195.2117)
		(width 0.12065)
		(layer "F.Cu")
		(net "SSD_PERST#10")
	)
	(segment
		(start 77.593952 -196.840348)
		(end 77.216 -197.2183)
		(width 0.12065)
		(layer "F.Cu")
		(net "SSD_PERST#10")
	)
	(segment
		(start 76.8858 -194.4116)
		(end 77.0382 -194.564)
		(width 0.12065)
		(layer "F.Cu")
		(net "SSD_PERST#10")
	)
	(segment
		(start 75.769724 -193.295524)
		(end 76.8858 -194.4116)
		(width 0.12065)
		(layer "F.Cu")
		(net "SSD_PERST#10")
	)
	(segment
		(start 77.593952 -195.767452)
		(end 77.593952 -196.840348)
		(width 0.12065)
		(layer "F.Cu")
		(net "SSD_PERST#10")
	)
	(segment
		(start 77.0382 -195.2117)
		(end 77.593952 -195.767452)
		(width 0.12065)
		(layer "F.Cu")
		(net "SSD_PERST#10")
	)
	(via
		(at 78.0796 -194.497452)
		(size 0.7112)
		(drill 0.3556)
		(layers "F.Cu" "B.Cu")
		(net "SSD_PERST#10")
	)
	(via
		(at 76.8858 -194.4116)
		(size 0.508)
		(drill 0.254)
		(layers "F.Cu" "B.Cu")
		(net "SSD_PERST#10")
	)
	(segment
		(start 82.722212 -193.085974)
		(end 81.879186 -193.929)
		(width 0.12065)
		(layer "B.Cu")
		(net "SSD_PERST#10")
	)
	(segment
		(start 78.648052 -193.929)
		(end 78.0796 -194.497452)
		(width 0.12065)
		(layer "B.Cu")
		(net "SSD_PERST#10")
	)
	(segment
		(start 77.065124 -195.236592)
		(end 77.065124 -194.590924)
		(width 0.12065)
		(layer "B.Cu")
		(net "SSD_PERST#10")
	)
	(segment
		(start 76.8858 -194.4116)
		(end 77.993748 -194.4116)
		(width 0.12065)
		(layer "B.Cu")
		(net "SSD_PERST#10")
	)
	(segment
		(start 81.879186 -193.929)
		(end 78.648052 -193.929)
		(width 0.12065)
		(layer "B.Cu")
		(net "SSD_PERST#10")
	)
	(segment
		(start 77.065124 -194.590924)
		(end 76.8858 -194.4116)
		(width 0.12065)
		(layer "B.Cu")
		(net "SSD_PERST#10")
	)
	(segment
		(start 77.993748 -194.4116)
		(end 78.0796 -194.497452)
		(width 0.12065)
		(layer "B.Cu")
		(net "SSD_PERST#10")
	)
	(segment
		(start 78.100174 -221.55912)
		(end 77.384148 -220.843094)
		(width 0.12065)
		(layer "F.Cu")
		(net "SSD_PERST#1_R")
	)
	(segment
		(start 78.100174 -225.54438)
		(end 78.100174 -221.55912)
		(width 0.12065)
		(layer "F.Cu")
		(net "SSD_PERST#1_R")
	)
	(segment
		(start 128.496314 -197.438264)
		(end 128.541272 -197.393306)
		(width 0.12065)
		(layer "F.Cu")
		(net "SSD_PERST#1_R")
	)
	(segment
		(start 85.66785 -184.79135)
		(end 91.44 -179.0192)
		(width 0.12065)
		(layer "F.Cu")
		(net "SSD_PERST#1_R")
	)
	(segment
		(start 128.541272 -196.465444)
		(end 129.008124 -195.998592)
		(width 0.12065)
		(layer "F.Cu")
		(net "SSD_PERST#1_R")
	)
	(segment
		(start 129.008124 -195.998592)
		(end 129.008124 -195.206874)
		(width 0.12065)
		(layer "F.Cu")
		(net "SSD_PERST#1_R")
	)
	(segment
		(start 128.541272 -197.393306)
		(end 128.541272 -196.465444)
		(width 0.12065)
		(layer "F.Cu")
		(net "SSD_PERST#1_R")
	)
	(segment
		(start 128.086612 -197.916292)
		(end 128.496314 -197.50659)
		(width 0.12065)
		(layer "F.Cu")
		(net "SSD_PERST#1_R")
	)
	(segment
		(start 77.384148 -220.843094)
		(end 77.384148 -210.474052)
		(width 0.12065)
		(layer "F.Cu")
		(net "SSD_PERST#1_R")
	)
	(segment
		(start 91.44 -179.0192)
		(end 91.44 -178.816)
		(width 0.12065)
		(layer "F.Cu")
		(net "SSD_PERST#1_R")
	)
	(segment
		(start 85.66785 -202.19035)
		(end 85.66785 -184.79135)
		(width 0.12065)
		(layer "F.Cu")
		(net "SSD_PERST#1_R")
	)
	(segment
		(start 128.496314 -197.50659)
		(end 128.496314 -197.438264)
		(width 0.12065)
		(layer "F.Cu")
		(net "SSD_PERST#1_R")
	)
	(segment
		(start 77.384148 -210.474052)
		(end 85.66785 -202.19035)
		(width 0.12065)
		(layer "F.Cu")
		(net "SSD_PERST#1_R")
	)
	(via
		(at 125.939296 -192.138046)
		(size 0.7112)
		(drill 0.3556)
		(layers "F.Cu" "B.Cu")
		(net "SSD_PERST#1_R")
	)
	(via
		(at 91.44 -178.816)
		(size 0.508)
		(drill 0.254)
		(layers "F.Cu" "B.Cu")
		(net "SSD_PERST#1_R")
	)
	(via
		(at 128.086612 -197.916292)
		(size 0.508)
		(drill 0.254)
		(layers "F.Cu" "B.Cu")
		(net "SSD_PERST#1_R")
	)
	(via
		(at 129.008124 -195.206874)
		(size 0.508)
		(drill 0.254)
		(layers "F.Cu" "B.Cu")
		(net "SSD_PERST#1_R")
	)
	(segment
		(start 125.939296 -192.138046)
		(end 129.008124 -195.206874)
		(width 0.12065)
		(layer "B.Cu")
		(net "SSD_PERST#1_R")
	)
	(segment
		(start 91.44 -178.816)
		(end 92.27185 -177.98415)
		(width 0.12065)
		(layer "B.Cu")
		(net "SSD_PERST#1_R")
	)
	(segment
		(start 92.27185 -177.98415)
		(end 111.7854 -177.98415)
		(width 0.12065)
		(layer "B.Cu")
		(net "SSD_PERST#1_R")
	)
	(segment
		(start 111.7854 -177.98415)
		(end 125.939296 -192.138046)
		(width 0.12065)
		(layer "B.Cu")
		(net "SSD_PERST#1_R")
	)
	(segment
		(start 128.7653 -200.3298)
		(end 128.4224 -199.9869)
		(width 0.12065)
		(layer "B.Cu")
		(net "SSD_PERST#1_R")
	)
	(segment
		(start 128.4224 -199.9869)
		(end 128.4224 -198.25208)
		(width 0.12065)
		(layer "B.Cu")
		(net "SSD_PERST#1_R")
	)
	(segment
		(start 128.4224 -198.25208)
		(end 128.086612 -197.916292)
		(width 0.12065)
		(layer "B.Cu")
		(net "SSD_PERST#1_R")
	)
	(segment
		(start 128.698244 -198.278242)
		(end 128.963166 -198.01332)
		(width 0.12065)
		(layer "F.Cu")
		(net "SSD_PERST#1")
	)
	(segment
		(start 128.698244 -199.973692)
		(end 128.698244 -198.278242)
		(width 0.12065)
		(layer "F.Cu")
		(net "SSD_PERST#1")
	)
	(segment
		(start 129.008124 -197.617334)
		(end 128.963166 -197.662292)
		(width 0.12065)
		(layer "F.Cu")
		(net "SSD_PERST#1")
	)
	(segment
		(start 129.008124 -196.887592)
		(end 129.008124 -197.617334)
		(width 0.12065)
		(layer "F.Cu")
		(net "SSD_PERST#1")
	)
	(segment
		(start 128.963166 -198.01332)
		(end 128.963166 -197.662292)
		(width 0.12065)
		(layer "F.Cu")
		(net "SSD_PERST#1")
	)
	(via
		(at 130.631692 -199.32523)
		(size 0.7112)
		(drill 0.3556)
		(layers "F.Cu" "B.Cu")
		(net "SSD_PERST#1")
	)
	(via
		(at 128.963166 -197.662292)
		(size 0.508)
		(drill 0.254)
		(layers "F.Cu" "B.Cu")
		(net "SSD_PERST#1")
	)
	(segment
		(start 128.963166 -197.662292)
		(end 128.963166 -197.866254)
		(width 0.12065)
		(layer "B.Cu")
		(net "SSD_PERST#1")
	)
	(segment
		(start 130.302 -206.454248)
		(end 130.387852 -206.368396)
		(width 0.12065)
		(layer "B.Cu")
		(net "SSD_PERST#1")
	)
	(segment
		(start 130.387852 -203.652374)
		(end 129.717292 -202.981814)
		(width 0.12065)
		(layer "B.Cu")
		(net "SSD_PERST#1")
	)
	(segment
		(start 130.387852 -206.368396)
		(end 130.387852 -203.652374)
		(width 0.12065)
		(layer "B.Cu")
		(net "SSD_PERST#1")
	)
	(segment
		(start 130.422142 -199.32523)
		(end 130.631692 -199.32523)
		(width 0.12065)
		(layer "B.Cu")
		(net "SSD_PERST#1")
	)
	(segment
		(start 130.254248 -199.702674)
		(end 130.631692 -199.32523)
		(width 0.12065)
		(layer "B.Cu")
		(net "SSD_PERST#1")
	)
	(segment
		(start 128.944878 -196.98335)
		(end 129.090928 -196.8373)
		(width 0.12065)
		(layer "B.Cu")
		(net "SSD_PERST#1")
	)
	(segment
		(start 130.254248 -201.063352)
		(end 130.254248 -199.702674)
		(width 0.12065)
		(layer "B.Cu")
		(net "SSD_PERST#1")
	)
	(segment
		(start 129.090928 -196.8373)
		(end 129.4384 -196.8373)
		(width 0.12065)
		(layer "B.Cu")
		(net "SSD_PERST#1")
	)
	(segment
		(start 128.963166 -197.866254)
		(end 130.422142 -199.32523)
		(width 0.12065)
		(layer "B.Cu")
		(net "SSD_PERST#1")
	)
	(segment
		(start 129.717292 -201.600308)
		(end 130.254248 -201.063352)
		(width 0.12065)
		(layer "B.Cu")
		(net "SSD_PERST#1")
	)
	(segment
		(start 128.963166 -197.662292)
		(end 128.944878 -197.644004)
		(width 0.12065)
		(layer "B.Cu")
		(net "SSD_PERST#1")
	)
	(segment
		(start 129.4384 -196.8373)
		(end 130.4798 -196.8373)
		(width 0.12065)
		(layer "B.Cu")
		(net "SSD_PERST#1")
	)
	(segment
		(start 128.944878 -197.644004)
		(end 128.944878 -196.98335)
		(width 0.12065)
		(layer "B.Cu")
		(net "SSD_PERST#1")
	)
	(segment
		(start 128.696212 -206.293974)
		(end 128.856486 -206.454248)
		(width 0.12065)
		(layer "B.Cu")
		(net "SSD_PERST#1")
	)
	(segment
		(start 128.856486 -206.454248)
		(end 130.302 -206.454248)
		(width 0.12065)
		(layer "B.Cu")
		(net "SSD_PERST#1")
	)
	(segment
		(start 129.717292 -202.981814)
		(end 129.717292 -201.600308)
		(width 0.12065)
		(layer "B.Cu")
		(net "SSD_PERST#1")
	)
	(segment
		(start 76.726796 -209.912204)
		(end 77.029564 -209.609436)
		(width 0.12065)
		(layer "F.Cu")
		(net "SSD_PERST#0_R")
	)
	(segment
		(start 74.312272 -183.257444)
		(end 74.312272 -184.01919)
		(width 0.12065)
		(layer "F.Cu")
		(net "SSD_PERST#0_R")
	)
	(segment
		(start 75.30465 -178.526694)
		(end 75.184 -178.647344)
		(width 0.12065)
		(layer "F.Cu")
		(net "SSD_PERST#0_R")
	)
	(segment
		(start 75.184 -178.647344)
		(end 75.184 -182.385716)
		(width 0.12065)
		(layer "F.Cu")
		(net "SSD_PERST#0_R")
	)
	(segment
		(start 85.3059 -185.754772)
		(end 84.2772 -184.726072)
		(width 0.12065)
		(layer "F.Cu")
		(net "SSD_PERST#0_R")
	)
	(segment
		(start 77.54112 -221.52102)
		(end 76.726796 -220.706696)
		(width 0.12065)
		(layer "F.Cu")
		(net "SSD_PERST#0_R")
	)
	(segment
		(start 74.779124 -182.790592)
		(end 74.312272 -183.257444)
		(width 0.12065)
		(layer "F.Cu")
		(net "SSD_PERST#0_R")
	)
	(segment
		(start 76.726796 -220.706696)
		(end 76.726796 -209.912204)
		(width 0.12065)
		(layer "F.Cu")
		(net "SSD_PERST#0_R")
	)
	(segment
		(start 74.312272 -184.01919)
		(end 73.84288 -184.488582)
		(width 0.12065)
		(layer "F.Cu")
		(net "SSD_PERST#0_R")
	)
	(segment
		(start 84.2772 -180.661056)
		(end 82.142838 -178.526694)
		(width 0.12065)
		(layer "F.Cu")
		(net "SSD_PERST#0_R")
	)
	(segment
		(start 77.54112 -224.32264)
		(end 77.54112 -221.52102)
		(width 0.12065)
		(layer "F.Cu")
		(net "SSD_PERST#0_R")
	)
	(segment
		(start 85.3059 -201.3331)
		(end 85.3059 -185.754772)
		(width 0.12065)
		(layer "F.Cu")
		(net "SSD_PERST#0_R")
	)
	(segment
		(start 84.2772 -184.726072)
		(end 84.2772 -180.661056)
		(width 0.12065)
		(layer "F.Cu")
		(net "SSD_PERST#0_R")
	)
	(segment
		(start 75.184 -182.385716)
		(end 74.779124 -182.790592)
		(width 0.12065)
		(layer "F.Cu")
		(net "SSD_PERST#0_R")
	)
	(segment
		(start 77.300074 -225.54438)
		(end 77.300074 -224.563686)
		(width 0.12065)
		(layer "F.Cu")
		(net "SSD_PERST#0_R")
	)
	(segment
		(start 77.300074 -224.563686)
		(end 77.54112 -224.32264)
		(width 0.12065)
		(layer "F.Cu")
		(net "SSD_PERST#0_R")
	)
	(segment
		(start 77.029564 -209.609436)
		(end 85.3059 -201.3331)
		(width 0.12065)
		(layer "F.Cu")
		(net "SSD_PERST#0_R")
	)
	(segment
		(start 82.142838 -178.526694)
		(end 75.30465 -178.526694)
		(width 0.12065)
		(layer "F.Cu")
		(net "SSD_PERST#0_R")
	)
	(via
		(at 73.84288 -184.488582)
		(size 0.508)
		(drill 0.254)
		(layers "F.Cu" "B.Cu")
		(net "SSD_PERST#0_R")
	)
	(via
		(at 77.029564 -209.609436)
		(size 0.7112)
		(drill 0.3556)
		(layers "F.Cu" "B.Cu")
		(net "SSD_PERST#0_R")
	)
	(segment
		(start 73.862946 -184.518554)
		(end 73.862946 -184.488582)
		(width 0.12065)
		(layer "B.Cu")
		(net "SSD_PERST#0_R")
	)
	(segment
		(start 74.594974 -186.100974)
		(end 73.857612 -185.363612)
		(width 0.12065)
		(layer "B.Cu")
		(net "SSD_PERST#0_R")
	)
	(segment
		(start 73.862946 -184.488582)
		(end 73.84288 -184.488582)
		(width 0.12065)
		(layer "B.Cu")
		(net "SSD_PERST#0_R")
	)
	(segment
		(start 73.857612 -185.363612)
		(end 73.857612 -184.523888)
		(width 0.12065)
		(layer "B.Cu")
		(net "SSD_PERST#0_R")
	)
	(segment
		(start 73.857612 -184.523888)
		(end 73.862946 -184.518554)
		(width 0.12065)
		(layer "B.Cu")
		(net "SSD_PERST#0_R")
	)
	(segment
		(start 75.102212 -186.100974)
		(end 74.594974 -186.100974)
		(width 0.12065)
		(layer "B.Cu")
		(net "SSD_PERST#0_R")
	)
	(segment
		(start 74.779124 -184.00903)
		(end 75.217528 -184.447434)
		(width 0.12065)
		(layer "F.Cu")
		(net "SSD_PERST#0")
	)
	(segment
		(start 74.469244 -186.083956)
		(end 75.217528 -185.335672)
		(width 0.12065)
		(layer "F.Cu")
		(net "SSD_PERST#0")
	)
	(segment
		(start 74.779124 -183.679592)
		(end 74.779124 -184.00903)
		(width 0.12065)
		(layer "F.Cu")
		(net "SSD_PERST#0")
	)
	(segment
		(start 74.469244 -186.765692)
		(end 74.469244 -186.083956)
		(width 0.12065)
		(layer "F.Cu")
		(net "SSD_PERST#0")
	)
	(segment
		(start 75.217528 -185.335672)
		(end 75.217528 -184.447434)
		(width 0.12065)
		(layer "F.Cu")
		(net "SSD_PERST#0")
	)
	(via
		(at 74.609452 -185.197242)
		(size 0.7112)
		(drill 0.3556)
		(layers "F.Cu" "B.Cu")
		(net "SSD_PERST#0")
	)
	(via
		(at 75.217528 -184.447434)
		(size 0.508)
		(drill 0.254)
		(layers "F.Cu" "B.Cu")
		(net "SSD_PERST#0")
	)
	(segment
		(start 74.804524 -184.03443)
		(end 75.217528 -184.447434)
		(width 0.12065)
		(layer "B.Cu")
		(net "SSD_PERST#0")
	)
	(segment
		(start 73.787 -183.7055)
		(end 74.778616 -183.7055)
		(width 0.12065)
		(layer "B.Cu")
		(net "SSD_PERST#0")
	)
	(segment
		(start 76.323952 -190.609474)
		(end 75.898248 -190.18377)
		(width 0.12065)
		(layer "B.Cu")
		(net "SSD_PERST#0")
	)
	(segment
		(start 74.778616 -183.7055)
		(end 74.804524 -183.679592)
		(width 0.12065)
		(layer "B.Cu")
		(net "SSD_PERST#0")
	)
	(segment
		(start 76.323952 -192.969896)
		(end 76.323952 -190.609474)
		(width 0.12065)
		(layer "B.Cu")
		(net "SSD_PERST#0")
	)
	(segment
		(start 74.823066 -185.410856)
		(end 74.609452 -185.197242)
		(width 0.12065)
		(layer "B.Cu")
		(net "SSD_PERST#0")
	)
	(segment
		(start 75.898248 -187.983622)
		(end 76.641452 -187.240418)
		(width 0.12065)
		(layer "B.Cu")
		(net "SSD_PERST#0")
	)
	(segment
		(start 76.641452 -186.56554)
		(end 75.486768 -185.410856)
		(width 0.12065)
		(layer "B.Cu")
		(net "SSD_PERST#0")
	)
	(segment
		(start 75.486768 -185.410856)
		(end 74.823066 -185.410856)
		(width 0.12065)
		(layer "B.Cu")
		(net "SSD_PERST#0")
	)
	(segment
		(start 76.073 -193.220848)
		(end 76.323952 -192.969896)
		(width 0.12065)
		(layer "B.Cu")
		(net "SSD_PERST#0")
	)
	(segment
		(start 74.609452 -185.05551)
		(end 75.217528 -184.447434)
		(width 0.12065)
		(layer "B.Cu")
		(net "SSD_PERST#0")
	)
	(segment
		(start 75.898248 -190.18377)
		(end 75.898248 -187.983622)
		(width 0.12065)
		(layer "B.Cu")
		(net "SSD_PERST#0")
	)
	(segment
		(start 74.729086 -193.220848)
		(end 76.073 -193.220848)
		(width 0.12065)
		(layer "B.Cu")
		(net "SSD_PERST#0")
	)
	(segment
		(start 74.609452 -185.197242)
		(end 74.609452 -185.05551)
		(width 0.12065)
		(layer "B.Cu")
		(net "SSD_PERST#0")
	)
	(segment
		(start 74.594212 -193.085974)
		(end 74.729086 -193.220848)
		(width 0.12065)
		(layer "B.Cu")
		(net "SSD_PERST#0")
	)
	(segment
		(start 76.641452 -187.240418)
		(end 76.641452 -186.56554)
		(width 0.12065)
		(layer "B.Cu")
		(net "SSD_PERST#0")
	)
	(segment
		(start 74.804524 -183.679592)
		(end 74.804524 -184.03443)
		(width 0.12065)
		(layer "B.Cu")
		(net "SSD_PERST#0")
	)
	(segment
		(start 329.300078 -224.201228)
		(end 329.435206 -224.0661)
		(width 0.12065)
		(layer "F.Cu")
		(net "SSD_ATNLED#9_R")
	)
	(segment
		(start 329.435206 -224.0661)
		(end 329.435206 -222.52432)
		(width 0.12065)
		(layer "F.Cu")
		(net "SSD_ATNLED#9_R")
	)
	(segment
		(start 337.852512 -171.536868)
		(end 338.660232 -170.729148)
		(width 0.12065)
		(layer "F.Cu")
		(net "SSD_ATNLED#9_R")
	)
	(segment
		(start 329.435206 -222.52432)
		(end 329.57135 -222.388176)
		(width 0.12065)
		(layer "F.Cu")
		(net "SSD_ATNLED#9_R")
	)
	(segment
		(start 342.763602 -178.533552)
		(end 342.55075 -178.746404)
		(width 0.12065)
		(layer "F.Cu")
		(net "SSD_ATNLED#9_R")
	)
	(segment
		(start 337.852512 -171.987718)
		(end 337.852512 -171.536868)
		(width 0.12065)
		(layer "F.Cu")
		(net "SSD_ATNLED#9_R")
	)
	(segment
		(start 329.57135 -210.72475)
		(end 329.326748 -210.480148)
		(width 0.12065)
		(layer "F.Cu")
		(net "SSD_ATNLED#9_R")
	)
	(segment
		(start 342.55075 -179.015898)
		(end 342.561926 -179.027074)
		(width 0.12065)
		(layer "F.Cu")
		(net "SSD_ATNLED#9_R")
	)
	(segment
		(start 340.33714 -187.57265)
		(end 340.52256 -187.57265)
		(width 0.12065)
		(layer "F.Cu")
		(net "SSD_ATNLED#9_R")
	)
	(segment
		(start 340.52256 -187.57265)
		(end 342.985852 -185.109358)
		(width 0.12065)
		(layer "F.Cu")
		(net "SSD_ATNLED#9_R")
	)
	(segment
		(start 340.553294 -170.729148)
		(end 340.800944 -170.976798)
		(width 0.12065)
		(layer "F.Cu")
		(net "SSD_ATNLED#9_R")
	)
	(segment
		(start 329.326748 -210.480148)
		(end 329.326748 -198.583042)
		(width 0.12065)
		(layer "F.Cu")
		(net "SSD_ATNLED#9_R")
	)
	(segment
		(start 329.300078 -225.54438)
		(end 329.300078 -224.201228)
		(width 0.12065)
		(layer "F.Cu")
		(net "SSD_ATNLED#9_R")
	)
	(segment
		(start 329.57135 -221.185994)
		(end 329.57135 -210.72475)
		(width 0.12065)
		(layer "F.Cu")
		(net "SSD_ATNLED#9_R")
	)
	(segment
		(start 329.572874 -221.187518)
		(end 329.57135 -221.185994)
		(width 0.12065)
		(layer "F.Cu")
		(net "SSD_ATNLED#9_R")
	)
	(segment
		(start 329.572874 -221.874334)
		(end 329.572874 -221.187518)
		(width 0.12065)
		(layer "F.Cu")
		(net "SSD_ATNLED#9_R")
	)
	(segment
		(start 342.763602 -171.514008)
		(end 342.763602 -178.533552)
		(width 0.12065)
		(layer "F.Cu")
		(net "SSD_ATNLED#9_R")
	)
	(segment
		(start 329.57135 -222.388176)
		(end 329.57135 -221.875858)
		(width 0.12065)
		(layer "F.Cu")
		(net "SSD_ATNLED#9_R")
	)
	(segment
		(start 342.985852 -179.451)
		(end 342.561926 -179.027074)
		(width 0.12065)
		(layer "F.Cu")
		(net "SSD_ATNLED#9_R")
	)
	(segment
		(start 342.985852 -185.109358)
		(end 342.985852 -179.451)
		(width 0.12065)
		(layer "F.Cu")
		(net "SSD_ATNLED#9_R")
	)
	(segment
		(start 342.55075 -178.746404)
		(end 342.55075 -179.015898)
		(width 0.12065)
		(layer "F.Cu")
		(net "SSD_ATNLED#9_R")
	)
	(segment
		(start 329.57135 -221.875858)
		(end 329.572874 -221.874334)
		(width 0.12065)
		(layer "F.Cu")
		(net "SSD_ATNLED#9_R")
	)
	(segment
		(start 338.660232 -170.729148)
		(end 340.553294 -170.729148)
		(width 0.12065)
		(layer "F.Cu")
		(net "SSD_ATNLED#9_R")
	)
	(segment
		(start 342.226392 -170.976798)
		(end 342.763602 -171.514008)
		(width 0.12065)
		(layer "F.Cu")
		(net "SSD_ATNLED#9_R")
	)
	(segment
		(start 340.800944 -170.976798)
		(end 342.226392 -170.976798)
		(width 0.12065)
		(layer "F.Cu")
		(net "SSD_ATNLED#9_R")
	)
	(segment
		(start 329.326748 -198.583042)
		(end 340.33714 -187.57265)
		(width 0.12065)
		(layer "F.Cu")
		(net "SSD_ATNLED#9_R")
	)
	(via
		(at 342.561926 -179.027074)
		(size 0.7112)
		(drill 0.3556)
		(layers "F.Cu" "B.Cu")
		(net "SSD_ATNLED#9_R")
	)
	(segment
		(start 337.852512 -172.876718)
		(end 337.852512 -173.745906)
		(width 0.12065)
		(layer "F.Cu")
		(net "SSD_ATNLED#9")
	)
	(segment
		(start 336.811112 -175.261778)
		(end 337.693 -174.37989)
		(width 0.12065)
		(layer "F.Cu")
		(net "SSD_ATNLED#9")
	)
	(segment
		(start 337.693 -174.37989)
		(end 337.693 -173.905418)
		(width 0.12065)
		(layer "F.Cu")
		(net "SSD_ATNLED#9")
	)
	(segment
		(start 336.811112 -175.962818)
		(end 336.811112 -175.261778)
		(width 0.12065)
		(layer "F.Cu")
		(net "SSD_ATNLED#9")
	)
	(segment
		(start 337.852512 -173.745906)
		(end 337.693 -173.905418)
		(width 0.12065)
		(layer "F.Cu")
		(net "SSD_ATNLED#9")
	)
	(via
		(at 338.595208 -174.24908)
		(size 0.7112)
		(drill 0.3556)
		(layers "F.Cu" "B.Cu")
		(net "SSD_ATNLED#9")
	)
	(via
		(at 337.693 -173.905418)
		(size 0.508)
		(drill 0.254)
		(layers "F.Cu" "B.Cu")
		(net "SSD_ATNLED#9")
	)
	(segment
		(start 338.58708 -174.24908)
		(end 338.595208 -174.24908)
		(width 0.12065)
		(layer "B.Cu")
		(net "SSD_ATNLED#9")
	)
	(segment
		(start 337.852512 -172.876718)
		(end 338.230718 -172.876718)
		(width 0.12065)
		(layer "B.Cu")
		(net "SSD_ATNLED#9")
	)
	(segment
		(start 338.230718 -172.876718)
		(end 338.595208 -173.241208)
		(width 0.12065)
		(layer "B.Cu")
		(net "SSD_ATNLED#9")
	)
	(segment
		(start 338.582 -174.244)
		(end 338.58708 -174.24908)
		(width 0.12065)
		(layer "B.Cu")
		(net "SSD_ATNLED#9")
	)
	(segment
		(start 338.595208 -173.241208)
		(end 338.595208 -174.24908)
		(width 0.12065)
		(layer "B.Cu")
		(net "SSD_ATNLED#9")
	)
	(segment
		(start 337.693 -173.905418)
		(end 338.031582 -174.244)
		(width 0.12065)
		(layer "B.Cu")
		(net "SSD_ATNLED#9")
	)
	(segment
		(start 338.031582 -174.244)
		(end 338.582 -174.244)
		(width 0.12065)
		(layer "B.Cu")
		(net "SSD_ATNLED#9")
	)
	(segment
		(start 223.405446 -188.201046)
		(end 224.893124 -189.688724)
		(width 0.12065)
		(layer "F.Cu")
		(net "SSD_ATNLED#8_R")
	)
	(segment
		(start 224.893124 -189.688724)
		(end 224.893124 -190.156592)
		(width 0.12065)
		(layer "F.Cu")
		(net "SSD_ATNLED#8_R")
	)
	(segment
		(start 224.7138 -183.1594)
		(end 224.7138 -185.798206)
		(width 0.12065)
		(layer "F.Cu")
		(net "SSD_ATNLED#8_R")
	)
	(segment
		(start 223.405446 -187.10656)
		(end 223.405446 -188.201046)
		(width 0.12065)
		(layer "F.Cu")
		(net "SSD_ATNLED#8_R")
	)
	(segment
		(start 224.7138 -185.798206)
		(end 223.405446 -187.10656)
		(width 0.12065)
		(layer "F.Cu")
		(net "SSD_ATNLED#8_R")
	)
	(via
		(at 224.7138 -183.1594)
		(size 0.508)
		(drill 0.254)
		(layers "F.Cu" "B.Cu")
		(net "SSD_ATNLED#8_R")
	)
	(via
		(at 224.7138 -179.832)
		(size 0.7112)
		(drill 0.3556)
		(layers "F.Cu" "B.Cu")
		(net "SSD_ATNLED#8_R")
	)
	(segment
		(start 260.72465 -162.545522)
		(end 255.519428 -157.3403)
		(width 0.12065)
		(layer "B.Cu")
		(net "SSD_ATNLED#8_R")
	)
	(segment
		(start 270.928846 -223.278954)
		(end 270.928846 -221.022418)
		(width 0.12065)
		(layer "B.Cu")
		(net "SSD_ATNLED#8_R")
	)
	(segment
		(start 270.928846 -221.022418)
		(end 260.72465 -210.818222)
		(width 0.12065)
		(layer "B.Cu")
		(net "SSD_ATNLED#8_R")
	)
	(segment
		(start 228.219508 -157.3403)
		(end 224.7138 -160.846008)
		(width 0.12065)
		(layer "B.Cu")
		(net "SSD_ATNLED#8_R")
	)
	(segment
		(start 224.7138 -160.846008)
		(end 224.7138 -179.832)
		(width 0.12065)
		(layer "B.Cu")
		(net "SSD_ATNLED#8_R")
	)
	(segment
		(start 270.100044 -225.92538)
		(end 270.100044 -224.107756)
		(width 0.12065)
		(layer "B.Cu")
		(net "SSD_ATNLED#8_R")
	)
	(segment
		(start 260.72465 -210.818222)
		(end 260.72465 -162.545522)
		(width 0.12065)
		(layer "B.Cu")
		(net "SSD_ATNLED#8_R")
	)
	(segment
		(start 270.100044 -224.107756)
		(end 270.928846 -223.278954)
		(width 0.12065)
		(layer "B.Cu")
		(net "SSD_ATNLED#8_R")
	)
	(segment
		(start 255.519428 -157.3403)
		(end 228.219508 -157.3403)
		(width 0.12065)
		(layer "B.Cu")
		(net "SSD_ATNLED#8_R")
	)
	(segment
		(start 224.7138 -179.832)
		(end 224.7138 -183.1594)
		(width 0.12065)
		(layer "B.Cu")
		(net "SSD_ATNLED#8_R")
	)
	(segment
		(start 223.851724 -193.58102)
		(end 224.136712 -193.296032)
		(width 0.12065)
		(layer "F.Cu")
		(net "SSD_ATNLED#8")
	)
	(segment
		(start 223.851724 -194.131692)
		(end 223.851724 -193.58102)
		(width 0.12065)
		(layer "F.Cu")
		(net "SSD_ATNLED#8")
	)
	(segment
		(start 224.246694 -193.18224)
		(end 224.309432 -193.18224)
		(width 0.12065)
		(layer "F.Cu")
		(net "SSD_ATNLED#8")
	)
	(segment
		(start 224.309432 -193.18224)
		(end 224.553018 -192.938654)
		(width 0.12065)
		(layer "F.Cu")
		(net "SSD_ATNLED#8")
	)
	(segment
		(start 224.553018 -192.938654)
		(end 224.553018 -192.908428)
		(width 0.12065)
		(layer "F.Cu")
		(net "SSD_ATNLED#8")
	)
	(segment
		(start 224.136712 -193.292222)
		(end 224.246694 -193.18224)
		(width 0.12065)
		(layer "F.Cu")
		(net "SSD_ATNLED#8")
	)
	(segment
		(start 224.733612 -192.727834)
		(end 224.733612 -192.074292)
		(width 0.12065)
		(layer "F.Cu")
		(net "SSD_ATNLED#8")
	)
	(segment
		(start 224.893124 -191.045592)
		(end 224.893124 -191.91478)
		(width 0.12065)
		(layer "F.Cu")
		(net "SSD_ATNLED#8")
	)
	(segment
		(start 224.893124 -191.91478)
		(end 224.733612 -192.074292)
		(width 0.12065)
		(layer "F.Cu")
		(net "SSD_ATNLED#8")
	)
	(segment
		(start 224.553018 -192.908428)
		(end 224.733612 -192.727834)
		(width 0.12065)
		(layer "F.Cu")
		(net "SSD_ATNLED#8")
	)
	(segment
		(start 224.136712 -193.296032)
		(end 224.136712 -193.292222)
		(width 0.12065)
		(layer "F.Cu")
		(net "SSD_ATNLED#8")
	)
	(via
		(at 224.733612 -192.074292)
		(size 0.508)
		(drill 0.254)
		(layers "F.Cu" "B.Cu")
		(net "SSD_ATNLED#8")
	)
	(via
		(at 225.2472 -192.913)
		(size 0.7112)
		(drill 0.3556)
		(layers "F.Cu" "B.Cu")
		(net "SSD_ATNLED#8")
	)
	(segment
		(start 224.733612 -192.074292)
		(end 224.733612 -192.399412)
		(width 0.12065)
		(layer "B.Cu")
		(net "SSD_ATNLED#8")
	)
	(segment
		(start 225.2472 -191.682116)
		(end 225.2472 -192.913)
		(width 0.12065)
		(layer "B.Cu")
		(net "SSD_ATNLED#8")
	)
	(segment
		(start 225.883724 -191.045592)
		(end 225.2472 -191.682116)
		(width 0.12065)
		(layer "B.Cu")
		(net "SSD_ATNLED#8")
	)
	(segment
		(start 224.733612 -192.399412)
		(end 225.2472 -192.913)
		(width 0.12065)
		(layer "B.Cu")
		(net "SSD_ATNLED#8")
	)
	(segment
		(start 130.0226 -209.3214)
		(end 129.179066 -210.164934)
		(width 0.12065)
		(layer "F.Cu")
		(net "SSD_ATNLED#7_R")
	)
	(segment
		(start 178.433222 -222.404178)
		(end 179.719732 -221.117668)
		(width 0.12065)
		(layer "F.Cu")
		(net "SSD_ATNLED#7_R")
	)
	(segment
		(start 179.300124 -224.385124)
		(end 178.433222 -223.518222)
		(width 0.12065)
		(layer "F.Cu")
		(net "SSD_ATNLED#7_R")
	)
	(segment
		(start 179.365402 -210.143598)
		(end 181.5846 -207.9244)
		(width 0.12065)
		(layer "F.Cu")
		(net "SSD_ATNLED#7_R")
	)
	(segment
		(start 178.433222 -223.518222)
		(end 178.433222 -222.404178)
		(width 0.12065)
		(layer "F.Cu")
		(net "SSD_ATNLED#7_R")
	)
	(segment
		(start 179.719732 -218.907868)
		(end 179.365402 -218.553538)
		(width 0.12065)
		(layer "F.Cu")
		(net "SSD_ATNLED#7_R")
	)
	(segment
		(start 130.195066 -209.3214)
		(end 130.0226 -209.3214)
		(width 0.12065)
		(layer "F.Cu")
		(net "SSD_ATNLED#7_R")
	)
	(segment
		(start 179.719732 -221.117668)
		(end 179.719732 -218.907868)
		(width 0.12065)
		(layer "F.Cu")
		(net "SSD_ATNLED#7_R")
	)
	(segment
		(start 179.300124 -225.54438)
		(end 179.300124 -224.385124)
		(width 0.12065)
		(layer "F.Cu")
		(net "SSD_ATNLED#7_R")
	)
	(segment
		(start 179.365402 -218.553538)
		(end 179.365402 -210.143598)
		(width 0.12065)
		(layer "F.Cu")
		(net "SSD_ATNLED#7_R")
	)
	(via
		(at 175.637698 -202.942698)
		(size 0.7112)
		(drill 0.3556)
		(layers "F.Cu" "B.Cu")
		(net "SSD_ATNLED#7_R")
	)
	(via
		(at 129.179066 -210.164934)
		(size 0.508)
		(drill 0.254)
		(layers "F.Cu" "B.Cu")
		(net "SSD_ATNLED#7_R")
	)
	(via
		(at 181.5846 -207.9244)
		(size 0.508)
		(drill 0.254)
		(layers "F.Cu" "B.Cu")
		(net "SSD_ATNLED#7_R")
	)
	(segment
		(start 135.370062 -210.937602)
		(end 129.951734 -210.937602)
		(width 0.12065)
		(layer "B.Cu")
		(net "SSD_ATNLED#7_R")
	)
	(segment
		(start 175.637698 -202.942698)
		(end 167.900096 -195.205096)
		(width 0.12065)
		(layer "B.Cu")
		(net "SSD_ATNLED#7_R")
	)
	(segment
		(start 181.5846 -207.9244)
		(end 180.6194 -207.9244)
		(width 0.12065)
		(layer "B.Cu")
		(net "SSD_ATNLED#7_R")
	)
	(segment
		(start 129.951734 -210.937602)
		(end 129.179066 -210.164934)
		(width 0.12065)
		(layer "B.Cu")
		(net "SSD_ATNLED#7_R")
	)
	(segment
		(start 167.900096 -195.205096)
		(end 151.102568 -195.205096)
		(width 0.12065)
		(layer "B.Cu")
		(net "SSD_ATNLED#7_R")
	)
	(segment
		(start 151.102568 -195.205096)
		(end 135.370062 -210.937602)
		(width 0.12065)
		(layer "B.Cu")
		(net "SSD_ATNLED#7_R")
	)
	(segment
		(start 180.6194 -207.9244)
		(end 175.637698 -202.942698)
		(width 0.12065)
		(layer "B.Cu")
		(net "SSD_ATNLED#7_R")
	)
	(segment
		(start 129.5654 -207.8736)
		(end 129.039874 -207.8736)
		(width 0.12065)
		(layer "F.Cu")
		(net "SSD_ATNLED#7")
	)
	(segment
		(start 128.8288 -207.662526)
		(end 128.789176 -207.662526)
		(width 0.12065)
		(layer "F.Cu")
		(net "SSD_ATNLED#7")
	)
	(segment
		(start 130.195066 -208.4324)
		(end 130.1242 -208.4324)
		(width 0.12065)
		(layer "F.Cu")
		(net "SSD_ATNLED#7")
	)
	(segment
		(start 128.698244 -205.612492)
		(end 128.698244 -206.502)
		(width 0.12065)
		(layer "F.Cu")
		(net "SSD_ATNLED#7")
	)
	(segment
		(start 129.039874 -207.8736)
		(end 128.8288 -207.662526)
		(width 0.12065)
		(layer "F.Cu")
		(net "SSD_ATNLED#7")
	)
	(segment
		(start 128.8288 -206.632556)
		(end 128.8288 -207.622902)
		(width 0.12065)
		(layer "F.Cu")
		(net "SSD_ATNLED#7")
	)
	(segment
		(start 128.8288 -207.622902)
		(end 128.789176 -207.662526)
		(width 0.12065)
		(layer "F.Cu")
		(net "SSD_ATNLED#7")
	)
	(segment
		(start 130.1242 -208.4324)
		(end 129.5654 -207.8736)
		(width 0.12065)
		(layer "F.Cu")
		(net "SSD_ATNLED#7")
	)
	(segment
		(start 128.698244 -206.502)
		(end 128.8288 -206.632556)
		(width 0.12065)
		(layer "F.Cu")
		(net "SSD_ATNLED#7")
	)
	(via
		(at 128.789176 -207.662526)
		(size 0.508)
		(drill 0.254)
		(layers "F.Cu" "B.Cu")
		(net "SSD_ATNLED#7")
	)
	(via
		(at 128.077214 -208.350612)
		(size 0.7112)
		(drill 0.3556)
		(layers "F.Cu" "B.Cu")
		(net "SSD_ATNLED#7")
	)
	(segment
		(start 128.077214 -207.964786)
		(end 128.077214 -208.350612)
		(width 0.12065)
		(layer "B.Cu")
		(net "SSD_ATNLED#7")
	)
	(segment
		(start 129.179066 -208.4324)
		(end 128.159002 -208.4324)
		(width 0.12065)
		(layer "B.Cu")
		(net "SSD_ATNLED#7")
	)
	(segment
		(start 128.379474 -207.662526)
		(end 128.077214 -207.964786)
		(width 0.12065)
		(layer "B.Cu")
		(net "SSD_ATNLED#7")
	)
	(segment
		(start 128.789176 -207.662526)
		(end 128.379474 -207.662526)
		(width 0.12065)
		(layer "B.Cu")
		(net "SSD_ATNLED#7")
	)
	(segment
		(start 128.159002 -208.4324)
		(end 128.077214 -208.350612)
		(width 0.12065)
		(layer "B.Cu")
		(net "SSD_ATNLED#7")
	)
	(segment
		(start 135.65505 -223.720914)
		(end 135.65505 -221.234)
		(width 0.12065)
		(layer "F.Cu")
		(net "SSD_ATNLED#6_R")
	)
	(segment
		(start 134.342124 -209.333592)
		(end 134.403592 -209.333592)
		(width 0.12065)
		(layer "F.Cu")
		(net "SSD_ATNLED#6_R")
	)
	(segment
		(start 134.403592 -209.333592)
		(end 135.773922 -210.703922)
		(width 0.12065)
		(layer "F.Cu")
		(net "SSD_ATNLED#6_R")
	)
	(segment
		(start 136.100058 -225.54438)
		(end 136.100058 -224.165922)
		(width 0.12065)
		(layer "F.Cu")
		(net "SSD_ATNLED#6_R")
	)
	(segment
		(start 135.65505 -221.234)
		(end 136.271 -220.61805)
		(width 0.12065)
		(layer "F.Cu")
		(net "SSD_ATNLED#6_R")
	)
	(segment
		(start 136.271 -220.61805)
		(end 136.271 -211.201)
		(width 0.12065)
		(layer "F.Cu")
		(net "SSD_ATNLED#6_R")
	)
	(segment
		(start 136.271 -211.201)
		(end 135.773922 -210.703922)
		(width 0.12065)
		(layer "F.Cu")
		(net "SSD_ATNLED#6_R")
	)
	(segment
		(start 136.100058 -224.165922)
		(end 135.65505 -223.720914)
		(width 0.12065)
		(layer "F.Cu")
		(net "SSD_ATNLED#6_R")
	)
	(via
		(at 135.773922 -210.703922)
		(size 0.7112)
		(drill 0.3556)
		(layers "F.Cu" "B.Cu")
		(net "SSD_ATNLED#6_R")
	)
	(segment
		(start 132.846826 -207.146144)
		(end 132.846826 -207.218026)
		(width 0.12065)
		(layer "F.Cu")
		(net "SSD_ATNLED#6")
	)
	(segment
		(start 133.682994 -207.99044)
		(end 133.61924 -207.99044)
		(width 0.12065)
		(layer "F.Cu")
		(net "SSD_ATNLED#6")
	)
	(segment
		(start 133.792976 -208.100422)
		(end 133.682994 -207.99044)
		(width 0.12065)
		(layer "F.Cu")
		(net "SSD_ATNLED#6")
	)
	(segment
		(start 131.299204 -205.612492)
		(end 131.299204 -206.381604)
		(width 0.12065)
		(layer "F.Cu")
		(net "SSD_ATNLED#6")
	)
	(segment
		(start 131.5466 -206.629)
		(end 132.2578 -206.629)
		(width 0.12065)
		(layer "F.Cu")
		(net "SSD_ATNLED#6")
	)
	(segment
		(start 133.61924 -207.99044)
		(end 133.2738 -207.645)
		(width 0.12065)
		(layer "F.Cu")
		(net "SSD_ATNLED#6")
	)
	(segment
		(start 132.44195 -206.81315)
		(end 132.513832 -206.81315)
		(width 0.12065)
		(layer "F.Cu")
		(net "SSD_ATNLED#6")
	)
	(segment
		(start 132.513832 -206.81315)
		(end 132.846826 -207.146144)
		(width 0.12065)
		(layer "F.Cu")
		(net "SSD_ATNLED#6")
	)
	(segment
		(start 134.073392 -208.444592)
		(end 133.792976 -208.164176)
		(width 0.12065)
		(layer "F.Cu")
		(net "SSD_ATNLED#6")
	)
	(segment
		(start 132.2578 -206.629)
		(end 132.44195 -206.81315)
		(width 0.12065)
		(layer "F.Cu")
		(net "SSD_ATNLED#6")
	)
	(segment
		(start 132.846826 -207.218026)
		(end 133.2738 -207.645)
		(width 0.12065)
		(layer "F.Cu")
		(net "SSD_ATNLED#6")
	)
	(segment
		(start 133.792976 -208.164176)
		(end 133.792976 -208.100422)
		(width 0.12065)
		(layer "F.Cu")
		(net "SSD_ATNLED#6")
	)
	(segment
		(start 134.342124 -208.444592)
		(end 134.073392 -208.444592)
		(width 0.12065)
		(layer "F.Cu")
		(net "SSD_ATNLED#6")
	)
	(segment
		(start 131.299204 -206.381604)
		(end 131.5466 -206.629)
		(width 0.12065)
		(layer "F.Cu")
		(net "SSD_ATNLED#6")
	)
	(via
		(at 132.334 -208.28)
		(size 0.7112)
		(drill 0.3556)
		(layers "F.Cu" "B.Cu")
		(net "SSD_ATNLED#6")
	)
	(via
		(at 133.2738 -207.645)
		(size 0.508)
		(drill 0.254)
		(layers "F.Cu" "B.Cu")
		(net "SSD_ATNLED#6")
	)
	(segment
		(start 132.588 -207.645)
		(end 132.334 -207.899)
		(width 0.12065)
		(layer "B.Cu")
		(net "SSD_ATNLED#6")
	)
	(segment
		(start 132.498592 -208.444592)
		(end 132.334 -208.28)
		(width 0.12065)
		(layer "B.Cu")
		(net "SSD_ATNLED#6")
	)
	(segment
		(start 133.2738 -207.645)
		(end 132.588 -207.645)
		(width 0.12065)
		(layer "B.Cu")
		(net "SSD_ATNLED#6")
	)
	(segment
		(start 133.326124 -208.444592)
		(end 132.498592 -208.444592)
		(width 0.12065)
		(layer "B.Cu")
		(net "SSD_ATNLED#6")
	)
	(segment
		(start 132.334 -207.899)
		(end 132.334 -208.28)
		(width 0.12065)
		(layer "B.Cu")
		(net "SSD_ATNLED#6")
	)
	(segment
		(start 76.819252 -181.969664)
		(end 76.819252 -181.56174)
		(width 0.12065)
		(layer "F.Cu")
		(net "SSD_ATNLED#5_R")
	)
	(segment
		(start 76.819252 -181.56174)
		(end 76.811124 -181.553612)
		(width 0.12065)
		(layer "F.Cu")
		(net "SSD_ATNLED#5_R")
	)
	(segment
		(start 76.811124 -181.553612)
		(end 76.811124 -179.331874)
		(width 0.12065)
		(layer "F.Cu")
		(net "SSD_ATNLED#5_R")
	)
	(segment
		(start 76.811124 -181.977792)
		(end 76.819252 -181.969664)
		(width 0.12065)
		(layer "F.Cu")
		(net "SSD_ATNLED#5_R")
	)
	(segment
		(start 76.811124 -182.790592)
		(end 76.811124 -181.977792)
		(width 0.12065)
		(layer "F.Cu")
		(net "SSD_ATNLED#5_R")
	)
	(via
		(at 76.811124 -179.331874)
		(size 0.508)
		(drill 0.254)
		(layers "F.Cu" "B.Cu")
		(net "SSD_ATNLED#5_R")
	)
	(via
		(at 63.21806 -179.85994)
		(size 0.7112)
		(drill 0.3556)
		(layers "F.Cu" "B.Cu")
		(net "SSD_ATNLED#5_R")
	)
	(segment
		(start 62.423548 -180.654452)
		(end 63.21806 -179.85994)
		(width 0.12065)
		(layer "B.Cu")
		(net "SSD_ATNLED#5_R")
	)
	(segment
		(start 62.900052 -223.863916)
		(end 62.423548 -223.387412)
		(width 0.12065)
		(layer "B.Cu")
		(net "SSD_ATNLED#5_R")
	)
	(segment
		(start 62.423548 -223.387412)
		(end 62.423548 -180.654452)
		(width 0.12065)
		(layer "B.Cu")
		(net "SSD_ATNLED#5_R")
	)
	(segment
		(start 64.862202 -178.215798)
		(end 63.21806 -179.85994)
		(width 0.12065)
		(layer "B.Cu")
		(net "SSD_ATNLED#5_R")
	)
	(segment
		(start 62.900052 -225.92538)
		(end 62.900052 -223.863916)
		(width 0.12065)
		(layer "B.Cu")
		(net "SSD_ATNLED#5_R")
	)
	(segment
		(start 76.811124 -179.331874)
		(end 75.695048 -178.215798)
		(width 0.12065)
		(layer "B.Cu")
		(net "SSD_ATNLED#5_R")
	)
	(segment
		(start 75.695048 -178.215798)
		(end 64.862202 -178.215798)
		(width 0.12065)
		(layer "B.Cu")
		(net "SSD_ATNLED#5_R")
	)
	(segment
		(start 76.811124 -184.107582)
		(end 76.53274 -184.385966)
		(width 0.12065)
		(layer "F.Cu")
		(net "SSD_ATNLED#5")
	)
	(segment
		(start 76.811124 -183.679592)
		(end 76.811124 -184.107582)
		(width 0.12065)
		(layer "F.Cu")
		(net "SSD_ATNLED#5")
	)
	(segment
		(start 76.53274 -185.301636)
		(end 76.53274 -184.506362)
		(width 0.12065)
		(layer "F.Cu")
		(net "SSD_ATNLED#5")
	)
	(segment
		(start 75.769724 -186.064652)
		(end 76.53274 -185.301636)
		(width 0.12065)
		(layer "F.Cu")
		(net "SSD_ATNLED#5")
	)
	(segment
		(start 76.53274 -184.385966)
		(end 76.53274 -184.506362)
		(width 0.12065)
		(layer "F.Cu")
		(net "SSD_ATNLED#5")
	)
	(segment
		(start 75.769724 -186.765692)
		(end 75.769724 -186.064652)
		(width 0.12065)
		(layer "F.Cu")
		(net "SSD_ATNLED#5")
	)
	(via
		(at 76.53274 -184.506362)
		(size 0.508)
		(drill 0.254)
		(layers "F.Cu" "B.Cu")
		(net "SSD_ATNLED#5")
	)
	(via
		(at 77.843634 -183.456326)
		(size 0.7112)
		(drill 0.3556)
		(layers "F.Cu" "B.Cu")
		(net "SSD_ATNLED#5")
	)
	(segment
		(start 76.57846 -184.552082)
		(end 77.117956 -184.552082)
		(width 0.12065)
		(layer "B.Cu")
		(net "SSD_ATNLED#5")
	)
	(segment
		(start 77.117956 -184.552082)
		(end 77.843634 -183.826404)
		(width 0.12065)
		(layer "B.Cu")
		(net "SSD_ATNLED#5")
	)
	(segment
		(start 76.848716 -183.683402)
		(end 77.075792 -183.456326)
		(width 0.12065)
		(layer "B.Cu")
		(net "SSD_ATNLED#5")
	)
	(segment
		(start 76.53274 -184.506362)
		(end 76.57846 -184.552082)
		(width 0.12065)
		(layer "B.Cu")
		(net "SSD_ATNLED#5")
	)
	(segment
		(start 77.843634 -183.826404)
		(end 77.843634 -183.456326)
		(width 0.12065)
		(layer "B.Cu")
		(net "SSD_ATNLED#5")
	)
	(segment
		(start 77.075792 -183.456326)
		(end 77.843634 -183.456326)
		(width 0.12065)
		(layer "B.Cu")
		(net "SSD_ATNLED#5")
	)
	(segment
		(start 333.788512 -171.987718)
		(end 333.656178 -171.855384)
		(width 0.12065)
		(layer "F.Cu")
		(net "SSD_ATNLED#4_R")
	)
	(segment
		(start 333.656178 -171.855384)
		(end 333.656178 -168.656)
		(width 0.12065)
		(layer "F.Cu")
		(net "SSD_ATNLED#4_R")
	)
	(via
		(at 333.656178 -168.656)
		(size 0.508)
		(drill 0.254)
		(layers "F.Cu" "B.Cu")
		(net "SSD_ATNLED#4_R")
	)
	(via
		(at 297.623738 -206.883)
		(size 0.7112)
		(drill 0.3556)
		(layers "F.Cu" "B.Cu")
		(net "SSD_ATNLED#4_R")
	)
	(segment
		(start 327.637648 -167.826944)
		(end 327.337928 -167.826944)
		(width 0.12065)
		(layer "B.Cu")
		(net "SSD_ATNLED#4_R")
	)
	(segment
		(start 332.661514 -167.827198)
		(end 327.637902 -167.827198)
		(width 0.12065)
		(layer "B.Cu")
		(net "SSD_ATNLED#4_R")
	)
	(segment
		(start 327.337928 -167.826944)
		(end 297.623738 -197.541134)
		(width 0.12065)
		(layer "B.Cu")
		(net "SSD_ATNLED#4_R")
	)
	(segment
		(start 298.100242 -225.92538)
		(end 298.100242 -224.237042)
		(width 0.12065)
		(layer "B.Cu")
		(net "SSD_ATNLED#4_R")
	)
	(segment
		(start 327.637902 -167.827198)
		(end 327.637648 -167.826944)
		(width 0.12065)
		(layer "B.Cu")
		(net "SSD_ATNLED#4_R")
	)
	(segment
		(start 297.623738 -197.541134)
		(end 297.623738 -206.883)
		(width 0.12065)
		(layer "B.Cu")
		(net "SSD_ATNLED#4_R")
	)
	(segment
		(start 298.100242 -224.237042)
		(end 297.623738 -223.760538)
		(width 0.12065)
		(layer "B.Cu")
		(net "SSD_ATNLED#4_R")
	)
	(segment
		(start 333.490316 -168.656)
		(end 332.661514 -167.827198)
		(width 0.12065)
		(layer "B.Cu")
		(net "SSD_ATNLED#4_R")
	)
	(segment
		(start 297.623738 -223.760538)
		(end 297.623738 -206.883)
		(width 0.12065)
		(layer "B.Cu")
		(net "SSD_ATNLED#4_R")
	)
	(segment
		(start 333.656178 -168.656)
		(end 333.490316 -168.656)
		(width 0.12065)
		(layer "B.Cu")
		(net "SSD_ATNLED#4_R")
	)
	(segment
		(start 334.210152 -175.962818)
		(end 334.210152 -174.571152)
		(width 0.12065)
		(layer "F.Cu")
		(net "SSD_ATNLED#4")
	)
	(segment
		(start 334.210152 -174.571152)
		(end 334.01 -174.371)
		(width 0.12065)
		(layer "F.Cu")
		(net "SSD_ATNLED#4")
	)
	(segment
		(start 333.788512 -174.149512)
		(end 334.01 -174.371)
		(width 0.12065)
		(layer "F.Cu")
		(net "SSD_ATNLED#4")
	)
	(segment
		(start 333.788512 -172.876718)
		(end 333.788512 -174.149512)
		(width 0.12065)
		(layer "F.Cu")
		(net "SSD_ATNLED#4")
	)
	(via
		(at 334.01 -174.371)
		(size 0.508)
		(drill 0.254)
		(layers "F.Cu" "B.Cu")
		(net "SSD_ATNLED#4")
	)
	(via
		(at 334.801718 -172.945044)
		(size 0.7112)
		(drill 0.3556)
		(layers "F.Cu" "B.Cu")
		(net "SSD_ATNLED#4")
	)
	(segment
		(start 334.733392 -172.876718)
		(end 334.801718 -172.945044)
		(width 0.12065)
		(layer "B.Cu")
		(net "SSD_ATNLED#4")
	)
	(segment
		(start 334.01 -174.371)
		(end 334.114902 -174.266098)
		(width 0.12065)
		(layer "B.Cu")
		(net "SSD_ATNLED#4")
	)
	(segment
		(start 333.788512 -172.876718)
		(end 334.733392 -172.876718)
		(width 0.12065)
		(layer "B.Cu")
		(net "SSD_ATNLED#4")
	)
	(segment
		(start 334.114902 -174.266098)
		(end 334.114902 -174.02937)
		(width 0.12065)
		(layer "B.Cu")
		(net "SSD_ATNLED#4")
	)
	(segment
		(start 334.114902 -174.02937)
		(end 334.801718 -173.342554)
		(width 0.12065)
		(layer "B.Cu")
		(net "SSD_ATNLED#4")
	)
	(segment
		(start 334.801718 -173.342554)
		(end 334.801718 -172.945044)
		(width 0.12065)
		(layer "B.Cu")
		(net "SSD_ATNLED#4")
	)
	(segment
		(start 209.59445 -223.771714)
		(end 209.59445 -192.36055)
		(width 0.12065)
		(layer "F.Cu")
		(net "SSD_ATNLED#3_R")
	)
	(segment
		(start 209.59445 -192.36055)
		(end 210.964526 -190.990474)
		(width 0.12065)
		(layer "F.Cu")
		(net "SSD_ATNLED#3_R")
	)
	(segment
		(start 213.487 -186.817)
		(end 213.36 -186.944)
		(width 0.12065)
		(layer "F.Cu")
		(net "SSD_ATNLED#3_R")
	)
	(segment
		(start 220.829124 -190.156592)
		(end 220.829124 -189.364874)
		(width 0.12065)
		(layer "F.Cu")
		(net "SSD_ATNLED#3_R")
	)
	(segment
		(start 213.36 -188.595)
		(end 210.964526 -190.990474)
		(width 0.12065)
		(layer "F.Cu")
		(net "SSD_ATNLED#3_R")
	)
	(segment
		(start 209.700114 -223.877378)
		(end 209.59445 -223.771714)
		(width 0.12065)
		(layer "F.Cu")
		(net "SSD_ATNLED#3_R")
	)
	(segment
		(start 213.36 -186.944)
		(end 213.36 -188.595)
		(width 0.12065)
		(layer "F.Cu")
		(net "SSD_ATNLED#3_R")
	)
	(segment
		(start 209.700114 -225.54438)
		(end 209.700114 -223.877378)
		(width 0.12065)
		(layer "F.Cu")
		(net "SSD_ATNLED#3_R")
	)
	(via
		(at 213.487 -186.817)
		(size 0.508)
		(drill 0.254)
		(layers "F.Cu" "B.Cu")
		(net "SSD_ATNLED#3_R")
	)
	(via
		(at 210.964526 -190.990474)
		(size 0.7112)
		(drill 0.3556)
		(layers "F.Cu" "B.Cu")
		(net "SSD_ATNLED#3_R")
	)
	(via
		(at 220.829124 -189.364874)
		(size 0.508)
		(drill 0.254)
		(layers "F.Cu" "B.Cu")
		(net "SSD_ATNLED#3_R")
	)
	(segment
		(start 214.3379 -187.6679)
		(end 213.487 -186.817)
		(width 0.127)
		(layer "In2.Cu")
		(net "SSD_ATNLED#3_R")
	)
	(segment
		(start 220.829124 -189.364874)
		(end 219.13215 -187.6679)
		(width 0.127)
		(layer "In2.Cu")
		(net "SSD_ATNLED#3_R")
	)
	(segment
		(start 219.13215 -187.6679)
		(end 214.3379 -187.6679)
		(width 0.127)
		(layer "In2.Cu")
		(net "SSD_ATNLED#3_R")
	)
	(segment
		(start 221.250764 -194.131692)
		(end 221.250764 -193.030094)
		(width 0.12065)
		(layer "F.Cu")
		(net "SSD_ATNLED#3")
	)
	(segment
		(start 220.829124 -191.045592)
		(end 220.829124 -192.608454)
		(width 0.12065)
		(layer "F.Cu")
		(net "SSD_ATNLED#3")
	)
	(segment
		(start 220.829124 -192.608454)
		(end 220.868748 -192.648078)
		(width 0.12065)
		(layer "F.Cu")
		(net "SSD_ATNLED#3")
	)
	(segment
		(start 221.250764 -193.030094)
		(end 220.868748 -192.648078)
		(width 0.12065)
		(layer "F.Cu")
		(net "SSD_ATNLED#3")
	)
	(via
		(at 221.644718 -190.55969)
		(size 0.7112)
		(drill 0.3556)
		(layers "F.Cu" "B.Cu")
		(net "SSD_ATNLED#3")
	)
	(via
		(at 220.868748 -192.648078)
		(size 0.508)
		(drill 0.254)
		(layers "F.Cu" "B.Cu")
		(net "SSD_ATNLED#3")
	)
	(segment
		(start 221.644718 -190.55969)
		(end 221.531688 -190.67272)
		(width 0.12065)
		(layer "B.Cu")
		(net "SSD_ATNLED#3")
	)
	(segment
		(start 220.857318 -192.636648)
		(end 220.868748 -192.648078)
		(width 0.12065)
		(layer "B.Cu")
		(net "SSD_ATNLED#3")
	)
	(segment
		(start 221.531688 -190.67272)
		(end 221.074996 -190.67272)
		(width 0.12065)
		(layer "B.Cu")
		(net "SSD_ATNLED#3")
	)
	(segment
		(start 220.88348 -192.607946)
		(end 220.857318 -192.634108)
		(width 0.12065)
		(layer "B.Cu")
		(net "SSD_ATNLED#3")
	)
	(segment
		(start 221.074996 -190.67272)
		(end 220.702124 -191.045592)
		(width 0.12065)
		(layer "B.Cu")
		(net "SSD_ATNLED#3")
	)
	(segment
		(start 220.857318 -192.634108)
		(end 220.857318 -192.636648)
		(width 0.12065)
		(layer "B.Cu")
		(net "SSD_ATNLED#3")
	)
	(segment
		(start 220.88348 -191.226948)
		(end 220.88348 -192.607946)
		(width 0.12065)
		(layer "B.Cu")
		(net "SSD_ATNLED#3")
	)
	(segment
		(start 220.702124 -191.045592)
		(end 220.88348 -191.226948)
		(width 0.12065)
		(layer "B.Cu")
		(net "SSD_ATNLED#3")
	)
	(segment
		(start 163.72205 -219.077286)
		(end 164.036502 -218.762834)
		(width 0.12065)
		(layer "F.Cu")
		(net "SSD_ATNLED#2_R")
	)
	(segment
		(start 131.040124 -195.998592)
		(end 131.891278 -195.147438)
		(width 0.12065)
		(layer "F.Cu")
		(net "SSD_ATNLED#2_R")
	)
	(segment
		(start 138.65225 -192.81775)
		(end 147.73275 -192.81775)
		(width 0.12065)
		(layer "F.Cu")
		(net "SSD_ATNLED#2_R")
	)
	(segment
		(start 131.891278 -195.147438)
		(end 132.015992 -195.147438)
		(width 0.12065)
		(layer "F.Cu")
		(net "SSD_ATNLED#2_R")
	)
	(segment
		(start 164.036502 -218.762834)
		(end 164.036502 -209.121502)
		(width 0.12065)
		(layer "F.Cu")
		(net "SSD_ATNLED#2_R")
	)
	(segment
		(start 138.176 -193.294)
		(end 138.65225 -192.81775)
		(width 0.12065)
		(layer "F.Cu")
		(net "SSD_ATNLED#2_R")
	)
	(segment
		(start 147.73275 -192.81775)
		(end 159.549592 -204.634592)
		(width 0.12065)
		(layer "F.Cu")
		(net "SSD_ATNLED#2_R")
	)
	(segment
		(start 164.100002 -222.850202)
		(end 163.72205 -222.47225)
		(width 0.12065)
		(layer "F.Cu")
		(net "SSD_ATNLED#2_R")
	)
	(segment
		(start 164.100002 -225.54438)
		(end 164.100002 -222.850202)
		(width 0.12065)
		(layer "F.Cu")
		(net "SSD_ATNLED#2_R")
	)
	(segment
		(start 163.72205 -222.47225)
		(end 163.72205 -219.077286)
		(width 0.12065)
		(layer "F.Cu")
		(net "SSD_ATNLED#2_R")
	)
	(segment
		(start 164.036502 -209.121502)
		(end 159.549592 -204.634592)
		(width 0.12065)
		(layer "F.Cu")
		(net "SSD_ATNLED#2_R")
	)
	(via
		(at 159.549592 -204.634592)
		(size 0.7112)
		(drill 0.3556)
		(layers "F.Cu" "B.Cu")
		(net "SSD_ATNLED#2_R")
	)
	(via
		(at 138.176 -193.294)
		(size 0.508)
		(drill 0.254)
		(layers "F.Cu" "B.Cu")
		(net "SSD_ATNLED#2_R")
	)
	(via
		(at 132.015992 -195.147438)
		(size 0.508)
		(drill 0.254)
		(layers "F.Cu" "B.Cu")
		(net "SSD_ATNLED#2_R")
	)
	(segment
		(start 132.341112 -195.1355)
		(end 133.547612 -193.929)
		(width 0.127)
		(layer "In2.Cu")
		(net "SSD_ATNLED#2_R")
	)
	(segment
		(start 132.015992 -195.147438)
		(end 132.02793 -195.1355)
		(width 0.127)
		(layer "In2.Cu")
		(net "SSD_ATNLED#2_R")
	)
	(segment
		(start 137.795 -193.929)
		(end 138.176 -193.548)
		(width 0.127)
		(layer "In2.Cu")
		(net "SSD_ATNLED#2_R")
	)
	(segment
		(start 132.02793 -195.1355)
		(end 132.341112 -195.1355)
		(width 0.127)
		(layer "In2.Cu")
		(net "SSD_ATNLED#2_R")
	)
	(segment
		(start 138.176 -193.548)
		(end 138.176 -193.294)
		(width 0.127)
		(layer "In2.Cu")
		(net "SSD_ATNLED#2_R")
	)
	(segment
		(start 133.547612 -193.929)
		(end 137.795 -193.929)
		(width 0.127)
		(layer "In2.Cu")
		(net "SSD_ATNLED#2_R")
	)
	(segment
		(start 129.998724 -199.272652)
		(end 130.880612 -198.390764)
		(width 0.12065)
		(layer "F.Cu")
		(net "SSD_ATNLED#2")
	)
	(segment
		(start 129.998724 -199.973692)
		(end 129.998724 -199.272652)
		(width 0.12065)
		(layer "F.Cu")
		(net "SSD_ATNLED#2")
	)
	(segment
		(start 131.040124 -197.75678)
		(end 130.880612 -197.916292)
		(width 0.12065)
		(layer "F.Cu")
		(net "SSD_ATNLED#2")
	)
	(segment
		(start 130.880612 -198.390764)
		(end 130.880612 -197.916292)
		(width 0.12065)
		(layer "F.Cu")
		(net "SSD_ATNLED#2")
	)
	(segment
		(start 131.040124 -196.887592)
		(end 131.040124 -197.75678)
		(width 0.12065)
		(layer "F.Cu")
		(net "SSD_ATNLED#2")
	)
	(via
		(at 130.880612 -197.916292)
		(size 0.508)
		(drill 0.254)
		(layers "F.Cu" "B.Cu")
		(net "SSD_ATNLED#2")
	)
	(via
		(at 131.655312 -198.492618)
		(size 0.7112)
		(drill 0.3556)
		(layers "F.Cu" "B.Cu")
		(net "SSD_ATNLED#2")
	)
	(segment
		(start 132.3721 -196.8119)
		(end 131.655312 -197.528688)
		(width 0.12065)
		(layer "B.Cu")
		(net "SSD_ATNLED#2")
	)
	(segment
		(start 131.655312 -197.528688)
		(end 131.655312 -198.492618)
		(width 0.12065)
		(layer "B.Cu")
		(net "SSD_ATNLED#2")
	)
	(segment
		(start 132.5626 -196.8119)
		(end 132.3721 -196.8119)
		(width 0.12065)
		(layer "B.Cu")
		(net "SSD_ATNLED#2")
	)
	(segment
		(start 130.880612 -197.916292)
		(end 131.456938 -198.492618)
		(width 0.12065)
		(layer "B.Cu")
		(net "SSD_ATNLED#2")
	)
	(segment
		(start 131.456938 -198.492618)
		(end 131.655312 -198.492618)
		(width 0.12065)
		(layer "B.Cu")
		(net "SSD_ATNLED#2")
	)
	(segment
		(start 338.868512 -185.322718)
		(end 338.868512 -186.097418)
		(width 0.12065)
		(layer "F.Cu")
		(net "SSD_ATNLED#14_R")
	)
	(via
		(at 338.868512 -186.097418)
		(size 0.508)
		(drill 0.254)
		(layers "F.Cu" "B.Cu")
		(net "SSD_ATNLED#14_R")
	)
	(via
		(at 343.789 -192.659)
		(size 0.7112)
		(drill 0.3556)
		(layers "F.Cu" "B.Cu")
		(net "SSD_ATNLED#14_R")
	)
	(segment
		(start 342.773 -215.011)
		(end 344.9066 -212.8774)
		(width 0.12065)
		(layer "B.Cu")
		(net "SSD_ATNLED#14_R")
	)
	(segment
		(start 338.105242 -206.6544)
		(end 338.105242 -202.152758)
		(width 0.12065)
		(layer "B.Cu")
		(net "SSD_ATNLED#14_R")
	)
	(segment
		(start 343.789 -192.659)
		(end 343.535 -192.913)
		(width 0.12065)
		(layer "B.Cu")
		(net "SSD_ATNLED#14_R")
	)
	(segment
		(start 344.9066 -212.8774)
		(end 344.9066 -212.344254)
		(width 0.12065)
		(layer "B.Cu")
		(net "SSD_ATNLED#14_R")
	)
	(segment
		(start 344.9066 -212.344254)
		(end 344.93581 -212.315044)
		(width 0.12065)
		(layer "B.Cu")
		(net "SSD_ATNLED#14_R")
	)
	(segment
		(start 344.4494 -195.8086)
		(end 344.4494 -193.8274)
		(width 0.12065)
		(layer "B.Cu")
		(net "SSD_ATNLED#14_R")
	)
	(segment
		(start 342.773 -223.4438)
		(end 342.773 -215.011)
		(width 0.12065)
		(layer "B.Cu")
		(net "SSD_ATNLED#14_R")
	)
	(segment
		(start 338.57565 -186.39028)
		(end 338.57565 -187.95365)
		(width 0.12065)
		(layer "B.Cu")
		(net "SSD_ATNLED#14_R")
	)
	(segment
		(start 338.7852 -207.334358)
		(end 338.105242 -206.6544)
		(width 0.12065)
		(layer "B.Cu")
		(net "SSD_ATNLED#14_R")
	)
	(segment
		(start 338.105242 -202.152758)
		(end 344.4494 -195.8086)
		(width 0.12065)
		(layer "B.Cu")
		(net "SSD_ATNLED#14_R")
	)
	(segment
		(start 338.868512 -186.097418)
		(end 338.57565 -186.39028)
		(width 0.12065)
		(layer "B.Cu")
		(net "SSD_ATNLED#14_R")
	)
	(segment
		(start 343.7001 -225.92538)
		(end 343.7001 -224.3709)
		(width 0.12065)
		(layer "B.Cu")
		(net "SSD_ATNLED#14_R")
	)
	(segment
		(start 342.106758 -207.334358)
		(end 338.7852 -207.334358)
		(width 0.12065)
		(layer "B.Cu")
		(net "SSD_ATNLED#14_R")
	)
	(segment
		(start 343.7001 -224.3709)
		(end 342.773 -223.4438)
		(width 0.12065)
		(layer "B.Cu")
		(net "SSD_ATNLED#14_R")
	)
	(segment
		(start 344.93581 -212.315044)
		(end 344.93581 -210.16341)
		(width 0.12065)
		(layer "B.Cu")
		(net "SSD_ATNLED#14_R")
	)
	(segment
		(start 344.93581 -210.16341)
		(end 342.106758 -207.334358)
		(width 0.12065)
		(layer "B.Cu")
		(net "SSD_ATNLED#14_R")
	)
	(segment
		(start 338.57565 -187.95365)
		(end 343.535 -192.913)
		(width 0.12065)
		(layer "B.Cu")
		(net "SSD_ATNLED#14_R")
	)
	(segment
		(start 344.4494 -193.8274)
		(end 343.535 -192.913)
		(width 0.12065)
		(layer "B.Cu")
		(net "SSD_ATNLED#14_R")
	)
	(segment
		(start 338.709 -183.769)
		(end 338.709 -183.642)
		(width 0.12065)
		(layer "F.Cu")
		(net "SSD_ATNLED#14")
	)
	(segment
		(start 338.111592 -182.790592)
		(end 338.709 -183.388)
		(width 0.12065)
		(layer "F.Cu")
		(net "SSD_ATNLED#14")
	)
	(segment
		(start 338.868512 -184.433718)
		(end 338.868512 -183.928512)
		(width 0.12065)
		(layer "F.Cu")
		(net "SSD_ATNLED#14")
	)
	(segment
		(start 338.709 -183.388)
		(end 338.709 -183.642)
		(width 0.12065)
		(layer "F.Cu")
		(net "SSD_ATNLED#14")
	)
	(segment
		(start 338.868512 -183.928512)
		(end 338.709 -183.769)
		(width 0.12065)
		(layer "F.Cu")
		(net "SSD_ATNLED#14")
	)
	(segment
		(start 338.111592 -181.601618)
		(end 338.111592 -182.790592)
		(width 0.12065)
		(layer "F.Cu")
		(net "SSD_ATNLED#14")
	)
	(via
		(at 338.709 -183.642)
		(size 0.508)
		(drill 0.254)
		(layers "F.Cu" "B.Cu")
		(net "SSD_ATNLED#14")
	)
	(via
		(at 337.82 -184.023)
		(size 0.7112)
		(drill 0.3556)
		(layers "F.Cu" "B.Cu")
		(net "SSD_ATNLED#14")
	)
	(segment
		(start 338.709 -183.642)
		(end 338.074 -183.642)
		(width 0.12065)
		(layer "B.Cu")
		(net "SSD_ATNLED#14")
	)
	(segment
		(start 337.82 -183.896)
		(end 337.82 -184.023)
		(width 0.12065)
		(layer "B.Cu")
		(net "SSD_ATNLED#14")
	)
	(segment
		(start 338.868512 -184.433718)
		(end 338.230718 -184.433718)
		(width 0.12065)
		(layer "B.Cu")
		(net "SSD_ATNLED#14")
	)
	(segment
		(start 338.230718 -184.433718)
		(end 337.82 -184.023)
		(width 0.12065)
		(layer "B.Cu")
		(net "SSD_ATNLED#14")
	)
	(segment
		(start 338.074 -183.642)
		(end 337.82 -183.896)
		(width 0.12065)
		(layer "B.Cu")
		(net "SSD_ATNLED#14")
	)
	(segment
		(start 296.926 -190.627)
		(end 296.926 -176.49698)
		(width 0.12065)
		(layer "F.Cu")
		(net "SSD_ATNLED#13_R")
	)
	(segment
		(start 296.500042 -225.54438)
		(end 296.500042 -223.996758)
		(width 0.12065)
		(layer "F.Cu")
		(net "SSD_ATNLED#13_R")
	)
	(segment
		(start 296.500042 -223.996758)
		(end 296.9641 -223.5327)
		(width 0.12065)
		(layer "F.Cu")
		(net "SSD_ATNLED#13_R")
	)
	(segment
		(start 296.926 -202.0697)
		(end 296.926 -190.627)
		(width 0.12065)
		(layer "F.Cu")
		(net "SSD_ATNLED#13_R")
	)
	(segment
		(start 229.771448 -156.685488)
		(end 229.771448 -205.235048)
		(width 0.12065)
		(layer "F.Cu")
		(net "SSD_ATNLED#13_R")
	)
	(segment
		(start 296.926 -176.49698)
		(end 272.84807 -152.41905)
		(width 0.12065)
		(layer "F.Cu")
		(net "SSD_ATNLED#13_R")
	)
	(segment
		(start 222.62338 -204.528166)
		(end 222.999046 -204.1525)
		(width 0.12065)
		(layer "F.Cu")
		(net "SSD_ATNLED#13_R")
	)
	(segment
		(start 296.3672 -208.7372)
		(end 296.3672 -202.6285)
		(width 0.12065)
		(layer "F.Cu")
		(net "SSD_ATNLED#13_R")
	)
	(segment
		(start 272.84807 -152.41905)
		(end 234.037886 -152.41905)
		(width 0.12065)
		(layer "F.Cu")
		(net "SSD_ATNLED#13_R")
	)
	(segment
		(start 230.224584 -205.688184)
		(end 230.224584 -205.8162)
		(width 0.12065)
		(layer "F.Cu")
		(net "SSD_ATNLED#13_R")
	)
	(segment
		(start 229.771448 -205.235048)
		(end 230.224584 -205.688184)
		(width 0.12065)
		(layer "F.Cu")
		(net "SSD_ATNLED#13_R")
	)
	(segment
		(start 234.037886 -152.41905)
		(end 229.771448 -156.685488)
		(width 0.12065)
		(layer "F.Cu")
		(net "SSD_ATNLED#13_R")
	)
	(segment
		(start 296.9641 -223.5327)
		(end 296.9641 -209.3341)
		(width 0.12065)
		(layer "F.Cu")
		(net "SSD_ATNLED#13_R")
	)
	(segment
		(start 296.3672 -202.6285)
		(end 296.926 -202.0697)
		(width 0.12065)
		(layer "F.Cu")
		(net "SSD_ATNLED#13_R")
	)
	(segment
		(start 296.9641 -209.3341)
		(end 296.3672 -208.7372)
		(width 0.12065)
		(layer "F.Cu")
		(net "SSD_ATNLED#13_R")
	)
	(segment
		(start 222.62338 -205.41234)
		(end 222.62338 -204.528166)
		(width 0.12065)
		(layer "F.Cu")
		(net "SSD_ATNLED#13_R")
	)
	(via
		(at 222.62338 -205.41234)
		(size 0.508)
		(drill 0.254)
		(layers "F.Cu" "B.Cu")
		(net "SSD_ATNLED#13_R")
	)
	(via
		(at 296.926 -190.627)
		(size 0.7112)
		(drill 0.3556)
		(layers "F.Cu" "B.Cu")
		(net "SSD_ATNLED#13_R")
	)
	(via
		(at 230.224584 -205.8162)
		(size 0.508)
		(drill 0.254)
		(layers "F.Cu" "B.Cu")
		(net "SSD_ATNLED#13_R")
	)
	(segment
		(start 222.62338 -205.41234)
		(end 222.8088 -205.59776)
		(width 0.127)
		(layer "In2.Cu")
		(net "SSD_ATNLED#13_R")
	)
	(segment
		(start 230.006144 -205.59776)
		(end 230.224584 -205.8162)
		(width 0.127)
		(layer "In2.Cu")
		(net "SSD_ATNLED#13_R")
	)
	(segment
		(start 222.8088 -205.59776)
		(end 230.006144 -205.59776)
		(width 0.127)
		(layer "In2.Cu")
		(net "SSD_ATNLED#13_R")
	)
	(segment
		(start 222.551244 -201.68997)
		(end 222.551244 -199.770492)
		(width 0.12065)
		(layer "F.Cu")
		(net "SSD_ATNLED#13")
	)
	(segment
		(start 222.99422 -202.40752)
		(end 222.99422 -203.258674)
		(width 0.12065)
		(layer "F.Cu")
		(net "SSD_ATNLED#13")
	)
	(segment
		(start 222.99422 -203.258674)
		(end 222.999046 -203.2635)
		(width 0.12065)
		(layer "F.Cu")
		(net "SSD_ATNLED#13")
	)
	(segment
		(start 222.99422 -202.132946)
		(end 222.551244 -201.68997)
		(width 0.12065)
		(layer "F.Cu")
		(net "SSD_ATNLED#13")
	)
	(segment
		(start 222.99422 -202.40752)
		(end 222.99422 -202.132946)
		(width 0.12065)
		(layer "F.Cu")
		(net "SSD_ATNLED#13")
	)
	(via
		(at 222.004382 -202.55865)
		(size 0.7112)
		(drill 0.3556)
		(layers "F.Cu" "B.Cu")
		(net "SSD_ATNLED#13")
	)
	(via
		(at 222.99422 -202.40752)
		(size 0.508)
		(drill 0.254)
		(layers "F.Cu" "B.Cu")
		(net "SSD_ATNLED#13")
	)
	(segment
		(start 222.999046 -203.25334)
		(end 222.384366 -203.25334)
		(width 0.12065)
		(layer "B.Cu")
		(net "SSD_ATNLED#13")
	)
	(segment
		(start 222.384366 -203.25334)
		(end 222.004382 -202.873356)
		(width 0.12065)
		(layer "B.Cu")
		(net "SSD_ATNLED#13")
	)
	(segment
		(start 222.99422 -202.40752)
		(end 222.296228 -202.40752)
		(width 0.12065)
		(layer "B.Cu")
		(net "SSD_ATNLED#13")
	)
	(segment
		(start 222.004382 -202.52817)
		(end 222.004382 -202.55865)
		(width 0.12065)
		(layer "B.Cu")
		(net "SSD_ATNLED#13")
	)
	(segment
		(start 222.125286 -202.407266)
		(end 222.004382 -202.52817)
		(width 0.12065)
		(layer "B.Cu")
		(net "SSD_ATNLED#13")
	)
	(segment
		(start 222.296228 -202.40752)
		(end 222.295974 -202.407266)
		(width 0.12065)
		(layer "B.Cu")
		(net "SSD_ATNLED#13")
	)
	(segment
		(start 222.004382 -202.873356)
		(end 222.004382 -202.55865)
		(width 0.12065)
		(layer "B.Cu")
		(net "SSD_ATNLED#13")
	)
	(segment
		(start 222.295974 -202.407266)
		(end 222.125286 -202.407266)
		(width 0.12065)
		(layer "B.Cu")
		(net "SSD_ATNLED#13")
	)
	(segment
		(start 227.179124 -203.491592)
		(end 227.179124 -207.772)
		(width 0.12065)
		(layer "F.Cu")
		(net "SSD_ATNLED#12_R")
	)
	(via
		(at 216.789 -207.609948)
		(size 0.7112)
		(drill 0.3556)
		(layers "F.Cu" "B.Cu")
		(net "SSD_ATNLED#12_R")
	)
	(via
		(at 227.179124 -207.772)
		(size 0.508)
		(drill 0.254)
		(layers "F.Cu" "B.Cu")
		(net "SSD_ATNLED#12_R")
	)
	(segment
		(start 227.179124 -207.772)
		(end 227.017072 -207.609948)
		(width 0.12065)
		(layer "B.Cu")
		(net "SSD_ATNLED#12_R")
	)
	(segment
		(start 208.100168 -225.92538)
		(end 208.100168 -224.279968)
		(width 0.12065)
		(layer "B.Cu")
		(net "SSD_ATNLED#12_R")
	)
	(segment
		(start 213.141052 -207.609948)
		(end 216.789 -207.609948)
		(width 0.12065)
		(layer "B.Cu")
		(net "SSD_ATNLED#12_R")
	)
	(segment
		(start 227.017072 -207.609948)
		(end 225.72472 -207.609948)
		(width 0.12065)
		(layer "B.Cu")
		(net "SSD_ATNLED#12_R")
	)
	(segment
		(start 220.38564 -207.609948)
		(end 216.789 -207.609948)
		(width 0.12065)
		(layer "B.Cu")
		(net "SSD_ATNLED#12_R")
	)
	(segment
		(start 208.100168 -224.279968)
		(end 207.772 -223.9518)
		(width 0.12065)
		(layer "B.Cu")
		(net "SSD_ATNLED#12_R")
	)
	(segment
		(start 207.772 -223.9518)
		(end 207.772 -221.943168)
		(width 0.12065)
		(layer "B.Cu")
		(net "SSD_ATNLED#12_R")
	)
	(segment
		(start 208.100168 -212.650832)
		(end 213.141052 -207.609948)
		(width 0.12065)
		(layer "B.Cu")
		(net "SSD_ATNLED#12_R")
	)
	(segment
		(start 220.720412 -207.94472)
		(end 220.38564 -207.609948)
		(width 0.12065)
		(layer "B.Cu")
		(net "SSD_ATNLED#12_R")
	)
	(segment
		(start 207.772 -221.943168)
		(end 208.100168 -221.615)
		(width 0.12065)
		(layer "B.Cu")
		(net "SSD_ATNLED#12_R")
	)
	(segment
		(start 225.389948 -207.94472)
		(end 220.720412 -207.94472)
		(width 0.12065)
		(layer "B.Cu")
		(net "SSD_ATNLED#12_R")
	)
	(segment
		(start 225.72472 -207.609948)
		(end 225.389948 -207.94472)
		(width 0.12065)
		(layer "B.Cu")
		(net "SSD_ATNLED#12_R")
	)
	(segment
		(start 208.100168 -221.615)
		(end 208.100168 -212.650832)
		(width 0.12065)
		(layer "B.Cu")
		(net "SSD_ATNLED#12_R")
	)
	(segment
		(start 225.152204 -199.770492)
		(end 225.152204 -200.324974)
		(width 0.12065)
		(layer "F.Cu")
		(net "SSD_ATNLED#12")
	)
	(segment
		(start 225.152204 -200.324974)
		(end 225.547174 -200.719944)
		(width 0.12065)
		(layer "F.Cu")
		(net "SSD_ATNLED#12")
	)
	(segment
		(start 227.1268 -200.754234)
		(end 227.103432 -200.730866)
		(width 0.12065)
		(layer "F.Cu")
		(net "SSD_ATNLED#12")
	)
	(segment
		(start 227.179124 -201.855324)
		(end 227.1268 -201.803)
		(width 0.12065)
		(layer "F.Cu")
		(net "SSD_ATNLED#12")
	)
	(segment
		(start 227.09251 -200.719944)
		(end 227.103432 -200.730866)
		(width 0.12065)
		(layer "F.Cu")
		(net "SSD_ATNLED#12")
	)
	(segment
		(start 227.179124 -202.602592)
		(end 227.179124 -201.855324)
		(width 0.12065)
		(layer "F.Cu")
		(net "SSD_ATNLED#12")
	)
	(segment
		(start 225.547174 -200.719944)
		(end 227.09251 -200.719944)
		(width 0.12065)
		(layer "F.Cu")
		(net "SSD_ATNLED#12")
	)
	(segment
		(start 227.1268 -201.803)
		(end 227.1268 -200.754234)
		(width 0.12065)
		(layer "F.Cu")
		(net "SSD_ATNLED#12")
	)
	(via
		(at 227.1268 -201.803)
		(size 0.508)
		(drill 0.254)
		(layers "F.Cu" "B.Cu")
		(net "SSD_ATNLED#12")
	)
	(via
		(at 227.103432 -200.730866)
		(size 0.7112)
		(drill 0.3556)
		(layers "F.Cu" "B.Cu")
		(net "SSD_ATNLED#12")
	)
	(segment
		(start 227.179124 -201.855324)
		(end 227.1268 -201.803)
		(width 0.12065)
		(layer "B.Cu")
		(net "SSD_ATNLED#12")
	)
	(segment
		(start 227.179124 -202.602592)
		(end 227.179124 -201.855324)
		(width 0.12065)
		(layer "B.Cu")
		(net "SSD_ATNLED#12")
	)
	(segment
		(start 151.8158 -189.9666)
		(end 159.893 -198.0438)
		(width 0.12065)
		(layer "F.Cu")
		(net "SSD_ATNLED#11_R")
	)
	(segment
		(start 66.082672 -199.9234)
		(end 64.198246 -198.038974)
		(width 0.12065)
		(layer "F.Cu")
		(net "SSD_ATNLED#11_R")
	)
	(segment
		(start 69.28612 -175.87595)
		(end 97.56648 -175.87595)
		(width 0.12065)
		(layer "F.Cu")
		(net "SSD_ATNLED#11_R")
	)
	(segment
		(start 159.893 -198.0438)
		(end 163.83 -198.0438)
		(width 0.12065)
		(layer "F.Cu")
		(net "SSD_ATNLED#11_R")
	)
	(segment
		(start 73.61047 -199.9234)
		(end 66.082672 -199.9234)
		(width 0.12065)
		(layer "F.Cu")
		(net "SSD_ATNLED#11_R")
	)
	(segment
		(start 64.198246 -180.963824)
		(end 69.28612 -175.87595)
		(width 0.12065)
		(layer "F.Cu")
		(net "SSD_ATNLED#11_R")
	)
	(segment
		(start 163.83 -198.0438)
		(end 164.0332 -198.247)
		(width 0.12065)
		(layer "F.Cu")
		(net "SSD_ATNLED#11_R")
	)
	(segment
		(start 97.56648 -175.87595)
		(end 111.65713 -189.9666)
		(width 0.12065)
		(layer "F.Cu")
		(net "SSD_ATNLED#11_R")
	)
	(segment
		(start 74.950066 -198.583804)
		(end 73.61047 -199.9234)
		(width 0.12065)
		(layer "F.Cu")
		(net "SSD_ATNLED#11_R")
	)
	(segment
		(start 111.65713 -189.9666)
		(end 151.8158 -189.9666)
		(width 0.12065)
		(layer "F.Cu")
		(net "SSD_ATNLED#11_R")
	)
	(segment
		(start 74.950066 -196.1134)
		(end 74.950066 -198.583804)
		(width 0.12065)
		(layer "F.Cu")
		(net "SSD_ATNLED#11_R")
	)
	(segment
		(start 64.198246 -198.038974)
		(end 64.198246 -180.963824)
		(width 0.12065)
		(layer "F.Cu")
		(net "SSD_ATNLED#11_R")
	)
	(via
		(at 164.0332 -198.247)
		(size 0.508)
		(drill 0.254)
		(layers "F.Cu" "B.Cu")
		(net "SSD_ATNLED#11_R")
	)
	(via
		(at 163.458652 -204.089)
		(size 0.7112)
		(drill 0.3556)
		(layers "F.Cu" "B.Cu")
		(net "SSD_ATNLED#11_R")
	)
	(segment
		(start 164.0332 -198.247)
		(end 164.0332 -198.3994)
		(width 0.12065)
		(layer "B.Cu")
		(net "SSD_ATNLED#11_R")
	)
	(segment
		(start 162.32505 -217.332814)
		(end 163.458652 -216.199212)
		(width 0.12065)
		(layer "B.Cu")
		(net "SSD_ATNLED#11_R")
	)
	(segment
		(start 162.500056 -223.596708)
		(end 162.32505 -223.421702)
		(width 0.12065)
		(layer "B.Cu")
		(net "SSD_ATNLED#11_R")
	)
	(segment
		(start 163.458652 -198.973948)
		(end 163.458652 -204.089)
		(width 0.12065)
		(layer "B.Cu")
		(net "SSD_ATNLED#11_R")
	)
	(segment
		(start 163.458652 -216.199212)
		(end 163.458652 -204.089)
		(width 0.12065)
		(layer "B.Cu")
		(net "SSD_ATNLED#11_R")
	)
	(segment
		(start 162.32505 -223.421702)
		(end 162.32505 -217.332814)
		(width 0.12065)
		(layer "B.Cu")
		(net "SSD_ATNLED#11_R")
	)
	(segment
		(start 162.500056 -225.92538)
		(end 162.500056 -223.596708)
		(width 0.12065)
		(layer "B.Cu")
		(net "SSD_ATNLED#11_R")
	)
	(segment
		(start 164.0332 -198.3994)
		(end 163.458652 -198.973948)
		(width 0.12065)
		(layer "B.Cu")
		(net "SSD_ATNLED#11_R")
	)
	(segment
		(start 74.469244 -194.32651)
		(end 74.597768 -194.455034)
		(width 0.12065)
		(layer "F.Cu")
		(net "SSD_ATNLED#11")
	)
	(segment
		(start 74.469244 -192.404492)
		(end 74.469244 -194.32651)
		(width 0.12065)
		(layer "F.Cu")
		(net "SSD_ATNLED#11")
	)
	(segment
		(start 74.950066 -194.807332)
		(end 74.597768 -194.455034)
		(width 0.12065)
		(layer "F.Cu")
		(net "SSD_ATNLED#11")
	)
	(segment
		(start 74.950066 -195.2244)
		(end 74.950066 -194.807332)
		(width 0.12065)
		(layer "F.Cu")
		(net "SSD_ATNLED#11")
	)
	(via
		(at 74.597768 -194.455034)
		(size 0.508)
		(drill 0.254)
		(layers "F.Cu" "B.Cu")
		(net "SSD_ATNLED#11")
	)
	(via
		(at 73.87082 -195.26377)
		(size 0.7112)
		(drill 0.3556)
		(layers "F.Cu" "B.Cu")
		(net "SSD_ATNLED#11")
	)
	(segment
		(start 74.582274 -194.437)
		(end 74.0918 -194.437)
		(width 0.12065)
		(layer "B.Cu")
		(net "SSD_ATNLED#11")
	)
	(segment
		(start 74.950066 -195.2244)
		(end 74.910696 -195.26377)
		(width 0.12065)
		(layer "B.Cu")
		(net "SSD_ATNLED#11")
	)
	(segment
		(start 73.87082 -194.65798)
		(end 73.87082 -195.26377)
		(width 0.12065)
		(layer "B.Cu")
		(net "SSD_ATNLED#11")
	)
	(segment
		(start 74.910696 -195.26377)
		(end 73.87082 -195.26377)
		(width 0.12065)
		(layer "B.Cu")
		(net "SSD_ATNLED#11")
	)
	(segment
		(start 74.59726 -194.451986)
		(end 74.582274 -194.437)
		(width 0.12065)
		(layer "B.Cu")
		(net "SSD_ATNLED#11")
	)
	(segment
		(start 74.59726 -194.455034)
		(end 74.59726 -194.451986)
		(width 0.12065)
		(layer "B.Cu")
		(net "SSD_ATNLED#11")
	)
	(segment
		(start 74.597768 -194.455034)
		(end 74.59726 -194.455034)
		(width 0.12065)
		(layer "B.Cu")
		(net "SSD_ATNLED#11")
	)
	(segment
		(start 74.0918 -194.437)
		(end 73.87082 -194.65798)
		(width 0.12065)
		(layer "B.Cu")
		(net "SSD_ATNLED#11")
	)
	(segment
		(start 79.097124 -196.125592)
		(end 79.097124 -196.900292)
		(width 0.12065)
		(layer "F.Cu")
		(net "SSD_ATNLED#10_R")
	)
	(via
		(at 92.083382 -205.240382)
		(size 0.7112)
		(drill 0.3556)
		(layers "F.Cu" "B.Cu")
		(net "SSD_ATNLED#10_R")
	)
	(via
		(at 79.097124 -196.900292)
		(size 0.508)
		(drill 0.254)
		(layers "F.Cu" "B.Cu")
		(net "SSD_ATNLED#10_R")
	)
	(segment
		(start 79.563468 -196.433948)
		(end 79.097124 -196.900292)
		(width 0.12065)
		(layer "B.Cu")
		(net "SSD_ATNLED#10_R")
	)
	(segment
		(start 94.100142 -223.690942)
		(end 93.599 -223.1898)
		(width 0.12065)
		(layer "B.Cu")
		(net "SSD_ATNLED#10_R")
	)
	(segment
		(start 93.599 -222.838264)
		(end 94.575884 -221.86138)
		(width 0.12065)
		(layer "B.Cu")
		(net "SSD_ATNLED#10_R")
	)
	(segment
		(start 80.306418 -196.433948)
		(end 79.563468 -196.433948)
		(width 0.12065)
		(layer "B.Cu")
		(net "SSD_ATNLED#10_R")
	)
	(segment
		(start 94.575884 -221.86138)
		(end 94.575884 -207.732884)
		(width 0.12065)
		(layer "B.Cu")
		(net "SSD_ATNLED#10_R")
	)
	(segment
		(start 94.100142 -225.92538)
		(end 94.100142 -223.690942)
		(width 0.12065)
		(layer "B.Cu")
		(net "SSD_ATNLED#10_R")
	)
	(segment
		(start 81.19999 -197.32752)
		(end 80.306418 -196.433948)
		(width 0.12065)
		(layer "B.Cu")
		(net "SSD_ATNLED#10_R")
	)
	(segment
		(start 84.17052 -197.32752)
		(end 81.19999 -197.32752)
		(width 0.12065)
		(layer "B.Cu")
		(net "SSD_ATNLED#10_R")
	)
	(segment
		(start 92.083382 -205.240382)
		(end 84.17052 -197.32752)
		(width 0.12065)
		(layer "B.Cu")
		(net "SSD_ATNLED#10_R")
	)
	(segment
		(start 93.599 -223.1898)
		(end 93.599 -222.838264)
		(width 0.12065)
		(layer "B.Cu")
		(net "SSD_ATNLED#10_R")
	)
	(segment
		(start 94.575884 -207.732884)
		(end 92.083382 -205.240382)
		(width 0.12065)
		(layer "B.Cu")
		(net "SSD_ATNLED#10_R")
	)
	(segment
		(start 79.097124 -195.236592)
		(end 79.097124 -194.489324)
		(width 0.12065)
		(layer "F.Cu")
		(net "SSD_ATNLED#10")
	)
	(segment
		(start 79.0448 -194.437)
		(end 79.0448 -193.218816)
		(width 0.12065)
		(layer "F.Cu")
		(net "SSD_ATNLED#10")
	)
	(segment
		(start 78.530704 -193.439288)
		(end 78.897988 -193.072004)
		(width 0.12065)
		(layer "F.Cu")
		(net "SSD_ATNLED#10")
	)
	(segment
		(start 77.070204 -193.143632)
		(end 77.36586 -193.439288)
		(width 0.12065)
		(layer "F.Cu")
		(net "SSD_ATNLED#10")
	)
	(segment
		(start 79.097124 -194.489324)
		(end 79.0448 -194.437)
		(width 0.12065)
		(layer "F.Cu")
		(net "SSD_ATNLED#10")
	)
	(segment
		(start 77.070204 -192.404492)
		(end 77.070204 -193.143632)
		(width 0.12065)
		(layer "F.Cu")
		(net "SSD_ATNLED#10")
	)
	(segment
		(start 77.36586 -193.439288)
		(end 78.530704 -193.439288)
		(width 0.12065)
		(layer "F.Cu")
		(net "SSD_ATNLED#10")
	)
	(segment
		(start 79.0448 -193.218816)
		(end 78.897988 -193.072004)
		(width 0.12065)
		(layer "F.Cu")
		(net "SSD_ATNLED#10")
	)
	(via
		(at 79.0448 -194.437)
		(size 0.508)
		(drill 0.254)
		(layers "F.Cu" "B.Cu")
		(net "SSD_ATNLED#10")
	)
	(via
		(at 78.897988 -193.072004)
		(size 0.7112)
		(drill 0.3556)
		(layers "F.Cu" "B.Cu")
		(net "SSD_ATNLED#10")
	)
	(segment
		(start 81.129124 -194.982592)
		(end 79.590392 -194.982592)
		(width 0.12065)
		(layer "B.Cu")
		(net "SSD_ATNLED#10")
	)
	(segment
		(start 79.590392 -194.982592)
		(end 79.0448 -194.437)
		(width 0.12065)
		(layer "B.Cu")
		(net "SSD_ATNLED#10")
	)
	(segment
		(start 93.218 -180.0606)
		(end 93.218 -178.816)
		(width 0.12065)
		(layer "F.Cu")
		(net "SSD_ATNLED#1_R")
	)
	(segment
		(start 89.27465 -184.00395)
		(end 93.218 -180.0606)
		(width 0.12065)
		(layer "F.Cu")
		(net "SSD_ATNLED#1_R")
	)
	(segment
		(start 95.09125 -205.482698)
		(end 89.27465 -199.666098)
		(width 0.12065)
		(layer "F.Cu")
		(net "SSD_ATNLED#1_R")
	)
	(segment
		(start 126.976124 -195.998592)
		(end 126.976124 -195.206874)
		(width 0.12065)
		(layer "F.Cu")
		(net "SSD_ATNLED#1_R")
	)
	(segment
		(start 95.700088 -225.54438)
		(end 95.700088 -223.872552)
		(width 0.12065)
		(layer "F.Cu")
		(net "SSD_ATNLED#1_R")
	)
	(segment
		(start 95.09125 -223.263714)
		(end 95.09125 -205.482698)
		(width 0.12065)
		(layer "F.Cu")
		(net "SSD_ATNLED#1_R")
	)
	(segment
		(start 89.27465 -199.666098)
		(end 89.27465 -184.00395)
		(width 0.12065)
		(layer "F.Cu")
		(net "SSD_ATNLED#1_R")
	)
	(segment
		(start 95.700088 -223.872552)
		(end 95.09125 -223.263714)
		(width 0.12065)
		(layer "F.Cu")
		(net "SSD_ATNLED#1_R")
	)
	(via
		(at 93.218 -178.816)
		(size 0.508)
		(drill 0.254)
		(layers "F.Cu" "B.Cu")
		(net "SSD_ATNLED#1_R")
	)
	(via
		(at 125.807978 -194.038728)
		(size 0.7112)
		(drill 0.3556)
		(layers "F.Cu" "B.Cu")
		(net "SSD_ATNLED#1_R")
	)
	(via
		(at 126.976124 -195.206874)
		(size 0.508)
		(drill 0.254)
		(layers "F.Cu" "B.Cu")
		(net "SSD_ATNLED#1_R")
	)
	(segment
		(start 93.792802 -178.70805)
		(end 110.4773 -178.70805)
		(width 0.12065)
		(layer "B.Cu")
		(net "SSD_ATNLED#1_R")
	)
	(segment
		(start 93.218 -178.816)
		(end 93.684852 -178.816)
		(width 0.12065)
		(layer "B.Cu")
		(net "SSD_ATNLED#1_R")
	)
	(segment
		(start 110.4773 -178.70805)
		(end 125.807978 -194.038728)
		(width 0.12065)
		(layer "B.Cu")
		(net "SSD_ATNLED#1_R")
	)
	(segment
		(start 125.807978 -194.038728)
		(end 126.976124 -195.206874)
		(width 0.12065)
		(layer "B.Cu")
		(net "SSD_ATNLED#1_R")
	)
	(segment
		(start 93.684852 -178.816)
		(end 93.792802 -178.70805)
		(width 0.12065)
		(layer "B.Cu")
		(net "SSD_ATNLED#1_R")
	)
	(segment
		(start 127.397764 -198.582026)
		(end 127.197612 -198.381874)
		(width 0.12065)
		(layer "F.Cu")
		(net "SSD_ATNLED#1")
	)
	(segment
		(start 127.397764 -199.973692)
		(end 127.397764 -198.582026)
		(width 0.12065)
		(layer "F.Cu")
		(net "SSD_ATNLED#1")
	)
	(segment
		(start 126.976124 -198.160386)
		(end 127.197612 -198.381874)
		(width 0.12065)
		(layer "F.Cu")
		(net "SSD_ATNLED#1")
	)
	(segment
		(start 126.976124 -196.887592)
		(end 126.976124 -198.160386)
		(width 0.12065)
		(layer "F.Cu")
		(net "SSD_ATNLED#1")
	)
	(via
		(at 127.197612 -198.381874)
		(size 0.508)
		(drill 0.254)
		(layers "F.Cu" "B.Cu")
		(net "SSD_ATNLED#1")
	)
	(via
		(at 128.058926 -196.759322)
		(size 0.7112)
		(drill 0.3556)
		(layers "F.Cu" "B.Cu")
		(net "SSD_ATNLED#1")
	)
	(segment
		(start 126.976124 -196.887592)
		(end 127.104394 -196.759322)
		(width 0.12065)
		(layer "B.Cu")
		(net "SSD_ATNLED#1")
	)
	(segment
		(start 127.197612 -198.144892)
		(end 128.016 -197.326504)
		(width 0.12065)
		(layer "B.Cu")
		(net "SSD_ATNLED#1")
	)
	(segment
		(start 127.197612 -198.381874)
		(end 127.197612 -198.144892)
		(width 0.12065)
		(layer "B.Cu")
		(net "SSD_ATNLED#1")
	)
	(segment
		(start 128.016 -197.326504)
		(end 128.016 -196.802248)
		(width 0.12065)
		(layer "B.Cu")
		(net "SSD_ATNLED#1")
	)
	(segment
		(start 127.104394 -196.759322)
		(end 128.058926 -196.759322)
		(width 0.12065)
		(layer "B.Cu")
		(net "SSD_ATNLED#1")
	)
	(segment
		(start 128.016 -196.802248)
		(end 128.058926 -196.759322)
		(width 0.12065)
		(layer "B.Cu")
		(net "SSD_ATNLED#1")
	)
	(segment
		(start 61.214 -183.261)
		(end 61.722 -183.769)
		(width 0.12065)
		(layer "F.Cu")
		(net "SSD_ATNLED#0_R")
	)
	(segment
		(start 61.300106 -223.992694)
		(end 61.3918 -223.901)
		(width 0.12065)
		(layer "F.Cu")
		(net "SSD_ATNLED#0_R")
	)
	(segment
		(start 61.3918 -223.76257)
		(end 61.728858 -223.425512)
		(width 0.12065)
		(layer "F.Cu")
		(net "SSD_ATNLED#0_R")
	)
	(segment
		(start 61.728858 -223.425512)
		(end 61.728858 -222.205042)
		(width 0.12065)
		(layer "F.Cu")
		(net "SSD_ATNLED#0_R")
	)
	(segment
		(start 61.3918 -223.901)
		(end 61.3918 -223.76257)
		(width 0.12065)
		(layer "F.Cu")
		(net "SSD_ATNLED#0_R")
	)
	(segment
		(start 61.300106 -225.54438)
		(end 61.300106 -223.992694)
		(width 0.12065)
		(layer "F.Cu")
		(net "SSD_ATNLED#0_R")
	)
	(segment
		(start 61.3918 -221.867984)
		(end 61.3918 -187.6552)
		(width 0.12065)
		(layer "F.Cu")
		(net "SSD_ATNLED#0_R")
	)
	(segment
		(start 61.3918 -187.6552)
		(end 61.722 -187.325)
		(width 0.12065)
		(layer "F.Cu")
		(net "SSD_ATNLED#0_R")
	)
	(segment
		(start 61.728858 -222.205042)
		(end 61.3918 -221.867984)
		(width 0.12065)
		(layer "F.Cu")
		(net "SSD_ATNLED#0_R")
	)
	(segment
		(start 61.722 -183.769)
		(end 61.722 -187.325)
		(width 0.12065)
		(layer "F.Cu")
		(net "SSD_ATNLED#0_R")
	)
	(segment
		(start 72.747124 -182.790592)
		(end 72.747124 -181.998874)
		(width 0.12065)
		(layer "F.Cu")
		(net "SSD_ATNLED#0_R")
	)
	(via
		(at 61.722 -187.325)
		(size 0.7112)
		(drill 0.3556)
		(layers "F.Cu" "B.Cu")
		(net "SSD_ATNLED#0_R")
	)
	(via
		(at 72.747124 -181.998874)
		(size 0.508)
		(drill 0.254)
		(layers "F.Cu" "B.Cu")
		(net "SSD_ATNLED#0_R")
	)
	(via
		(at 61.214 -183.261)
		(size 0.508)
		(drill 0.254)
		(layers "F.Cu" "B.Cu")
		(net "SSD_ATNLED#0_R")
	)
	(segment
		(start 72.747124 -181.998874)
		(end 71.46925 -180.721)
		(width 0.127)
		(layer "In5.Cu")
		(net "SSD_ATNLED#0_R")
	)
	(segment
		(start 63.754 -180.721)
		(end 61.214 -183.261)
		(width 0.127)
		(layer "In5.Cu")
		(net "SSD_ATNLED#0_R")
	)
	(segment
		(start 71.46925 -180.721)
		(end 63.754 -180.721)
		(width 0.127)
		(layer "In5.Cu")
		(net "SSD_ATNLED#0_R")
	)
	(segment
		(start 73.168764 -185.374026)
		(end 72.968612 -185.173874)
		(width 0.12065)
		(layer "F.Cu")
		(net "SSD_ATNLED#0")
	)
	(segment
		(start 72.968612 -183.90108)
		(end 72.968612 -185.173874)
		(width 0.12065)
		(layer "F.Cu")
		(net "SSD_ATNLED#0")
	)
	(segment
		(start 72.747124 -183.679592)
		(end 72.968612 -183.90108)
		(width 0.12065)
		(layer "F.Cu")
		(net "SSD_ATNLED#0")
	)
	(segment
		(start 73.168764 -186.765692)
		(end 73.168764 -185.374026)
		(width 0.12065)
		(layer "F.Cu")
		(net "SSD_ATNLED#0")
	)
	(via
		(at 70.87743 -185.185812)
		(size 0.7112)
		(drill 0.3556)
		(layers "F.Cu" "B.Cu")
		(net "SSD_ATNLED#0")
	)
	(via
		(at 72.968612 -185.173874)
		(size 0.508)
		(drill 0.254)
		(layers "F.Cu" "B.Cu")
		(net "SSD_ATNLED#0")
	)
	(segment
		(start 71.188834 -184.874408)
		(end 70.87743 -185.185812)
		(width 0.12065)
		(layer "B.Cu")
		(net "SSD_ATNLED#0")
	)
	(segment
		(start 72.145652 -184.874408)
		(end 71.188834 -184.874408)
		(width 0.12065)
		(layer "B.Cu")
		(net "SSD_ATNLED#0")
	)
	(segment
		(start 72.445118 -185.173874)
		(end 72.145652 -184.874408)
		(width 0.12065)
		(layer "B.Cu")
		(net "SSD_ATNLED#0")
	)
	(segment
		(start 72.968612 -185.173874)
		(end 72.445118 -185.173874)
		(width 0.12065)
		(layer "B.Cu")
		(net "SSD_ATNLED#0")
	)
	(segment
		(start 72.747124 -183.679592)
		(end 72.968612 -183.90108)
		(width 0.12065)
		(layer "B.Cu")
		(net "SSD_ATNLED#0")
	)
	(segment
		(start 72.968612 -183.90108)
		(end 72.968612 -185.173874)
		(width 0.12065)
		(layer "B.Cu")
		(net "SSD_ATNLED#0")
	)
	(segment
		(start 25.908 -119.4816)
		(end 26.232358 -119.805958)
		(width 0.12065)
		(layer "F.Cu")
		(net "SPI_FLASH_SELECT")
	)
	(segment
		(start 33.988248 -105.336848)
		(end 33.988248 -104.29367)
		(width 0.12065)
		(layer "F.Cu")
		(net "SPI_FLASH_SELECT")
	)
	(segment
		(start 38.5064 -105.016808)
		(end 38.5064 -104.0765)
		(width 0.12065)
		(layer "F.Cu")
		(net "SPI_FLASH_SELECT")
	)
	(segment
		(start 37.503608 -106.0196)
		(end 38.5064 -105.016808)
		(width 0.12065)
		(layer "F.Cu")
		(net "SPI_FLASH_SELECT")
	)
	(segment
		(start 29.493464 -123.2916)
		(end 30.1117 -123.2916)
		(width 0.12065)
		(layer "F.Cu")
		(net "SPI_FLASH_SELECT")
	)
	(segment
		(start 33.988248 -105.336848)
		(end 34.671 -106.0196)
		(width 0.12065)
		(layer "F.Cu")
		(net "SPI_FLASH_SELECT")
	)
	(segment
		(start 33.988248 -104.29367)
		(end 34.181034 -104.100884)
		(width 0.12065)
		(layer "F.Cu")
		(net "SPI_FLASH_SELECT")
	)
	(segment
		(start 26.232358 -119.805958)
		(end 26.232358 -120.030494)
		(width 0.12065)
		(layer "F.Cu")
		(net "SPI_FLASH_SELECT")
	)
	(segment
		(start 39.5478 -104.0765)
		(end 38.5064 -104.0765)
		(width 0.12065)
		(layer "F.Cu")
		(net "SPI_FLASH_SELECT")
	)
	(segment
		(start 30.1117 -123.2916)
		(end 30.504892 -123.684792)
		(width 0.12065)
		(layer "F.Cu")
		(net "SPI_FLASH_SELECT")
	)
	(segment
		(start 26.232358 -120.030494)
		(end 29.493464 -123.2916)
		(width 0.12065)
		(layer "F.Cu")
		(net "SPI_FLASH_SELECT")
	)
	(segment
		(start 34.671 -106.0196)
		(end 37.503608 -106.0196)
		(width 0.12065)
		(layer "F.Cu")
		(net "SPI_FLASH_SELECT")
	)
	(segment
		(start 25.7048 -119.4816)
		(end 25.908 -119.4816)
		(width 0.12065)
		(layer "F.Cu")
		(net "SPI_FLASH_SELECT")
	)
	(via
		(at 33.988248 -105.336848)
		(size 0.7112)
		(drill 0.3556)
		(layers "F.Cu" "B.Cu")
		(net "SPI_FLASH_SELECT")
	)
	(via
		(at 25.7048 -119.4816)
		(size 0.508)
		(drill 0.254)
		(layers "F.Cu" "B.Cu")
		(net "SPI_FLASH_SELECT")
	)
	(via
		(at 34.671 -106.0196)
		(size 0.508)
		(drill 0.254)
		(layers "F.Cu" "B.Cu")
		(net "SPI_FLASH_SELECT")
	)
	(segment
		(start 29.972 -113.9952)
		(end 28.2448 -113.9952)
		(width 0.127)
		(layer "In2.Cu")
		(net "SPI_FLASH_SELECT")
	)
	(segment
		(start 27.1272 -117.8052)
		(end 25.7048 -119.2276)
		(width 0.127)
		(layer "In2.Cu")
		(net "SPI_FLASH_SELECT")
	)
	(segment
		(start 25.7048 -119.2276)
		(end 25.7048 -119.4816)
		(width 0.127)
		(layer "In2.Cu")
		(net "SPI_FLASH_SELECT")
	)
	(segment
		(start 28.2448 -113.9952)
		(end 27.686 -114.554)
		(width 0.127)
		(layer "In2.Cu")
		(net "SPI_FLASH_SELECT")
	)
	(segment
		(start 32.893 -111.0742)
		(end 29.972 -113.9952)
		(width 0.127)
		(layer "In2.Cu")
		(net "SPI_FLASH_SELECT")
	)
	(segment
		(start 27.686 -114.554)
		(end 27.686 -115.697)
		(width 0.127)
		(layer "In2.Cu")
		(net "SPI_FLASH_SELECT")
	)
	(segment
		(start 34.671 -106.0196)
		(end 34.2392 -106.4514)
		(width 0.127)
		(layer "In2.Cu")
		(net "SPI_FLASH_SELECT")
	)
	(segment
		(start 34.2392 -108.216446)
		(end 32.893 -109.562646)
		(width 0.127)
		(layer "In2.Cu")
		(net "SPI_FLASH_SELECT")
	)
	(segment
		(start 34.2392 -106.4514)
		(end 34.2392 -108.216446)
		(width 0.127)
		(layer "In2.Cu")
		(net "SPI_FLASH_SELECT")
	)
	(segment
		(start 27.1272 -116.2558)
		(end 27.1272 -117.8052)
		(width 0.127)
		(layer "In2.Cu")
		(net "SPI_FLASH_SELECT")
	)
	(segment
		(start 27.686 -115.697)
		(end 27.1272 -116.2558)
		(width 0.127)
		(layer "In2.Cu")
		(net "SPI_FLASH_SELECT")
	)
	(segment
		(start 32.893 -109.562646)
		(end 32.893 -111.0742)
		(width 0.127)
		(layer "In2.Cu")
		(net "SPI_FLASH_SELECT")
	)
	(segment
		(start 134.292086 -73.291192)
		(end 134.589774 -72.993504)
		(width 0.12065)
		(layer "F.Cu")
		(net "SPI_DATA0_3")
	)
	(segment
		(start 134.292086 -74.023982)
		(end 134.292086 -73.291192)
		(width 0.12065)
		(layer "F.Cu")
		(net "SPI_DATA0_3")
	)
	(segment
		(start 230.599996 -33.999932)
		(end 230.100124 -33.50006)
		(width 0.12065)
		(layer "F.Cu")
		(net "SPI_DATA0_3")
	)
	(via
		(at 134.405116 -64.773556)
		(size 0.7112)
		(drill 0.3556)
		(layers "F.Cu" "B.Cu")
		(net "SPI_DATA0_3")
	)
	(via
		(at 230.100124 -33.50006)
		(size 0.4572)
		(drill 0.2032)
		(layers "F.Cu" "B.Cu")
		(net "SPI_DATA0_3")
	)
	(via
		(at 134.589774 -72.993504)
		(size 0.508)
		(drill 0.254)
		(layers "F.Cu" "B.Cu")
		(net "SPI_DATA0_3")
	)
	(via
		(at 195.67779 -48.04791)
		(size 0.508)
		(drill 0.254)
		(layers "F.Cu" "B.Cu")
		(net "SPI_DATA0_3")
	)
	(segment
		(start 194.749674 -46.422818)
		(end 195.177156 -46.8503)
		(width 0.12065)
		(layer "B.Cu")
		(net "SPI_DATA0_3")
	)
	(segment
		(start 170.719496 -43.802554)
		(end 191.280542 -43.802554)
		(width 0.12065)
		(layer "B.Cu")
		(net "SPI_DATA0_3")
	)
	(segment
		(start 134.405116 -64.773556)
		(end 134.75081 -64.427862)
		(width 0.12065)
		(layer "B.Cu")
		(net "SPI_DATA0_3")
	)
	(segment
		(start 134.75081 -64.065912)
		(end 140.064236 -58.752486)
		(width 0.12065)
		(layer "B.Cu")
		(net "SPI_DATA0_3")
	)
	(segment
		(start 140.064236 -58.752486)
		(end 140.769848 -58.752486)
		(width 0.12065)
		(layer "B.Cu")
		(net "SPI_DATA0_3")
	)
	(segment
		(start 133.096 -71.49973)
		(end 133.096 -66.082672)
		(width 0.12065)
		(layer "B.Cu")
		(net "SPI_DATA0_3")
	)
	(segment
		(start 191.280542 -43.802554)
		(end 193.900806 -46.422818)
		(width 0.12065)
		(layer "B.Cu")
		(net "SPI_DATA0_3")
	)
	(segment
		(start 193.900806 -46.422818)
		(end 194.749674 -46.422818)
		(width 0.12065)
		(layer "B.Cu")
		(net "SPI_DATA0_3")
	)
	(segment
		(start 195.177156 -47.547276)
		(end 195.67779 -48.04791)
		(width 0.12065)
		(layer "B.Cu")
		(net "SPI_DATA0_3")
	)
	(segment
		(start 195.177156 -46.8503)
		(end 195.177156 -47.547276)
		(width 0.12065)
		(layer "B.Cu")
		(net "SPI_DATA0_3")
	)
	(segment
		(start 133.096 -66.082672)
		(end 134.405116 -64.773556)
		(width 0.12065)
		(layer "B.Cu")
		(net "SPI_DATA0_3")
	)
	(segment
		(start 163.48202 -51.04003)
		(end 170.719496 -43.802554)
		(width 0.12065)
		(layer "B.Cu")
		(net "SPI_DATA0_3")
	)
	(segment
		(start 148.482558 -51.04003)
		(end 163.48202 -51.04003)
		(width 0.12065)
		(layer "B.Cu")
		(net "SPI_DATA0_3")
	)
	(segment
		(start 134.589774 -72.993504)
		(end 133.096 -71.49973)
		(width 0.12065)
		(layer "B.Cu")
		(net "SPI_DATA0_3")
	)
	(segment
		(start 134.75081 -64.427862)
		(end 134.75081 -64.065912)
		(width 0.12065)
		(layer "B.Cu")
		(net "SPI_DATA0_3")
	)
	(segment
		(start 140.769848 -58.752486)
		(end 148.482558 -51.04003)
		(width 0.12065)
		(layer "B.Cu")
		(net "SPI_DATA0_3")
	)
	(segment
		(start 208.28 -41.3512)
		(end 215.4682 -41.3512)
		(width 0.127)
		(layer "In5.Cu")
		(net "SPI_DATA0_3")
	)
	(segment
		(start 230.100124 -33.943036)
		(end 230.100124 -33.50006)
		(width 0.1016)
		(layer "In5.Cu")
		(net "SPI_DATA0_3")
	)
	(segment
		(start 215.4682 -41.3512)
		(end 216.023444 -41.906444)
		(width 0.127)
		(layer "In5.Cu")
		(net "SPI_DATA0_3")
	)
	(segment
		(start 228.4984 -41.658794)
		(end 228.4984 -35.257232)
		(width 0.1016)
		(layer "In5.Cu")
		(net "SPI_DATA0_3")
	)
	(segment
		(start 216.023444 -41.906444)
		(end 223.344486 -41.906444)
		(width 0.127)
		(layer "In5.Cu")
		(net "SPI_DATA0_3")
	)
	(segment
		(start 229.263448 -34.893758)
		(end 229.493826 -34.66338)
		(width 0.1016)
		(layer "In5.Cu")
		(net "SPI_DATA0_3")
	)
	(segment
		(start 207.712564 -41.918636)
		(end 208.28 -41.3512)
		(width 0.127)
		(layer "In5.Cu")
		(net "SPI_DATA0_3")
	)
	(segment
		(start 195.67779 -48.04791)
		(end 195.67779 -47.906686)
		(width 0.127)
		(layer "In5.Cu")
		(net "SPI_DATA0_3")
	)
	(segment
		(start 223.344486 -41.906444)
		(end 223.39173 -41.8592)
		(width 0.127)
		(layer "In5.Cu")
		(net "SPI_DATA0_3")
	)
	(segment
		(start 195.332604 -47.5615)
		(end 195.332604 -46.461426)
		(width 0.127)
		(layer "In5.Cu")
		(net "SPI_DATA0_3")
	)
	(segment
		(start 229.493826 -34.549334)
		(end 230.100124 -33.943036)
		(width 0.1016)
		(layer "In5.Cu")
		(net "SPI_DATA0_3")
	)
	(segment
		(start 223.426274 -41.893744)
		(end 228.26345 -41.893744)
		(width 0.1016)
		(layer "In5.Cu")
		(net "SPI_DATA0_3")
	)
	(segment
		(start 228.4984 -35.257232)
		(end 228.861874 -34.893758)
		(width 0.1016)
		(layer "In5.Cu")
		(net "SPI_DATA0_3")
	)
	(segment
		(start 195.67779 -47.906686)
		(end 195.332604 -47.5615)
		(width 0.127)
		(layer "In5.Cu")
		(net "SPI_DATA0_3")
	)
	(segment
		(start 199.875394 -41.918636)
		(end 207.712564 -41.918636)
		(width 0.127)
		(layer "In5.Cu")
		(net "SPI_DATA0_3")
	)
	(segment
		(start 228.26345 -41.893744)
		(end 228.4984 -41.658794)
		(width 0.1016)
		(layer "In5.Cu")
		(net "SPI_DATA0_3")
	)
	(segment
		(start 195.332604 -46.461426)
		(end 199.875394 -41.918636)
		(width 0.127)
		(layer "In5.Cu")
		(net "SPI_DATA0_3")
	)
	(segment
		(start 229.493826 -34.66338)
		(end 229.493826 -34.549334)
		(width 0.1016)
		(layer "In5.Cu")
		(net "SPI_DATA0_3")
	)
	(segment
		(start 228.861874 -34.893758)
		(end 229.263448 -34.893758)
		(width 0.1016)
		(layer "In5.Cu")
		(net "SPI_DATA0_3")
	)
	(segment
		(start 223.39173 -41.8592)
		(end 223.426274 -41.893744)
		(width 0.1016)
		(layer "In5.Cu")
		(net "SPI_DATA0_3")
	)
	(segment
		(start 230.599996 -34.99993)
		(end 230.100124 -34.500058)
		(width 0.12065)
		(layer "F.Cu")
		(net "SPI_DATA0_2")
	)
	(segment
		(start 137.09777 -59.947556)
		(end 136.601454 -59.947556)
		(width 0.12065)
		(layer "F.Cu")
		(net "SPI_DATA0_2")
	)
	(segment
		(start 136.601454 -59.947556)
		(end 135.96493 -59.311032)
		(width 0.12065)
		(layer "F.Cu")
		(net "SPI_DATA0_2")
	)
	(segment
		(start 137.16889 -60.018676)
		(end 137.09777 -59.947556)
		(width 0.12065)
		(layer "F.Cu")
		(net "SPI_DATA0_2")
	)
	(via
		(at 230.100124 -34.500058)
		(size 0.4572)
		(drill 0.2032)
		(layers "F.Cu" "B.Cu")
		(net "SPI_DATA0_2")
	)
	(via
		(at 196.591936 -48.035972)
		(size 0.508)
		(drill 0.254)
		(layers "F.Cu" "B.Cu")
		(net "SPI_DATA0_2")
	)
	(via
		(at 139.358624 -58.207148)
		(size 0.7112)
		(drill 0.3556)
		(layers "F.Cu" "B.Cu")
		(net "SPI_DATA0_2")
	)
	(via
		(at 137.16889 -60.018676)
		(size 0.508)
		(drill 0.254)
		(layers "F.Cu" "B.Cu")
		(net "SPI_DATA0_2")
	)
	(segment
		(start 196.591936 -47.219616)
		(end 195.072254 -45.699934)
		(width 0.12065)
		(layer "B.Cu")
		(net "SPI_DATA0_2")
	)
	(segment
		(start 195.072254 -45.699934)
		(end 193.887598 -45.699934)
		(width 0.12065)
		(layer "B.Cu")
		(net "SPI_DATA0_2")
	)
	(segment
		(start 163.444428 -50.367946)
		(end 147.262088 -50.367946)
		(width 0.12065)
		(layer "B.Cu")
		(net "SPI_DATA0_2")
	)
	(segment
		(start 193.887598 -45.699934)
		(end 191.488568 -43.300904)
		(width 0.12065)
		(layer "B.Cu")
		(net "SPI_DATA0_2")
	)
	(segment
		(start 170.51147 -43.300904)
		(end 163.444428 -50.367946)
		(width 0.12065)
		(layer "B.Cu")
		(net "SPI_DATA0_2")
	)
	(segment
		(start 196.591936 -48.035972)
		(end 196.591936 -47.219616)
		(width 0.12065)
		(layer "B.Cu")
		(net "SPI_DATA0_2")
	)
	(segment
		(start 139.358624 -58.207148)
		(end 138.980418 -58.207148)
		(width 0.12065)
		(layer "B.Cu")
		(net "SPI_DATA0_2")
	)
	(segment
		(start 191.488568 -43.300904)
		(end 170.51147 -43.300904)
		(width 0.12065)
		(layer "B.Cu")
		(net "SPI_DATA0_2")
	)
	(segment
		(start 147.262088 -50.367946)
		(end 139.489688 -58.140346)
		(width 0.12065)
		(layer "B.Cu")
		(net "SPI_DATA0_2")
	)
	(segment
		(start 138.980418 -58.207148)
		(end 137.16889 -60.018676)
		(width 0.12065)
		(layer "B.Cu")
		(net "SPI_DATA0_2")
	)
	(segment
		(start 139.425426 -58.140346)
		(end 139.358624 -58.207148)
		(width 0.12065)
		(layer "B.Cu")
		(net "SPI_DATA0_2")
	)
	(segment
		(start 139.489688 -58.140346)
		(end 139.425426 -58.140346)
		(width 0.12065)
		(layer "B.Cu")
		(net "SPI_DATA0_2")
	)
	(segment
		(start 198.71055 -47.703486)
		(end 196.924422 -47.703486)
		(width 0.127)
		(layer "In5.Cu")
		(net "SPI_DATA0_2")
	)
	(segment
		(start 223.6216 -42.291)
		(end 215.7222 -42.291)
		(width 0.127)
		(layer "In5.Cu")
		(net "SPI_DATA0_2")
	)
	(segment
		(start 230.067104 -34.500058)
		(end 229.460806 -35.106356)
		(width 0.1016)
		(layer "In5.Cu")
		(net "SPI_DATA0_2")
	)
	(segment
		(start 229.460806 -35.106356)
		(end 228.936804 -35.106356)
		(width 0.1016)
		(layer "In5.Cu")
		(net "SPI_DATA0_2")
	)
	(segment
		(start 215.7222 -42.291)
		(end 215.2904 -41.8592)
		(width 0.127)
		(layer "In5.Cu")
		(net "SPI_DATA0_2")
	)
	(segment
		(start 215.2904 -41.8592)
		(end 208.661 -41.8592)
		(width 0.127)
		(layer "In5.Cu")
		(net "SPI_DATA0_2")
	)
	(segment
		(start 228.7016 -35.34156)
		(end 228.7016 -41.743122)
		(width 0.1016)
		(layer "In5.Cu")
		(net "SPI_DATA0_2")
	)
	(segment
		(start 196.924422 -47.703486)
		(end 196.591936 -48.035972)
		(width 0.127)
		(layer "In5.Cu")
		(net "SPI_DATA0_2")
	)
	(segment
		(start 199.429624 -43.905678)
		(end 199.429624 -46.984412)
		(width 0.127)
		(layer "In5.Cu")
		(net "SPI_DATA0_2")
	)
	(segment
		(start 199.429624 -46.984412)
		(end 198.71055 -47.703486)
		(width 0.127)
		(layer "In5.Cu")
		(net "SPI_DATA0_2")
	)
	(segment
		(start 230.100124 -34.500058)
		(end 230.067104 -34.500058)
		(width 0.1016)
		(layer "In5.Cu")
		(net "SPI_DATA0_2")
	)
	(segment
		(start 223.806258 -42.106342)
		(end 223.6216 -42.291)
		(width 0.1016)
		(layer "In5.Cu")
		(net "SPI_DATA0_2")
	)
	(segment
		(start 228.7016 -41.743122)
		(end 228.33838 -42.106342)
		(width 0.1016)
		(layer "In5.Cu")
		(net "SPI_DATA0_2")
	)
	(segment
		(start 200.908666 -42.426636)
		(end 199.429624 -43.905678)
		(width 0.127)
		(layer "In5.Cu")
		(net "SPI_DATA0_2")
	)
	(segment
		(start 228.936804 -35.106356)
		(end 228.7016 -35.34156)
		(width 0.1016)
		(layer "In5.Cu")
		(net "SPI_DATA0_2")
	)
	(segment
		(start 208.661 -41.8592)
		(end 208.093564 -42.426636)
		(width 0.127)
		(layer "In5.Cu")
		(net "SPI_DATA0_2")
	)
	(segment
		(start 208.093564 -42.426636)
		(end 200.908666 -42.426636)
		(width 0.127)
		(layer "In5.Cu")
		(net "SPI_DATA0_2")
	)
	(segment
		(start 228.33838 -42.106342)
		(end 223.806258 -42.106342)
		(width 0.1016)
		(layer "In5.Cu")
		(net "SPI_DATA0_2")
	)
	(segment
		(start 133.891274 -58.198766)
		(end 133.891274 -59.29122)
		(width 0.12065)
		(layer "F.Cu")
		(net "SPI_DATA0_1")
	)
	(segment
		(start 137.143236 -59.09564)
		(end 137.004806 -58.95721)
		(width 0.12065)
		(layer "F.Cu")
		(net "SPI_DATA0_1")
	)
	(segment
		(start 137.004806 -58.95721)
		(end 136.751314 -58.95721)
		(width 0.12065)
		(layer "F.Cu")
		(net "SPI_DATA0_1")
	)
	(segment
		(start 136.751314 -58.95721)
		(end 135.728202 -57.934098)
		(width 0.12065)
		(layer "F.Cu")
		(net "SPI_DATA0_1")
	)
	(segment
		(start 135.728202 -57.934098)
		(end 134.155942 -57.934098)
		(width 0.12065)
		(layer "F.Cu")
		(net "SPI_DATA0_1")
	)
	(segment
		(start 134.155942 -57.934098)
		(end 133.891274 -58.198766)
		(width 0.12065)
		(layer "F.Cu")
		(net "SPI_DATA0_1")
	)
	(segment
		(start 230.599996 -36.999926)
		(end 230.100124 -36.500054)
		(width 0.12065)
		(layer "F.Cu")
		(net "SPI_DATA0_1")
	)
	(via
		(at 175.5394 -42.732452)
		(size 0.7112)
		(drill 0.3556)
		(layers "F.Cu" "B.Cu")
		(net "SPI_DATA0_1")
	)
	(via
		(at 137.143236 -59.09564)
		(size 0.508)
		(drill 0.254)
		(layers "F.Cu" "B.Cu")
		(net "SPI_DATA0_1")
	)
	(via
		(at 204.02931 -44.2087)
		(size 0.508)
		(drill 0.254)
		(layers "F.Cu" "B.Cu")
		(net "SPI_DATA0_1")
	)
	(via
		(at 230.100124 -36.500054)
		(size 0.4572)
		(drill 0.2032)
		(layers "F.Cu" "B.Cu")
		(net "SPI_DATA0_1")
	)
	(segment
		(start 198.730616 -42.93489)
		(end 197.045326 -44.62018)
		(width 0.12065)
		(layer "B.Cu")
		(net "SPI_DATA0_1")
	)
	(segment
		(start 170.370246 -42.732452)
		(end 175.5394 -42.732452)
		(width 0.12065)
		(layer "B.Cu")
		(net "SPI_DATA0_1")
	)
	(segment
		(start 147.054062 -49.866296)
		(end 163.236402 -49.866296)
		(width 0.12065)
		(layer "B.Cu")
		(net "SPI_DATA0_1")
	)
	(segment
		(start 193.51752 -44.62018)
		(end 191.629792 -42.732452)
		(width 0.12065)
		(layer "B.Cu")
		(net "SPI_DATA0_1")
	)
	(segment
		(start 137.143236 -59.09564)
		(end 138.533378 -57.705498)
		(width 0.12065)
		(layer "B.Cu")
		(net "SPI_DATA0_1")
	)
	(segment
		(start 139.056364 -57.705498)
		(end 139.123166 -57.638696)
		(width 0.12065)
		(layer "B.Cu")
		(net "SPI_DATA0_1")
	)
	(segment
		(start 202.7555 -42.93489)
		(end 198.730616 -42.93489)
		(width 0.12065)
		(layer "B.Cu")
		(net "SPI_DATA0_1")
	)
	(segment
		(start 191.629792 -42.732452)
		(end 175.5394 -42.732452)
		(width 0.12065)
		(layer "B.Cu")
		(net "SPI_DATA0_1")
	)
	(segment
		(start 197.045326 -44.62018)
		(end 193.51752 -44.62018)
		(width 0.12065)
		(layer "B.Cu")
		(net "SPI_DATA0_1")
	)
	(segment
		(start 139.123166 -57.638696)
		(end 139.281662 -57.638696)
		(width 0.12065)
		(layer "B.Cu")
		(net "SPI_DATA0_1")
	)
	(segment
		(start 139.281662 -57.638696)
		(end 147.054062 -49.866296)
		(width 0.12065)
		(layer "B.Cu")
		(net "SPI_DATA0_1")
	)
	(segment
		(start 163.236402 -49.866296)
		(end 170.370246 -42.732452)
		(width 0.12065)
		(layer "B.Cu")
		(net "SPI_DATA0_1")
	)
	(segment
		(start 138.533378 -57.705498)
		(end 139.056364 -57.705498)
		(width 0.12065)
		(layer "B.Cu")
		(net "SPI_DATA0_1")
	)
	(segment
		(start 204.02931 -44.2087)
		(end 202.7555 -42.93489)
		(width 0.12065)
		(layer "B.Cu")
		(net "SPI_DATA0_1")
	)
	(segment
		(start 204.541374 -43.696636)
		(end 209.051144 -43.696636)
		(width 0.127)
		(layer "In5.Cu")
		(net "SPI_DATA0_1")
	)
	(segment
		(start 230.100124 -36.752276)
		(end 230.100124 -36.500054)
		(width 0.1016)
		(layer "In5.Cu")
		(net "SPI_DATA0_1")
	)
	(segment
		(start 229.697026 -42.747692)
		(end 229.697026 -37.155374)
		(width 0.1016)
		(layer "In5.Cu")
		(net "SPI_DATA0_1")
	)
	(segment
		(start 229.697026 -37.155374)
		(end 230.100124 -36.752276)
		(width 0.1016)
		(layer "In5.Cu")
		(net "SPI_DATA0_1")
	)
	(segment
		(start 209.61858 -43.1292)
		(end 215.045544 -43.1292)
		(width 0.127)
		(layer "In5.Cu")
		(net "SPI_DATA0_1")
	)
	(segment
		(start 215.0618 -43.145456)
		(end 224.374202 -43.145456)
		(width 0.127)
		(layer "In5.Cu")
		(net "SPI_DATA0_1")
	)
	(segment
		(start 215.045544 -43.1292)
		(end 215.0618 -43.145456)
		(width 0.127)
		(layer "In5.Cu")
		(net "SPI_DATA0_1")
	)
	(segment
		(start 204.02931 -44.2087)
		(end 204.541374 -43.696636)
		(width 0.127)
		(layer "In5.Cu")
		(net "SPI_DATA0_1")
	)
	(segment
		(start 224.415604 -43.104054)
		(end 229.340664 -43.104054)
		(width 0.1016)
		(layer "In5.Cu")
		(net "SPI_DATA0_1")
	)
	(segment
		(start 229.340664 -43.104054)
		(end 229.697026 -42.747692)
		(width 0.1016)
		(layer "In5.Cu")
		(net "SPI_DATA0_1")
	)
	(segment
		(start 209.051144 -43.696636)
		(end 209.61858 -43.1292)
		(width 0.127)
		(layer "In5.Cu")
		(net "SPI_DATA0_1")
	)
	(segment
		(start 224.374202 -43.145456)
		(end 224.415604 -43.104054)
		(width 0.1016)
		(layer "In5.Cu")
		(net "SPI_DATA0_1")
	)
	(segment
		(start 139.560046 -73.931526)
		(end 140.734796 -73.931526)
		(width 0.12065)
		(layer "F.Cu")
		(net "SPI_DATA0_0")
	)
	(segment
		(start 138.428222 -72.799702)
		(end 138.428222 -71.463408)
		(width 0.12065)
		(layer "F.Cu")
		(net "SPI_DATA0_0")
	)
	(segment
		(start 139.560046 -73.931526)
		(end 138.428222 -72.799702)
		(width 0.12065)
		(layer "F.Cu")
		(net "SPI_DATA0_0")
	)
	(segment
		(start 230.599996 -37.999924)
		(end 230.100124 -37.500052)
		(width 0.12065)
		(layer "F.Cu")
		(net "SPI_DATA0_0")
	)
	(via
		(at 230.100124 -37.500052)
		(size 0.4572)
		(drill 0.2032)
		(layers "F.Cu" "B.Cu")
		(net "SPI_DATA0_0")
	)
	(via
		(at 140.734796 -73.931526)
		(size 0.7112)
		(drill 0.3556)
		(layers "F.Cu" "B.Cu")
		(net "SPI_DATA0_0")
	)
	(via
		(at 193.944748 -48.142906)
		(size 0.508)
		(drill 0.254)
		(layers "F.Cu" "B.Cu")
		(net "SPI_DATA0_0")
	)
	(via
		(at 138.428222 -71.463408)
		(size 0.508)
		(drill 0.254)
		(layers "F.Cu" "B.Cu")
		(net "SPI_DATA0_0")
	)
	(segment
		(start 164.020754 -52.29733)
		(end 149.867874 -52.29733)
		(width 0.12065)
		(layer "B.Cu")
		(net "SPI_DATA0_0")
	)
	(segment
		(start 193.944748 -48.142906)
		(end 193.614548 -47.812706)
		(width 0.12065)
		(layer "B.Cu")
		(net "SPI_DATA0_0")
	)
	(segment
		(start 193.44005 -47.812706)
		(end 190.687198 -45.059854)
		(width 0.12065)
		(layer "B.Cu")
		(net "SPI_DATA0_0")
	)
	(segment
		(start 137.00506 -63.59017)
		(end 137.00506 -70.040246)
		(width 0.12065)
		(layer "B.Cu")
		(net "SPI_DATA0_0")
	)
	(segment
		(start 144.111726 -57.540398)
		(end 144.111726 -57.553606)
		(width 0.12065)
		(layer "B.Cu")
		(net "SPI_DATA0_0")
	)
	(segment
		(start 147.861274 -54.30393)
		(end 147.348194 -54.30393)
		(width 0.12065)
		(layer "B.Cu")
		(net "SPI_DATA0_0")
	)
	(segment
		(start 140.58519 -60.01004)
		(end 137.00506 -63.59017)
		(width 0.12065)
		(layer "B.Cu")
		(net "SPI_DATA0_0")
	)
	(segment
		(start 171.25823 -45.059854)
		(end 164.020754 -52.29733)
		(width 0.12065)
		(layer "B.Cu")
		(net "SPI_DATA0_0")
	)
	(segment
		(start 137.00506 -70.040246)
		(end 138.428222 -71.463408)
		(width 0.12065)
		(layer "B.Cu")
		(net "SPI_DATA0_0")
	)
	(segment
		(start 190.687198 -45.059854)
		(end 171.25823 -45.059854)
		(width 0.12065)
		(layer "B.Cu")
		(net "SPI_DATA0_0")
	)
	(segment
		(start 149.867874 -52.29733)
		(end 147.861274 -54.30393)
		(width 0.12065)
		(layer "B.Cu")
		(net "SPI_DATA0_0")
	)
	(segment
		(start 144.111726 -57.553606)
		(end 141.655292 -60.01004)
		(width 0.12065)
		(layer "B.Cu")
		(net "SPI_DATA0_0")
	)
	(segment
		(start 147.348194 -54.30393)
		(end 144.111726 -57.540398)
		(width 0.12065)
		(layer "B.Cu")
		(net "SPI_DATA0_0")
	)
	(segment
		(start 193.614548 -47.812706)
		(end 193.44005 -47.812706)
		(width 0.12065)
		(layer "B.Cu")
		(net "SPI_DATA0_0")
	)
	(segment
		(start 141.655292 -60.01004)
		(end 140.58519 -60.01004)
		(width 0.12065)
		(layer "B.Cu")
		(net "SPI_DATA0_0")
	)
	(segment
		(start 224.057972 -43.89755)
		(end 224.257362 -44.09694)
		(width 0.1016)
		(layer "In5.Cu")
		(net "SPI_DATA0_0")
	)
	(segment
		(start 214.714836 -43.89755)
		(end 224.057972 -43.89755)
		(width 0.127)
		(layer "In5.Cu")
		(net "SPI_DATA0_0")
	)
	(segment
		(start 197.423024 -49.31791)
		(end 197.588124 -49.15281)
		(width 0.127)
		(layer "In5.Cu")
		(net "SPI_DATA0_0")
	)
	(segment
		(start 230.697024 -43.74769)
		(end 230.697024 -38.539928)
		(width 0.1016)
		(layer "In5.Cu")
		(net "SPI_DATA0_0")
	)
	(segment
		(start 214.467186 -44.1452)
		(end 214.714836 -43.89755)
		(width 0.127)
		(layer "In5.Cu")
		(net "SPI_DATA0_0")
	)
	(segment
		(start 197.588124 -49.15281)
		(end 197.588378 -49.15281)
		(width 0.127)
		(layer "In5.Cu")
		(net "SPI_DATA0_0")
	)
	(segment
		(start 230.347774 -44.09694)
		(end 230.697024 -43.74769)
		(width 0.1016)
		(layer "In5.Cu")
		(net "SPI_DATA0_0")
	)
	(segment
		(start 197.588378 -49.15281)
		(end 197.703694 -49.037494)
		(width 0.127)
		(layer "In5.Cu")
		(net "SPI_DATA0_0")
	)
	(segment
		(start 210.039966 -44.1452)
		(end 214.467186 -44.1452)
		(width 0.127)
		(layer "In5.Cu")
		(net "SPI_DATA0_0")
	)
	(segment
		(start 224.257362 -44.09694)
		(end 230.347774 -44.09694)
		(width 0.1016)
		(layer "In5.Cu")
		(net "SPI_DATA0_0")
	)
	(segment
		(start 193.944748 -48.142906)
		(end 195.119752 -49.31791)
		(width 0.127)
		(layer "In5.Cu")
		(net "SPI_DATA0_0")
	)
	(segment
		(start 195.119752 -49.31791)
		(end 197.423024 -49.31791)
		(width 0.127)
		(layer "In5.Cu")
		(net "SPI_DATA0_0")
	)
	(segment
		(start 230.100124 -37.943028)
		(end 230.100124 -37.500052)
		(width 0.1016)
		(layer "In5.Cu")
		(net "SPI_DATA0_0")
	)
	(segment
		(start 205.147672 -49.037494)
		(end 210.039966 -44.1452)
		(width 0.127)
		(layer "In5.Cu")
		(net "SPI_DATA0_0")
	)
	(segment
		(start 197.703694 -49.037494)
		(end 205.147672 -49.037494)
		(width 0.127)
		(layer "In5.Cu")
		(net "SPI_DATA0_0")
	)
	(segment
		(start 230.697024 -38.539928)
		(end 230.100124 -37.943028)
		(width 0.1016)
		(layer "In5.Cu")
		(net "SPI_DATA0_0")
	)
	(segment
		(start 230.599996 -38.999922)
		(end 230.100124 -38.50005)
		(width 0.12065)
		(layer "F.Cu")
		(net "SPI_CSB0_1")
	)
	(via
		(at 230.100124 -38.50005)
		(size 0.4572)
		(drill 0.2032)
		(layers "F.Cu" "B.Cu")
		(net "SPI_CSB0_1")
	)
	(segment
		(start 230.548434 -38.94836)
		(end 230.100124 -38.50005)
		(width 0.12065)
		(layer "B.Cu")
		(net "SPI_CSB0_1")
	)
	(segment
		(start 230.63708 -38.94836)
		(end 230.548434 -38.94836)
		(width 0.12065)
		(layer "B.Cu")
		(net "SPI_CSB0_1")
	)
	(segment
		(start 131.011168 -60.194698)
		(end 131.470146 -60.194698)
		(width 0.12065)
		(layer "F.Cu")
		(net "SPI_CSB0_0")
	)
	(segment
		(start 131.710684 -57.432448)
		(end 130.774694 -58.368438)
		(width 0.12065)
		(layer "F.Cu")
		(net "SPI_CSB0_0")
	)
	(segment
		(start 137.108692 -58.129424)
		(end 136.869678 -57.89041)
		(width 0.12065)
		(layer "F.Cu")
		(net "SPI_CSB0_0")
	)
	(segment
		(start 136.398762 -57.89041)
		(end 135.9408 -57.432448)
		(width 0.12065)
		(layer "F.Cu")
		(net "SPI_CSB0_0")
	)
	(segment
		(start 130.774694 -58.368438)
		(end 130.774694 -59.958224)
		(width 0.12065)
		(layer "F.Cu")
		(net "SPI_CSB0_0")
	)
	(segment
		(start 131.959604 -61.397388)
		(end 131.959604 -63.223902)
		(width 0.12065)
		(layer "F.Cu")
		(net "SPI_CSB0_0")
	)
	(segment
		(start 130.774694 -59.958224)
		(end 131.011168 -60.194698)
		(width 0.12065)
		(layer "F.Cu")
		(net "SPI_CSB0_0")
	)
	(segment
		(start 230.599996 -39.99992)
		(end 230.100124 -39.500048)
		(width 0.12065)
		(layer "F.Cu")
		(net "SPI_CSB0_0")
	)
	(segment
		(start 135.9408 -57.432448)
		(end 131.710684 -57.432448)
		(width 0.12065)
		(layer "F.Cu")
		(net "SPI_CSB0_0")
	)
	(segment
		(start 131.470146 -60.194698)
		(end 131.470146 -60.90793)
		(width 0.12065)
		(layer "F.Cu")
		(net "SPI_CSB0_0")
	)
	(segment
		(start 131.470146 -60.90793)
		(end 131.959604 -61.397388)
		(width 0.12065)
		(layer "F.Cu")
		(net "SPI_CSB0_0")
	)
	(segment
		(start 136.869678 -57.89041)
		(end 136.398762 -57.89041)
		(width 0.12065)
		(layer "F.Cu")
		(net "SPI_CSB0_0")
	)
	(via
		(at 230.100124 -39.500048)
		(size 0.4572)
		(drill 0.2032)
		(layers "F.Cu" "B.Cu")
		(net "SPI_CSB0_0")
	)
	(via
		(at 137.108692 -58.129424)
		(size 0.508)
		(drill 0.254)
		(layers "F.Cu" "B.Cu")
		(net "SPI_CSB0_0")
	)
	(via
		(at 204.89291 -44.2087)
		(size 0.508)
		(drill 0.254)
		(layers "F.Cu" "B.Cu")
		(net "SPI_CSB0_0")
	)
	(via
		(at 185.8772 -42.164)
		(size 0.7112)
		(drill 0.3556)
		(layers "F.Cu" "B.Cu")
		(net "SPI_CSB0_0")
	)
	(segment
		(start 191.808608 -42.164)
		(end 193.715894 -44.071286)
		(width 0.12065)
		(layer "B.Cu")
		(net "SPI_CSB0_0")
	)
	(segment
		(start 185.8772 -42.164)
		(end 191.808608 -42.164)
		(width 0.12065)
		(layer "B.Cu")
		(net "SPI_CSB0_0")
	)
	(segment
		(start 138.83894 -57.203848)
		(end 138.325352 -57.203848)
		(width 0.12065)
		(layer "B.Cu")
		(net "SPI_CSB0_0")
	)
	(segment
		(start 198.520812 -42.380154)
		(end 203.064364 -42.380154)
		(width 0.12065)
		(layer "B.Cu")
		(net "SPI_CSB0_0")
	)
	(segment
		(start 137.399776 -58.129424)
		(end 137.108692 -58.129424)
		(width 0.12065)
		(layer "B.Cu")
		(net "SPI_CSB0_0")
	)
	(segment
		(start 193.715894 -44.071286)
		(end 196.82968 -44.071286)
		(width 0.12065)
		(layer "B.Cu")
		(net "SPI_CSB0_0")
	)
	(segment
		(start 138.325352 -57.203848)
		(end 137.399776 -58.129424)
		(width 0.12065)
		(layer "B.Cu")
		(net "SPI_CSB0_0")
	)
	(segment
		(start 141.46784 -54.742842)
		(end 141.299946 -54.742842)
		(width 0.12065)
		(layer "B.Cu")
		(net "SPI_CSB0_0")
	)
	(segment
		(start 170.229022 -42.164)
		(end 163.028376 -49.364646)
		(width 0.12065)
		(layer "B.Cu")
		(net "SPI_CSB0_0")
	)
	(segment
		(start 203.064364 -42.380154)
		(end 204.89291 -44.2087)
		(width 0.12065)
		(layer "B.Cu")
		(net "SPI_CSB0_0")
	)
	(segment
		(start 141.299946 -54.742842)
		(end 138.83894 -57.203848)
		(width 0.12065)
		(layer "B.Cu")
		(net "SPI_CSB0_0")
	)
	(segment
		(start 146.846036 -49.364646)
		(end 141.46784 -54.742842)
		(width 0.12065)
		(layer "B.Cu")
		(net "SPI_CSB0_0")
	)
	(segment
		(start 163.028376 -49.364646)
		(end 146.846036 -49.364646)
		(width 0.12065)
		(layer "B.Cu")
		(net "SPI_CSB0_0")
	)
	(segment
		(start 196.82968 -44.071286)
		(end 198.520812 -42.380154)
		(width 0.12065)
		(layer "B.Cu")
		(net "SPI_CSB0_0")
	)
	(segment
		(start 185.8772 -42.164)
		(end 170.229022 -42.164)
		(width 0.12065)
		(layer "B.Cu")
		(net "SPI_CSB0_0")
	)
	(segment
		(start 230.493824 -43.663362)
		(end 230.493824 -39.893748)
		(width 0.1016)
		(layer "In5.Cu")
		(net "SPI_CSB0_0")
	)
	(segment
		(start 224.36836 -43.6372)
		(end 224.47123 -43.74007)
		(width 0.127)
		(layer "In5.Cu")
		(net "SPI_CSB0_0")
	)
	(segment
		(start 209.2579 -44.2087)
		(end 209.8294 -43.6372)
		(width 0.127)
		(layer "In5.Cu")
		(net "SPI_CSB0_0")
	)
	(segment
		(start 230.493824 -39.893748)
		(end 230.100124 -39.500048)
		(width 0.1016)
		(layer "In5.Cu")
		(net "SPI_CSB0_0")
	)
	(segment
		(start 209.8294 -43.6372)
		(end 224.36836 -43.6372)
		(width 0.127)
		(layer "In5.Cu")
		(net "SPI_CSB0_0")
	)
	(segment
		(start 224.6249 -43.89374)
		(end 230.263446 -43.89374)
		(width 0.1016)
		(layer "In5.Cu")
		(net "SPI_CSB0_0")
	)
	(segment
		(start 224.47123 -43.74007)
		(end 224.6249 -43.89374)
		(width 0.1016)
		(layer "In5.Cu")
		(net "SPI_CSB0_0")
	)
	(segment
		(start 230.263446 -43.89374)
		(end 230.493824 -43.663362)
		(width 0.1016)
		(layer "In5.Cu")
		(net "SPI_CSB0_0")
	)
	(segment
		(start 204.89291 -44.2087)
		(end 209.2579 -44.2087)
		(width 0.127)
		(layer "In5.Cu")
		(net "SPI_CSB0_0")
	)
	(segment
		(start 230.599996 -35.999928)
		(end 230.100124 -35.500056)
		(width 0.12065)
		(layer "F.Cu")
		(net "SPI_CLK0")
	)
	(segment
		(start 136.386062 -74.88174)
		(end 136.875774 -74.392028)
		(width 0.12065)
		(layer "F.Cu")
		(net "SPI_CLK0")
	)
	(segment
		(start 136.875774 -74.392028)
		(end 136.875774 -72.968104)
		(width 0.12065)
		(layer "F.Cu")
		(net "SPI_CLK0")
	)
	(segment
		(start 136.875774 -72.968104)
		(end 137.028174 -72.815704)
		(width 0.12065)
		(layer "F.Cu")
		(net "SPI_CLK0")
	)
	(via
		(at 137.028174 -72.815704)
		(size 0.508)
		(drill 0.254)
		(layers "F.Cu" "B.Cu")
		(net "SPI_CLK0")
	)
	(via
		(at 190.975234 -44.458636)
		(size 0.7112)
		(drill 0.3556)
		(layers "F.Cu" "B.Cu")
		(net "SPI_CLK0")
	)
	(via
		(at 230.100124 -35.500056)
		(size 0.4572)
		(drill 0.2032)
		(layers "F.Cu" "B.Cu")
		(net "SPI_CLK0")
	)
	(via
		(at 194.8053 -48.070008)
		(size 0.508)
		(drill 0.254)
		(layers "F.Cu" "B.Cu")
		(net "SPI_CLK0")
	)
	(segment
		(start 163.742624 -51.66868)
		(end 170.9801 -44.431204)
		(width 0.12065)
		(layer "B.Cu")
		(net "SPI_CLK0")
	)
	(segment
		(start 134.8232 -70.61073)
		(end 134.8232 -65.588642)
		(width 0.12065)
		(layer "B.Cu")
		(net "SPI_CLK0")
	)
	(segment
		(start 190.947802 -44.431204)
		(end 190.975234 -44.458636)
		(width 0.12065)
		(layer "B.Cu")
		(net "SPI_CLK0")
	)
	(segment
		(start 148.743162 -51.66868)
		(end 163.742624 -51.66868)
		(width 0.12065)
		(layer "B.Cu")
		(net "SPI_CLK0")
	)
	(segment
		(start 170.9801 -44.431204)
		(end 190.947802 -44.431204)
		(width 0.12065)
		(layer "B.Cu")
		(net "SPI_CLK0")
	)
	(segment
		(start 141.030452 -59.381136)
		(end 148.743162 -51.66868)
		(width 0.12065)
		(layer "B.Cu")
		(net "SPI_CLK0")
	)
	(segment
		(start 134.8232 -65.588642)
		(end 136.37641 -64.035432)
		(width 0.12065)
		(layer "B.Cu")
		(net "SPI_CLK0")
	)
	(segment
		(start 137.028174 -72.815704)
		(end 134.8232 -70.61073)
		(width 0.12065)
		(layer "B.Cu")
		(net "SPI_CLK0")
	)
	(segment
		(start 136.37641 -64.035432)
		(end 136.37641 -63.329566)
		(width 0.12065)
		(layer "B.Cu")
		(net "SPI_CLK0")
	)
	(segment
		(start 136.37641 -63.329566)
		(end 140.32484 -59.381136)
		(width 0.12065)
		(layer "B.Cu")
		(net "SPI_CLK0")
	)
	(segment
		(start 193.581782 -47.065184)
		(end 190.975234 -44.458636)
		(width 0.12065)
		(layer "B.Cu")
		(net "SPI_CLK0")
	)
	(segment
		(start 194.8053 -48.070008)
		(end 193.800476 -47.065184)
		(width 0.12065)
		(layer "B.Cu")
		(net "SPI_CLK0")
	)
	(segment
		(start 140.32484 -59.381136)
		(end 141.030452 -59.381136)
		(width 0.12065)
		(layer "B.Cu")
		(net "SPI_CLK0")
	)
	(segment
		(start 193.800476 -47.065184)
		(end 193.581782 -47.065184)
		(width 0.12065)
		(layer "B.Cu")
		(net "SPI_CLK0")
	)
	(segment
		(start 224.3328 -42.9006)
		(end 229.25659 -42.9006)
		(width 0.1016)
		(layer "In5.Cu")
		(net "SPI_CLK0")
	)
	(segment
		(start 201.232008 -43.061636)
		(end 208.356708 -43.061636)
		(width 0.127)
		(layer "In5.Cu")
		(net "SPI_CLK0")
	)
	(segment
		(start 208.356708 -43.061636)
		(end 208.924144 -42.4942)
		(width 0.127)
		(layer "In5.Cu")
		(net "SPI_CLK0")
	)
	(segment
		(start 208.924144 -42.4942)
		(end 215.1888 -42.4942)
		(width 0.127)
		(layer "In5.Cu")
		(net "SPI_CLK0")
	)
	(segment
		(start 199.157082 -48.402494)
		(end 200.073514 -47.486062)
		(width 0.127)
		(layer "In5.Cu")
		(net "SPI_CLK0")
	)
	(segment
		(start 215.1888 -42.4942)
		(end 215.601042 -42.906442)
		(width 0.127)
		(layer "In5.Cu")
		(net "SPI_CLK0")
	)
	(segment
		(start 197.440296 -48.402494)
		(end 199.157082 -48.402494)
		(width 0.127)
		(layer "In5.Cu")
		(net "SPI_CLK0")
	)
	(segment
		(start 194.8053 -48.070008)
		(end 195.04279 -48.307498)
		(width 0.127)
		(layer "In5.Cu")
		(net "SPI_CLK0")
	)
	(segment
		(start 215.601042 -42.906442)
		(end 224.326958 -42.906442)
		(width 0.127)
		(layer "In5.Cu")
		(net "SPI_CLK0")
	)
	(segment
		(start 197.15988 -48.68291)
		(end 197.440296 -48.402494)
		(width 0.127)
		(layer "In5.Cu")
		(net "SPI_CLK0")
	)
	(segment
		(start 195.414392 -48.68291)
		(end 197.15988 -48.68291)
		(width 0.127)
		(layer "In5.Cu")
		(net "SPI_CLK0")
	)
	(segment
		(start 195.04279 -48.311308)
		(end 195.414392 -48.68291)
		(width 0.127)
		(layer "In5.Cu")
		(net "SPI_CLK0")
	)
	(segment
		(start 200.073514 -44.22013)
		(end 201.232008 -43.061636)
		(width 0.127)
		(layer "In5.Cu")
		(net "SPI_CLK0")
	)
	(segment
		(start 229.493826 -36.54933)
		(end 230.100124 -35.943032)
		(width 0.1016)
		(layer "In5.Cu")
		(net "SPI_CLK0")
	)
	(segment
		(start 200.073514 -47.486062)
		(end 200.073514 -44.22013)
		(width 0.127)
		(layer "In5.Cu")
		(net "SPI_CLK0")
	)
	(segment
		(start 229.25659 -42.9006)
		(end 229.493826 -42.663364)
		(width 0.1016)
		(layer "In5.Cu")
		(net "SPI_CLK0")
	)
	(segment
		(start 195.04279 -48.307498)
		(end 195.04279 -48.311308)
		(width 0.127)
		(layer "In5.Cu")
		(net "SPI_CLK0")
	)
	(segment
		(start 224.326958 -42.906442)
		(end 224.3328 -42.9006)
		(width 0.127)
		(layer "In5.Cu")
		(net "SPI_CLK0")
	)
	(segment
		(start 230.100124 -35.943032)
		(end 230.100124 -35.500056)
		(width 0.1016)
		(layer "In5.Cu")
		(net "SPI_CLK0")
	)
	(segment
		(start 229.493826 -42.663364)
		(end 229.493826 -36.54933)
		(width 0.1016)
		(layer "In5.Cu")
		(net "SPI_CLK0")
	)
	(segment
		(start 87.716614 -82.79003)
		(end 89.281 -82.79003)
		(width 0.12065)
		(layer "F.Cu")
		(net "SMART_UART_EN")
	)
	(segment
		(start 89.281 -82.79003)
		(end 89.47023 -82.6008)
		(width 0.12065)
		(layer "F.Cu")
		(net "SMART_UART_EN")
	)
	(segment
		(start 90.043 -82.6008)
		(end 90.10015 -82.6008)
		(width 0.12065)
		(layer "F.Cu")
		(net "SMART_UART_EN")
	)
	(segment
		(start 89.47023 -82.6008)
		(end 90.043 -82.6008)
		(width 0.12065)
		(layer "F.Cu")
		(net "SMART_UART_EN")
	)
	(segment
		(start 90.2208 -82.72145)
		(end 90.2208 -83.5025)
		(width 0.12065)
		(layer "F.Cu")
		(net "SMART_UART_EN")
	)
	(segment
		(start 90.10015 -82.6008)
		(end 90.2208 -82.72145)
		(width 0.12065)
		(layer "F.Cu")
		(net "SMART_UART_EN")
	)
	(via
		(at 90.043 -82.6008)
		(size 0.7112)
		(drill 0.3556)
		(layers "F.Cu" "B.Cu")
		(net "SMART_UART_EN")
	)
	(segment
		(start 267.9954 -2.286)
		(end 266.954 -2.286)
		(width 0.12065)
		(layer "F.Cu")
		(net "SLIDE_SW_PMC_RST#")
	)
	(segment
		(start 266.941554 -1.638046)
		(end 266.378944 -2.200656)
		(width 0.12065)
		(layer "F.Cu")
		(net "SLIDE_SW_PMC_RST#")
	)
	(segment
		(start 266.954 -2.286)
		(end 266.393168 -2.846832)
		(width 0.12065)
		(layer "F.Cu")
		(net "SLIDE_SW_PMC_RST#")
	)
	(segment
		(start 268.2748 -2.5654)
		(end 267.9954 -2.286)
		(width 0.12065)
		(layer "F.Cu")
		(net "SLIDE_SW_PMC_RST#")
	)
	(segment
		(start 266.941554 -0.432308)
		(end 266.941554 -1.638046)
		(width 0.12065)
		(layer "F.Cu")
		(net "SLIDE_SW_PMC_RST#")
	)
	(segment
		(start 266.378944 -2.200656)
		(end 266.378944 -2.846832)
		(width 0.12065)
		(layer "F.Cu")
		(net "SLIDE_SW_PMC_RST#")
	)
	(segment
		(start 266.393168 -2.846832)
		(end 266.378944 -2.846832)
		(width 0.12065)
		(layer "F.Cu")
		(net "SLIDE_SW_PMC_RST#")
	)
	(via
		(at 347.60916 -42.998136)
		(size 0.7112)
		(drill 0.3556)
		(layers "F.Cu" "B.Cu")
		(net "SLIDE_SW_PMC_RST#")
	)
	(via
		(at 268.2748 -2.5654)
		(size 0.508)
		(drill 0.254)
		(layers "F.Cu" "B.Cu")
		(net "SLIDE_SW_PMC_RST#")
	)
	(segment
		(start 277.819612 1.762252)
		(end 269.812516 1.762252)
		(width 0.12065)
		(layer "B.Cu")
		(net "SLIDE_SW_PMC_RST#")
	)
	(segment
		(start 349.18396 -42.998136)
		(end 347.60916 -42.998136)
		(width 0.12065)
		(layer "B.Cu")
		(net "SLIDE_SW_PMC_RST#")
	)
	(segment
		(start 269.565882 1.526794)
		(end 268.351 0.311912)
		(width 0.12065)
		(layer "B.Cu")
		(net "SLIDE_SW_PMC_RST#")
	)
	(segment
		(start 326.429878 -2.79908)
		(end 282.380944 -2.79908)
		(width 0.12065)
		(layer "B.Cu")
		(net "SLIDE_SW_PMC_RST#")
	)
	(segment
		(start 330.777596 -30.563058)
		(end 330.777596 -25.21839)
		(width 0.12065)
		(layer "B.Cu")
		(net "SLIDE_SW_PMC_RST#")
	)
	(segment
		(start 268.351 -2.4892)
		(end 268.2748 -2.5654)
		(width 0.12065)
		(layer "B.Cu")
		(net "SLIDE_SW_PMC_RST#")
	)
	(segment
		(start 282.380944 -2.79908)
		(end 277.819612 1.762252)
		(width 0.12065)
		(layer "B.Cu")
		(net "SLIDE_SW_PMC_RST#")
	)
	(segment
		(start 331.1271 -30.912562)
		(end 330.777596 -30.563058)
		(width 0.12065)
		(layer "B.Cu")
		(net "SLIDE_SW_PMC_RST#")
	)
	(segment
		(start 349.196406 -42.98569)
		(end 349.18396 -42.998136)
		(width 0.12065)
		(layer "B.Cu")
		(net "SLIDE_SW_PMC_RST#")
	)
	(segment
		(start 334.83677 -42.998136)
		(end 331.1271 -39.288466)
		(width 0.12065)
		(layer "B.Cu")
		(net "SLIDE_SW_PMC_RST#")
	)
	(segment
		(start 329.86218 -6.231382)
		(end 326.429878 -2.79908)
		(width 0.12065)
		(layer "B.Cu")
		(net "SLIDE_SW_PMC_RST#")
	)
	(segment
		(start 330.777596 -25.21839)
		(end 329.86218 -24.302974)
		(width 0.12065)
		(layer "B.Cu")
		(net "SLIDE_SW_PMC_RST#")
	)
	(segment
		(start 269.577058 1.526794)
		(end 269.565882 1.526794)
		(width 0.12065)
		(layer "B.Cu")
		(net "SLIDE_SW_PMC_RST#")
	)
	(segment
		(start 269.812516 1.762252)
		(end 269.577058 1.526794)
		(width 0.12065)
		(layer "B.Cu")
		(net "SLIDE_SW_PMC_RST#")
	)
	(segment
		(start 329.86218 -24.302974)
		(end 329.86218 -6.231382)
		(width 0.12065)
		(layer "B.Cu")
		(net "SLIDE_SW_PMC_RST#")
	)
	(segment
		(start 268.351 0.311912)
		(end 268.351 -2.4892)
		(width 0.12065)
		(layer "B.Cu")
		(net "SLIDE_SW_PMC_RST#")
	)
	(segment
		(start 347.60916 -42.998136)
		(end 334.83677 -42.998136)
		(width 0.12065)
		(layer "B.Cu")
		(net "SLIDE_SW_PMC_RST#")
	)
	(segment
		(start 331.1271 -39.288466)
		(end 331.1271 -30.912562)
		(width 0.12065)
		(layer "B.Cu")
		(net "SLIDE_SW_PMC_RST#")
	)
	(segment
		(start 336.423 -86.946232)
		(end 330.959968 -81.4832)
		(width 0.12065)
		(layer "F.Cu")
		(net "SHUTDOWN_RELEASE")
	)
	(segment
		(start 336.423 -155.575)
		(end 336.423 -86.946232)
		(width 0.12065)
		(layer "F.Cu")
		(net "SHUTDOWN_RELEASE")
	)
	(segment
		(start 300.566328 -43.34129)
		(end 326.74179 -43.34129)
		(width 0.12065)
		(layer "F.Cu")
		(net "SHUTDOWN_RELEASE")
	)
	(segment
		(start 326.74179 -43.34129)
		(end 327.908412 -44.507912)
		(width 0.12065)
		(layer "F.Cu")
		(net "SHUTDOWN_RELEASE")
	)
	(segment
		(start 262.10006 -224.33026)
		(end 261.671054 -223.901254)
		(width 0.12065)
		(layer "F.Cu")
		(net "SHUTDOWN_RELEASE")
	)
	(segment
		(start 295.31564 -48.591978)
		(end 300.566328 -43.34129)
		(width 0.12065)
		(layer "F.Cu")
		(net "SHUTDOWN_RELEASE")
	)
	(segment
		(start 332.66253 -44.90593)
		(end 328.30643 -44.90593)
		(width 0.12065)
		(layer "F.Cu")
		(net "SHUTDOWN_RELEASE")
	)
	(segment
		(start 330.2 -161.798)
		(end 336.423 -155.575)
		(width 0.12065)
		(layer "F.Cu")
		(net "SHUTDOWN_RELEASE")
	)
	(segment
		(start 261.671054 -223.901254)
		(end 261.671054 -161.853118)
		(width 0.12065)
		(layer "F.Cu")
		(net "SHUTDOWN_RELEASE")
	)
	(segment
		(start 295.31564 -75.360022)
		(end 295.31564 -48.591978)
		(width 0.12065)
		(layer "F.Cu")
		(net "SHUTDOWN_RELEASE")
	)
	(segment
		(start 330.959968 -81.4832)
		(end 301.438818 -81.4832)
		(width 0.12065)
		(layer "F.Cu")
		(net "SHUTDOWN_RELEASE")
	)
	(segment
		(start 261.671054 -161.853118)
		(end 254.503936 -154.686)
		(width 0.12065)
		(layer "F.Cu")
		(net "SHUTDOWN_RELEASE")
	)
	(segment
		(start 328.30643 -44.90593)
		(end 327.908412 -44.507912)
		(width 0.12065)
		(layer "F.Cu")
		(net "SHUTDOWN_RELEASE")
	)
	(segment
		(start 262.10006 -225.54438)
		(end 262.10006 -224.33026)
		(width 0.12065)
		(layer "F.Cu")
		(net "SHUTDOWN_RELEASE")
	)
	(segment
		(start 301.438818 -81.4832)
		(end 295.31564 -75.360022)
		(width 0.12065)
		(layer "F.Cu")
		(net "SHUTDOWN_RELEASE")
	)
	(segment
		(start 333.060548 -44.507912)
		(end 332.66253 -44.90593)
		(width 0.12065)
		(layer "F.Cu")
		(net "SHUTDOWN_RELEASE")
	)
	(segment
		(start 243.5606 -154.686)
		(end 243.0526 -154.178)
		(width 0.12065)
		(layer "F.Cu")
		(net "SHUTDOWN_RELEASE")
	)
	(segment
		(start 254.503936 -154.686)
		(end 243.5606 -154.686)
		(width 0.12065)
		(layer "F.Cu")
		(net "SHUTDOWN_RELEASE")
	)
	(via
		(at 243.0526 -154.178)
		(size 0.508)
		(drill 0.254)
		(layers "F.Cu" "B.Cu")
		(net "SHUTDOWN_RELEASE")
	)
	(via
		(at 330.2 -161.798)
		(size 0.508)
		(drill 0.254)
		(layers "F.Cu" "B.Cu")
		(net "SHUTDOWN_RELEASE")
	)
	(via
		(at 322.326 -154.686)
		(size 0.7112)
		(drill 0.3556)
		(layers "F.Cu" "B.Cu")
		(net "SHUTDOWN_RELEASE")
	)
	(segment
		(start 330.2 -161.798)
		(end 323.088 -154.686)
		(width 0.12065)
		(layer "B.Cu")
		(net "SHUTDOWN_RELEASE")
	)
	(segment
		(start 243.5606 -154.686)
		(end 322.326 -154.686)
		(width 0.12065)
		(layer "B.Cu")
		(net "SHUTDOWN_RELEASE")
	)
	(segment
		(start 323.088 -154.686)
		(end 322.326 -154.686)
		(width 0.12065)
		(layer "B.Cu")
		(net "SHUTDOWN_RELEASE")
	)
	(segment
		(start 243.0526 -154.178)
		(end 243.5606 -154.686)
		(width 0.12065)
		(layer "B.Cu")
		(net "SHUTDOWN_RELEASE")
	)
	(segment
		(start 89.662 -81.788)
		(end 89.16035 -82.28965)
		(width 0.12065)
		(layer "F.Cu")
		(net "SAS_SMART_R_TX")
	)
	(segment
		(start 89.662 -81.0006)
		(end 89.662 -81.3562)
		(width 0.12065)
		(layer "F.Cu")
		(net "SAS_SMART_R_TX")
	)
	(segment
		(start 88.4047 -80.899)
		(end 89.5604 -80.899)
		(width 0.12065)
		(layer "F.Cu")
		(net "SAS_SMART_R_TX")
	)
	(segment
		(start 89.662 -81.3562)
		(end 89.662 -81.788)
		(width 0.12065)
		(layer "F.Cu")
		(net "SAS_SMART_R_TX")
	)
	(segment
		(start 89.16035 -82.28965)
		(end 87.716614 -82.28965)
		(width 0.12065)
		(layer "F.Cu")
		(net "SAS_SMART_R_TX")
	)
	(segment
		(start 89.5604 -80.899)
		(end 89.662 -81.0006)
		(width 0.12065)
		(layer "F.Cu")
		(net "SAS_SMART_R_TX")
	)
	(via
		(at 89.662 -81.3562)
		(size 0.7112)
		(drill 0.3556)
		(layers "F.Cu" "B.Cu")
		(net "SAS_SMART_R_TX")
	)
	(segment
		(start 85.379814 -82.28965)
		(end 84.16925 -82.28965)
		(width 0.12065)
		(layer "F.Cu")
		(net "SAS_SMART_R_RX")
	)
	(segment
		(start 83.8708 -81.0006)
		(end 84.5947 -81.0006)
		(width 0.12065)
		(layer "F.Cu")
		(net "SAS_SMART_R_RX")
	)
	(segment
		(start 83.566 -81.4324)
		(end 83.566 -81.3054)
		(width 0.12065)
		(layer "F.Cu")
		(net "SAS_SMART_R_RX")
	)
	(segment
		(start 84.16925 -82.28965)
		(end 83.566 -81.6864)
		(width 0.12065)
		(layer "F.Cu")
		(net "SAS_SMART_R_RX")
	)
	(segment
		(start 83.566 -81.3054)
		(end 83.8708 -81.0006)
		(width 0.12065)
		(layer "F.Cu")
		(net "SAS_SMART_R_RX")
	)
	(segment
		(start 83.566 -81.6864)
		(end 83.566 -81.4324)
		(width 0.12065)
		(layer "F.Cu")
		(net "SAS_SMART_R_RX")
	)
	(via
		(at 83.566 -81.4324)
		(size 0.7112)
		(drill 0.3556)
		(layers "F.Cu" "B.Cu")
		(net "SAS_SMART_R_RX")
	)
	(segment
		(start 132.183886 -83.576414)
		(end 132.310886 -83.703414)
		(width 0.1524)
		(layer "F.Cu")
		(net "RTC_OSCO")
	)
	(segment
		(start 133.263386 -83.703414)
		(end 133.453886 -83.512914)
		(width 0.1524)
		(layer "F.Cu")
		(net "RTC_OSCO")
	)
	(segment
		(start 133.453886 -83.512914)
		(end 134.634986 -83.512914)
		(width 0.1524)
		(layer "F.Cu")
		(net "RTC_OSCO")
	)
	(segment
		(start 132.310886 -83.703414)
		(end 133.263386 -83.703414)
		(width 0.1524)
		(layer "F.Cu")
		(net "RTC_OSCO")
	)
	(segment
		(start 134.634986 -83.512914)
		(end 135.358886 -84.236814)
		(width 0.1524)
		(layer "F.Cu")
		(net "RTC_OSCO")
	)
	(segment
		(start 130.532886 -83.576414)
		(end 132.183886 -83.576414)
		(width 0.1524)
		(layer "F.Cu")
		(net "RTC_OSCO")
	)
	(segment
		(start 133.263386 -82.179414)
		(end 133.453886 -82.369914)
		(width 0.1524)
		(layer "F.Cu")
		(net "RTC_OSCI")
	)
	(segment
		(start 133.453886 -82.369914)
		(end 134.634986 -82.369914)
		(width 0.1524)
		(layer "F.Cu")
		(net "RTC_OSCI")
	)
	(segment
		(start 132.310886 -82.179414)
		(end 133.263386 -82.179414)
		(width 0.1524)
		(layer "F.Cu")
		(net "RTC_OSCI")
	)
	(segment
		(start 130.532886 -82.306414)
		(end 132.183886 -82.306414)
		(width 0.1524)
		(layer "F.Cu")
		(net "RTC_OSCI")
	)
	(segment
		(start 134.634986 -82.369914)
		(end 135.358886 -81.646014)
		(width 0.1524)
		(layer "F.Cu")
		(net "RTC_OSCI")
	)
	(segment
		(start 132.183886 -82.306414)
		(end 132.310886 -82.179414)
		(width 0.1524)
		(layer "F.Cu")
		(net "RTC_OSCI")
	)
	(segment
		(start 131.485386 -84.846414)
		(end 130.532886 -84.846414)
		(width 0.1524)
		(layer "F.Cu")
		(net "RTC_INT_N")
	)
	(segment
		(start 132.6769 -87.42426)
		(end 132.6769 -86.487)
		(width 0.1524)
		(layer "F.Cu")
		(net "RTC_INT_N")
	)
	(segment
		(start 132.250688 -87.850472)
		(end 132.6769 -87.42426)
		(width 0.1524)
		(layer "F.Cu")
		(net "RTC_INT_N")
	)
	(segment
		(start 132.6769 -86.487)
		(end 132.6769 -86.037928)
		(width 0.1524)
		(layer "F.Cu")
		(net "RTC_INT_N")
	)
	(segment
		(start 132.6769 -86.037928)
		(end 131.485386 -84.846414)
		(width 0.1524)
		(layer "F.Cu")
		(net "RTC_INT_N")
	)
	(via
		(at 132.250688 -87.850472)
		(size 0.7112)
		(drill 0.3556)
		(layers "F.Cu" "B.Cu")
		(net "RTC_INT_N")
	)
	(segment
		(start 123.954286 -86.116414)
		(end 123.954286 -86.472014)
		(width 0.12065)
		(layer "F.Cu")
		(net "RTC_I2C_SDA")
	)
	(segment
		(start 123.001786 -86.116414)
		(end 123.954286 -86.116414)
		(width 0.12065)
		(layer "F.Cu")
		(net "RTC_I2C_SDA")
	)
	(segment
		(start 123.954286 -86.116414)
		(end 125.452886 -86.116414)
		(width 0.12065)
		(layer "F.Cu")
		(net "RTC_I2C_SDA")
	)
	(via
		(at 123.954286 -86.472014)
		(size 0.7112)
		(drill 0.3556)
		(layers "F.Cu" "B.Cu")
		(net "RTC_I2C_SDA")
	)
	(segment
		(start 125.452886 -84.846414)
		(end 123.979686 -84.846414)
		(width 0.12065)
		(layer "F.Cu")
		(net "RTC_I2C_SCL")
	)
	(segment
		(start 123.979686 -84.846414)
		(end 123.979686 -84.490814)
		(width 0.12065)
		(layer "F.Cu")
		(net "RTC_I2C_SCL")
	)
	(segment
		(start 123.979686 -84.846414)
		(end 123.001786 -84.846414)
		(width 0.12065)
		(layer "F.Cu")
		(net "RTC_I2C_SCL")
	)
	(via
		(at 123.979686 -84.490814)
		(size 0.7112)
		(drill 0.3556)
		(layers "F.Cu" "B.Cu")
		(net "RTC_I2C_SCL")
	)
	(segment
		(start 125.452886 -83.576414)
		(end 122.38863 -83.576414)
		(width 0.1524)
		(layer "F.Cu")
		(net "RTC_CLK_OUT")
	)
	(segment
		(start 122.38863 -83.576414)
		(end 122.377454 -83.58759)
		(width 0.1524)
		(layer "F.Cu")
		(net "RTC_CLK_OUT")
	)
	(segment
		(start 264.441432 -2.282698)
		(end 265.027918 -2.869184)
		(width 0.12065)
		(layer "F.Cu")
		(net "RST_BTN#_R")
	)
	(segment
		(start 265.027918 -3.9116)
		(end 265.0871 -3.970782)
		(width 0.12065)
		(layer "F.Cu")
		(net "RST_BTN#_R")
	)
	(segment
		(start 264.441432 -0.432308)
		(end 264.441432 -2.282698)
		(width 0.12065)
		(layer "F.Cu")
		(net "RST_BTN#_R")
	)
	(segment
		(start 265.027918 -2.869184)
		(end 265.027918 -3.9116)
		(width 0.12065)
		(layer "F.Cu")
		(net "RST_BTN#_R")
	)
	(via
		(at 265.0871 -3.970782)
		(size 0.7112)
		(drill 0.3556)
		(layers "F.Cu" "B.Cu")
		(net "RST_BTN#_R")
	)
	(segment
		(start 264.138918 -2.869184)
		(end 264.138918 -3.83413)
		(width 0.12065)
		(layer "F.Cu")
		(net "RST_BTN#")
	)
	(segment
		(start 263.45642 -3.95605)
		(end 263.160256 -4.252214)
		(width 0.12065)
		(layer "F.Cu")
		(net "RST_BTN#")
	)
	(segment
		(start 264.016998 -3.95605)
		(end 263.45642 -3.95605)
		(width 0.12065)
		(layer "F.Cu")
		(net "RST_BTN#")
	)
	(segment
		(start 259.9944 -2.921)
		(end 262.198104 -5.124704)
		(width 0.12065)
		(layer "F.Cu")
		(net "RST_BTN#")
	)
	(segment
		(start 260.30174 0.730504)
		(end 260.30174 -0.514096)
		(width 0.12065)
		(layer "F.Cu")
		(net "RST_BTN#")
	)
	(segment
		(start 262.198104 -5.124704)
		(end 262.571738 -5.124704)
		(width 0.12065)
		(layer "F.Cu")
		(net "RST_BTN#")
	)
	(segment
		(start 263.160256 -4.252214)
		(end 263.160256 -4.880864)
		(width 0.12065)
		(layer "F.Cu")
		(net "RST_BTN#")
	)
	(segment
		(start 262.916416 -5.124704)
		(end 262.571738 -5.124704)
		(width 0.12065)
		(layer "F.Cu")
		(net "RST_BTN#")
	)
	(segment
		(start 263.160256 -4.880864)
		(end 262.916416 -5.124704)
		(width 0.12065)
		(layer "F.Cu")
		(net "RST_BTN#")
	)
	(segment
		(start 259.768594 1.26365)
		(end 260.30174 0.730504)
		(width 0.12065)
		(layer "F.Cu")
		(net "RST_BTN#")
	)
	(segment
		(start 264.138918 -3.83413)
		(end 264.07745 -3.895598)
		(width 0.12065)
		(layer "F.Cu")
		(net "RST_BTN#")
	)
	(segment
		(start 260.30174 -0.514096)
		(end 260.30174 -1.14046)
		(width 0.12065)
		(layer "F.Cu")
		(net "RST_BTN#")
	)
	(segment
		(start 264.07745 -3.895598)
		(end 264.016998 -3.95605)
		(width 0.12065)
		(layer "F.Cu")
		(net "RST_BTN#")
	)
	(segment
		(start 259.9944 -1.4478)
		(end 259.9944 -2.921)
		(width 0.12065)
		(layer "F.Cu")
		(net "RST_BTN#")
	)
	(segment
		(start 260.30174 -1.14046)
		(end 259.9944 -1.4478)
		(width 0.12065)
		(layer "F.Cu")
		(net "RST_BTN#")
	)
	(via
		(at 259.768594 1.26365)
		(size 0.508)
		(drill 0.254)
		(layers "F.Cu" "B.Cu")
		(net "RST_BTN#")
	)
	(via
		(at 262.571738 -5.124704)
		(size 0.7112)
		(drill 0.3556)
		(layers "F.Cu" "B.Cu")
		(net "RST_BTN#")
	)
	(segment
		(start 334.04302 -40.634666)
		(end 331.856588 -38.448234)
		(width 0.12065)
		(layer "B.Cu")
		(net "RST_BTN#")
	)
	(segment
		(start 336.09153 -41.057068)
		(end 335.669128 -40.634666)
		(width 0.12065)
		(layer "B.Cu")
		(net "RST_BTN#")
	)
	(segment
		(start 331.856588 -30.617922)
		(end 331.501496 -30.26283)
		(width 0.12065)
		(layer "B.Cu")
		(net "RST_BTN#")
	)
	(segment
		(start 336.09153 -41.057068)
		(end 342.59139 -41.057068)
		(width 0.12065)
		(layer "B.Cu")
		(net "RST_BTN#")
	)
	(segment
		(start 331.856588 -38.448234)
		(end 331.856588 -30.617922)
		(width 0.12065)
		(layer "B.Cu")
		(net "RST_BTN#")
	)
	(segment
		(start 331.501496 -30.26283)
		(end 331.501496 -24.918162)
		(width 0.12065)
		(layer "B.Cu")
		(net "RST_BTN#")
	)
	(segment
		(start 326.730106 -2.07518)
		(end 282.681172 -2.07518)
		(width 0.12065)
		(layer "B.Cu")
		(net "RST_BTN#")
	)
	(segment
		(start 268.262354 1.26365)
		(end 259.768594 1.26365)
		(width 0.12065)
		(layer "B.Cu")
		(net "RST_BTN#")
	)
	(segment
		(start 278.071834 2.534158)
		(end 269.532862 2.534158)
		(width 0.12065)
		(layer "B.Cu")
		(net "RST_BTN#")
	)
	(segment
		(start 269.532862 2.534158)
		(end 268.262354 1.26365)
		(width 0.12065)
		(layer "B.Cu")
		(net "RST_BTN#")
	)
	(segment
		(start 331.501496 -24.918162)
		(end 330.58608 -24.002746)
		(width 0.12065)
		(layer "B.Cu")
		(net "RST_BTN#")
	)
	(segment
		(start 330.58608 -24.002746)
		(end 330.58608 -5.931154)
		(width 0.12065)
		(layer "B.Cu")
		(net "RST_BTN#")
	)
	(segment
		(start 330.58608 -5.931154)
		(end 326.730106 -2.07518)
		(width 0.12065)
		(layer "B.Cu")
		(net "RST_BTN#")
	)
	(segment
		(start 335.669128 -40.634666)
		(end 334.04302 -40.634666)
		(width 0.12065)
		(layer "B.Cu")
		(net "RST_BTN#")
	)
	(segment
		(start 282.681172 -2.07518)
		(end 278.071834 2.534158)
		(width 0.12065)
		(layer "B.Cu")
		(net "RST_BTN#")
	)
	(segment
		(start 18.214086 -149.659086)
		(end 18.214086 -150.61438)
		(width 0.12065)
		(layer "F.Cu")
		(net "RST_BMC_DDR3_R_N")
	)
	(segment
		(start 16.70812 -149.041358)
		(end 17.189958 -149.041358)
		(width 0.12065)
		(layer "F.Cu")
		(net "RST_BMC_DDR3_R_N")
	)
	(segment
		(start 16.764 -150.0505)
		(end 16.70812 -149.99462)
		(width 0.12065)
		(layer "F.Cu")
		(net "RST_BMC_DDR3_R_N")
	)
	(segment
		(start 17.865852 -149.310852)
		(end 18.214086 -149.659086)
		(width 0.12065)
		(layer "F.Cu")
		(net "RST_BMC_DDR3_R_N")
	)
	(segment
		(start 17.189958 -149.041358)
		(end 17.459452 -149.310852)
		(width 0.12065)
		(layer "F.Cu")
		(net "RST_BMC_DDR3_R_N")
	)
	(segment
		(start 17.459452 -149.310852)
		(end 17.865852 -149.310852)
		(width 0.12065)
		(layer "F.Cu")
		(net "RST_BMC_DDR3_R_N")
	)
	(segment
		(start 16.70812 -149.99462)
		(end 16.70812 -149.041358)
		(width 0.12065)
		(layer "F.Cu")
		(net "RST_BMC_DDR3_R_N")
	)
	(via
		(at 16.70812 -149.041358)
		(size 0.7112)
		(drill 0.3556)
		(layers "F.Cu" "B.Cu")
		(net "RST_BMC_DDR3_R_N")
	)
	(segment
		(start 243.59997 -38.999922)
		(end 244.099842 -38.50005)
		(width 0.12065)
		(layer "F.Cu")
		(net "RS232_URTSB0")
	)
	(via
		(at 244.099842 -38.50005)
		(size 0.4572)
		(drill 0.2032)
		(layers "F.Cu" "B.Cu")
		(net "RS232_URTSB0")
	)
	(segment
		(start 243.59997 -38.999922)
		(end 244.099842 -38.50005)
		(width 0.12065)
		(layer "B.Cu")
		(net "RS232_URTSB0")
	)
	(segment
		(start 243.59997 -39.99992)
		(end 244.099842 -39.500048)
		(width 0.12065)
		(layer "F.Cu")
		(net "RS232_UCTSB0")
	)
	(via
		(at 244.099842 -39.500048)
		(size 0.4572)
		(drill 0.2032)
		(layers "F.Cu" "B.Cu")
		(net "RS232_UCTSB0")
	)
	(segment
		(start 244.599968 -39.99992)
		(end 244.599714 -39.99992)
		(width 0.12065)
		(layer "B.Cu")
		(net "RS232_UCTSB0")
	)
	(segment
		(start 244.599714 -39.99992)
		(end 244.099842 -39.500048)
		(width 0.12065)
		(layer "B.Cu")
		(net "RS232_UCTSB0")
	)
	(segment
		(start 31.304738 -134.884922)
		(end 30.904942 -135.284718)
		(width 0.12065)
		(layer "F.Cu")
		(net "ROMD7")
	)
	(via
		(at 25.4889 -139.749784)
		(size 0.7112)
		(drill 0.3556)
		(layers "F.Cu" "B.Cu")
		(net "ROMD7")
	)
	(via
		(at 30.904942 -135.284718)
		(size 0.4572)
		(drill 0.2032)
		(layers "F.Cu" "B.Cu")
		(net "ROMD7")
	)
	(segment
		(start 25.486614 -139.747498)
		(end 25.486614 -139.74064)
		(width 0.12065)
		(layer "B.Cu")
		(net "ROMD7")
	)
	(segment
		(start 28.95092 -136.652)
		(end 29.452824 -136.652)
		(width 0.12065)
		(layer "B.Cu")
		(net "ROMD7")
	)
	(segment
		(start 25.365456 -139.619482)
		(end 24.351488 -139.619482)
		(width 0.12065)
		(layer "B.Cu")
		(net "ROMD7")
	)
	(segment
		(start 25.4889 -139.749784)
		(end 25.486614 -139.747498)
		(width 0.12065)
		(layer "B.Cu")
		(net "ROMD7")
	)
	(segment
		(start 25.862534 -139.740386)
		(end 28.95092 -136.652)
		(width 0.12065)
		(layer "B.Cu")
		(net "ROMD7")
	)
	(segment
		(start 30.820106 -135.284718)
		(end 30.904942 -135.284718)
		(width 0.12065)
		(layer "B.Cu")
		(net "ROMD7")
	)
	(segment
		(start 29.452824 -136.652)
		(end 30.820106 -135.284718)
		(width 0.12065)
		(layer "B.Cu")
		(net "ROMD7")
	)
	(segment
		(start 25.4889 -139.749784)
		(end 25.4889 -139.740386)
		(width 0.12065)
		(layer "B.Cu")
		(net "ROMD7")
	)
	(segment
		(start 24.351488 -139.619482)
		(end 24.35098 -139.618974)
		(width 0.12065)
		(layer "B.Cu")
		(net "ROMD7")
	)
	(segment
		(start 25.486614 -139.74064)
		(end 25.365456 -139.619482)
		(width 0.12065)
		(layer "B.Cu")
		(net "ROMD7")
	)
	(segment
		(start 25.4889 -139.740386)
		(end 25.862534 -139.740386)
		(width 0.12065)
		(layer "B.Cu")
		(net "ROMD7")
	)
	(segment
		(start 25.197308 -137.324846)
		(end 27.265122 -137.324846)
		(width 0.12065)
		(layer "F.Cu")
		(net "ROMD6")
	)
	(segment
		(start 25.187656 -137.315194)
		(end 25.197308 -137.324846)
		(width 0.12065)
		(layer "F.Cu")
		(net "ROMD6")
	)
	(segment
		(start 27.265122 -137.324846)
		(end 28.9052 -135.684768)
		(width 0.12065)
		(layer "F.Cu")
		(net "ROMD6")
	)
	(segment
		(start 24.856694 -137.315194)
		(end 25.187656 -137.315194)
		(width 0.12065)
		(layer "F.Cu")
		(net "ROMD6")
	)
	(segment
		(start 24.3205 -136.779)
		(end 24.856694 -137.315194)
		(width 0.12065)
		(layer "F.Cu")
		(net "ROMD6")
	)
	(segment
		(start 28.9052 -135.684768)
		(end 29.704792 -135.684768)
		(width 0.12065)
		(layer "F.Cu")
		(net "ROMD6")
	)
	(via
		(at 25.187656 -137.315194)
		(size 0.7112)
		(drill 0.3556)
		(layers "F.Cu" "B.Cu")
		(net "ROMD6")
	)
	(segment
		(start 32.104838 -134.084822)
		(end 31.705042 -134.484618)
		(width 0.12065)
		(layer "F.Cu")
		(net "ROMD5")
	)
	(via
		(at 31.705042 -134.484618)
		(size 0.4572)
		(drill 0.2032)
		(layers "F.Cu" "B.Cu")
		(net "ROMD5")
	)
	(via
		(at 25.46858 -138.479784)
		(size 0.7112)
		(drill 0.3556)
		(layers "F.Cu" "B.Cu")
		(net "ROMD5")
	)
	(segment
		(start 30.743144 -134.894066)
		(end 31.295594 -134.894066)
		(width 0.12065)
		(layer "B.Cu")
		(net "ROMD5")
	)
	(segment
		(start 26.79573 -138.480546)
		(end 28.929076 -136.3472)
		(width 0.12065)
		(layer "B.Cu")
		(net "ROMD5")
	)
	(segment
		(start 25.46858 -138.479784)
		(end 25.469342 -138.480546)
		(width 0.12065)
		(layer "B.Cu")
		(net "ROMD5")
	)
	(segment
		(start 25.46858 -138.479784)
		(end 25.34539 -138.602974)
		(width 0.12065)
		(layer "B.Cu")
		(net "ROMD5")
	)
	(segment
		(start 28.929076 -136.3472)
		(end 29.29001 -136.3472)
		(width 0.12065)
		(layer "B.Cu")
		(net "ROMD5")
	)
	(segment
		(start 29.29001 -136.3472)
		(end 30.743144 -134.894066)
		(width 0.12065)
		(layer "B.Cu")
		(net "ROMD5")
	)
	(segment
		(start 25.469342 -138.480546)
		(end 26.79573 -138.480546)
		(width 0.12065)
		(layer "B.Cu")
		(net "ROMD5")
	)
	(segment
		(start 31.295594 -134.894066)
		(end 31.705042 -134.484618)
		(width 0.12065)
		(layer "B.Cu")
		(net "ROMD5")
	)
	(segment
		(start 25.34539 -138.602974)
		(end 24.35098 -138.602974)
		(width 0.12065)
		(layer "B.Cu")
		(net "ROMD5")
	)
	(segment
		(start 27.5336 -136.6012)
		(end 28.8544 -135.2804)
		(width 0.12065)
		(layer "F.Cu")
		(net "ROMD4")
	)
	(segment
		(start 28.8544 -135.2804)
		(end 30.109414 -135.2804)
		(width 0.12065)
		(layer "F.Cu")
		(net "ROMD4")
	)
	(segment
		(start 24.3205 -135.763)
		(end 25.1587 -136.6012)
		(width 0.12065)
		(layer "F.Cu")
		(net "ROMD4")
	)
	(segment
		(start 25.1587 -136.6012)
		(end 26.2382 -136.6012)
		(width 0.12065)
		(layer "F.Cu")
		(net "ROMD4")
	)
	(segment
		(start 26.2382 -136.6012)
		(end 27.5336 -136.6012)
		(width 0.12065)
		(layer "F.Cu")
		(net "ROMD4")
	)
	(segment
		(start 30.109414 -135.2804)
		(end 30.504892 -134.884922)
		(width 0.12065)
		(layer "F.Cu")
		(net "ROMD4")
	)
	(via
		(at 26.2382 -136.6012)
		(size 0.7112)
		(drill 0.3556)
		(layers "F.Cu" "B.Cu")
		(net "ROMD4")
	)
	(segment
		(start 25.278588 -135.7376)
		(end 28.001722 -135.7376)
		(width 0.12065)
		(layer "F.Cu")
		(net "ROMD3")
	)
	(segment
		(start 25.266904 -135.749284)
		(end 25.278588 -135.7376)
		(width 0.12065)
		(layer "F.Cu")
		(net "ROMD3")
	)
	(segment
		(start 24.3205 -134.747)
		(end 24.3205 -134.80288)
		(width 0.12065)
		(layer "F.Cu")
		(net "ROMD3")
	)
	(segment
		(start 28.8544 -134.884922)
		(end 29.704792 -134.884922)
		(width 0.12065)
		(layer "F.Cu")
		(net "ROMD3")
	)
	(segment
		(start 24.3205 -134.80288)
		(end 25.266904 -135.749284)
		(width 0.12065)
		(layer "F.Cu")
		(net "ROMD3")
	)
	(segment
		(start 28.001722 -135.7376)
		(end 28.8544 -134.884922)
		(width 0.12065)
		(layer "F.Cu")
		(net "ROMD3")
	)
	(via
		(at 25.266904 -135.749284)
		(size 0.7112)
		(drill 0.3556)
		(layers "F.Cu" "B.Cu")
		(net "ROMD3")
	)
	(segment
		(start 60.002674 -72.023986)
		(end 58.561986 -72.023986)
		(width 0.12065)
		(layer "F.Cu")
		(net "ROMD2_R")
	)
	(segment
		(start 58.561986 -72.023986)
		(end 58.5216 -71.9836)
		(width 0.12065)
		(layer "F.Cu")
		(net "ROMD2_R")
	)
	(via
		(at 54.553104 -89.612978)
		(size 0.508)
		(drill 0.254)
		(layers "F.Cu" "B.Cu")
		(net "ROMD2_R")
	)
	(via
		(at 17.91081 -136.836404)
		(size 0.7112)
		(drill 0.3556)
		(layers "F.Cu" "B.Cu")
		(net "ROMD2_R")
	)
	(via
		(at 58.5216 -71.9836)
		(size 0.508)
		(drill 0.254)
		(layers "F.Cu" "B.Cu")
		(net "ROMD2_R")
	)
	(via
		(at 16.7132 -136.8806)
		(size 0.508)
		(drill 0.254)
		(layers "F.Cu" "B.Cu")
		(net "ROMD2_R")
	)
	(segment
		(start 16.7132 -136.8806)
		(end 17.180052 -136.8806)
		(width 0.12065)
		(layer "B.Cu")
		(net "ROMD2_R")
	)
	(segment
		(start 19.381978 -137.795)
		(end 20.5105 -137.795)
		(width 0.12065)
		(layer "B.Cu")
		(net "ROMD2_R")
	)
	(segment
		(start 18.84426 -137.257282)
		(end 19.381978 -137.795)
		(width 0.12065)
		(layer "B.Cu")
		(net "ROMD2_R")
	)
	(segment
		(start 17.91081 -136.836404)
		(end 18.331688 -137.257282)
		(width 0.12065)
		(layer "B.Cu")
		(net "ROMD2_R")
	)
	(segment
		(start 17.224248 -136.836404)
		(end 17.91081 -136.836404)
		(width 0.12065)
		(layer "B.Cu")
		(net "ROMD2_R")
	)
	(segment
		(start 18.331688 -137.257282)
		(end 18.84426 -137.257282)
		(width 0.12065)
		(layer "B.Cu")
		(net "ROMD2_R")
	)
	(segment
		(start 17.180052 -136.8806)
		(end 17.224248 -136.836404)
		(width 0.12065)
		(layer "B.Cu")
		(net "ROMD2_R")
	)
	(segment
		(start 9.289034 -121.759726)
		(end 9.289034 -121.339102)
		(width 0.127)
		(layer "In2.Cu")
		(net "ROMD2_R")
	)
	(segment
		(start 47.016162 -90.678)
		(end 47.026068 -90.668094)
		(width 0.127)
		(layer "In2.Cu")
		(net "ROMD2_R")
	)
	(segment
		(start 47.026068 -90.668094)
		(end 47.446692 -90.668094)
		(width 0.127)
		(layer "In2.Cu")
		(net "ROMD2_R")
	)
	(segment
		(start 13.857986 -136.015984)
		(end 13.857732 -136.015984)
		(width 0.127)
		(layer "In2.Cu")
		(net "ROMD2_R")
	)
	(segment
		(start 13.390118 -107.728004)
		(end 13.300202 -107.578652)
		(width 0.127)
		(layer "In2.Cu")
		(net "ROMD2_R")
	)
	(segment
		(start 19.07286 -100.323904)
		(end 19.07286 -99.965256)
		(width 0.127)
		(layer "In2.Cu")
		(net "ROMD2_R")
	)
	(segment
		(start 26.162254 -94.567502)
		(end 30.051756 -90.678)
		(width 0.127)
		(layer "In2.Cu")
		(net "ROMD2_R")
	)
	(segment
		(start 8.5979 -130.755898)
		(end 8.5979 -122.45086)
		(width 0.127)
		(layer "In2.Cu")
		(net "ROMD2_R")
	)
	(segment
		(start 13.858494 -136.016492)
		(end 13.857986 -136.015984)
		(width 0.127)
		(layer "In2.Cu")
		(net "ROMD2_R")
	)
	(segment
		(start 10.05078 -114.84102)
		(end 11.0998 -113.792)
		(width 0.127)
		(layer "In2.Cu")
		(net "ROMD2_R")
	)
	(segment
		(start 9.28878 -120.76684)
		(end 10.05078 -120.00484)
		(width 0.127)
		(layer "In2.Cu")
		(net "ROMD2_R")
	)
	(segment
		(start 9.289034 -121.339102)
		(end 9.28878 -121.338848)
		(width 0.127)
		(layer "In2.Cu")
		(net "ROMD2_R")
	)
	(segment
		(start 47.456598 -90.678)
		(end 50.640996 -90.678)
		(width 0.127)
		(layer "In2.Cu")
		(net "ROMD2_R")
	)
	(segment
		(start 9.28878 -121.338848)
		(end 9.28878 -120.76684)
		(width 0.127)
		(layer "In2.Cu")
		(net "ROMD2_R")
	)
	(segment
		(start 15.933166 -136.8806)
		(end 15.907766 -136.906)
		(width 0.127)
		(layer "In2.Cu")
		(net "ROMD2_R")
	)
	(segment
		(start 11.0998 -111.620554)
		(end 13.390118 -109.330236)
		(width 0.127)
		(layer "In2.Cu")
		(net "ROMD2_R")
	)
	(segment
		(start 47.446692 -90.668094)
		(end 47.456598 -90.678)
		(width 0.127)
		(layer "In2.Cu")
		(net "ROMD2_R")
	)
	(segment
		(start 14.338808 -136.016492)
		(end 13.858494 -136.016492)
		(width 0.127)
		(layer "In2.Cu")
		(net "ROMD2_R")
	)
	(segment
		(start 13.390118 -106.007408)
		(end 13.739622 -105.657904)
		(width 0.127)
		(layer "In2.Cu")
		(net "ROMD2_R")
	)
	(segment
		(start 13.1953 -107.47375)
		(end 13.1953 -106.202734)
		(width 0.127)
		(layer "In2.Cu")
		(net "ROMD2_R")
	)
	(segment
		(start 15.228316 -136.906)
		(end 14.338808 -136.016492)
		(width 0.127)
		(layer "In2.Cu")
		(net "ROMD2_R")
	)
	(segment
		(start 22.280626 -96.75749)
		(end 23.25497 -96.75749)
		(width 0.127)
		(layer "In2.Cu")
		(net "ROMD2_R")
	)
	(segment
		(start 11.0998 -113.792)
		(end 11.0998 -111.620554)
		(width 0.127)
		(layer "In2.Cu")
		(net "ROMD2_R")
	)
	(segment
		(start 13.857732 -136.015984)
		(end 9.090406 -131.248658)
		(width 0.127)
		(layer "In2.Cu")
		(net "ROMD2_R")
	)
	(segment
		(start 13.300202 -107.578652)
		(end 13.1953 -107.47375)
		(width 0.127)
		(layer "In2.Cu")
		(net "ROMD2_R")
	)
	(segment
		(start 9.090406 -131.248658)
		(end 9.090406 -131.248404)
		(width 0.127)
		(layer "In2.Cu")
		(net "ROMD2_R")
	)
	(segment
		(start 50.640996 -90.678)
		(end 51.706018 -89.612978)
		(width 0.127)
		(layer "In2.Cu")
		(net "ROMD2_R")
	)
	(segment
		(start 16.230092 -103.166672)
		(end 19.07286 -100.323904)
		(width 0.127)
		(layer "In2.Cu")
		(net "ROMD2_R")
	)
	(segment
		(start 8.5979 -122.45086)
		(end 9.289034 -121.759726)
		(width 0.127)
		(layer "In2.Cu")
		(net "ROMD2_R")
	)
	(segment
		(start 15.907766 -136.906)
		(end 15.228316 -136.906)
		(width 0.127)
		(layer "In2.Cu")
		(net "ROMD2_R")
	)
	(segment
		(start 30.051756 -90.678)
		(end 47.016162 -90.678)
		(width 0.127)
		(layer "In2.Cu")
		(net "ROMD2_R")
	)
	(segment
		(start 16.7132 -136.8806)
		(end 15.933166 -136.8806)
		(width 0.127)
		(layer "In2.Cu")
		(net "ROMD2_R")
	)
	(segment
		(start 23.25497 -96.75749)
		(end 25.444958 -94.567502)
		(width 0.127)
		(layer "In2.Cu")
		(net "ROMD2_R")
	)
	(segment
		(start 13.739622 -105.657904)
		(end 16.230092 -103.166672)
		(width 0.127)
		(layer "In2.Cu")
		(net "ROMD2_R")
	)
	(segment
		(start 19.07286 -99.965256)
		(end 22.280626 -96.75749)
		(width 0.127)
		(layer "In2.Cu")
		(net "ROMD2_R")
	)
	(segment
		(start 10.05078 -120.00484)
		(end 10.05078 -114.84102)
		(width 0.127)
		(layer "In2.Cu")
		(net "ROMD2_R")
	)
	(segment
		(start 13.390118 -109.330236)
		(end 13.390118 -107.728004)
		(width 0.127)
		(layer "In2.Cu")
		(net "ROMD2_R")
	)
	(segment
		(start 25.444958 -94.567502)
		(end 26.162254 -94.567502)
		(width 0.127)
		(layer "In2.Cu")
		(net "ROMD2_R")
	)
	(segment
		(start 13.1953 -106.202734)
		(end 13.390118 -106.007916)
		(width 0.127)
		(layer "In2.Cu")
		(net "ROMD2_R")
	)
	(segment
		(start 9.090406 -131.248404)
		(end 8.5979 -130.755898)
		(width 0.127)
		(layer "In2.Cu")
		(net "ROMD2_R")
	)
	(segment
		(start 13.390118 -106.007916)
		(end 13.390118 -106.007408)
		(width 0.127)
		(layer "In2.Cu")
		(net "ROMD2_R")
	)
	(segment
		(start 51.706018 -89.612978)
		(end 54.553104 -89.612978)
		(width 0.127)
		(layer "In2.Cu")
		(net "ROMD2_R")
	)
	(segment
		(start 54.958742 -89.612978)
		(end 56.93156 -87.64016)
		(width 0.127)
		(layer "In5.Cu")
		(net "ROMD2_R")
	)
	(segment
		(start 54.553104 -89.612978)
		(end 54.958742 -89.612978)
		(width 0.127)
		(layer "In5.Cu")
		(net "ROMD2_R")
	)
	(segment
		(start 56.93156 -73.57364)
		(end 58.5216 -71.9836)
		(width 0.127)
		(layer "In5.Cu")
		(net "ROMD2_R")
	)
	(segment
		(start 56.93156 -87.64016)
		(end 56.93156 -73.57364)
		(width 0.127)
		(layer "In5.Cu")
		(net "ROMD2_R")
	)
	(segment
		(start 31.304738 -134.084822)
		(end 30.904942 -134.484618)
		(width 0.12065)
		(layer "F.Cu")
		(net "ROMD2")
	)
	(segment
		(start 76.8858 -75.695048)
		(end 76.1873 -75.695048)
		(width 0.12065)
		(layer "F.Cu")
		(net "ROMD2")
	)
	(segment
		(start 76.1873 -75.695048)
		(end 76.0984 -75.606148)
		(width 0.12065)
		(layer "F.Cu")
		(net "ROMD2")
	)
	(via
		(at 30.904942 -134.484618)
		(size 0.4572)
		(drill 0.2032)
		(layers "F.Cu" "B.Cu")
		(net "ROMD2")
	)
	(via
		(at 25.990804 -137.241788)
		(size 0.7112)
		(drill 0.3556)
		(layers "F.Cu" "B.Cu")
		(net "ROMD2")
	)
	(via
		(at 74.678286 -92.218002)
		(size 0.508)
		(drill 0.254)
		(layers "F.Cu" "B.Cu")
		(net "ROMD2")
	)
	(via
		(at 76.0984 -75.606148)
		(size 0.508)
		(drill 0.254)
		(layers "F.Cu" "B.Cu")
		(net "ROMD2")
	)
	(via
		(at 18.872454 -136.75106)
		(size 0.508)
		(drill 0.254)
		(layers "F.Cu" "B.Cu")
		(net "ROMD2")
	)
	(segment
		(start 30.793182 -134.484618)
		(end 29.1592 -136.1186)
		(width 0.12065)
		(layer "B.Cu")
		(net "ROMD2")
	)
	(segment
		(start 27.430984 -137.241788)
		(end 25.990804 -137.241788)
		(width 0.12065)
		(layer "B.Cu")
		(net "ROMD2")
	)
	(segment
		(start 20.89785 -137.29335)
		(end 21.3995 -137.795)
		(width 0.12065)
		(layer "B.Cu")
		(net "ROMD2")
	)
	(segment
		(start 29.1592 -136.1186)
		(end 28.554172 -136.1186)
		(width 0.12065)
		(layer "B.Cu")
		(net "ROMD2")
	)
	(segment
		(start 19.047714 -136.75106)
		(end 19.590004 -137.29335)
		(width 0.12065)
		(layer "B.Cu")
		(net "ROMD2")
	)
	(segment
		(start 18.872454 -136.75106)
		(end 19.047714 -136.75106)
		(width 0.12065)
		(layer "B.Cu")
		(net "ROMD2")
	)
	(segment
		(start 22.084538 -137.109962)
		(end 21.3995 -137.795)
		(width 0.12065)
		(layer "B.Cu")
		(net "ROMD2")
	)
	(segment
		(start 24.35098 -137.586974)
		(end 23.873968 -137.109962)
		(width 0.12065)
		(layer "B.Cu")
		(net "ROMD2")
	)
	(segment
		(start 19.590004 -137.29335)
		(end 20.89785 -137.29335)
		(width 0.12065)
		(layer "B.Cu")
		(net "ROMD2")
	)
	(segment
		(start 30.904942 -134.484618)
		(end 30.793182 -134.484618)
		(width 0.12065)
		(layer "B.Cu")
		(net "ROMD2")
	)
	(segment
		(start 25.990804 -137.241788)
		(end 24.696166 -137.241788)
		(width 0.12065)
		(layer "B.Cu")
		(net "ROMD2")
	)
	(segment
		(start 24.696166 -137.241788)
		(end 24.35098 -137.586974)
		(width 0.12065)
		(layer "B.Cu")
		(net "ROMD2")
	)
	(segment
		(start 23.873968 -137.109962)
		(end 22.084538 -137.109962)
		(width 0.12065)
		(layer "B.Cu")
		(net "ROMD2")
	)
	(segment
		(start 28.554172 -136.1186)
		(end 27.430984 -137.241788)
		(width 0.12065)
		(layer "B.Cu")
		(net "ROMD2")
	)
	(segment
		(start 35.014408 -92.5449)
		(end 35.354006 -92.205302)
		(width 0.127)
		(layer "In2.Cu")
		(net "ROMD2")
	)
	(segment
		(start 20.08886 -100.74529)
		(end 20.08886 -100.386388)
		(width 0.127)
		(layer "In2.Cu")
		(net "ROMD2")
	)
	(segment
		(start 20.60321 -100.111306)
		(end 21.171662 -99.542854)
		(width 0.127)
		(layer "In2.Cu")
		(net "ROMD2")
	)
	(segment
		(start 17.959578 -136.75106)
		(end 16.298672 -135.090154)
		(width 0.127)
		(layer "In2.Cu")
		(net "ROMD2")
	)
	(segment
		(start 14.849602 -135.090154)
		(end 14.759686 -135.000238)
		(width 0.127)
		(layer "In2.Cu")
		(net "ROMD2")
	)
	(segment
		(start 14.2113 -107.052618)
		(end 14.2113 -106.623866)
		(width 0.127)
		(layer "In2.Cu")
		(net "ROMD2")
	)
	(segment
		(start 10.106406 -130.827526)
		(end 10.106406 -123.726194)
		(width 0.127)
		(layer "In2.Cu")
		(net "ROMD2")
	)
	(segment
		(start 20.08886 -100.386388)
		(end 20.363942 -100.111306)
		(width 0.127)
		(layer "In2.Cu")
		(net "ROMD2")
	)
	(segment
		(start 20.363942 -100.111306)
		(end 20.60321 -100.111306)
		(width 0.127)
		(layer "In2.Cu")
		(net "ROMD2")
	)
	(segment
		(start 14.406118 -109.2708)
		(end 14.406118 -107.7976)
		(width 0.127)
		(layer "In2.Cu")
		(net "ROMD2")
	)
	(segment
		(start 17.26819 -103.566468)
		(end 17.26819 -103.56596)
		(width 0.127)
		(layer "In2.Cu")
		(net "ROMD2")
	)
	(segment
		(start 15.1511 -105.684066)
		(end 16.789146 -104.045512)
		(width 0.127)
		(layer "In2.Cu")
		(net "ROMD2")
	)
	(segment
		(start 10.10666 -123.72594)
		(end 10.10666 -123.725686)
		(width 0.127)
		(layer "In2.Cu")
		(net "ROMD2")
	)
	(segment
		(start 51.388518 -91.713812)
		(end 52.929028 -90.173302)
		(width 0.127)
		(layer "In2.Cu")
		(net "ROMD2")
	)
	(segment
		(start 29.253688 -92.9132)
		(end 30.150054 -92.9132)
		(width 0.127)
		(layer "In2.Cu")
		(net "ROMD2")
	)
	(segment
		(start 14.279118 -134.999984)
		(end 14.278864 -134.999984)
		(width 0.127)
		(layer "In2.Cu")
		(net "ROMD2")
	)
	(segment
		(start 14.278864 -134.999984)
		(end 10.106406 -130.827526)
		(width 0.127)
		(layer "In2.Cu")
		(net "ROMD2")
	)
	(segment
		(start 11.06678 -115.30711)
		(end 13.6652 -112.70869)
		(width 0.127)
		(layer "In2.Cu")
		(net "ROMD2")
	)
	(segment
		(start 14.279372 -135.000238)
		(end 14.279118 -134.999984)
		(width 0.127)
		(layer "In2.Cu")
		(net "ROMD2")
	)
	(segment
		(start 35.354006 -92.205302)
		(end 37.031676 -92.205302)
		(width 0.127)
		(layer "In2.Cu")
		(net "ROMD2")
	)
	(segment
		(start 14.406626 -107.797092)
		(end 14.406626 -107.786678)
		(width 0.127)
		(layer "In2.Cu")
		(net "ROMD2")
	)
	(segment
		(start 14.406372 -111.967264)
		(end 14.406372 -109.271054)
		(width 0.127)
		(layer "In2.Cu")
		(net "ROMD2")
	)
	(segment
		(start 14.406626 -107.786678)
		(end 14.486382 -107.706922)
		(width 0.127)
		(layer "In2.Cu")
		(net "ROMD2")
	)
	(segment
		(start 14.406118 -107.7976)
		(end 14.406626 -107.797092)
		(width 0.127)
		(layer "In2.Cu")
		(net "ROMD2")
	)
	(segment
		(start 10.688066 -121.378472)
		(end 11.06678 -120.999758)
		(width 0.127)
		(layer "In2.Cu")
		(net "ROMD2")
	)
	(segment
		(start 30.57779 -92.485464)
		(end 31.952946 -92.485464)
		(width 0.127)
		(layer "In2.Cu")
		(net "ROMD2")
	)
	(segment
		(start 10.688066 -123.14428)
		(end 10.688066 -121.378472)
		(width 0.127)
		(layer "In2.Cu")
		(net "ROMD2")
	)
	(segment
		(start 11.06678 -120.999758)
		(end 11.06678 -115.30711)
		(width 0.127)
		(layer "In2.Cu")
		(net "ROMD2")
	)
	(segment
		(start 32.012382 -92.5449)
		(end 35.014408 -92.5449)
		(width 0.127)
		(layer "In2.Cu")
		(net "ROMD2")
	)
	(segment
		(start 14.759686 -135.000238)
		(end 14.279372 -135.000238)
		(width 0.127)
		(layer "In2.Cu")
		(net "ROMD2")
	)
	(segment
		(start 30.150054 -92.9132)
		(end 30.57779 -92.485464)
		(width 0.127)
		(layer "In2.Cu")
		(net "ROMD2")
	)
	(segment
		(start 14.406372 -109.271054)
		(end 14.406118 -109.2708)
		(width 0.127)
		(layer "In2.Cu")
		(net "ROMD2")
	)
	(segment
		(start 37.031676 -92.205302)
		(end 37.523166 -91.713812)
		(width 0.127)
		(layer "In2.Cu")
		(net "ROMD2")
	)
	(segment
		(start 18.872454 -136.75106)
		(end 17.959578 -136.75106)
		(width 0.127)
		(layer "In2.Cu")
		(net "ROMD2")
	)
	(segment
		(start 17.26819 -103.56596)
		(end 20.08886 -100.74529)
		(width 0.127)
		(layer "In2.Cu")
		(net "ROMD2")
	)
	(segment
		(start 31.952946 -92.485464)
		(end 32.012382 -92.5449)
		(width 0.127)
		(layer "In2.Cu")
		(net "ROMD2")
	)
	(segment
		(start 26.561288 -95.6056)
		(end 29.253688 -92.9132)
		(width 0.127)
		(layer "In2.Cu")
		(net "ROMD2")
	)
	(segment
		(start 14.486382 -107.706922)
		(end 14.486382 -107.3277)
		(width 0.127)
		(layer "In2.Cu")
		(net "ROMD2")
	)
	(segment
		(start 72.633586 -90.173302)
		(end 74.678286 -92.218002)
		(width 0.127)
		(layer "In2.Cu")
		(net "ROMD2")
	)
	(segment
		(start 10.10666 -123.725686)
		(end 10.688066 -123.14428)
		(width 0.127)
		(layer "In2.Cu")
		(net "ROMD2")
	)
	(segment
		(start 25.843992 -95.6056)
		(end 26.561288 -95.6056)
		(width 0.127)
		(layer "In2.Cu")
		(net "ROMD2")
	)
	(segment
		(start 37.523166 -91.713812)
		(end 51.388518 -91.713812)
		(width 0.127)
		(layer "In2.Cu")
		(net "ROMD2")
	)
	(segment
		(start 13.6652 -112.708436)
		(end 14.406372 -111.967264)
		(width 0.127)
		(layer "In2.Cu")
		(net "ROMD2")
	)
	(segment
		(start 21.171662 -99.542854)
		(end 21.906738 -99.542854)
		(width 0.127)
		(layer "In2.Cu")
		(net "ROMD2")
	)
	(segment
		(start 52.929028 -90.173302)
		(end 72.633586 -90.173302)
		(width 0.127)
		(layer "In2.Cu")
		(net "ROMD2")
	)
	(segment
		(start 13.6652 -112.70869)
		(end 13.6652 -112.708436)
		(width 0.127)
		(layer "In2.Cu")
		(net "ROMD2")
	)
	(segment
		(start 14.486382 -107.3277)
		(end 14.2113 -107.052618)
		(width 0.127)
		(layer "In2.Cu")
		(net "ROMD2")
	)
	(segment
		(start 16.789146 -104.045512)
		(end 17.26819 -103.566468)
		(width 0.127)
		(layer "In2.Cu")
		(net "ROMD2")
	)
	(segment
		(start 21.906738 -99.542854)
		(end 25.843992 -95.6056)
		(width 0.127)
		(layer "In2.Cu")
		(net "ROMD2")
	)
	(segment
		(start 10.106406 -123.726194)
		(end 10.10666 -123.72594)
		(width 0.127)
		(layer "In2.Cu")
		(net "ROMD2")
	)
	(segment
		(start 14.2113 -106.623866)
		(end 15.1511 -105.684066)
		(width 0.127)
		(layer "In2.Cu")
		(net "ROMD2")
	)
	(segment
		(start 16.298672 -135.090154)
		(end 14.849602 -135.090154)
		(width 0.127)
		(layer "In2.Cu")
		(net "ROMD2")
	)
	(segment
		(start 75.561952 -76.142596)
		(end 75.561952 -76.908406)
		(width 0.127)
		(layer "In5.Cu")
		(net "ROMD2")
	)
	(segment
		(start 74.394314 -91.481148)
		(end 74.394314 -91.93403)
		(width 0.127)
		(layer "In5.Cu")
		(net "ROMD2")
	)
	(segment
		(start 74.0537 -91.140534)
		(end 74.394314 -91.481148)
		(width 0.127)
		(layer "In5.Cu")
		(net "ROMD2")
	)
	(segment
		(start 74.394314 -91.93403)
		(end 74.678286 -92.218002)
		(width 0.127)
		(layer "In5.Cu")
		(net "ROMD2")
	)
	(segment
		(start 76.0984 -75.606148)
		(end 75.561952 -76.142596)
		(width 0.127)
		(layer "In5.Cu")
		(net "ROMD2")
	)
	(segment
		(start 74.0537 -78.416658)
		(end 74.0537 -91.140534)
		(width 0.127)
		(layer "In5.Cu")
		(net "ROMD2")
	)
	(segment
		(start 75.561952 -76.908406)
		(end 74.0537 -78.416658)
		(width 0.127)
		(layer "In5.Cu")
		(net "ROMD2")
	)
	(segment
		(start 67.622674 -60.875926)
		(end 67.691 -60.8076)
		(width 0.12065)
		(layer "F.Cu")
		(net "ROMD1_R")
	)
	(segment
		(start 67.622674 -62.40907)
		(end 67.622674 -63.5254)
		(width 0.12065)
		(layer "F.Cu")
		(net "ROMD1_R")
	)
	(segment
		(start 67.622674 -62.230254)
		(end 67.622674 -60.875926)
		(width 0.12065)
		(layer "F.Cu")
		(net "ROMD1_R")
	)
	(segment
		(start 19.7358 -136.779)
		(end 19.083274 -136.126474)
		(width 0.12065)
		(layer "F.Cu")
		(net "ROMD1_R")
	)
	(segment
		(start 84.539836 -61.12129)
		(end 84.539836 -62.212728)
		(width 0.12065)
		(layer "F.Cu")
		(net "ROMD1_R")
	)
	(segment
		(start 84.539836 -62.391544)
		(end 84.539836 -62.212728)
		(width 0.12065)
		(layer "F.Cu")
		(net "ROMD1_R")
	)
	(segment
		(start 83.108546 -59.69)
		(end 84.539836 -61.12129)
		(width 0.12065)
		(layer "F.Cu")
		(net "ROMD1_R")
	)
	(segment
		(start 19.083274 -136.126474)
		(end 18.07718 -136.126474)
		(width 0.12065)
		(layer "F.Cu")
		(net "ROMD1_R")
	)
	(segment
		(start 73.44918 -59.69)
		(end 83.108546 -59.69)
		(width 0.12065)
		(layer "F.Cu")
		(net "ROMD1_R")
	)
	(segment
		(start 68.181474 -64.0842)
		(end 69.05498 -64.0842)
		(width 0.12065)
		(layer "F.Cu")
		(net "ROMD1_R")
	)
	(segment
		(start 67.622674 -63.5254)
		(end 68.181474 -64.0842)
		(width 0.12065)
		(layer "F.Cu")
		(net "ROMD1_R")
	)
	(segment
		(start 67.622674 -62.230254)
		(end 67.622674 -62.40907)
		(width 0.12065)
		(layer "F.Cu")
		(net "ROMD1_R")
	)
	(segment
		(start 69.05498 -64.0842)
		(end 73.44918 -59.69)
		(width 0.12065)
		(layer "F.Cu")
		(net "ROMD1_R")
	)
	(via
		(at 67.6148 -61.849)
		(size 0.7112)
		(drill 0.3556)
		(layers "F.Cu" "B.Cu")
		(net "ROMD1_R")
	)
	(via
		(at 19.7358 -136.779)
		(size 0.508)
		(drill 0.254)
		(layers "F.Cu" "B.Cu")
		(net "ROMD1_R")
	)
	(via
		(at 55.77332 -90.67038)
		(size 0.508)
		(drill 0.254)
		(layers "F.Cu" "B.Cu")
		(net "ROMD1_R")
	)
	(via
		(at 67.691 -60.8076)
		(size 0.508)
		(drill 0.254)
		(layers "F.Cu" "B.Cu")
		(net "ROMD1_R")
	)
	(segment
		(start 20.5105 -136.779)
		(end 19.7358 -136.779)
		(width 0.12065)
		(layer "B.Cu")
		(net "ROMD1_R")
	)
	(segment
		(start 67.691 -60.8076)
		(end 67.691 -61.7728)
		(width 0.12065)
		(layer "B.Cu")
		(net "ROMD1_R")
	)
	(segment
		(start 67.691 -61.7728)
		(end 67.6148 -61.849)
		(width 0.12065)
		(layer "B.Cu")
		(net "ROMD1_R")
	)
	(segment
		(start 14.914372 -109.060488)
		(end 14.914118 -109.060234)
		(width 0.127)
		(layer "In2.Cu")
		(net "ROMD1_R")
	)
	(segment
		(start 21.0439 -100.389182)
		(end 21.381974 -100.051108)
		(width 0.127)
		(layer "In2.Cu")
		(net "ROMD1_R")
	)
	(segment
		(start 42.468292 -92.221812)
		(end 42.498518 -92.252038)
		(width 0.127)
		(layer "In2.Cu")
		(net "ROMD1_R")
	)
	(segment
		(start 37.242242 -92.713302)
		(end 37.733732 -92.221812)
		(width 0.127)
		(layer "In2.Cu")
		(net "ROMD1_R")
	)
	(segment
		(start 21.0439 -101.236018)
		(end 21.0439 -100.389182)
		(width 0.127)
		(layer "In2.Cu")
		(net "ROMD1_R")
	)
	(segment
		(start 26.79446 -96.090994)
		(end 29.438854 -93.4466)
		(width 0.127)
		(layer "In2.Cu")
		(net "ROMD1_R")
	)
	(segment
		(start 11.358118 -123.192794)
		(end 11.358372 -123.192794)
		(width 0.127)
		(layer "In2.Cu")
		(net "ROMD1_R")
	)
	(segment
		(start 11.547348 -123.003818)
		(end 11.547348 -121.441972)
		(width 0.127)
		(layer "In2.Cu")
		(net "ROMD1_R")
	)
	(segment
		(start 37.733732 -92.221812)
		(end 42.468292 -92.221812)
		(width 0.127)
		(layer "In2.Cu")
		(net "ROMD1_R")
	)
	(segment
		(start 15.059914 -134.5819)
		(end 14.970252 -134.492238)
		(width 0.127)
		(layer "In2.Cu")
		(net "ROMD1_R")
	)
	(segment
		(start 14.914118 -108.008166)
		(end 14.914626 -108.007658)
		(width 0.127)
		(layer "In2.Cu")
		(net "ROMD1_R")
	)
	(segment
		(start 10.614406 -127.53975)
		(end 10.614406 -123.93676)
		(width 0.127)
		(layer "In2.Cu")
		(net "ROMD1_R")
	)
	(segment
		(start 51.63058 -92.252038)
		(end 53.201316 -90.681302)
		(width 0.127)
		(layer "In2.Cu")
		(net "ROMD1_R")
	)
	(segment
		(start 14.914118 -109.060234)
		(end 14.914118 -108.008166)
		(width 0.127)
		(layer "In2.Cu")
		(net "ROMD1_R")
	)
	(segment
		(start 10.61466 -123.936252)
		(end 11.358118 -123.192794)
		(width 0.127)
		(layer "In2.Cu")
		(net "ROMD1_R")
	)
	(segment
		(start 42.498518 -92.252038)
		(end 51.63058 -92.252038)
		(width 0.127)
		(layer "In2.Cu")
		(net "ROMD1_R")
	)
	(segment
		(start 15.6591 -106.866182)
		(end 15.658846 -106.865928)
		(width 0.127)
		(layer "In2.Cu")
		(net "ROMD1_R")
	)
	(segment
		(start 16.810228 -134.5819)
		(end 15.059914 -134.5819)
		(width 0.127)
		(layer "In2.Cu")
		(net "ROMD1_R")
	)
	(segment
		(start 23.085552 -99.082606)
		(end 23.318724 -99.082606)
		(width 0.127)
		(layer "In2.Cu")
		(net "ROMD1_R")
	)
	(segment
		(start 19.833336 -102.446582)
		(end 21.0439 -101.236018)
		(width 0.127)
		(layer "In2.Cu")
		(net "ROMD1_R")
	)
	(segment
		(start 29.438854 -93.4466)
		(end 30.503876 -93.4466)
		(width 0.127)
		(layer "In2.Cu")
		(net "ROMD1_R")
	)
	(segment
		(start 13.024612 -133.027166)
		(end 13.024612 -133.026912)
		(width 0.127)
		(layer "In2.Cu")
		(net "ROMD1_R")
	)
	(segment
		(start 15.758922 -106.10088)
		(end 15.758922 -106.100626)
		(width 0.127)
		(layer "In2.Cu")
		(net "ROMD1_R")
	)
	(segment
		(start 18.321528 -136.0932)
		(end 16.810228 -134.5819)
		(width 0.127)
		(layer "In2.Cu")
		(net "ROMD1_R")
	)
	(segment
		(start 23.320248 -99.081082)
		(end 23.742904 -99.081336)
		(width 0.127)
		(layer "In2.Cu")
		(net "ROMD1_R")
	)
	(segment
		(start 14.914372 -112.178084)
		(end 14.914372 -109.060488)
		(width 0.127)
		(layer "In2.Cu")
		(net "ROMD1_R")
	)
	(segment
		(start 35.564572 -92.713302)
		(end 37.242242 -92.713302)
		(width 0.127)
		(layer "In2.Cu")
		(net "ROMD1_R")
	)
	(segment
		(start 14.914626 -107.997244)
		(end 15.6591 -107.25277)
		(width 0.127)
		(layer "In2.Cu")
		(net "ROMD1_R")
	)
	(segment
		(start 14.489938 -134.492238)
		(end 14.489684 -134.491984)
		(width 0.127)
		(layer "In2.Cu")
		(net "ROMD1_R")
	)
	(segment
		(start 16.50238 -105.357168)
		(end 16.502634 -105.357168)
		(width 0.127)
		(layer "In2.Cu")
		(net "ROMD1_R")
	)
	(segment
		(start 31.545784 -93.1926)
		(end 35.085274 -93.1926)
		(width 0.127)
		(layer "In2.Cu")
		(net "ROMD1_R")
	)
	(segment
		(start 26.706576 -96.1136)
		(end 26.729182 -96.090994)
		(width 0.127)
		(layer "In2.Cu")
		(net "ROMD1_R")
	)
	(segment
		(start 15.658846 -106.865928)
		(end 15.658846 -106.340148)
		(width 0.127)
		(layer "In2.Cu")
		(net "ROMD1_R")
	)
	(segment
		(start 14.489684 -134.491984)
		(end 14.48943 -134.491984)
		(width 0.127)
		(layer "In2.Cu")
		(net "ROMD1_R")
	)
	(segment
		(start 14.1732 -112.919256)
		(end 14.1732 -112.919002)
		(width 0.127)
		(layer "In2.Cu")
		(net "ROMD1_R")
	)
	(segment
		(start 15.758922 -106.100626)
		(end 16.50238 -105.357168)
		(width 0.127)
		(layer "In2.Cu")
		(net "ROMD1_R")
	)
	(segment
		(start 11.547348 -121.441972)
		(end 12.9286 -120.06072)
		(width 0.127)
		(layer "In2.Cu")
		(net "ROMD1_R")
	)
	(segment
		(start 14.914626 -108.007658)
		(end 14.914626 -107.997244)
		(width 0.127)
		(layer "In2.Cu")
		(net "ROMD1_R")
	)
	(segment
		(start 12.9286 -114.163856)
		(end 14.1732 -112.919256)
		(width 0.127)
		(layer "In2.Cu")
		(net "ROMD1_R")
	)
	(segment
		(start 53.201316 -90.681302)
		(end 55.762398 -90.681302)
		(width 0.127)
		(layer "In2.Cu")
		(net "ROMD1_R")
	)
	(segment
		(start 22.11705 -100.051108)
		(end 23.085552 -99.082606)
		(width 0.127)
		(layer "In2.Cu")
		(net "ROMD1_R")
	)
	(segment
		(start 10.61466 -123.936506)
		(end 10.61466 -123.936252)
		(width 0.127)
		(layer "In2.Cu")
		(net "ROMD1_R")
	)
	(segment
		(start 11.358372 -123.192794)
		(end 11.547348 -123.003818)
		(width 0.127)
		(layer "In2.Cu")
		(net "ROMD1_R")
	)
	(segment
		(start 31.346648 -92.993464)
		(end 31.545784 -93.1926)
		(width 0.127)
		(layer "In2.Cu")
		(net "ROMD1_R")
	)
	(segment
		(start 35.085274 -93.1926)
		(end 35.564572 -92.713302)
		(width 0.127)
		(layer "In2.Cu")
		(net "ROMD1_R")
	)
	(segment
		(start 16.502634 -105.357168)
		(end 19.41322 -102.446582)
		(width 0.127)
		(layer "In2.Cu")
		(net "ROMD1_R")
	)
	(segment
		(start 26.241248 -96.1136)
		(end 26.706576 -96.1136)
		(width 0.127)
		(layer "In2.Cu")
		(net "ROMD1_R")
	)
	(segment
		(start 23.318724 -99.082606)
		(end 23.320248 -99.081082)
		(width 0.127)
		(layer "In2.Cu")
		(net "ROMD1_R")
	)
	(segment
		(start 23.742904 -99.081336)
		(end 25.197054 -97.627186)
		(width 0.127)
		(layer "In2.Cu")
		(net "ROMD1_R")
	)
	(segment
		(start 14.48943 -134.491984)
		(end 13.024612 -133.027166)
		(width 0.127)
		(layer "In2.Cu")
		(net "ROMD1_R")
	)
	(segment
		(start 15.658846 -106.340148)
		(end 15.6591 -106.339894)
		(width 0.127)
		(layer "In2.Cu")
		(net "ROMD1_R")
	)
	(segment
		(start 30.503876 -93.4466)
		(end 30.957012 -92.993464)
		(width 0.127)
		(layer "In2.Cu")
		(net "ROMD1_R")
	)
	(segment
		(start 25.197054 -97.157794)
		(end 26.241248 -96.1136)
		(width 0.127)
		(layer "In2.Cu")
		(net "ROMD1_R")
	)
	(segment
		(start 30.957012 -92.993464)
		(end 31.346648 -92.993464)
		(width 0.127)
		(layer "In2.Cu")
		(net "ROMD1_R")
	)
	(segment
		(start 13.024612 -133.026912)
		(end 10.61466 -130.61696)
		(width 0.127)
		(layer "In2.Cu")
		(net "ROMD1_R")
	)
	(segment
		(start 19.7358 -136.779)
		(end 19.05 -136.0932)
		(width 0.127)
		(layer "In2.Cu")
		(net "ROMD1_R")
	)
	(segment
		(start 21.381974 -100.051108)
		(end 22.11705 -100.051108)
		(width 0.127)
		(layer "In2.Cu")
		(net "ROMD1_R")
	)
	(segment
		(start 14.1732 -112.919002)
		(end 14.544802 -112.5474)
		(width 0.127)
		(layer "In2.Cu")
		(net "ROMD1_R")
	)
	(segment
		(start 15.6591 -106.339894)
		(end 15.6591 -106.200702)
		(width 0.127)
		(layer "In2.Cu")
		(net "ROMD1_R")
	)
	(segment
		(start 19.41322 -102.446582)
		(end 19.833336 -102.446582)
		(width 0.127)
		(layer "In2.Cu")
		(net "ROMD1_R")
	)
	(segment
		(start 55.762398 -90.681302)
		(end 55.77332 -90.67038)
		(width 0.127)
		(layer "In2.Cu")
		(net "ROMD1_R")
	)
	(segment
		(start 25.197054 -97.627186)
		(end 25.197054 -97.157794)
		(width 0.127)
		(layer "In2.Cu")
		(net "ROMD1_R")
	)
	(segment
		(start 14.544802 -112.5474)
		(end 14.545056 -112.5474)
		(width 0.127)
		(layer "In2.Cu")
		(net "ROMD1_R")
	)
	(segment
		(start 10.61466 -130.61696)
		(end 10.614406 -127.53975)
		(width 0.127)
		(layer "In2.Cu")
		(net "ROMD1_R")
	)
	(segment
		(start 12.9286 -120.06072)
		(end 12.9286 -114.163856)
		(width 0.127)
		(layer "In2.Cu")
		(net "ROMD1_R")
	)
	(segment
		(start 15.6591 -107.25277)
		(end 15.6591 -106.866182)
		(width 0.127)
		(layer "In2.Cu")
		(net "ROMD1_R")
	)
	(segment
		(start 19.05 -136.0932)
		(end 18.321528 -136.0932)
		(width 0.127)
		(layer "In2.Cu")
		(net "ROMD1_R")
	)
	(segment
		(start 26.729182 -96.090994)
		(end 26.79446 -96.090994)
		(width 0.127)
		(layer "In2.Cu")
		(net "ROMD1_R")
	)
	(segment
		(start 14.970252 -134.492238)
		(end 14.489938 -134.492238)
		(width 0.127)
		(layer "In2.Cu")
		(net "ROMD1_R")
	)
	(segment
		(start 10.614406 -123.93676)
		(end 10.61466 -123.936506)
		(width 0.127)
		(layer "In2.Cu")
		(net "ROMD1_R")
	)
	(segment
		(start 15.6591 -106.200702)
		(end 15.758922 -106.10088)
		(width 0.127)
		(layer "In2.Cu")
		(net "ROMD1_R")
	)
	(segment
		(start 14.545056 -112.5474)
		(end 14.914372 -112.178084)
		(width 0.127)
		(layer "In2.Cu")
		(net "ROMD1_R")
	)
	(segment
		(start 64.102234 -64.38011)
		(end 64.102234 -64.380364)
		(width 0.127)
		(layer "In5.Cu")
		(net "ROMD1_R")
	)
	(segment
		(start 58.20156 -88.24214)
		(end 55.77332 -90.67038)
		(width 0.127)
		(layer "In5.Cu")
		(net "ROMD1_R")
	)
	(segment
		(start 58.20156 -75.548744)
		(end 58.20156 -88.24214)
		(width 0.127)
		(layer "In5.Cu")
		(net "ROMD1_R")
	)
	(segment
		(start 59.8932 -73.857104)
		(end 58.20156 -75.548744)
		(width 0.127)
		(layer "In5.Cu")
		(net "ROMD1_R")
	)
	(segment
		(start 67.691 -60.8076)
		(end 67.674744 -60.8076)
		(width 0.127)
		(layer "In5.Cu")
		(net "ROMD1_R")
	)
	(segment
		(start 67.674744 -60.8076)
		(end 64.102234 -64.38011)
		(width 0.127)
		(layer "In5.Cu")
		(net "ROMD1_R")
	)
	(segment
		(start 59.8932 -68.589398)
		(end 59.8932 -73.857104)
		(width 0.127)
		(layer "In5.Cu")
		(net "ROMD1_R")
	)
	(segment
		(start 64.102234 -64.380364)
		(end 59.8932 -68.589398)
		(width 0.127)
		(layer "In5.Cu")
		(net "ROMD1_R")
	)
	(segment
		(start 30.504892 -134.084822)
		(end 30.105096 -134.484618)
		(width 0.12065)
		(layer "F.Cu")
		(net "ROMD1")
	)
	(via
		(at 28.9306 -135.551164)
		(size 0.7112)
		(drill 0.3556)
		(layers "F.Cu" "B.Cu")
		(net "ROMD1")
	)
	(via
		(at 30.105096 -134.484618)
		(size 0.4572)
		(drill 0.2032)
		(layers "F.Cu" "B.Cu")
		(net "ROMD1")
	)
	(segment
		(start 29.099764 -135.382)
		(end 29.207714 -135.382)
		(width 0.12065)
		(layer "B.Cu")
		(net "ROMD1")
	)
	(segment
		(start 28.79852 -135.683244)
		(end 28.9306 -135.551164)
		(width 0.12065)
		(layer "B.Cu")
		(net "ROMD1")
	)
	(segment
		(start 28.9306 -135.551164)
		(end 29.099764 -135.382)
		(width 0.12065)
		(layer "B.Cu")
		(net "ROMD1")
	)
	(segment
		(start 28.34259 -135.683244)
		(end 28.79852 -135.683244)
		(width 0.12065)
		(layer "B.Cu")
		(net "ROMD1")
	)
	(segment
		(start 29.207714 -135.382)
		(end 30.105096 -134.484618)
		(width 0.12065)
		(layer "B.Cu")
		(net "ROMD1")
	)
	(segment
		(start 27.417522 -136.608312)
		(end 28.34259 -135.683244)
		(width 0.12065)
		(layer "B.Cu")
		(net "ROMD1")
	)
	(segment
		(start 21.570188 -136.608312)
		(end 27.417522 -136.608312)
		(width 0.12065)
		(layer "B.Cu")
		(net "ROMD1")
	)
	(segment
		(start 21.3995 -136.779)
		(end 21.570188 -136.608312)
		(width 0.12065)
		(layer "B.Cu")
		(net "ROMD1")
	)
	(segment
		(start 85.809836 -62.212728)
		(end 85.809836 -60.994036)
		(width 0.12065)
		(layer "F.Cu")
		(net "ROMD0_R")
	)
	(segment
		(start 85.809836 -60.994036)
		(end 83.82 -59.0042)
		(width 0.12065)
		(layer "F.Cu")
		(net "ROMD0_R")
	)
	(segment
		(start 73.075546 -59.0042)
		(end 71.873872 -60.205874)
		(width 0.12065)
		(layer "F.Cu")
		(net "ROMD0_R")
	)
	(segment
		(start 18.227802 -134.934452)
		(end 19.6342 -134.934452)
		(width 0.12065)
		(layer "F.Cu")
		(net "ROMD0_R")
	)
	(segment
		(start 71.873872 -60.205874)
		(end 68.892674 -60.205874)
		(width 0.12065)
		(layer "F.Cu")
		(net "ROMD0_R")
	)
	(segment
		(start 85.809836 -62.391544)
		(end 85.809836 -62.212728)
		(width 0.12065)
		(layer "F.Cu")
		(net "ROMD0_R")
	)
	(segment
		(start 68.892674 -62.40907)
		(end 68.892674 -62.230254)
		(width 0.12065)
		(layer "F.Cu")
		(net "ROMD0_R")
	)
	(segment
		(start 83.82 -59.0042)
		(end 73.075546 -59.0042)
		(width 0.12065)
		(layer "F.Cu")
		(net "ROMD0_R")
	)
	(segment
		(start 68.892674 -62.230254)
		(end 68.892674 -60.205874)
		(width 0.12065)
		(layer "F.Cu")
		(net "ROMD0_R")
	)
	(segment
		(start 18.07718 -135.085074)
		(end 18.227802 -134.934452)
		(width 0.12065)
		(layer "F.Cu")
		(net "ROMD0_R")
	)
	(via
		(at 69.5452 -60.96)
		(size 0.7112)
		(drill 0.3556)
		(layers "F.Cu" "B.Cu")
		(net "ROMD0_R")
	)
	(via
		(at 68.892674 -60.205874)
		(size 0.508)
		(drill 0.254)
		(layers "F.Cu" "B.Cu")
		(net "ROMD0_R")
	)
	(via
		(at 55.118 -91.44)
		(size 0.508)
		(drill 0.254)
		(layers "F.Cu" "B.Cu")
		(net "ROMD0_R")
	)
	(via
		(at 19.6342 -134.934452)
		(size 0.508)
		(drill 0.254)
		(layers "F.Cu" "B.Cu")
		(net "ROMD0_R")
	)
	(segment
		(start 69.5452 -60.8584)
		(end 69.5452 -60.96)
		(width 0.12065)
		(layer "B.Cu")
		(net "ROMD0_R")
	)
	(segment
		(start 19.6342 -134.934452)
		(end 19.6342 -135.2804)
		(width 0.12065)
		(layer "B.Cu")
		(net "ROMD0_R")
	)
	(segment
		(start 20.1168 -135.763)
		(end 20.5105 -135.763)
		(width 0.12065)
		(layer "B.Cu")
		(net "ROMD0_R")
	)
	(segment
		(start 19.6342 -135.2804)
		(end 20.1168 -135.763)
		(width 0.12065)
		(layer "B.Cu")
		(net "ROMD0_R")
	)
	(segment
		(start 68.892674 -60.205874)
		(end 69.5452 -60.8584)
		(width 0.12065)
		(layer "B.Cu")
		(net "ROMD0_R")
	)
	(segment
		(start 26.504392 -96.7486)
		(end 26.96972 -96.7486)
		(width 0.127)
		(layer "In2.Cu")
		(net "ROMD0_R")
	)
	(segment
		(start 15.549626 -108.260388)
		(end 16.2941 -107.515914)
		(width 0.127)
		(layer "In2.Cu")
		(net "ROMD0_R")
	)
	(segment
		(start 11.24966 -130.353816)
		(end 11.24966 -127.276352)
		(width 0.127)
		(layer "In2.Cu")
		(net "ROMD0_R")
	)
	(segment
		(start 37.862002 -93.348302)
		(end 38.353492 -92.856812)
		(width 0.127)
		(layer "In2.Cu")
		(net "ROMD0_R")
	)
	(segment
		(start 23.461218 -99.71659)
		(end 24.005794 -99.71659)
		(width 0.127)
		(layer "In2.Cu")
		(net "ROMD0_R")
	)
	(segment
		(start 51.893724 -92.887038)
		(end 52.513738 -92.267024)
		(width 0.127)
		(layer "In2.Cu")
		(net "ROMD0_R")
	)
	(segment
		(start 20.096226 -103.081836)
		(end 22.6187 -100.559362)
		(width 0.127)
		(layer "In2.Cu")
		(net "ROMD0_R")
	)
	(segment
		(start 26.992326 -96.725994)
		(end 27.518106 -96.725994)
		(width 0.127)
		(layer "In2.Cu")
		(net "ROMD0_R")
	)
	(segment
		(start 38.353492 -92.856812)
		(end 42.205148 -92.856812)
		(width 0.127)
		(layer "In2.Cu")
		(net "ROMD0_R")
	)
	(segment
		(start 11.249406 -124.199904)
		(end 11.24966 -124.19965)
		(width 0.127)
		(layer "In2.Cu")
		(net "ROMD0_R")
	)
	(segment
		(start 23.0886 -100.089462)
		(end 23.0886 -100.089208)
		(width 0.127)
		(layer "In2.Cu")
		(net "ROMD0_R")
	)
	(segment
		(start 19.370548 -134.6708)
		(end 18.6182 -134.6708)
		(width 0.127)
		(layer "In2.Cu")
		(net "ROMD0_R")
	)
	(segment
		(start 52.513738 -92.267024)
		(end 54.290976 -92.267024)
		(width 0.127)
		(layer "In2.Cu")
		(net "ROMD0_R")
	)
	(segment
		(start 15.549372 -108.797344)
		(end 15.549118 -108.79709)
		(width 0.127)
		(layer "In2.Cu")
		(net "ROMD0_R")
	)
	(segment
		(start 15.549626 -108.270802)
		(end 15.549626 -108.260388)
		(width 0.127)
		(layer "In2.Cu")
		(net "ROMD0_R")
	)
	(segment
		(start 22.990302 -100.187506)
		(end 22.990556 -100.187506)
		(width 0.127)
		(layer "In2.Cu")
		(net "ROMD0_R")
	)
	(segment
		(start 16.393922 -106.36377)
		(end 16.765524 -105.992168)
		(width 0.127)
		(layer "In2.Cu")
		(net "ROMD0_R")
	)
	(segment
		(start 27.599894 -96.726248)
		(end 30.104334 -94.221808)
		(width 0.127)
		(layer "In2.Cu")
		(net "ROMD0_R")
	)
	(segment
		(start 19.6342 -134.934452)
		(end 19.370548 -134.6708)
		(width 0.127)
		(layer "In2.Cu")
		(net "ROMD0_R")
	)
	(segment
		(start 26.96972 -96.7486)
		(end 26.992326 -96.725994)
		(width 0.127)
		(layer "In2.Cu")
		(net "ROMD0_R")
	)
	(segment
		(start 15.23365 -133.857238)
		(end 15.233396 -133.857238)
		(width 0.127)
		(layer "In2.Cu")
		(net "ROMD0_R")
	)
	(segment
		(start 11.249406 -127.276098)
		(end 11.249406 -124.199904)
		(width 0.127)
		(layer "In2.Cu")
		(net "ROMD0_R")
	)
	(segment
		(start 34.95421 -94.221808)
		(end 35.827716 -93.348302)
		(width 0.127)
		(layer "In2.Cu")
		(net "ROMD0_R")
	)
	(segment
		(start 42.205148 -92.856812)
		(end 42.235374 -92.887038)
		(width 0.127)
		(layer "In2.Cu")
		(net "ROMD0_R")
	)
	(segment
		(start 14.8082 -119.079264)
		(end 14.8082 -113.1824)
		(width 0.127)
		(layer "In2.Cu")
		(net "ROMD0_R")
	)
	(segment
		(start 12.182348 -122.094752)
		(end 12.182348 -121.705116)
		(width 0.127)
		(layer "In2.Cu")
		(net "ROMD0_R")
	)
	(segment
		(start 23.0886 -100.089208)
		(end 23.461218 -99.71659)
		(width 0.127)
		(layer "In2.Cu")
		(net "ROMD0_R")
	)
	(segment
		(start 11.621262 -123.827794)
		(end 11.621516 -123.827794)
		(width 0.127)
		(layer "In2.Cu")
		(net "ROMD0_R")
	)
	(segment
		(start 27.518106 -96.725994)
		(end 27.51836 -96.726248)
		(width 0.127)
		(layer "In2.Cu")
		(net "ROMD0_R")
	)
	(segment
		(start 19.67611 -103.081836)
		(end 20.096226 -103.081836)
		(width 0.127)
		(layer "In2.Cu")
		(net "ROMD0_R")
	)
	(segment
		(start 22.6187 -100.559362)
		(end 22.6187 -100.559108)
		(width 0.127)
		(layer "In2.Cu")
		(net "ROMD0_R")
	)
	(segment
		(start 11.24966 -127.276352)
		(end 11.249406 -127.276098)
		(width 0.127)
		(layer "In2.Cu")
		(net "ROMD0_R")
	)
	(segment
		(start 15.549118 -108.79709)
		(end 15.549118 -108.27131)
		(width 0.127)
		(layer "In2.Cu")
		(net "ROMD0_R")
	)
	(segment
		(start 16.393922 -106.364024)
		(end 16.393922 -106.36377)
		(width 0.127)
		(layer "In2.Cu")
		(net "ROMD0_R")
	)
	(segment
		(start 15.549372 -112.441228)
		(end 15.549372 -108.797344)
		(width 0.127)
		(layer "In2.Cu")
		(net "ROMD0_R")
	)
	(segment
		(start 18.6182 -134.6708)
		(end 17.8943 -133.9469)
		(width 0.127)
		(layer "In2.Cu")
		(net "ROMD0_R")
	)
	(segment
		(start 12.484608 -122.964702)
		(end 12.484608 -122.397012)
		(width 0.127)
		(layer "In2.Cu")
		(net "ROMD0_R")
	)
	(segment
		(start 42.235374 -92.887038)
		(end 51.893724 -92.887038)
		(width 0.127)
		(layer "In2.Cu")
		(net "ROMD0_R")
	)
	(segment
		(start 15.323312 -133.9469)
		(end 15.23365 -133.857238)
		(width 0.127)
		(layer "In2.Cu")
		(net "ROMD0_R")
	)
	(segment
		(start 14.752574 -133.856984)
		(end 13.659612 -132.764022)
		(width 0.127)
		(layer "In2.Cu")
		(net "ROMD0_R")
	)
	(segment
		(start 11.24966 -124.19965)
		(end 11.24966 -124.199396)
		(width 0.127)
		(layer "In2.Cu")
		(net "ROMD0_R")
	)
	(segment
		(start 24.005794 -99.71659)
		(end 25.832054 -97.89033)
		(width 0.127)
		(layer "In2.Cu")
		(net "ROMD0_R")
	)
	(segment
		(start 22.990556 -100.187506)
		(end 23.0886 -100.089462)
		(width 0.127)
		(layer "In2.Cu")
		(net "ROMD0_R")
	)
	(segment
		(start 27.51836 -96.726248)
		(end 27.599894 -96.726248)
		(width 0.127)
		(layer "In2.Cu")
		(net "ROMD0_R")
	)
	(segment
		(start 25.832054 -97.420938)
		(end 26.504392 -96.7486)
		(width 0.127)
		(layer "In2.Cu")
		(net "ROMD0_R")
	)
	(segment
		(start 16.2941 -106.463846)
		(end 16.393922 -106.364024)
		(width 0.127)
		(layer "In2.Cu")
		(net "ROMD0_R")
	)
	(segment
		(start 30.104334 -94.221808)
		(end 34.95421 -94.221808)
		(width 0.127)
		(layer "In2.Cu")
		(net "ROMD0_R")
	)
	(segment
		(start 35.827716 -93.348302)
		(end 37.862002 -93.348302)
		(width 0.127)
		(layer "In2.Cu")
		(net "ROMD0_R")
	)
	(segment
		(start 12.182348 -121.705116)
		(end 14.8082 -119.079264)
		(width 0.127)
		(layer "In2.Cu")
		(net "ROMD0_R")
	)
	(segment
		(start 16.2941 -107.515914)
		(end 16.2941 -106.463846)
		(width 0.127)
		(layer "In2.Cu")
		(net "ROMD0_R")
	)
	(segment
		(start 12.484608 -122.397012)
		(end 12.182348 -122.094752)
		(width 0.127)
		(layer "In2.Cu")
		(net "ROMD0_R")
	)
	(segment
		(start 25.832054 -97.89033)
		(end 25.832054 -97.420938)
		(width 0.127)
		(layer "In2.Cu")
		(net "ROMD0_R")
	)
	(segment
		(start 15.549118 -108.27131)
		(end 15.549626 -108.270802)
		(width 0.127)
		(layer "In2.Cu")
		(net "ROMD0_R")
	)
	(segment
		(start 15.233142 -133.856984)
		(end 14.752574 -133.856984)
		(width 0.127)
		(layer "In2.Cu")
		(net "ROMD0_R")
	)
	(segment
		(start 16.765778 -105.992168)
		(end 19.67611 -103.081836)
		(width 0.127)
		(layer "In2.Cu")
		(net "ROMD0_R")
	)
	(segment
		(start 22.6187 -100.559108)
		(end 22.990302 -100.187506)
		(width 0.127)
		(layer "In2.Cu")
		(net "ROMD0_R")
	)
	(segment
		(start 14.8082 -113.1824)
		(end 15.549372 -112.441228)
		(width 0.127)
		(layer "In2.Cu")
		(net "ROMD0_R")
	)
	(segment
		(start 15.233396 -133.857238)
		(end 15.233142 -133.856984)
		(width 0.127)
		(layer "In2.Cu")
		(net "ROMD0_R")
	)
	(segment
		(start 54.290976 -92.267024)
		(end 55.118 -91.44)
		(width 0.127)
		(layer "In2.Cu")
		(net "ROMD0_R")
	)
	(segment
		(start 16.765524 -105.992168)
		(end 16.765778 -105.992168)
		(width 0.127)
		(layer "In2.Cu")
		(net "ROMD0_R")
	)
	(segment
		(start 13.659612 -132.763768)
		(end 11.24966 -130.353816)
		(width 0.127)
		(layer "In2.Cu")
		(net "ROMD0_R")
	)
	(segment
		(start 17.8943 -133.9469)
		(end 15.323312 -133.9469)
		(width 0.127)
		(layer "In2.Cu")
		(net "ROMD0_R")
	)
	(segment
		(start 11.24966 -124.199396)
		(end 11.621262 -123.827794)
		(width 0.127)
		(layer "In2.Cu")
		(net "ROMD0_R")
	)
	(segment
		(start 13.659612 -132.764022)
		(end 13.659612 -132.763768)
		(width 0.127)
		(layer "In2.Cu")
		(net "ROMD0_R")
	)
	(segment
		(start 11.621516 -123.827794)
		(end 12.484608 -122.964702)
		(width 0.127)
		(layer "In2.Cu")
		(net "ROMD0_R")
	)
	(segment
		(start 68.8594 -60.1726)
		(end 68.892674 -60.205874)
		(width 0.127)
		(layer "In5.Cu")
		(net "ROMD0_R")
	)
	(segment
		(start 67.4116 -60.1726)
		(end 68.8594 -60.1726)
		(width 0.127)
		(layer "In5.Cu")
		(net "ROMD0_R")
	)
	(segment
		(start 57.56656 -75.2856)
		(end 59.2582 -73.59396)
		(width 0.127)
		(layer "In5.Cu")
		(net "ROMD0_R")
	)
	(segment
		(start 57.56656 -87.903558)
		(end 57.56656 -75.2856)
		(width 0.127)
		(layer "In5.Cu")
		(net "ROMD0_R")
	)
	(segment
		(start 63.467234 -64.116966)
		(end 67.4116 -60.1726)
		(width 0.127)
		(layer "In5.Cu")
		(net "ROMD0_R")
	)
	(segment
		(start 59.2582 -68.326254)
		(end 63.467234 -64.11722)
		(width 0.127)
		(layer "In5.Cu")
		(net "ROMD0_R")
	)
	(segment
		(start 55.118 -90.352118)
		(end 57.56656 -87.903558)
		(width 0.127)
		(layer "In5.Cu")
		(net "ROMD0_R")
	)
	(segment
		(start 55.118 -91.44)
		(end 55.118 -90.352118)
		(width 0.127)
		(layer "In5.Cu")
		(net "ROMD0_R")
	)
	(segment
		(start 63.467234 -64.11722)
		(end 63.467234 -64.116966)
		(width 0.127)
		(layer "In5.Cu")
		(net "ROMD0_R")
	)
	(segment
		(start 59.2582 -73.59396)
		(end 59.2582 -68.326254)
		(width 0.127)
		(layer "In5.Cu")
		(net "ROMD0_R")
	)
	(segment
		(start 29.704792 -134.084822)
		(end 29.304996 -134.484618)
		(width 0.12065)
		(layer "F.Cu")
		(net "ROMD0")
	)
	(via
		(at 26.704544 -135.933688)
		(size 0.7112)
		(drill 0.3556)
		(layers "F.Cu" "B.Cu")
		(net "ROMD0")
	)
	(via
		(at 29.304996 -134.484618)
		(size 0.4572)
		(drill 0.2032)
		(layers "F.Cu" "B.Cu")
		(net "ROMD0")
	)
	(segment
		(start 26.704544 -135.933688)
		(end 26.69667 -135.925814)
		(width 0.12065)
		(layer "B.Cu")
		(net "ROMD0")
	)
	(segment
		(start 21.562314 -135.925814)
		(end 21.3995 -135.763)
		(width 0.12065)
		(layer "B.Cu")
		(net "ROMD0")
	)
	(segment
		(start 29.304996 -134.484618)
		(end 29.019246 -134.484618)
		(width 0.12065)
		(layer "B.Cu")
		(net "ROMD0")
	)
	(segment
		(start 27.570176 -135.933688)
		(end 26.704544 -135.933688)
		(width 0.12065)
		(layer "B.Cu")
		(net "ROMD0")
	)
	(segment
		(start 26.69667 -135.925814)
		(end 21.562314 -135.925814)
		(width 0.12065)
		(layer "B.Cu")
		(net "ROMD0")
	)
	(segment
		(start 29.019246 -134.484618)
		(end 27.570176 -135.933688)
		(width 0.12065)
		(layer "B.Cu")
		(net "ROMD0")
	)
	(segment
		(start 31.304738 -130.88493)
		(end 31.704534 -130.485134)
		(width 0.12065)
		(layer "F.Cu")
		(net "ROMA9")
	)
	(via
		(at 31.704534 -130.485134)
		(size 0.4572)
		(drill 0.2032)
		(layers "F.Cu" "B.Cu")
		(net "ROMA9")
	)
	(via
		(at 26.933398 -128.958594)
		(size 0.7112)
		(drill 0.3556)
		(layers "F.Cu" "B.Cu")
		(net "ROMA9")
	)
	(segment
		(start 24.816562 -128.45923)
		(end 26.434034 -128.45923)
		(width 0.12065)
		(layer "B.Cu")
		(net "ROMA9")
	)
	(segment
		(start 21.3995 -127.690118)
		(end 22.375114 -128.665732)
		(width 0.12065)
		(layer "B.Cu")
		(net "ROMA9")
	)
	(segment
		(start 21.3995 -127.635)
		(end 21.3995 -127.690118)
		(width 0.12065)
		(layer "B.Cu")
		(net "ROMA9")
	)
	(segment
		(start 26.933398 -128.958594)
		(end 28.069286 -130.094482)
		(width 0.12065)
		(layer "B.Cu")
		(net "ROMA9")
	)
	(segment
		(start 22.375114 -128.665732)
		(end 24.61006 -128.665732)
		(width 0.12065)
		(layer "B.Cu")
		(net "ROMA9")
	)
	(segment
		(start 31.313882 -130.094482)
		(end 31.704534 -130.485134)
		(width 0.12065)
		(layer "B.Cu")
		(net "ROMA9")
	)
	(segment
		(start 24.61006 -128.665732)
		(end 24.816562 -128.45923)
		(width 0.12065)
		(layer "B.Cu")
		(net "ROMA9")
	)
	(segment
		(start 26.434034 -128.45923)
		(end 26.933398 -128.958594)
		(width 0.12065)
		(layer "B.Cu")
		(net "ROMA9")
	)
	(segment
		(start 28.069286 -130.094482)
		(end 31.313882 -130.094482)
		(width 0.12065)
		(layer "B.Cu")
		(net "ROMA9")
	)
	(segment
		(start 32.104838 -130.88493)
		(end 32.504634 -130.485134)
		(width 0.12065)
		(layer "F.Cu")
		(net "ROMA8")
	)
	(via
		(at 25.202134 -129.389632)
		(size 0.7112)
		(drill 0.3556)
		(layers "F.Cu" "B.Cu")
		(net "ROMA8")
	)
	(via
		(at 32.504634 -130.485134)
		(size 0.4572)
		(drill 0.2032)
		(layers "F.Cu" "B.Cu")
		(net "ROMA8")
	)
	(segment
		(start 21.676868 -129.389632)
		(end 25.202134 -129.389632)
		(width 0.12065)
		(layer "B.Cu")
		(net "ROMA8")
	)
	(segment
		(start 32.027876 -130.961892)
		(end 26.810208 -130.961892)
		(width 0.12065)
		(layer "B.Cu")
		(net "ROMA8")
	)
	(segment
		(start 32.504634 -130.485134)
		(end 32.027876 -130.961892)
		(width 0.12065)
		(layer "B.Cu")
		(net "ROMA8")
	)
	(segment
		(start 25.237948 -129.389632)
		(end 25.202134 -129.389632)
		(width 0.12065)
		(layer "B.Cu")
		(net "ROMA8")
	)
	(segment
		(start 26.810208 -130.961892)
		(end 25.237948 -129.389632)
		(width 0.12065)
		(layer "B.Cu")
		(net "ROMA8")
	)
	(segment
		(start 21.3995 -129.667)
		(end 21.676868 -129.389632)
		(width 0.12065)
		(layer "B.Cu")
		(net "ROMA8")
	)
	(segment
		(start 22.477222 -131.143248)
		(end 24.539448 -131.143248)
		(width 0.12065)
		(layer "F.Cu")
		(net "ROMA7")
	)
	(segment
		(start 25.881076 -132.484876)
		(end 29.704792 -132.484876)
		(width 0.12065)
		(layer "F.Cu")
		(net "ROMA7")
	)
	(segment
		(start 22.100794 -131.519676)
		(end 22.477222 -131.143248)
		(width 0.12065)
		(layer "F.Cu")
		(net "ROMA7")
	)
	(segment
		(start 21.2344 -133.5278)
		(end 20.764754 -133.997446)
		(width 0.12065)
		(layer "F.Cu")
		(net "ROMA7")
	)
	(segment
		(start 22.100794 -133.067806)
		(end 22.100794 -131.519676)
		(width 0.12065)
		(layer "F.Cu")
		(net "ROMA7")
	)
	(segment
		(start 21.2344 -133.5278)
		(end 21.6408 -133.5278)
		(width 0.12065)
		(layer "F.Cu")
		(net "ROMA7")
	)
	(segment
		(start 21.6408 -133.5278)
		(end 22.100794 -133.067806)
		(width 0.12065)
		(layer "F.Cu")
		(net "ROMA7")
	)
	(segment
		(start 20.764754 -134.238746)
		(end 20.5613 -134.4422)
		(width 0.12065)
		(layer "F.Cu")
		(net "ROMA7")
	)
	(segment
		(start 24.539448 -131.143248)
		(end 25.881076 -132.484876)
		(width 0.12065)
		(layer "F.Cu")
		(net "ROMA7")
	)
	(segment
		(start 20.764754 -133.997446)
		(end 20.764754 -134.238746)
		(width 0.12065)
		(layer "F.Cu")
		(net "ROMA7")
	)
	(via
		(at 21.2344 -133.5278)
		(size 0.7112)
		(drill 0.3556)
		(layers "F.Cu" "B.Cu")
		(net "ROMA7")
	)
	(segment
		(start 25.690322 -133.068822)
		(end 26.235406 -133.068822)
		(width 0.12065)
		(layer "F.Cu")
		(net "ROMA6")
	)
	(segment
		(start 26.235406 -133.068822)
		(end 28.627578 -133.068822)
		(width 0.12065)
		(layer "F.Cu")
		(net "ROMA6")
	)
	(segment
		(start 30.122368 -132.8674)
		(end 30.504892 -132.484876)
		(width 0.12065)
		(layer "F.Cu")
		(net "ROMA6")
	)
	(segment
		(start 28.627578 -133.068822)
		(end 28.829 -132.8674)
		(width 0.12065)
		(layer "F.Cu")
		(net "ROMA6")
	)
	(segment
		(start 28.829 -132.8674)
		(end 30.122368 -132.8674)
		(width 0.12065)
		(layer "F.Cu")
		(net "ROMA6")
	)
	(segment
		(start 24.3205 -131.699)
		(end 25.690322 -133.068822)
		(width 0.12065)
		(layer "F.Cu")
		(net "ROMA6")
	)
	(via
		(at 26.235406 -133.068822)
		(size 0.7112)
		(drill 0.3556)
		(layers "F.Cu" "B.Cu")
		(net "ROMA6")
	)
	(segment
		(start 31.304738 -132.484876)
		(end 30.904942 -132.08508)
		(width 0.12065)
		(layer "F.Cu")
		(net "ROMA5")
	)
	(via
		(at 30.904942 -132.08508)
		(size 0.4572)
		(drill 0.2032)
		(layers "F.Cu" "B.Cu")
		(net "ROMA5")
	)
	(via
		(at 28.894278 -132.305044)
		(size 0.7112)
		(drill 0.3556)
		(layers "F.Cu" "B.Cu")
		(net "ROMA5")
	)
	(segment
		(start 27.218386 -132.776214)
		(end 27.689556 -132.305044)
		(width 0.12065)
		(layer "B.Cu")
		(net "ROMA5")
	)
	(segment
		(start 30.498542 -132.020818)
		(end 30.904942 -132.020818)
		(width 0.12065)
		(layer "B.Cu")
		(net "ROMA5")
	)
	(segment
		(start 25.100026 -132.323586)
		(end 25.552654 -132.776214)
		(width 0.12065)
		(layer "B.Cu")
		(net "ROMA5")
	)
	(segment
		(start 28.894278 -132.305044)
		(end 30.214316 -132.305044)
		(width 0.12065)
		(layer "B.Cu")
		(net "ROMA5")
	)
	(segment
		(start 27.689556 -132.305044)
		(end 28.894278 -132.305044)
		(width 0.12065)
		(layer "B.Cu")
		(net "ROMA5")
	)
	(segment
		(start 30.214316 -132.305044)
		(end 30.498542 -132.020818)
		(width 0.12065)
		(layer "B.Cu")
		(net "ROMA5")
	)
	(segment
		(start 21.3995 -131.709414)
		(end 22.013672 -132.323586)
		(width 0.12065)
		(layer "B.Cu")
		(net "ROMA5")
	)
	(segment
		(start 25.552654 -132.776214)
		(end 27.218386 -132.776214)
		(width 0.12065)
		(layer "B.Cu")
		(net "ROMA5")
	)
	(segment
		(start 21.3995 -131.699)
		(end 21.3995 -131.709414)
		(width 0.12065)
		(layer "B.Cu")
		(net "ROMA5")
	)
	(segment
		(start 22.013672 -132.323586)
		(end 25.100026 -132.323586)
		(width 0.12065)
		(layer "B.Cu")
		(net "ROMA5")
	)
	(segment
		(start 30.904942 -132.020818)
		(end 30.904942 -132.08508)
		(width 0.12065)
		(layer "B.Cu")
		(net "ROMA5")
	)
	(segment
		(start 32.104838 -132.484876)
		(end 31.704788 -132.084826)
		(width 0.12065)
		(layer "F.Cu")
		(net "ROMA4")
	)
	(via
		(at 25.341072 -131.648962)
		(size 0.7112)
		(drill 0.3556)
		(layers "F.Cu" "B.Cu")
		(net "ROMA4")
	)
	(via
		(at 31.704788 -132.084826)
		(size 0.4572)
		(drill 0.2032)
		(layers "F.Cu" "B.Cu")
		(net "ROMA4")
	)
	(segment
		(start 25.341072 -131.657344)
		(end 25.341072 -131.648962)
		(width 0.12065)
		(layer "B.Cu")
		(net "ROMA4")
	)
	(segment
		(start 31.704788 -132.084826)
		(end 31.31439 -131.694428)
		(width 0.12065)
		(layer "B.Cu")
		(net "ROMA4")
	)
	(segment
		(start 26.046176 -132.362448)
		(end 25.341072 -131.657344)
		(width 0.12065)
		(layer "B.Cu")
		(net "ROMA4")
	)
	(segment
		(start 24.386286 -131.462018)
		(end 25.154128 -131.462018)
		(width 0.12065)
		(layer "B.Cu")
		(net "ROMA4")
	)
	(segment
		(start 27.944572 -131.694428)
		(end 27.276552 -132.362448)
		(width 0.12065)
		(layer "B.Cu")
		(net "ROMA4")
	)
	(segment
		(start 27.276552 -132.362448)
		(end 26.046176 -132.362448)
		(width 0.12065)
		(layer "B.Cu")
		(net "ROMA4")
	)
	(segment
		(start 31.31439 -131.694428)
		(end 27.944572 -131.694428)
		(width 0.12065)
		(layer "B.Cu")
		(net "ROMA4")
	)
	(segment
		(start 25.154128 -131.462018)
		(end 25.341072 -131.648962)
		(width 0.12065)
		(layer "B.Cu")
		(net "ROMA4")
	)
	(segment
		(start 32.904938 -132.484876)
		(end 33.304734 -132.884672)
		(width 0.12065)
		(layer "F.Cu")
		(net "ROMA3")
	)
	(via
		(at 33.304734 -132.884672)
		(size 0.4572)
		(drill 0.2032)
		(layers "F.Cu" "B.Cu")
		(net "ROMA3")
	)
	(via
		(at 27.264614 -134.329424)
		(size 0.7112)
		(drill 0.3556)
		(layers "F.Cu" "B.Cu")
		(net "ROMA3")
	)
	(segment
		(start 32.691324 -133.498082)
		(end 28.198064 -133.498082)
		(width 0.12065)
		(layer "B.Cu")
		(net "ROMA3")
	)
	(segment
		(start 28.198064 -133.498082)
		(end 27.366722 -134.329424)
		(width 0.12065)
		(layer "B.Cu")
		(net "ROMA3")
	)
	(segment
		(start 24.802846 -133.890766)
		(end 24.583644 -133.671564)
		(width 0.12065)
		(layer "B.Cu")
		(net "ROMA3")
	)
	(segment
		(start 26.755598 -134.329424)
		(end 26.31694 -133.890766)
		(width 0.12065)
		(layer "B.Cu")
		(net "ROMA3")
	)
	(segment
		(start 33.304734 -132.884672)
		(end 32.691324 -133.498082)
		(width 0.12065)
		(layer "B.Cu")
		(net "ROMA3")
	)
	(segment
		(start 27.264614 -134.329424)
		(end 26.755598 -134.329424)
		(width 0.12065)
		(layer "B.Cu")
		(net "ROMA3")
	)
	(segment
		(start 26.31694 -133.890766)
		(end 24.802846 -133.890766)
		(width 0.12065)
		(layer "B.Cu")
		(net "ROMA3")
	)
	(segment
		(start 27.366722 -134.329424)
		(end 27.264614 -134.329424)
		(width 0.12065)
		(layer "B.Cu")
		(net "ROMA3")
	)
	(segment
		(start 16.884142 -129.896616)
		(end 17.113758 -129.667)
		(width 0.12065)
		(layer "F.Cu")
		(net "ROMA23")
	)
	(segment
		(start 17.059148 -130.846068)
		(end 16.884142 -130.671062)
		(width 0.12065)
		(layer "F.Cu")
		(net "ROMA23")
	)
	(segment
		(start 17.113758 -129.667)
		(end 17.9705 -129.667)
		(width 0.12065)
		(layer "F.Cu")
		(net "ROMA23")
	)
	(segment
		(start 16.884142 -130.671062)
		(end 16.884142 -129.896616)
		(width 0.12065)
		(layer "F.Cu")
		(net "ROMA23")
	)
	(segment
		(start 32.904938 -129.284984)
		(end 33.304734 -129.68478)
		(width 0.12065)
		(layer "F.Cu")
		(net "ROMA23")
	)
	(via
		(at 33.304734 -129.68478)
		(size 0.4572)
		(drill 0.2032)
		(layers "F.Cu" "B.Cu")
		(net "ROMA23")
	)
	(via
		(at 16.884142 -129.896616)
		(size 0.7112)
		(drill 0.3556)
		(layers "F.Cu" "B.Cu")
		(net "ROMA23")
	)
	(via
		(at 17.059148 -130.846068)
		(size 0.508)
		(drill 0.254)
		(layers "F.Cu" "B.Cu")
		(net "ROMA23")
	)
	(segment
		(start 30.365954 -130.4671)
		(end 30.74162 -130.091434)
		(width 0.127)
		(layer "In2.Cu")
		(net "ROMA23")
	)
	(segment
		(start 32.89808 -130.091434)
		(end 33.304734 -129.68478)
		(width 0.127)
		(layer "In2.Cu")
		(net "ROMA23")
	)
	(segment
		(start 30.74162 -130.091434)
		(end 32.89808 -130.091434)
		(width 0.127)
		(layer "In2.Cu")
		(net "ROMA23")
	)
	(segment
		(start 17.059148 -130.846068)
		(end 17.185132 -130.846068)
		(width 0.127)
		(layer "In2.Cu")
		(net "ROMA23")
	)
	(segment
		(start 17.5641 -130.4671)
		(end 30.365954 -130.4671)
		(width 0.127)
		(layer "In2.Cu")
		(net "ROMA23")
	)
	(segment
		(start 17.185132 -130.846068)
		(end 17.5641 -130.4671)
		(width 0.127)
		(layer "In2.Cu")
		(net "ROMA23")
	)
	(segment
		(start 24.40432 -128.44018)
		(end 25.35428 -128.44018)
		(width 0.12065)
		(layer "F.Cu")
		(net "ROMA22")
	)
	(segment
		(start 25.70988 -128.44018)
		(end 26.4287 -129.159)
		(width 0.12065)
		(layer "F.Cu")
		(net "ROMA22")
	)
	(segment
		(start 24.3205 -128.524)
		(end 24.40432 -128.44018)
		(width 0.12065)
		(layer "F.Cu")
		(net "ROMA22")
	)
	(segment
		(start 27.08148 -129.159)
		(end 28.00731 -130.08483)
		(width 0.12065)
		(layer "F.Cu")
		(net "ROMA22")
	)
	(segment
		(start 26.4287 -129.159)
		(end 27.08148 -129.159)
		(width 0.12065)
		(layer "F.Cu")
		(net "ROMA22")
	)
	(segment
		(start 28.00731 -130.08483)
		(end 29.704792 -130.08483)
		(width 0.12065)
		(layer "F.Cu")
		(net "ROMA22")
	)
	(segment
		(start 25.35428 -128.44018)
		(end 25.70988 -128.44018)
		(width 0.12065)
		(layer "F.Cu")
		(net "ROMA22")
	)
	(via
		(at 25.35428 -128.44018)
		(size 0.7112)
		(drill 0.3556)
		(layers "F.Cu" "B.Cu")
		(net "ROMA22")
	)
	(segment
		(start 31.304738 -131.684776)
		(end 30.904942 -131.28498)
		(width 0.12065)
		(layer "F.Cu")
		(net "ROMA21")
	)
	(segment
		(start 30.904942 -131.28498)
		(end 30.904942 -130.485134)
		(width 0.12065)
		(layer "F.Cu")
		(net "ROMA21")
	)
	(via
		(at 27.131772 -130.3909)
		(size 0.7112)
		(drill 0.3556)
		(layers "F.Cu" "B.Cu")
		(net "ROMA21")
	)
	(via
		(at 30.904942 -130.485134)
		(size 0.4572)
		(drill 0.2032)
		(layers "F.Cu" "B.Cu")
		(net "ROMA21")
	)
	(segment
		(start 30.904942 -130.485134)
		(end 27.226006 -130.485134)
		(width 0.12065)
		(layer "B.Cu")
		(net "ROMA21")
	)
	(segment
		(start 27.226006 -130.485134)
		(end 27.131772 -130.3909)
		(width 0.12065)
		(layer "B.Cu")
		(net "ROMA21")
	)
	(segment
		(start 27.131772 -130.3909)
		(end 25.562052 -128.82118)
		(width 0.12065)
		(layer "B.Cu")
		(net "ROMA21")
	)
	(segment
		(start 24.760174 -129.027682)
		(end 21.776182 -129.027682)
		(width 0.12065)
		(layer "B.Cu")
		(net "ROMA21")
	)
	(segment
		(start 21.776182 -129.027682)
		(end 21.3995 -128.651)
		(width 0.12065)
		(layer "B.Cu")
		(net "ROMA21")
	)
	(segment
		(start 25.562052 -128.82118)
		(end 24.966676 -128.82118)
		(width 0.12065)
		(layer "B.Cu")
		(net "ROMA21")
	)
	(segment
		(start 24.966676 -128.82118)
		(end 24.760174 -129.027682)
		(width 0.12065)
		(layer "B.Cu")
		(net "ROMA21")
	)
	(segment
		(start 26.1874 -131.4196)
		(end 25.8826 -131.4196)
		(width 0.12065)
		(layer "F.Cu")
		(net "ROMA20")
	)
	(segment
		(start 24.882348 -130.419348)
		(end 22.176994 -130.419348)
		(width 0.12065)
		(layer "F.Cu")
		(net "ROMA20")
	)
	(segment
		(start 22.176994 -130.419348)
		(end 21.376894 -131.219448)
		(width 0.12065)
		(layer "F.Cu")
		(net "ROMA20")
	)
	(segment
		(start 29.704792 -131.684776)
		(end 26.452576 -131.684776)
		(width 0.12065)
		(layer "F.Cu")
		(net "ROMA20")
	)
	(segment
		(start 21.376894 -131.22021)
		(end 21.256244 -131.34086)
		(width 0.12065)
		(layer "F.Cu")
		(net "ROMA20")
	)
	(segment
		(start 21.376894 -131.219448)
		(end 21.376894 -131.22021)
		(width 0.12065)
		(layer "F.Cu")
		(net "ROMA20")
	)
	(segment
		(start 25.8826 -131.4196)
		(end 24.882348 -130.419348)
		(width 0.12065)
		(layer "F.Cu")
		(net "ROMA20")
	)
	(segment
		(start 21.256244 -131.34086)
		(end 21.086826 -131.34086)
		(width 0.12065)
		(layer "F.Cu")
		(net "ROMA20")
	)
	(segment
		(start 26.452576 -131.684776)
		(end 26.1874 -131.4196)
		(width 0.12065)
		(layer "F.Cu")
		(net "ROMA20")
	)
	(via
		(at 26.1874 -131.4196)
		(size 0.7112)
		(drill 0.3556)
		(layers "F.Cu" "B.Cu")
		(net "ROMA20")
	)
	(segment
		(start 29.704792 -133.284976)
		(end 29.0322 -133.284976)
		(width 0.12065)
		(layer "F.Cu")
		(net "ROMA2")
	)
	(segment
		(start 29.0322 -133.284976)
		(end 28.312872 -134.004304)
		(width 0.12065)
		(layer "F.Cu")
		(net "ROMA2")
	)
	(segment
		(start 25.377902 -134.004304)
		(end 25.356566 -133.982968)
		(width 0.12065)
		(layer "F.Cu")
		(net "ROMA2")
	)
	(segment
		(start 24.3205 -132.946902)
		(end 25.356566 -133.982968)
		(width 0.12065)
		(layer "F.Cu")
		(net "ROMA2")
	)
	(segment
		(start 25.356566 -133.982968)
		(end 25.356566 -133.99008)
		(width 0.12065)
		(layer "F.Cu")
		(net "ROMA2")
	)
	(segment
		(start 28.312872 -134.004304)
		(end 25.377902 -134.004304)
		(width 0.12065)
		(layer "F.Cu")
		(net "ROMA2")
	)
	(segment
		(start 24.3205 -132.715)
		(end 24.3205 -132.946902)
		(width 0.12065)
		(layer "F.Cu")
		(net "ROMA2")
	)
	(via
		(at 25.356566 -133.99008)
		(size 0.7112)
		(drill 0.3556)
		(layers "F.Cu" "B.Cu")
		(net "ROMA2")
	)
	(segment
		(start 18.25498 -130.96748)
		(end 17.9705 -130.683)
		(width 0.12065)
		(layer "F.Cu")
		(net "ROMA19")
	)
	(segment
		(start 18.104612 -131.699)
		(end 18.17116 -131.632452)
		(width 0.12065)
		(layer "F.Cu")
		(net "ROMA19")
	)
	(segment
		(start 17.1958 -131.699)
		(end 18.104612 -131.699)
		(width 0.12065)
		(layer "F.Cu")
		(net "ROMA19")
	)
	(segment
		(start 18.25498 -131.548632)
		(end 18.25498 -130.96748)
		(width 0.12065)
		(layer "F.Cu")
		(net "ROMA19")
	)
	(segment
		(start 32.904938 -130.88493)
		(end 33.304734 -130.485134)
		(width 0.12065)
		(layer "F.Cu")
		(net "ROMA19")
	)
	(segment
		(start 18.17116 -131.632452)
		(end 18.25498 -131.548632)
		(width 0.12065)
		(layer "F.Cu")
		(net "ROMA19")
	)
	(via
		(at 33.304734 -130.485134)
		(size 0.4572)
		(drill 0.2032)
		(layers "F.Cu" "B.Cu")
		(net "ROMA19")
	)
	(via
		(at 18.17116 -131.632452)
		(size 0.7112)
		(drill 0.3556)
		(layers "F.Cu" "B.Cu")
		(net "ROMA19")
	)
	(via
		(at 17.1958 -131.699)
		(size 0.508)
		(drill 0.254)
		(layers "F.Cu" "B.Cu")
		(net "ROMA19")
	)
	(segment
		(start 20.088606 -130.8481)
		(end 18.0467 -130.8481)
		(width 0.127)
		(layer "In2.Cu")
		(net "ROMA19")
	)
	(segment
		(start 20.11934 -130.878834)
		(end 20.088606 -130.8481)
		(width 0.127)
		(layer "In2.Cu")
		(net "ROMA19")
	)
	(segment
		(start 18.0467 -130.8481)
		(end 17.1958 -131.699)
		(width 0.127)
		(layer "In2.Cu")
		(net "ROMA19")
	)
	(segment
		(start 32.911034 -130.878834)
		(end 20.11934 -130.878834)
		(width 0.127)
		(layer "In2.Cu")
		(net "ROMA19")
	)
	(segment
		(start 33.304734 -130.485134)
		(end 32.911034 -130.878834)
		(width 0.127)
		(layer "In2.Cu")
		(net "ROMA19")
	)
	(segment
		(start 32.104838 -131.684776)
		(end 32.504634 -132.084572)
		(width 0.12065)
		(layer "F.Cu")
		(net "ROMA18")
	)
	(via
		(at 27.07005 -131.794504)
		(size 0.7112)
		(drill 0.3556)
		(layers "F.Cu" "B.Cu")
		(net "ROMA18")
	)
	(via
		(at 32.504634 -132.084572)
		(size 0.4572)
		(drill 0.2032)
		(layers "F.Cu" "B.Cu")
		(net "ROMA18")
	)
	(segment
		(start 26.406348 -131.910328)
		(end 24.942038 -130.446018)
		(width 0.12065)
		(layer "B.Cu")
		(net "ROMA18")
	)
	(segment
		(start 26.954226 -131.910328)
		(end 26.406348 -131.910328)
		(width 0.12065)
		(layer "B.Cu")
		(net "ROMA18")
	)
	(segment
		(start 27.392376 -131.472178)
		(end 27.07005 -131.794504)
		(width 0.12065)
		(layer "B.Cu")
		(net "ROMA18")
	)
	(segment
		(start 32.504634 -132.084572)
		(end 31.89224 -131.472178)
		(width 0.12065)
		(layer "B.Cu")
		(net "ROMA18")
	)
	(segment
		(start 31.89224 -131.472178)
		(end 27.392376 -131.472178)
		(width 0.12065)
		(layer "B.Cu")
		(net "ROMA18")
	)
	(segment
		(start 24.942038 -130.446018)
		(end 24.386286 -130.446018)
		(width 0.12065)
		(layer "B.Cu")
		(net "ROMA18")
	)
	(segment
		(start 27.07005 -131.794504)
		(end 26.954226 -131.910328)
		(width 0.12065)
		(layer "B.Cu")
		(net "ROMA18")
	)
	(segment
		(start 32.904938 -131.684776)
		(end 33.304734 -132.084572)
		(width 0.12065)
		(layer "F.Cu")
		(net "ROMA17")
	)
	(via
		(at 33.0708 -131.318)
		(size 0.7112)
		(drill 0.3556)
		(layers "F.Cu" "B.Cu")
		(net "ROMA17")
	)
	(via
		(at 33.304734 -132.084572)
		(size 0.4572)
		(drill 0.2032)
		(layers "F.Cu" "B.Cu")
		(net "ROMA17")
	)
	(segment
		(start 33.0708 -131.318)
		(end 32.628586 -130.875786)
		(width 0.12065)
		(layer "B.Cu")
		(net "ROMA17")
	)
	(segment
		(start 25.087072 -129.975356)
		(end 25.087072 -129.968498)
		(width 0.12065)
		(layer "B.Cu")
		(net "ROMA17")
	)
	(segment
		(start 24.85644 -129.847848)
		(end 22.234652 -129.847848)
		(width 0.12065)
		(layer "B.Cu")
		(net "ROMA17")
	)
	(segment
		(start 33.304734 -131.551934)
		(end 33.304734 -132.084572)
		(width 0.12065)
		(layer "B.Cu")
		(net "ROMA17")
	)
	(segment
		(start 25.087072 -129.968498)
		(end 25.076658 -129.958084)
		(width 0.12065)
		(layer "B.Cu")
		(net "ROMA17")
	)
	(segment
		(start 26.315416 -131.2037)
		(end 25.087072 -129.975356)
		(width 0.12065)
		(layer "B.Cu")
		(net "ROMA17")
	)
	(segment
		(start 32.10052 -131.2037)
		(end 26.315416 -131.2037)
		(width 0.12065)
		(layer "B.Cu")
		(net "ROMA17")
	)
	(segment
		(start 25.076658 -129.958084)
		(end 24.966676 -129.958084)
		(width 0.12065)
		(layer "B.Cu")
		(net "ROMA17")
	)
	(segment
		(start 33.0708 -131.318)
		(end 33.304734 -131.551934)
		(width 0.12065)
		(layer "B.Cu")
		(net "ROMA17")
	)
	(segment
		(start 22.234652 -129.847848)
		(end 21.3995 -130.683)
		(width 0.12065)
		(layer "B.Cu")
		(net "ROMA17")
	)
	(segment
		(start 32.628586 -130.875786)
		(end 32.428434 -130.875786)
		(width 0.12065)
		(layer "B.Cu")
		(net "ROMA17")
	)
	(segment
		(start 32.428434 -130.875786)
		(end 32.10052 -131.2037)
		(width 0.12065)
		(layer "B.Cu")
		(net "ROMA17")
	)
	(segment
		(start 24.966676 -129.958084)
		(end 24.85644 -129.847848)
		(width 0.12065)
		(layer "B.Cu")
		(net "ROMA17")
	)
	(segment
		(start 32.904938 -134.084822)
		(end 33.304734 -134.484618)
		(width 0.12065)
		(layer "F.Cu")
		(net "ROMA16")
	)
	(via
		(at 25.92705 -134.544054)
		(size 0.7112)
		(drill 0.3556)
		(layers "F.Cu" "B.Cu")
		(net "ROMA16")
	)
	(via
		(at 33.304734 -134.484618)
		(size 0.4572)
		(drill 0.2032)
		(layers "F.Cu" "B.Cu")
		(net "ROMA16")
	)
	(segment
		(start 33.304734 -134.484618)
		(end 32.61487 -133.794754)
		(width 0.12065)
		(layer "B.Cu")
		(net "ROMA16")
	)
	(segment
		(start 28.69057 -133.794754)
		(end 27.557476 -134.927848)
		(width 0.12065)
		(layer "B.Cu")
		(net "ROMA16")
	)
	(segment
		(start 25.92705 -134.544054)
		(end 24.727154 -134.544054)
		(width 0.12065)
		(layer "B.Cu")
		(net "ROMA16")
	)
	(segment
		(start 32.61487 -133.794754)
		(end 28.69057 -133.794754)
		(width 0.12065)
		(layer "B.Cu")
		(net "ROMA16")
	)
	(segment
		(start 27.557476 -134.927848)
		(end 26.310844 -134.927848)
		(width 0.12065)
		(layer "B.Cu")
		(net "ROMA16")
	)
	(segment
		(start 24.727154 -134.544054)
		(end 24.583644 -134.687564)
		(width 0.12065)
		(layer "B.Cu")
		(net "ROMA16")
	)
	(segment
		(start 26.310844 -134.927848)
		(end 25.92705 -134.544054)
		(width 0.12065)
		(layer "B.Cu")
		(net "ROMA16")
	)
	(segment
		(start 30.13964 -130.450082)
		(end 30.504892 -130.08483)
		(width 0.12065)
		(layer "F.Cu")
		(net "ROMA15")
	)
	(segment
		(start 24.053546 -129.01168)
		(end 25.765506 -129.01168)
		(width 0.12065)
		(layer "F.Cu")
		(net "ROMA15")
	)
	(segment
		(start 22.714458 -128.87325)
		(end 22.92096 -129.079752)
		(width 0.12065)
		(layer "F.Cu")
		(net "ROMA15")
	)
	(segment
		(start 26.700226 -129.9464)
		(end 26.924 -129.9464)
		(width 0.12065)
		(layer "F.Cu")
		(net "ROMA15")
	)
	(segment
		(start 27.427682 -130.450082)
		(end 30.13964 -130.450082)
		(width 0.12065)
		(layer "F.Cu")
		(net "ROMA15")
	)
	(segment
		(start 25.765506 -129.01168)
		(end 26.700226 -129.9464)
		(width 0.12065)
		(layer "F.Cu")
		(net "ROMA15")
	)
	(segment
		(start 22.92096 -129.079752)
		(end 23.985474 -129.079752)
		(width 0.12065)
		(layer "F.Cu")
		(net "ROMA15")
	)
	(segment
		(start 21.309076 -128.227074)
		(end 21.955252 -128.87325)
		(width 0.12065)
		(layer "F.Cu")
		(net "ROMA15")
	)
	(segment
		(start 21.955252 -128.87325)
		(end 22.714458 -128.87325)
		(width 0.12065)
		(layer "F.Cu")
		(net "ROMA15")
	)
	(segment
		(start 26.924 -129.9464)
		(end 27.427682 -130.450082)
		(width 0.12065)
		(layer "F.Cu")
		(net "ROMA15")
	)
	(segment
		(start 23.985474 -129.079752)
		(end 24.053546 -129.01168)
		(width 0.12065)
		(layer "F.Cu")
		(net "ROMA15")
	)
	(via
		(at 26.924 -129.9464)
		(size 0.7112)
		(drill 0.3556)
		(layers "F.Cu" "B.Cu")
		(net "ROMA15")
	)
	(segment
		(start 31.304738 -130.08483)
		(end 30.904942 -129.685034)
		(width 0.12065)
		(layer "F.Cu")
		(net "ROMA14")
	)
	(via
		(at 26.17597 -127.867918)
		(size 0.7112)
		(drill 0.3556)
		(layers "F.Cu" "B.Cu")
		(net "ROMA14")
	)
	(via
		(at 30.904942 -129.685034)
		(size 0.4572)
		(drill 0.2032)
		(layers "F.Cu" "B.Cu")
		(net "ROMA14")
	)
	(segment
		(start 28.615132 -129.685034)
		(end 30.904942 -129.685034)
		(width 0.12065)
		(layer "B.Cu")
		(net "ROMA14")
	)
	(segment
		(start 26.006552 -128.037336)
		(end 26.17597 -127.867918)
		(width 0.12065)
		(layer "B.Cu")
		(net "ROMA14")
	)
	(segment
		(start 26.798016 -127.867918)
		(end 28.615132 -129.685034)
		(width 0.12065)
		(layer "B.Cu")
		(net "ROMA14")
	)
	(segment
		(start 26.17597 -127.867918)
		(end 26.798016 -127.867918)
		(width 0.12065)
		(layer "B.Cu")
		(net "ROMA14")
	)
	(segment
		(start 24.240998 -128.037336)
		(end 26.006552 -128.037336)
		(width 0.12065)
		(layer "B.Cu")
		(net "ROMA14")
	)
	(segment
		(start 32.104838 -130.08483)
		(end 31.705042 -129.685034)
		(width 0.12065)
		(layer "F.Cu")
		(net "ROMA13")
	)
	(via
		(at 31.705042 -129.685034)
		(size 0.4572)
		(drill 0.2032)
		(layers "F.Cu" "B.Cu")
		(net "ROMA13")
	)
	(via
		(at 25.416002 -126.738888)
		(size 0.7112)
		(drill 0.3556)
		(layers "F.Cu" "B.Cu")
		(net "ROMA13")
	)
	(segment
		(start 28.6004 -129.294382)
		(end 31.31439 -129.294382)
		(width 0.12065)
		(layer "B.Cu")
		(net "ROMA13")
	)
	(segment
		(start 25.416002 -126.738888)
		(end 26.044906 -126.738888)
		(width 0.12065)
		(layer "B.Cu")
		(net "ROMA13")
	)
	(segment
		(start 25.416002 -126.738888)
		(end 25.133554 -127.021336)
		(width 0.12065)
		(layer "B.Cu")
		(net "ROMA13")
	)
	(segment
		(start 31.31439 -129.294382)
		(end 31.705042 -129.685034)
		(width 0.12065)
		(layer "B.Cu")
		(net "ROMA13")
	)
	(segment
		(start 26.044906 -126.738888)
		(end 28.6004 -129.294382)
		(width 0.12065)
		(layer "B.Cu")
		(net "ROMA13")
	)
	(segment
		(start 25.133554 -127.021336)
		(end 24.240998 -127.021336)
		(width 0.12065)
		(layer "B.Cu")
		(net "ROMA13")
	)
	(segment
		(start 32.904938 -130.08483)
		(end 32.505142 -129.685034)
		(width 0.12065)
		(layer "F.Cu")
		(net "ROMA12")
	)
	(via
		(at 32.505142 -129.685034)
		(size 0.4572)
		(drill 0.2032)
		(layers "F.Cu" "B.Cu")
		(net "ROMA12")
	)
	(via
		(at 32.5374 -128.9558)
		(size 0.7112)
		(drill 0.3556)
		(layers "F.Cu" "B.Cu")
		(net "ROMA12")
	)
	(segment
		(start 26.705814 -126.895352)
		(end 28.829 -129.018538)
		(width 0.12065)
		(layer "B.Cu")
		(net "ROMA12")
	)
	(segment
		(start 25.823418 -126.005336)
		(end 26.705814 -126.887732)
		(width 0.12065)
		(layer "B.Cu")
		(net "ROMA12")
	)
	(segment
		(start 32.618172 -129.572004)
		(end 32.618172 -129.036572)
		(width 0.12065)
		(layer "B.Cu")
		(net "ROMA12")
	)
	(segment
		(start 32.618172 -129.036572)
		(end 32.5374 -128.9558)
		(width 0.12065)
		(layer "B.Cu")
		(net "ROMA12")
	)
	(segment
		(start 26.705814 -126.887732)
		(end 26.705814 -126.895352)
		(width 0.12065)
		(layer "B.Cu")
		(net "ROMA12")
	)
	(segment
		(start 24.240998 -126.005336)
		(end 25.823418 -126.005336)
		(width 0.12065)
		(layer "B.Cu")
		(net "ROMA12")
	)
	(segment
		(start 32.505142 -129.685034)
		(end 32.618172 -129.572004)
		(width 0.12065)
		(layer "B.Cu")
		(net "ROMA12")
	)
	(segment
		(start 32.094932 -128.9558)
		(end 32.5374 -128.9558)
		(width 0.12065)
		(layer "B.Cu")
		(net "ROMA12")
	)
	(segment
		(start 28.829 -129.018538)
		(end 32.032194 -129.018538)
		(width 0.12065)
		(layer "B.Cu")
		(net "ROMA12")
	)
	(segment
		(start 32.032194 -129.018538)
		(end 32.094932 -128.9558)
		(width 0.12065)
		(layer "B.Cu")
		(net "ROMA12")
	)
	(segment
		(start 21.309076 -129.243074)
		(end 21.507704 -129.441702)
		(width 0.12065)
		(layer "F.Cu")
		(net "ROMA11")
	)
	(segment
		(start 25.917652 -129.833878)
		(end 26.968704 -130.88493)
		(width 0.12065)
		(layer "F.Cu")
		(net "ROMA11")
	)
	(segment
		(start 25.917652 -129.774696)
		(end 25.917652 -129.833878)
		(width 0.12065)
		(layer "F.Cu")
		(net "ROMA11")
	)
	(segment
		(start 25.584658 -129.441702)
		(end 25.917652 -129.774696)
		(width 0.12065)
		(layer "F.Cu")
		(net "ROMA11")
	)
	(segment
		(start 21.507704 -129.441702)
		(end 22.479 -129.441702)
		(width 0.12065)
		(layer "F.Cu")
		(net "ROMA11")
	)
	(segment
		(start 26.968704 -130.88493)
		(end 29.704792 -130.88493)
		(width 0.12065)
		(layer "F.Cu")
		(net "ROMA11")
	)
	(segment
		(start 22.479 -129.441702)
		(end 25.584658 -129.441702)
		(width 0.12065)
		(layer "F.Cu")
		(net "ROMA11")
	)
	(via
		(at 22.479 -129.441702)
		(size 0.7112)
		(drill 0.3556)
		(layers "F.Cu" "B.Cu")
		(net "ROMA11")
	)
	(segment
		(start 30.221174 -130.88493)
		(end 30.504892 -130.88493)
		(width 0.12065)
		(layer "F.Cu")
		(net "ROMA10")
	)
	(segment
		(start 22.02688 -130.057398)
		(end 21.759418 -130.32486)
		(width 0.12065)
		(layer "F.Cu")
		(net "ROMA10")
	)
	(segment
		(start 25.301956 -130.057398)
		(end 22.02688 -130.057398)
		(width 0.12065)
		(layer "F.Cu")
		(net "ROMA10")
	)
	(segment
		(start 25.3492 -130.010154)
		(end 26.190194 -130.851148)
		(width 0.12065)
		(layer "F.Cu")
		(net "ROMA10")
	)
	(segment
		(start 26.830782 -131.250182)
		(end 29.855922 -131.250182)
		(width 0.12065)
		(layer "F.Cu")
		(net "ROMA10")
	)
	(segment
		(start 26.190194 -130.851148)
		(end 26.431748 -130.851148)
		(width 0.12065)
		(layer "F.Cu")
		(net "ROMA10")
	)
	(segment
		(start 25.3492 -130.010154)
		(end 25.301956 -130.057398)
		(width 0.12065)
		(layer "F.Cu")
		(net "ROMA10")
	)
	(segment
		(start 29.855922 -131.250182)
		(end 30.221174 -130.88493)
		(width 0.12065)
		(layer "F.Cu")
		(net "ROMA10")
	)
	(segment
		(start 26.431748 -130.851148)
		(end 26.830782 -131.250182)
		(width 0.12065)
		(layer "F.Cu")
		(net "ROMA10")
	)
	(segment
		(start 21.759418 -130.32486)
		(end 21.086826 -130.32486)
		(width 0.12065)
		(layer "F.Cu")
		(net "ROMA10")
	)
	(via
		(at 25.3492 -130.010154)
		(size 0.7112)
		(drill 0.3556)
		(layers "F.Cu" "B.Cu")
		(net "ROMA10")
	)
	(segment
		(start 28.194 -134.747)
		(end 29.2608 -133.6802)
		(width 0.12065)
		(layer "F.Cu")
		(net "ROMA1")
	)
	(segment
		(start 24.3205 -133.757924)
		(end 25.497282 -134.934706)
		(width 0.12065)
		(layer "F.Cu")
		(net "ROMA1")
	)
	(segment
		(start 24.3205 -133.731)
		(end 24.3205 -133.757924)
		(width 0.12065)
		(layer "F.Cu")
		(net "ROMA1")
	)
	(segment
		(start 30.109668 -133.6802)
		(end 30.504892 -133.284976)
		(width 0.12065)
		(layer "F.Cu")
		(net "ROMA1")
	)
	(segment
		(start 26.241502 -134.934706)
		(end 26.429208 -134.747)
		(width 0.12065)
		(layer "F.Cu")
		(net "ROMA1")
	)
	(segment
		(start 25.497282 -134.934706)
		(end 26.241502 -134.934706)
		(width 0.12065)
		(layer "F.Cu")
		(net "ROMA1")
	)
	(segment
		(start 29.2608 -133.6802)
		(end 30.109668 -133.6802)
		(width 0.12065)
		(layer "F.Cu")
		(net "ROMA1")
	)
	(segment
		(start 26.429208 -134.747)
		(end 28.194 -134.747)
		(width 0.12065)
		(layer "F.Cu")
		(net "ROMA1")
	)
	(via
		(at 26.241502 -134.934706)
		(size 0.7112)
		(drill 0.3556)
		(layers "F.Cu" "B.Cu")
		(net "ROMA1")
	)
	(segment
		(start 104.3686 -55.1434)
		(end 92.7862 -55.1434)
		(width 0.12065)
		(layer "F.Cu")
		(net "ROMA0")
	)
	(segment
		(start 92.7862 -55.1434)
		(end 90.2716 -52.6288)
		(width 0.12065)
		(layer "F.Cu")
		(net "ROMA0")
	)
	(segment
		(start 90.2716 -52.6288)
		(end 87.9348 -52.6288)
		(width 0.12065)
		(layer "F.Cu")
		(net "ROMA0")
	)
	(segment
		(start 31.304738 -133.284976)
		(end 30.904942 -132.88518)
		(width 0.12065)
		(layer "F.Cu")
		(net "ROMA0")
	)
	(via
		(at 30.904942 -132.88518)
		(size 0.4572)
		(drill 0.2032)
		(layers "F.Cu" "B.Cu")
		(net "ROMA0")
	)
	(via
		(at 104.3686 -55.1434)
		(size 0.508)
		(drill 0.254)
		(layers "F.Cu" "B.Cu")
		(net "ROMA0")
	)
	(segment
		(start 15.184882 -124.841)
		(end 15.577058 -124.841)
		(width 0.127)
		(layer "In2.Cu")
		(net "ROMA0")
	)
	(segment
		(start 15.902432 -132.5499)
		(end 15.81277 -132.460238)
		(width 0.127)
		(layer "In2.Cu")
		(net "ROMA0")
	)
	(segment
		(start 77.348842 -94.544134)
		(end 78.780132 -95.975424)
		(width 0.127)
		(layer "In2.Cu")
		(net "ROMA0")
	)
	(segment
		(start 15.577058 -124.841)
		(end 15.9766 -124.441458)
		(width 0.127)
		(layer "In2.Cu")
		(net "ROMA0")
	)
	(segment
		(start 53.650388 -94.428818)
		(end 60.186062 -94.428818)
		(width 0.127)
		(layer "In2.Cu")
		(net "ROMA0")
	)
	(segment
		(start 31.579566 -96.507808)
		(end 35.901884 -96.507808)
		(width 0.127)
		(layer "In2.Cu")
		(net "ROMA0")
	)
	(segment
		(start 103.7336 -71.943976)
		(end 103.7336 -55.7784)
		(width 0.127)
		(layer "In2.Cu")
		(net "ROMA0")
	)
	(segment
		(start 15.056612 -132.184648)
		(end 14.6177 -131.745736)
		(width 0.127)
		(layer "In2.Cu")
		(net "ROMA0")
	)
	(segment
		(start 103.7336 -55.7784)
		(end 104.3686 -55.1434)
		(width 0.127)
		(layer "In2.Cu")
		(net "ROMA0")
	)
	(segment
		(start 22.205442 -104.838246)
		(end 22.317202 -104.726486)
		(width 0.127)
		(layer "In2.Cu")
		(net "ROMA0")
	)
	(segment
		(start 24.001476 -102.531164)
		(end 24.523954 -102.009194)
		(width 0.127)
		(layer "In2.Cu")
		(net "ROMA0")
	)
	(segment
		(start 15.81277 -132.460238)
		(end 15.812516 -132.460238)
		(width 0.127)
		(layer "In2.Cu")
		(net "ROMA0")
	)
	(segment
		(start 17.54886 -132.5499)
		(end 15.902432 -132.5499)
		(width 0.127)
		(layer "In2.Cu")
		(net "ROMA0")
	)
	(segment
		(start 18.161 -113.231168)
		(end 18.61185 -112.780318)
		(width 0.127)
		(layer "In2.Cu")
		(net "ROMA0")
	)
	(segment
		(start 71.736712 -94.161864)
		(end 72.118982 -94.544134)
		(width 0.127)
		(layer "In2.Cu")
		(net "ROMA0")
	)
	(segment
		(start 22.205442 -104.839516)
		(end 22.205442 -104.838246)
		(width 0.127)
		(layer "In2.Cu")
		(net "ROMA0")
	)
	(segment
		(start 15.056612 -132.184902)
		(end 15.056612 -132.184648)
		(width 0.127)
		(layer "In2.Cu")
		(net "ROMA0")
	)
	(segment
		(start 25.467818 -102.009194)
		(end 26.82367 -100.653342)
		(width 0.127)
		(layer "In2.Cu")
		(net "ROMA0")
	)
	(segment
		(start 88.737694 -95.975424)
		(end 101.1174 -83.595718)
		(width 0.127)
		(layer "In2.Cu")
		(net "ROMA0")
	)
	(segment
		(start 101.1174 -79.680562)
		(end 103.733346 -77.063854)
		(width 0.127)
		(layer "In2.Cu")
		(net "ROMA0")
	)
	(segment
		(start 60.453016 -94.161864)
		(end 71.736712 -94.161864)
		(width 0.127)
		(layer "In2.Cu")
		(net "ROMA0")
	)
	(segment
		(start 26.82367 -100.653342)
		(end 28.291536 -100.653342)
		(width 0.127)
		(layer "In2.Cu")
		(net "ROMA0")
	)
	(segment
		(start 15.9766 -123.7488)
		(end 17.680432 -122.044968)
		(width 0.127)
		(layer "In2.Cu")
		(net "ROMA0")
	)
	(segment
		(start 18.61185 -112.780318)
		(end 18.61185 -108.433108)
		(width 0.127)
		(layer "In2.Cu")
		(net "ROMA0")
	)
	(segment
		(start 15.331694 -132.459984)
		(end 15.056612 -132.184902)
		(width 0.127)
		(layer "In2.Cu")
		(net "ROMA0")
	)
	(segment
		(start 72.118982 -94.544134)
		(end 77.348842 -94.544134)
		(width 0.127)
		(layer "In2.Cu")
		(net "ROMA0")
	)
	(segment
		(start 60.186062 -94.428818)
		(end 60.453016 -94.161864)
		(width 0.127)
		(layer "In2.Cu")
		(net "ROMA0")
	)
	(segment
		(start 18.61185 -108.433108)
		(end 22.205442 -104.839516)
		(width 0.127)
		(layer "In2.Cu")
		(net "ROMA0")
	)
	(segment
		(start 35.901884 -96.507808)
		(end 36.613846 -95.795846)
		(width 0.127)
		(layer "In2.Cu")
		(net "ROMA0")
	)
	(segment
		(start 52.28336 -95.795846)
		(end 53.650388 -94.428818)
		(width 0.127)
		(layer "In2.Cu")
		(net "ROMA0")
	)
	(segment
		(start 17.85366 -132.2451)
		(end 17.54886 -132.5499)
		(width 0.127)
		(layer "In2.Cu")
		(net "ROMA0")
	)
	(segment
		(start 15.812516 -132.460238)
		(end 15.812262 -132.459984)
		(width 0.127)
		(layer "In2.Cu")
		(net "ROMA0")
	)
	(segment
		(start 78.780132 -95.975424)
		(end 88.737694 -95.975424)
		(width 0.127)
		(layer "In2.Cu")
		(net "ROMA0")
	)
	(segment
		(start 22.32914 -104.204008)
		(end 24.001476 -102.531164)
		(width 0.127)
		(layer "In2.Cu")
		(net "ROMA0")
	)
	(segment
		(start 14.6177 -125.408182)
		(end 15.184882 -124.841)
		(width 0.127)
		(layer "In2.Cu")
		(net "ROMA0")
	)
	(segment
		(start 17.680432 -118.692168)
		(end 18.161 -118.2116)
		(width 0.127)
		(layer "In2.Cu")
		(net "ROMA0")
	)
	(segment
		(start 103.733346 -74.862182)
		(end 103.7336 -71.943976)
		(width 0.127)
		(layer "In2.Cu")
		(net "ROMA0")
	)
	(segment
		(start 14.6177 -131.745736)
		(end 14.6177 -125.408182)
		(width 0.127)
		(layer "In2.Cu")
		(net "ROMA0")
	)
	(segment
		(start 15.9766 -124.441458)
		(end 15.9766 -123.7488)
		(width 0.127)
		(layer "In2.Cu")
		(net "ROMA0")
	)
	(segment
		(start 17.680432 -122.044968)
		(end 17.680432 -118.692168)
		(width 0.127)
		(layer "In2.Cu")
		(net "ROMA0")
	)
	(segment
		(start 15.812262 -132.459984)
		(end 15.331694 -132.459984)
		(width 0.127)
		(layer "In2.Cu")
		(net "ROMA0")
	)
	(segment
		(start 22.317202 -104.726486)
		(end 22.317202 -104.215946)
		(width 0.127)
		(layer "In2.Cu")
		(net "ROMA0")
	)
	(segment
		(start 24.523954 -102.009194)
		(end 25.467818 -102.009194)
		(width 0.127)
		(layer "In2.Cu")
		(net "ROMA0")
	)
	(segment
		(start 30.810962 -98.133916)
		(end 30.810962 -97.276412)
		(width 0.127)
		(layer "In2.Cu")
		(net "ROMA0")
	)
	(segment
		(start 20.570698 -132.88518)
		(end 19.930618 -132.2451)
		(width 0.127)
		(layer "In2.Cu")
		(net "ROMA0")
	)
	(segment
		(start 30.810962 -97.276412)
		(end 31.579566 -96.507808)
		(width 0.127)
		(layer "In2.Cu")
		(net "ROMA0")
	)
	(segment
		(start 36.613846 -95.795846)
		(end 52.28336 -95.795846)
		(width 0.127)
		(layer "In2.Cu")
		(net "ROMA0")
	)
	(segment
		(start 30.904942 -132.88518)
		(end 20.570698 -132.88518)
		(width 0.127)
		(layer "In2.Cu")
		(net "ROMA0")
	)
	(segment
		(start 103.733346 -77.063854)
		(end 103.733346 -74.862182)
		(width 0.127)
		(layer "In2.Cu")
		(net "ROMA0")
	)
	(segment
		(start 28.291536 -100.653342)
		(end 30.810962 -98.133916)
		(width 0.127)
		(layer "In2.Cu")
		(net "ROMA0")
	)
	(segment
		(start 101.1174 -83.595718)
		(end 101.1174 -79.680562)
		(width 0.127)
		(layer "In2.Cu")
		(net "ROMA0")
	)
	(segment
		(start 19.930618 -132.2451)
		(end 17.85366 -132.2451)
		(width 0.127)
		(layer "In2.Cu")
		(net "ROMA0")
	)
	(segment
		(start 18.161 -118.2116)
		(end 18.161 -113.231168)
		(width 0.127)
		(layer "In2.Cu")
		(net "ROMA0")
	)
	(segment
		(start 22.317202 -104.215946)
		(end 22.32914 -104.204008)
		(width 0.127)
		(layer "In2.Cu")
		(net "ROMA0")
	)
	(segment
		(start 38.0238 -118.637304)
		(end 37.963094 -118.576598)
		(width 0.12065)
		(layer "F.Cu")
		(net "RMII0_BMC_C_TX_EN")
	)
	(segment
		(start 38.0238 -119.645176)
		(end 38.0238 -118.637304)
		(width 0.12065)
		(layer "F.Cu")
		(net "RMII0_BMC_C_TX_EN")
	)
	(segment
		(start 37.1348 -117.7544)
		(end 37.1348 -117.1575)
		(width 0.12065)
		(layer "F.Cu")
		(net "RMII0_BMC_C_TX_EN")
	)
	(segment
		(start 37.956998 -118.576598)
		(end 37.1348 -117.7544)
		(width 0.12065)
		(layer "F.Cu")
		(net "RMII0_BMC_C_TX_EN")
	)
	(segment
		(start 37.704776 -122.084846)
		(end 37.704776 -119.9642)
		(width 0.12065)
		(layer "F.Cu")
		(net "RMII0_BMC_C_TX_EN")
	)
	(segment
		(start 37.704776 -119.9642)
		(end 38.0238 -119.645176)
		(width 0.12065)
		(layer "F.Cu")
		(net "RMII0_BMC_C_TX_EN")
	)
	(segment
		(start 37.963094 -118.576598)
		(end 37.956998 -118.576598)
		(width 0.12065)
		(layer "F.Cu")
		(net "RMII0_BMC_C_TX_EN")
	)
	(via
		(at 37.963094 -118.576598)
		(size 0.7112)
		(drill 0.3556)
		(layers "F.Cu" "B.Cu")
		(net "RMII0_BMC_C_TX_EN")
	)
	(segment
		(start 37.704776 -124.484892)
		(end 37.30498 -124.085096)
		(width 0.12065)
		(layer "F.Cu")
		(net "RMII0_BMC_C_PHY_TXD1")
	)
	(via
		(at 37.30498 -124.085096)
		(size 0.4572)
		(drill 0.2032)
		(layers "F.Cu" "B.Cu")
		(net "RMII0_BMC_C_PHY_TXD1")
	)
	(segment
		(start 36.176204 -119.027448)
		(end 36.242244 -119.093488)
		(width 0.12065)
		(layer "B.Cu")
		(net "RMII0_BMC_C_PHY_TXD1")
	)
	(segment
		(start 36.242244 -120.476264)
		(end 35.6743 -121.044208)
		(width 0.12065)
		(layer "B.Cu")
		(net "RMII0_BMC_C_PHY_TXD1")
	)
	(segment
		(start 36.914328 -123.446794)
		(end 36.915852 -123.448318)
		(width 0.12065)
		(layer "B.Cu")
		(net "RMII0_BMC_C_PHY_TXD1")
	)
	(segment
		(start 36.915852 -123.09094)
		(end 36.915852 -123.121674)
		(width 0.12065)
		(layer "B.Cu")
		(net "RMII0_BMC_C_PHY_TXD1")
	)
	(segment
		(start 36.242244 -119.093488)
		(end 36.242244 -120.476264)
		(width 0.12065)
		(layer "B.Cu")
		(net "RMII0_BMC_C_PHY_TXD1")
	)
	(segment
		(start 36.915852 -123.121674)
		(end 36.914328 -123.123198)
		(width 0.12065)
		(layer "B.Cu")
		(net "RMII0_BMC_C_PHY_TXD1")
	)
	(segment
		(start 36.915852 -123.695968)
		(end 37.30498 -124.085096)
		(width 0.12065)
		(layer "B.Cu")
		(net "RMII0_BMC_C_PHY_TXD1")
	)
	(segment
		(start 35.814 -117.2845)
		(end 36.176204 -117.646704)
		(width 0.12065)
		(layer "B.Cu")
		(net "RMII0_BMC_C_PHY_TXD1")
	)
	(segment
		(start 35.6743 -121.044208)
		(end 35.6743 -121.849388)
		(width 0.12065)
		(layer "B.Cu")
		(net "RMII0_BMC_C_PHY_TXD1")
	)
	(segment
		(start 36.915852 -123.448318)
		(end 36.915852 -123.695968)
		(width 0.12065)
		(layer "B.Cu")
		(net "RMII0_BMC_C_PHY_TXD1")
	)
	(segment
		(start 35.6743 -121.849388)
		(end 36.915852 -123.09094)
		(width 0.12065)
		(layer "B.Cu")
		(net "RMII0_BMC_C_PHY_TXD1")
	)
	(segment
		(start 36.176204 -117.646704)
		(end 36.176204 -119.027448)
		(width 0.12065)
		(layer "B.Cu")
		(net "RMII0_BMC_C_PHY_TXD1")
	)
	(segment
		(start 36.914328 -123.123198)
		(end 36.914328 -123.446794)
		(width 0.12065)
		(layer "B.Cu")
		(net "RMII0_BMC_C_PHY_TXD1")
	)
	(segment
		(start 37.704776 -123.684792)
		(end 37.30498 -123.284996)
		(width 0.12065)
		(layer "F.Cu")
		(net "RMII0_BMC_C_PHY_TXD0")
	)
	(via
		(at 37.30498 -123.284996)
		(size 0.4572)
		(drill 0.2032)
		(layers "F.Cu" "B.Cu")
		(net "RMII0_BMC_C_PHY_TXD0")
	)
	(segment
		(start 35.9918 -121.752106)
		(end 37.30498 -123.065286)
		(width 0.12065)
		(layer "B.Cu")
		(net "RMII0_BMC_C_PHY_TXD0")
	)
	(segment
		(start 37.30498 -123.065286)
		(end 37.30498 -123.284996)
		(width 0.12065)
		(layer "B.Cu")
		(net "RMII0_BMC_C_PHY_TXD0")
	)
	(segment
		(start 36.4998 -120.654318)
		(end 35.9918 -121.162318)
		(width 0.12065)
		(layer "B.Cu")
		(net "RMII0_BMC_C_PHY_TXD0")
	)
	(segment
		(start 36.550854 -117.563646)
		(end 36.550854 -119.104918)
		(width 0.12065)
		(layer "B.Cu")
		(net "RMII0_BMC_C_PHY_TXD0")
	)
	(segment
		(start 36.4998 -119.155972)
		(end 36.4998 -120.654318)
		(width 0.12065)
		(layer "B.Cu")
		(net "RMII0_BMC_C_PHY_TXD0")
	)
	(segment
		(start 36.550854 -119.104918)
		(end 36.4998 -119.155972)
		(width 0.12065)
		(layer "B.Cu")
		(net "RMII0_BMC_C_PHY_TXD0")
	)
	(segment
		(start 35.9918 -121.162318)
		(end 35.9918 -121.752106)
		(width 0.12065)
		(layer "B.Cu")
		(net "RMII0_BMC_C_PHY_TXD0")
	)
	(segment
		(start 36.83 -117.2845)
		(end 36.550854 -117.563646)
		(width 0.12065)
		(layer "B.Cu")
		(net "RMII0_BMC_C_PHY_TXD0")
	)
	(segment
		(start 38.504876 -122.084846)
		(end 38.504876 -119.111776)
		(width 0.12065)
		(layer "F.Cu")
		(net "RMII0_BMC_C_CRS_DV")
	)
	(segment
		(start 38.6334 -117.6401)
		(end 38.1508 -117.1575)
		(width 0.12065)
		(layer "F.Cu")
		(net "RMII0_BMC_C_CRS_DV")
	)
	(segment
		(start 38.1508 -116.476018)
		(end 38.144196 -116.469414)
		(width 0.12065)
		(layer "F.Cu")
		(net "RMII0_BMC_C_CRS_DV")
	)
	(segment
		(start 38.504876 -119.111776)
		(end 38.6334 -118.983252)
		(width 0.12065)
		(layer "F.Cu")
		(net "RMII0_BMC_C_CRS_DV")
	)
	(segment
		(start 38.144196 -115.332002)
		(end 38.144196 -116.469414)
		(width 0.12065)
		(layer "F.Cu")
		(net "RMII0_BMC_C_CRS_DV")
	)
	(segment
		(start 38.6334 -118.983252)
		(end 38.6334 -117.6401)
		(width 0.12065)
		(layer "F.Cu")
		(net "RMII0_BMC_C_CRS_DV")
	)
	(segment
		(start 38.260528 -115.21567)
		(end 38.144196 -115.332002)
		(width 0.12065)
		(layer "F.Cu")
		(net "RMII0_BMC_C_CRS_DV")
	)
	(segment
		(start 38.1508 -117.1575)
		(end 38.1508 -116.476018)
		(width 0.12065)
		(layer "F.Cu")
		(net "RMII0_BMC_C_CRS_DV")
	)
	(via
		(at 38.144196 -116.469414)
		(size 0.7112)
		(drill 0.3556)
		(layers "F.Cu" "B.Cu")
		(net "RMII0_BMC_C_CRS_DV")
	)
	(segment
		(start 233.59999 -34.99993)
		(end 233.100118 -34.500058)
		(width 0.12065)
		(layer "F.Cu")
		(net "RMII_TXD_1")
	)
	(via
		(at 233.100118 -34.500058)
		(size 0.4572)
		(drill 0.2032)
		(layers "F.Cu" "B.Cu")
		(net "RMII_TXD_1")
	)
	(segment
		(start 233.5911 -35.0012)
		(end 233.5911 -34.99104)
		(width 0.12065)
		(layer "B.Cu")
		(net "RMII_TXD_1")
	)
	(segment
		(start 233.5911 -34.99104)
		(end 233.100118 -34.500058)
		(width 0.12065)
		(layer "B.Cu")
		(net "RMII_TXD_1")
	)
	(segment
		(start 233.59999 -33.999932)
		(end 233.100118 -33.50006)
		(width 0.12065)
		(layer "F.Cu")
		(net "RMII_TXD_0")
	)
	(via
		(at 233.100118 -33.50006)
		(size 0.4572)
		(drill 0.2032)
		(layers "F.Cu" "B.Cu")
		(net "RMII_TXD_0")
	)
	(segment
		(start 233.100118 -33.510982)
		(end 233.100118 -33.50006)
		(width 0.12065)
		(layer "B.Cu")
		(net "RMII_TXD_0")
	)
	(segment
		(start 232.6005 -34.0106)
		(end 233.100118 -33.510982)
		(width 0.12065)
		(layer "B.Cu")
		(net "RMII_TXD_0")
	)
	(segment
		(start 234.599988 -39.99992)
		(end 234.100116 -39.500048)
		(width 0.12065)
		(layer "F.Cu")
		(net "RMII_TX_EN")
	)
	(via
		(at 234.100116 -39.500048)
		(size 0.4572)
		(drill 0.2032)
		(layers "F.Cu" "B.Cu")
		(net "RMII_TX_EN")
	)
	(segment
		(start 233.6038 -39.996364)
		(end 234.100116 -39.500048)
		(width 0.12065)
		(layer "B.Cu")
		(net "RMII_TX_EN")
	)
	(segment
		(start 233.6038 -40.005)
		(end 233.6038 -39.996364)
		(width 0.12065)
		(layer "B.Cu")
		(net "RMII_TX_EN")
	)
	(segment
		(start 233.59999 -37.999924)
		(end 233.100118 -37.500052)
		(width 0.12065)
		(layer "F.Cu")
		(net "RMII_RXD_1")
	)
	(via
		(at 233.100118 -37.500052)
		(size 0.4572)
		(drill 0.2032)
		(layers "F.Cu" "B.Cu")
		(net "RMII_RXD_1")
	)
	(segment
		(start 233.59999 -37.999924)
		(end 233.100118 -37.500052)
		(width 0.12065)
		(layer "B.Cu")
		(net "RMII_RXD_1")
	)
	(segment
		(start 233.59999 -36.999926)
		(end 233.100118 -36.500054)
		(width 0.12065)
		(layer "F.Cu")
		(net "RMII_RXD_0")
	)
	(via
		(at 233.100118 -36.500054)
		(size 0.4572)
		(drill 0.2032)
		(layers "F.Cu" "B.Cu")
		(net "RMII_RXD_0")
	)
	(segment
		(start 233.095546 -36.500054)
		(end 233.100118 -36.500054)
		(width 0.12065)
		(layer "B.Cu")
		(net "RMII_RXD_0")
	)
	(segment
		(start 232.6005 -36.9951)
		(end 233.095546 -36.500054)
		(width 0.12065)
		(layer "B.Cu")
		(net "RMII_RXD_0")
	)
	(segment
		(start 233.59999 -35.999928)
		(end 233.100118 -35.500056)
		(width 0.12065)
		(layer "F.Cu")
		(net "RMII_RX_ER")
	)
	(via
		(at 233.100118 -35.500056)
		(size 0.4572)
		(drill 0.2032)
		(layers "F.Cu" "B.Cu")
		(net "RMII_RX_ER")
	)
	(segment
		(start 232.595674 -36.0045)
		(end 233.100118 -35.500056)
		(width 0.12065)
		(layer "B.Cu")
		(net "RMII_RX_ER")
	)
	(segment
		(start 231.5972 -36.0045)
		(end 232.595674 -36.0045)
		(width 0.12065)
		(layer "B.Cu")
		(net "RMII_RX_ER")
	)
	(segment
		(start 233.59999 -38.999922)
		(end 233.100118 -38.50005)
		(width 0.12065)
		(layer "F.Cu")
		(net "RMII_REF_CLK")
	)
	(via
		(at 233.100118 -38.50005)
		(size 0.4572)
		(drill 0.2032)
		(layers "F.Cu" "B.Cu")
		(net "RMII_REF_CLK")
	)
	(segment
		(start 232.611168 -38.989)
		(end 233.100118 -38.50005)
		(width 0.12065)
		(layer "B.Cu")
		(net "RMII_REF_CLK")
	)
	(segment
		(start 232.6005 -38.989)
		(end 232.611168 -38.989)
		(width 0.12065)
		(layer "B.Cu")
		(net "RMII_REF_CLK")
	)
	(segment
		(start 23.775416 -73.91654)
		(end 23.922228 -73.769728)
		(width 0.12065)
		(layer "F.Cu")
		(net "RMII_PHY_BMC_RXD1_R")
	)
	(segment
		(start 22.584918 -73.91654)
		(end 23.775416 -73.91654)
		(width 0.12065)
		(layer "F.Cu")
		(net "RMII_PHY_BMC_RXD1_R")
	)
	(segment
		(start 25.471628 -73.769728)
		(end 25.5905 -73.8886)
		(width 0.12065)
		(layer "F.Cu")
		(net "RMII_PHY_BMC_RXD1_R")
	)
	(segment
		(start 23.922228 -73.769728)
		(end 25.471628 -73.769728)
		(width 0.12065)
		(layer "F.Cu")
		(net "RMII_PHY_BMC_RXD1_R")
	)
	(segment
		(start 27.851354 -74.117454)
		(end 27.559 -73.8251)
		(width 0.12065)
		(layer "F.Cu")
		(net "RMII_PHY_BMC_RXD1")
	)
	(segment
		(start 29.553408 -77.842872)
		(end 29.553408 -75.000104)
		(width 0.12065)
		(layer "F.Cu")
		(net "RMII_PHY_BMC_RXD1")
	)
	(segment
		(start 26.51506 -73.85304)
		(end 27.53106 -73.85304)
		(width 0.12065)
		(layer "F.Cu")
		(net "RMII_PHY_BMC_RXD1")
	)
	(segment
		(start 29.397198 -74.843894)
		(end 29.386022 -74.843894)
		(width 0.12065)
		(layer "F.Cu")
		(net "RMII_PHY_BMC_RXD1")
	)
	(segment
		(start 38.504876 -122.884946)
		(end 38.10508 -122.48515)
		(width 0.12065)
		(layer "F.Cu")
		(net "RMII_PHY_BMC_RXD1")
	)
	(segment
		(start 29.386022 -74.843894)
		(end 28.659582 -74.117454)
		(width 0.12065)
		(layer "F.Cu")
		(net "RMII_PHY_BMC_RXD1")
	)
	(segment
		(start 28.659582 -74.117454)
		(end 27.851354 -74.117454)
		(width 0.12065)
		(layer "F.Cu")
		(net "RMII_PHY_BMC_RXD1")
	)
	(segment
		(start 29.553408 -75.000104)
		(end 29.397198 -74.843894)
		(width 0.12065)
		(layer "F.Cu")
		(net "RMII_PHY_BMC_RXD1")
	)
	(segment
		(start 26.4795 -73.8886)
		(end 26.51506 -73.85304)
		(width 0.12065)
		(layer "F.Cu")
		(net "RMII_PHY_BMC_RXD1")
	)
	(segment
		(start 29.840936 -78.1304)
		(end 29.553408 -77.842872)
		(width 0.12065)
		(layer "F.Cu")
		(net "RMII_PHY_BMC_RXD1")
	)
	(segment
		(start 27.53106 -73.85304)
		(end 27.559 -73.8251)
		(width 0.12065)
		(layer "F.Cu")
		(net "RMII_PHY_BMC_RXD1")
	)
	(via
		(at 38.10508 -122.48515)
		(size 0.4572)
		(drill 0.2032)
		(layers "F.Cu" "B.Cu")
		(net "RMII_PHY_BMC_RXD1")
	)
	(via
		(at 29.840936 -78.1304)
		(size 0.508)
		(drill 0.254)
		(layers "F.Cu" "B.Cu")
		(net "RMII_PHY_BMC_RXD1")
	)
	(segment
		(start 38.769036 -115.870228)
		(end 38.529514 -116.10975)
		(width 0.12065)
		(layer "B.Cu")
		(net "RMII_PHY_BMC_RXD1")
	)
	(segment
		(start 39.54272 -114.98072)
		(end 38.769036 -115.754404)
		(width 0.12065)
		(layer "B.Cu")
		(net "RMII_PHY_BMC_RXD1")
	)
	(segment
		(start 39.937436 -109.980476)
		(end 34.036 -104.07904)
		(width 0.12065)
		(layer "B.Cu")
		(net "RMII_PHY_BMC_RXD1")
	)
	(segment
		(start 29.523436 -78.4479)
		(end 29.840936 -78.1304)
		(width 0.12065)
		(layer "B.Cu")
		(net "RMII_PHY_BMC_RXD1")
	)
	(segment
		(start 34.036 -104.07904)
		(end 34.036 -85.201506)
		(width 0.12065)
		(layer "B.Cu")
		(net "RMII_PHY_BMC_RXD1")
	)
	(segment
		(start 39.081202 -112.63249)
		(end 39.937436 -111.776256)
		(width 0.12065)
		(layer "B.Cu")
		(net "RMII_PHY_BMC_RXD1")
	)
	(segment
		(start 38.040564 -119.745506)
		(end 38.040564 -122.420634)
		(width 0.12065)
		(layer "B.Cu")
		(net "RMII_PHY_BMC_RXD1")
	)
	(segment
		(start 39.54272 -114.98072)
		(end 39.081202 -114.519202)
		(width 0.12065)
		(layer "B.Cu")
		(net "RMII_PHY_BMC_RXD1")
	)
	(segment
		(start 39.081202 -114.519202)
		(end 39.081202 -112.63249)
		(width 0.12065)
		(layer "B.Cu")
		(net "RMII_PHY_BMC_RXD1")
	)
	(segment
		(start 34.027872 -84.780374)
		(end 29.523436 -80.275938)
		(width 0.12065)
		(layer "B.Cu")
		(net "RMII_PHY_BMC_RXD1")
	)
	(segment
		(start 34.027872 -85.193378)
		(end 34.027872 -84.780374)
		(width 0.12065)
		(layer "B.Cu")
		(net "RMII_PHY_BMC_RXD1")
	)
	(segment
		(start 39.937436 -111.776256)
		(end 39.937436 -109.980476)
		(width 0.12065)
		(layer "B.Cu")
		(net "RMII_PHY_BMC_RXD1")
	)
	(segment
		(start 38.040564 -122.420634)
		(end 38.10508 -122.48515)
		(width 0.12065)
		(layer "B.Cu")
		(net "RMII_PHY_BMC_RXD1")
	)
	(segment
		(start 29.523436 -80.275938)
		(end 29.523436 -78.4479)
		(width 0.12065)
		(layer "B.Cu")
		(net "RMII_PHY_BMC_RXD1")
	)
	(segment
		(start 38.769036 -115.754404)
		(end 38.769036 -115.870228)
		(width 0.12065)
		(layer "B.Cu")
		(net "RMII_PHY_BMC_RXD1")
	)
	(segment
		(start 34.036 -85.201506)
		(end 34.027872 -85.193378)
		(width 0.12065)
		(layer "B.Cu")
		(net "RMII_PHY_BMC_RXD1")
	)
	(segment
		(start 38.529514 -119.256556)
		(end 38.040564 -119.745506)
		(width 0.12065)
		(layer "B.Cu")
		(net "RMII_PHY_BMC_RXD1")
	)
	(segment
		(start 38.529514 -116.10975)
		(end 38.529514 -119.256556)
		(width 0.12065)
		(layer "B.Cu")
		(net "RMII_PHY_BMC_RXD1")
	)
	(segment
		(start 25.2984 -74.9046)
		(end 24.538178 -74.144378)
		(width 0.12065)
		(layer "F.Cu")
		(net "RMII_PHY_BMC_RXD0_R")
	)
	(segment
		(start 24.077422 -74.144378)
		(end 23.805134 -74.416666)
		(width 0.12065)
		(layer "F.Cu")
		(net "RMII_PHY_BMC_RXD0_R")
	)
	(segment
		(start 24.538178 -74.144378)
		(end 24.077422 -74.144378)
		(width 0.12065)
		(layer "F.Cu")
		(net "RMII_PHY_BMC_RXD0_R")
	)
	(segment
		(start 23.805134 -74.416666)
		(end 22.584918 -74.416666)
		(width 0.12065)
		(layer "F.Cu")
		(net "RMII_PHY_BMC_RXD0_R")
	)
	(segment
		(start 25.5905 -74.9046)
		(end 25.2984 -74.9046)
		(width 0.12065)
		(layer "F.Cu")
		(net "RMII_PHY_BMC_RXD0_R")
	)
	(segment
		(start 27.899868 -74.500232)
		(end 27.559 -74.8411)
		(width 0.12065)
		(layer "F.Cu")
		(net "RMII_PHY_BMC_RXD0")
	)
	(segment
		(start 29.178758 -75.178158)
		(end 28.500832 -74.500232)
		(width 0.12065)
		(layer "F.Cu")
		(net "RMII_PHY_BMC_RXD0")
	)
	(segment
		(start 29.178758 -77.886052)
		(end 29.178758 -75.178158)
		(width 0.12065)
		(layer "F.Cu")
		(net "RMII_PHY_BMC_RXD0")
	)
	(segment
		(start 27.4955 -74.9046)
		(end 26.4795 -74.9046)
		(width 0.12065)
		(layer "F.Cu")
		(net "RMII_PHY_BMC_RXD0")
	)
	(segment
		(start 28.500832 -74.500232)
		(end 27.899868 -74.500232)
		(width 0.12065)
		(layer "F.Cu")
		(net "RMII_PHY_BMC_RXD0")
	)
	(segment
		(start 28.93441 -78.1304)
		(end 29.178758 -77.886052)
		(width 0.12065)
		(layer "F.Cu")
		(net "RMII_PHY_BMC_RXD0")
	)
	(segment
		(start 38.504876 -123.684792)
		(end 38.10508 -123.284996)
		(width 0.12065)
		(layer "F.Cu")
		(net "RMII_PHY_BMC_RXD0")
	)
	(segment
		(start 27.559 -74.8411)
		(end 27.4955 -74.9046)
		(width 0.12065)
		(layer "F.Cu")
		(net "RMII_PHY_BMC_RXD0")
	)
	(via
		(at 28.93441 -78.1304)
		(size 0.508)
		(drill 0.254)
		(layers "F.Cu" "B.Cu")
		(net "RMII_PHY_BMC_RXD0")
	)
	(via
		(at 38.10508 -123.284996)
		(size 0.4572)
		(drill 0.2032)
		(layers "F.Cu" "B.Cu")
		(net "RMII_PHY_BMC_RXD0")
	)
	(segment
		(start 29.0576 -80.339946)
		(end 33.653222 -84.935568)
		(width 0.12065)
		(layer "B.Cu")
		(net "RMII_PHY_BMC_RXD0")
	)
	(segment
		(start 38.394386 -115.252246)
		(end 38.394386 -115.715034)
		(width 0.12065)
		(layer "B.Cu")
		(net "RMII_PHY_BMC_RXD0")
	)
	(segment
		(start 38.706552 -112.454436)
		(end 38.706552 -114.427508)
		(width 0.12065)
		(layer "B.Cu")
		(net "RMII_PHY_BMC_RXD0")
	)
	(segment
		(start 38.394386 -115.715034)
		(end 38.154864 -115.954556)
		(width 0.12065)
		(layer "B.Cu")
		(net "RMII_PHY_BMC_RXD0")
	)
	(segment
		(start 37.714428 -122.684794)
		(end 38.10508 -123.075446)
		(width 0.12065)
		(layer "B.Cu")
		(net "RMII_PHY_BMC_RXD0")
	)
	(segment
		(start 38.154864 -119.187468)
		(end 37.732208 -119.610124)
		(width 0.12065)
		(layer "B.Cu")
		(net "RMII_PHY_BMC_RXD0")
	)
	(segment
		(start 38.706552 -114.427508)
		(end 38.1381 -114.99596)
		(width 0.12065)
		(layer "B.Cu")
		(net "RMII_PHY_BMC_RXD0")
	)
	(segment
		(start 39.554658 -111.60633)
		(end 38.706552 -112.454436)
		(width 0.12065)
		(layer "B.Cu")
		(net "RMII_PHY_BMC_RXD0")
	)
	(segment
		(start 39.554658 -110.139226)
		(end 39.554658 -111.60633)
		(width 0.12065)
		(layer "B.Cu")
		(net "RMII_PHY_BMC_RXD0")
	)
	(segment
		(start 38.10508 -123.075446)
		(end 38.10508 -123.284996)
		(width 0.12065)
		(layer "B.Cu")
		(net "RMII_PHY_BMC_RXD0")
	)
	(segment
		(start 33.653222 -84.935568)
		(end 33.653222 -104.23779)
		(width 0.12065)
		(layer "B.Cu")
		(net "RMII_PHY_BMC_RXD0")
	)
	(segment
		(start 37.732208 -122.305572)
		(end 37.714428 -122.323352)
		(width 0.12065)
		(layer "B.Cu")
		(net "RMII_PHY_BMC_RXD0")
	)
	(segment
		(start 33.653222 -104.23779)
		(end 39.554658 -110.139226)
		(width 0.12065)
		(layer "B.Cu")
		(net "RMII_PHY_BMC_RXD0")
	)
	(segment
		(start 37.714428 -122.323352)
		(end 37.714428 -122.684794)
		(width 0.12065)
		(layer "B.Cu")
		(net "RMII_PHY_BMC_RXD0")
	)
	(segment
		(start 37.732208 -119.610124)
		(end 37.732208 -122.305572)
		(width 0.12065)
		(layer "B.Cu")
		(net "RMII_PHY_BMC_RXD0")
	)
	(segment
		(start 28.93441 -78.1304)
		(end 29.0576 -78.25359)
		(width 0.12065)
		(layer "B.Cu")
		(net "RMII_PHY_BMC_RXD0")
	)
	(segment
		(start 38.1381 -114.99596)
		(end 38.394386 -115.252246)
		(width 0.12065)
		(layer "B.Cu")
		(net "RMII_PHY_BMC_RXD0")
	)
	(segment
		(start 38.154864 -115.954556)
		(end 38.154864 -119.187468)
		(width 0.12065)
		(layer "B.Cu")
		(net "RMII_PHY_BMC_RXD0")
	)
	(segment
		(start 29.0576 -78.25359)
		(end 29.0576 -80.339946)
		(width 0.12065)
		(layer "B.Cu")
		(net "RMII_PHY_BMC_RXD0")
	)
	(segment
		(start 233.59999 -39.99992)
		(end 233.100118 -39.500048)
		(width 0.12065)
		(layer "F.Cu")
		(net "RMII_CRS_DV")
	)
	(via
		(at 233.100118 -39.500048)
		(size 0.4572)
		(drill 0.2032)
		(layers "F.Cu" "B.Cu")
		(net "RMII_CRS_DV")
	)
	(segment
		(start 232.61066 -41.00068)
		(end 232.6132 -40.99814)
		(width 0.1016)
		(layer "B.Cu")
		(net "RMII_CRS_DV")
	)
	(segment
		(start 232.6132 -39.986966)
		(end 233.100118 -39.500048)
		(width 0.1016)
		(layer "B.Cu")
		(net "RMII_CRS_DV")
	)
	(segment
		(start 232.6132 -40.99814)
		(end 232.6132 -39.986966)
		(width 0.1016)
		(layer "B.Cu")
		(net "RMII_CRS_DV")
	)
	(segment
		(start 24.041862 -74.916538)
		(end 22.584918 -74.916538)
		(width 0.12065)
		(layer "F.Cu")
		(net "RMII_BMC_TX_EN")
	)
	(segment
		(start 36.569904 -115.703604)
		(end 37.1348 -116.2685)
		(width 0.12065)
		(layer "F.Cu")
		(net "RMII_BMC_TX_EN")
	)
	(segment
		(start 33.275016 -107.36834)
		(end 34.231072 -108.324396)
		(width 0.12065)
		(layer "F.Cu")
		(net "RMII_BMC_TX_EN")
	)
	(segment
		(start 34.231072 -108.324396)
		(end 34.231072 -109.077252)
		(width 0.12065)
		(layer "F.Cu")
		(net "RMII_BMC_TX_EN")
	)
	(segment
		(start 34.231072 -109.481366)
		(end 36.569904 -111.820198)
		(width 0.12065)
		(layer "F.Cu")
		(net "RMII_BMC_TX_EN")
	)
	(segment
		(start 36.569904 -111.820198)
		(end 36.569904 -115.703604)
		(width 0.12065)
		(layer "F.Cu")
		(net "RMII_BMC_TX_EN")
	)
	(segment
		(start 34.231072 -109.077252)
		(end 34.231072 -109.481366)
		(width 0.12065)
		(layer "F.Cu")
		(net "RMII_BMC_TX_EN")
	)
	(segment
		(start 24.3078 -74.6506)
		(end 24.041862 -74.916538)
		(width 0.12065)
		(layer "F.Cu")
		(net "RMII_BMC_TX_EN")
	)
	(via
		(at 24.3078 -74.6506)
		(size 0.508)
		(drill 0.254)
		(layers "F.Cu" "B.Cu")
		(net "RMII_BMC_TX_EN")
	)
	(via
		(at 9.906 -76.073)
		(size 0.508)
		(drill 0.254)
		(layers "F.Cu" "B.Cu")
		(net "RMII_BMC_TX_EN")
	)
	(via
		(at 33.275016 -107.36834)
		(size 0.508)
		(drill 0.254)
		(layers "F.Cu" "B.Cu")
		(net "RMII_BMC_TX_EN")
	)
	(via
		(at 34.231072 -109.077252)
		(size 0.7112)
		(drill 0.3556)
		(layers "F.Cu" "B.Cu")
		(net "RMII_BMC_TX_EN")
	)
	(segment
		(start 26.7208 -70.79234)
		(end 26.7208 -72.2122)
		(width 0.12065)
		(layer "B.Cu")
		(net "RMII_BMC_TX_EN")
	)
	(segment
		(start 26.7208 -72.2122)
		(end 24.3078 -74.6252)
		(width 0.12065)
		(layer "B.Cu")
		(net "RMII_BMC_TX_EN")
	)
	(segment
		(start 24.3078 -74.6252)
		(end 24.3078 -74.6506)
		(width 0.12065)
		(layer "B.Cu")
		(net "RMII_BMC_TX_EN")
	)
	(segment
		(start 25.8953 -69.96684)
		(end 26.7208 -70.79234)
		(width 0.12065)
		(layer "B.Cu")
		(net "RMII_BMC_TX_EN")
	)
	(segment
		(start 24.0792 -74.422)
		(end 24.3078 -74.6506)
		(width 0.127)
		(layer "In2.Cu")
		(net "RMII_BMC_TX_EN")
	)
	(segment
		(start 10.9982 -74.422)
		(end 16.251682 -74.422)
		(width 0.127)
		(layer "In2.Cu")
		(net "RMII_BMC_TX_EN")
	)
	(segment
		(start 19.714718 -74.7776)
		(end 20.070318 -74.422)
		(width 0.127)
		(layer "In2.Cu")
		(net "RMII_BMC_TX_EN")
	)
	(segment
		(start 9.906 -76.073)
		(end 9.906 -75.5142)
		(width 0.127)
		(layer "In2.Cu")
		(net "RMII_BMC_TX_EN")
	)
	(segment
		(start 16.251682 -74.422)
		(end 16.607282 -74.7776)
		(width 0.127)
		(layer "In2.Cu")
		(net "RMII_BMC_TX_EN")
	)
	(segment
		(start 9.906 -75.5142)
		(end 10.9982 -74.422)
		(width 0.127)
		(layer "In2.Cu")
		(net "RMII_BMC_TX_EN")
	)
	(segment
		(start 20.070318 -74.422)
		(end 24.0792 -74.422)
		(width 0.127)
		(layer "In2.Cu")
		(net "RMII_BMC_TX_EN")
	)
	(segment
		(start 16.607282 -74.7776)
		(end 19.714718 -74.7776)
		(width 0.127)
		(layer "In2.Cu")
		(net "RMII_BMC_TX_EN")
	)
	(segment
		(start 15.5956 -88.537796)
		(end 14.2875 -87.229696)
		(width 0.127)
		(layer "In5.Cu")
		(net "RMII_BMC_TX_EN")
	)
	(segment
		(start 10.729214 -76.540614)
		(end 10.2616 -76.073)
		(width 0.127)
		(layer "In5.Cu")
		(net "RMII_BMC_TX_EN")
	)
	(segment
		(start 25.246076 -99.3394)
		(end 19.147536 -99.3394)
		(width 0.127)
		(layer "In5.Cu")
		(net "RMII_BMC_TX_EN")
	)
	(segment
		(start 19.147536 -99.3394)
		(end 15.5956 -95.787464)
		(width 0.127)
		(layer "In5.Cu")
		(net "RMII_BMC_TX_EN")
	)
	(segment
		(start 12.956794 -81.2292)
		(end 12.3698 -80.642206)
		(width 0.127)
		(layer "In5.Cu")
		(net "RMII_BMC_TX_EN")
	)
	(segment
		(start 14.2875 -87.229696)
		(end 14.2875 -84.0867)
		(width 0.127)
		(layer "In5.Cu")
		(net "RMII_BMC_TX_EN")
	)
	(segment
		(start 14.3383 -84.0359)
		(end 14.3383 -82.405982)
		(width 0.127)
		(layer "In5.Cu")
		(net "RMII_BMC_TX_EN")
	)
	(segment
		(start 14.3383 -82.405982)
		(end 13.161518 -81.2292)
		(width 0.127)
		(layer "In5.Cu")
		(net "RMII_BMC_TX_EN")
	)
	(segment
		(start 12.3698 -79.023718)
		(end 12.6111 -78.782418)
		(width 0.127)
		(layer "In5.Cu")
		(net "RMII_BMC_TX_EN")
	)
	(segment
		(start 12.6111 -78.392782)
		(end 10.758932 -76.540614)
		(width 0.127)
		(layer "In5.Cu")
		(net "RMII_BMC_TX_EN")
	)
	(segment
		(start 14.2875 -84.0867)
		(end 14.3383 -84.0359)
		(width 0.127)
		(layer "In5.Cu")
		(net "RMII_BMC_TX_EN")
	)
	(segment
		(start 12.3698 -80.642206)
		(end 12.3698 -79.023718)
		(width 0.127)
		(layer "In5.Cu")
		(net "RMII_BMC_TX_EN")
	)
	(segment
		(start 10.2616 -76.073)
		(end 9.906 -76.073)
		(width 0.127)
		(layer "In5.Cu")
		(net "RMII_BMC_TX_EN")
	)
	(segment
		(start 13.161518 -81.2292)
		(end 12.956794 -81.2292)
		(width 0.127)
		(layer "In5.Cu")
		(net "RMII_BMC_TX_EN")
	)
	(segment
		(start 15.5956 -95.787464)
		(end 15.5956 -88.537796)
		(width 0.127)
		(layer "In5.Cu")
		(net "RMII_BMC_TX_EN")
	)
	(segment
		(start 12.6111 -78.782418)
		(end 12.6111 -78.392782)
		(width 0.127)
		(layer "In5.Cu")
		(net "RMII_BMC_TX_EN")
	)
	(segment
		(start 10.758932 -76.540614)
		(end 10.729214 -76.540614)
		(width 0.127)
		(layer "In5.Cu")
		(net "RMII_BMC_TX_EN")
	)
	(segment
		(start 33.275016 -107.36834)
		(end 25.246076 -99.3394)
		(width 0.127)
		(layer "In5.Cu")
		(net "RMII_BMC_TX_EN")
	)
	(segment
		(start 39.304722 -125.284738)
		(end 38.90518 -124.885196)
		(width 0.12065)
		(layer "F.Cu")
		(net "RMII_BMC_RX_ER")
	)
	(segment
		(start 39.304722 -125.284992)
		(end 39.304722 -125.284738)
		(width 0.12065)
		(layer "F.Cu")
		(net "RMII_BMC_RX_ER")
	)
	(via
		(at 38.90518 -124.885196)
		(size 0.4572)
		(drill 0.2032)
		(layers "F.Cu" "B.Cu")
		(net "RMII_BMC_RX_ER")
	)
	(via
		(at 34.832544 -107.390692)
		(size 0.7112)
		(drill 0.3556)
		(layers "F.Cu" "B.Cu")
		(net "RMII_BMC_RX_ER")
	)
	(via
		(at 38.8874 -111.506)
		(size 0.508)
		(drill 0.254)
		(layers "F.Cu" "B.Cu")
		(net "RMII_BMC_RX_ER")
	)
	(segment
		(start 34.330386 -108.289598)
		(end 34.330386 -107.89285)
		(width 0.12065)
		(layer "B.Cu")
		(net "RMII_BMC_RX_ER")
	)
	(segment
		(start 35.56762 -107.390692)
		(end 34.832544 -107.390692)
		(width 0.12065)
		(layer "B.Cu")
		(net "RMII_BMC_RX_ER")
	)
	(segment
		(start 38.8874 -111.506)
		(end 37.719 -111.506)
		(width 0.12065)
		(layer "B.Cu")
		(net "RMII_BMC_RX_ER")
	)
	(segment
		(start 37.105844 -108.928916)
		(end 35.56762 -107.390692)
		(width 0.12065)
		(layer "B.Cu")
		(net "RMII_BMC_RX_ER")
	)
	(segment
		(start 37.105844 -110.892844)
		(end 37.105844 -108.928916)
		(width 0.12065)
		(layer "B.Cu")
		(net "RMII_BMC_RX_ER")
	)
	(segment
		(start 37.719 -111.506)
		(end 37.105844 -110.892844)
		(width 0.12065)
		(layer "B.Cu")
		(net "RMII_BMC_RX_ER")
	)
	(segment
		(start 34.330386 -107.89285)
		(end 34.832544 -107.390692)
		(width 0.12065)
		(layer "B.Cu")
		(net "RMII_BMC_RX_ER")
	)
	(segment
		(start 39.298626 -113.614708)
		(end 39.298626 -124.49175)
		(width 0.127)
		(layer "In2.Cu")
		(net "RMII_BMC_RX_ER")
	)
	(segment
		(start 38.8874 -113.203482)
		(end 39.298626 -113.614708)
		(width 0.127)
		(layer "In2.Cu")
		(net "RMII_BMC_RX_ER")
	)
	(segment
		(start 38.8874 -111.506)
		(end 38.8874 -113.203482)
		(width 0.127)
		(layer "In2.Cu")
		(net "RMII_BMC_RX_ER")
	)
	(segment
		(start 39.298626 -124.49175)
		(end 38.90518 -124.885196)
		(width 0.127)
		(layer "In2.Cu")
		(net "RMII_BMC_RX_ER")
	)
	(segment
		(start 23.619714 -75.431396)
		(end 23.627842 -75.439524)
		(width 0.12065)
		(layer "F.Cu")
		(net "RMII_BMC_PHY_TXD1")
	)
	(segment
		(start 22.584918 -75.416664)
		(end 23.384256 -75.416664)
		(width 0.12065)
		(layer "F.Cu")
		(net "RMII_BMC_PHY_TXD1")
	)
	(segment
		(start 23.627842 -75.439524)
		(end 23.766272 -75.439524)
		(width 0.12065)
		(layer "F.Cu")
		(net "RMII_BMC_PHY_TXD1")
	)
	(segment
		(start 24.478996 -75.778106)
		(end 24.586692 -75.67041)
		(width 0.12065)
		(layer "F.Cu")
		(net "RMII_BMC_PHY_TXD1")
	)
	(segment
		(start 24.104854 -75.778106)
		(end 24.478996 -75.778106)
		(width 0.12065)
		(layer "F.Cu")
		(net "RMII_BMC_PHY_TXD1")
	)
	(segment
		(start 23.384256 -75.416664)
		(end 23.398988 -75.431396)
		(width 0.12065)
		(layer "F.Cu")
		(net "RMII_BMC_PHY_TXD1")
	)
	(segment
		(start 25.5143 -75.9968)
		(end 25.5905 -75.9206)
		(width 0.12065)
		(layer "F.Cu")
		(net "RMII_BMC_PHY_TXD1")
	)
	(segment
		(start 24.586692 -75.67041)
		(end 24.913082 -75.9968)
		(width 0.12065)
		(layer "F.Cu")
		(net "RMII_BMC_PHY_TXD1")
	)
	(segment
		(start 23.398988 -75.431396)
		(end 23.619714 -75.431396)
		(width 0.12065)
		(layer "F.Cu")
		(net "RMII_BMC_PHY_TXD1")
	)
	(segment
		(start 23.766272 -75.439524)
		(end 24.104854 -75.778106)
		(width 0.12065)
		(layer "F.Cu")
		(net "RMII_BMC_PHY_TXD1")
	)
	(segment
		(start 24.913082 -75.9968)
		(end 25.5143 -75.9968)
		(width 0.12065)
		(layer "F.Cu")
		(net "RMII_BMC_PHY_TXD1")
	)
	(via
		(at 24.586692 -75.67041)
		(size 0.508)
		(drill 0.254)
		(layers "F.Cu" "B.Cu")
		(net "RMII_BMC_PHY_TXD1")
	)
	(segment
		(start 24.273256 -94.258384)
		(end 25.131268 -95.116396)
		(width 0.12065)
		(layer "B.Cu")
		(net "RMII_BMC_PHY_TXD1")
	)
	(segment
		(start 25.15616 -100.575618)
		(end 25.15616 -100.598478)
		(width 0.12065)
		(layer "B.Cu")
		(net "RMII_BMC_PHY_TXD1")
	)
	(segment
		(start 24.27351 -79.804514)
		(end 24.27351 -93.941138)
		(width 0.12065)
		(layer "B.Cu")
		(net "RMII_BMC_PHY_TXD1")
	)
	(segment
		(start 24.27351 -93.941138)
		(end 24.273256 -93.941392)
		(width 0.12065)
		(layer "B.Cu")
		(net "RMII_BMC_PHY_TXD1")
	)
	(segment
		(start 30.404308 -109.820202)
		(end 32.582358 -111.998252)
		(width 0.12065)
		(layer "B.Cu")
		(net "RMII_BMC_PHY_TXD1")
	)
	(segment
		(start 24.586692 -75.67041)
		(end 23.70709 -76.550012)
		(width 0.12065)
		(layer "B.Cu")
		(net "RMII_BMC_PHY_TXD1")
	)
	(segment
		(start 36.115752 -116.093748)
		(end 35.814 -116.3955)
		(width 0.12065)
		(layer "B.Cu")
		(net "RMII_BMC_PHY_TXD1")
	)
	(segment
		(start 36.178998 -113.048034)
		(end 36.178998 -114.419126)
		(width 0.12065)
		(layer "B.Cu")
		(net "RMII_BMC_PHY_TXD1")
	)
	(segment
		(start 25.131268 -100.550726)
		(end 25.15616 -100.575618)
		(width 0.12065)
		(layer "B.Cu")
		(net "RMII_BMC_PHY_TXD1")
	)
	(segment
		(start 23.70709 -79.238094)
		(end 24.27351 -79.804514)
		(width 0.12065)
		(layer "B.Cu")
		(net "RMII_BMC_PHY_TXD1")
	)
	(segment
		(start 24.273256 -93.941392)
		(end 24.273256 -94.258384)
		(width 0.12065)
		(layer "B.Cu")
		(net "RMII_BMC_PHY_TXD1")
	)
	(segment
		(start 35.546284 -111.998252)
		(end 36.182808 -112.634776)
		(width 0.12065)
		(layer "B.Cu")
		(net "RMII_BMC_PHY_TXD1")
	)
	(segment
		(start 35.687 -114.911124)
		(end 35.687 -114.99596)
		(width 0.12065)
		(layer "B.Cu")
		(net "RMII_BMC_PHY_TXD1")
	)
	(segment
		(start 32.582358 -111.998252)
		(end 35.546284 -111.998252)
		(width 0.12065)
		(layer "B.Cu")
		(net "RMII_BMC_PHY_TXD1")
	)
	(segment
		(start 36.115752 -115.424712)
		(end 36.115752 -116.093748)
		(width 0.12065)
		(layer "B.Cu")
		(net "RMII_BMC_PHY_TXD1")
	)
	(segment
		(start 36.182808 -113.044224)
		(end 36.178998 -113.048034)
		(width 0.12065)
		(layer "B.Cu")
		(net "RMII_BMC_PHY_TXD1")
	)
	(segment
		(start 30.404308 -105.846626)
		(end 30.404308 -109.820202)
		(width 0.12065)
		(layer "B.Cu")
		(net "RMII_BMC_PHY_TXD1")
	)
	(segment
		(start 23.70709 -76.550012)
		(end 23.70709 -79.238094)
		(width 0.12065)
		(layer "B.Cu")
		(net "RMII_BMC_PHY_TXD1")
	)
	(segment
		(start 25.15616 -100.598478)
		(end 30.404308 -105.846626)
		(width 0.12065)
		(layer "B.Cu")
		(net "RMII_BMC_PHY_TXD1")
	)
	(segment
		(start 25.131268 -95.116396)
		(end 25.131268 -100.550726)
		(width 0.12065)
		(layer "B.Cu")
		(net "RMII_BMC_PHY_TXD1")
	)
	(segment
		(start 36.178998 -114.419126)
		(end 35.687 -114.911124)
		(width 0.12065)
		(layer "B.Cu")
		(net "RMII_BMC_PHY_TXD1")
	)
	(segment
		(start 35.687 -114.99596)
		(end 36.115752 -115.424712)
		(width 0.12065)
		(layer "B.Cu")
		(net "RMII_BMC_PHY_TXD1")
	)
	(segment
		(start 36.182808 -112.634776)
		(end 36.182808 -113.044224)
		(width 0.12065)
		(layer "B.Cu")
		(net "RMII_BMC_PHY_TXD1")
	)
	(segment
		(start 25.5905 -76.9366)
		(end 25.5905 -76.736956)
		(width 0.12065)
		(layer "F.Cu")
		(net "RMII_BMC_PHY_TXD0")
	)
	(segment
		(start 23.954232 -76.169012)
		(end 24.178768 -76.169012)
		(width 0.12065)
		(layer "F.Cu")
		(net "RMII_BMC_PHY_TXD0")
	)
	(segment
		(start 25.23109 -76.377546)
		(end 24.786082 -76.377546)
		(width 0.12065)
		(layer "F.Cu")
		(net "RMII_BMC_PHY_TXD0")
	)
	(segment
		(start 24.178768 -76.169012)
		(end 24.586692 -76.576936)
		(width 0.12065)
		(layer "F.Cu")
		(net "RMII_BMC_PHY_TXD0")
	)
	(segment
		(start 24.786082 -76.377546)
		(end 24.586692 -76.576936)
		(width 0.12065)
		(layer "F.Cu")
		(net "RMII_BMC_PHY_TXD0")
	)
	(segment
		(start 23.436834 -75.843384)
		(end 23.628604 -75.843384)
		(width 0.12065)
		(layer "F.Cu")
		(net "RMII_BMC_PHY_TXD0")
	)
	(segment
		(start 25.5905 -76.736956)
		(end 25.23109 -76.377546)
		(width 0.12065)
		(layer "F.Cu")
		(net "RMII_BMC_PHY_TXD0")
	)
	(segment
		(start 22.584918 -75.916536)
		(end 23.363682 -75.916536)
		(width 0.12065)
		(layer "F.Cu")
		(net "RMII_BMC_PHY_TXD0")
	)
	(segment
		(start 23.628604 -75.843384)
		(end 23.954232 -76.169012)
		(width 0.12065)
		(layer "F.Cu")
		(net "RMII_BMC_PHY_TXD0")
	)
	(segment
		(start 23.363682 -75.916536)
		(end 23.436834 -75.843384)
		(width 0.12065)
		(layer "F.Cu")
		(net "RMII_BMC_PHY_TXD0")
	)
	(via
		(at 24.586692 -76.576936)
		(size 0.508)
		(drill 0.254)
		(layers "F.Cu" "B.Cu")
		(net "RMII_BMC_PHY_TXD0")
	)
	(segment
		(start 25.505918 -100.395532)
		(end 31.001716 -105.89133)
		(width 0.12065)
		(layer "B.Cu")
		(net "RMII_BMC_PHY_TXD0")
	)
	(segment
		(start 36.501324 -116.066824)
		(end 36.83 -116.3955)
		(width 0.12065)
		(layer "B.Cu")
		(net "RMII_BMC_PHY_TXD0")
	)
	(segment
		(start 36.627054 -114.500914)
		(end 37.1221 -114.99596)
		(width 0.12065)
		(layer "B.Cu")
		(net "RMII_BMC_PHY_TXD0")
	)
	(segment
		(start 36.553648 -114.420904)
		(end 36.630356 -114.497612)
		(width 0.12065)
		(layer "B.Cu")
		(net "RMII_BMC_PHY_TXD0")
	)
	(segment
		(start 32.760412 -111.623602)
		(end 35.701732 -111.623602)
		(width 0.12065)
		(layer "B.Cu")
		(net "RMII_BMC_PHY_TXD0")
	)
	(segment
		(start 31.001716 -105.89133)
		(end 31.001716 -109.864906)
		(width 0.12065)
		(layer "B.Cu")
		(net "RMII_BMC_PHY_TXD0")
	)
	(segment
		(start 24.586692 -76.576936)
		(end 24.08174 -77.081888)
		(width 0.12065)
		(layer "B.Cu")
		(net "RMII_BMC_PHY_TXD0")
	)
	(segment
		(start 35.701732 -111.623602)
		(end 35.920934 -111.842804)
		(width 0.12065)
		(layer "B.Cu")
		(net "RMII_BMC_PHY_TXD0")
	)
	(segment
		(start 31.001716 -109.864906)
		(end 32.760412 -111.623602)
		(width 0.12065)
		(layer "B.Cu")
		(net "RMII_BMC_PHY_TXD0")
	)
	(segment
		(start 36.557458 -112.479582)
		(end 36.557458 -113.199418)
		(width 0.12065)
		(layer "B.Cu")
		(net "RMII_BMC_PHY_TXD0")
	)
	(segment
		(start 36.501324 -115.616736)
		(end 36.501324 -116.066824)
		(width 0.12065)
		(layer "B.Cu")
		(net "RMII_BMC_PHY_TXD0")
	)
	(segment
		(start 37.1221 -114.99596)
		(end 36.501324 -115.616736)
		(width 0.12065)
		(layer "B.Cu")
		(net "RMII_BMC_PHY_TXD0")
	)
	(segment
		(start 36.630356 -114.497612)
		(end 36.627054 -114.500914)
		(width 0.12065)
		(layer "B.Cu")
		(net "RMII_BMC_PHY_TXD0")
	)
	(segment
		(start 25.505918 -94.949518)
		(end 25.505918 -100.395532)
		(width 0.12065)
		(layer "B.Cu")
		(net "RMII_BMC_PHY_TXD0")
	)
	(segment
		(start 35.920934 -111.842804)
		(end 35.920934 -111.843058)
		(width 0.12065)
		(layer "B.Cu")
		(net "RMII_BMC_PHY_TXD0")
	)
	(segment
		(start 24.656288 -94.099888)
		(end 25.505918 -94.949518)
		(width 0.12065)
		(layer "B.Cu")
		(net "RMII_BMC_PHY_TXD0")
	)
	(segment
		(start 36.557458 -113.199418)
		(end 36.553648 -113.203228)
		(width 0.12065)
		(layer "B.Cu")
		(net "RMII_BMC_PHY_TXD0")
	)
	(segment
		(start 24.08174 -79.071978)
		(end 24.656288 -79.646526)
		(width 0.12065)
		(layer "B.Cu")
		(net "RMII_BMC_PHY_TXD0")
	)
	(segment
		(start 24.656288 -79.646526)
		(end 24.656288 -94.099888)
		(width 0.12065)
		(layer "B.Cu")
		(net "RMII_BMC_PHY_TXD0")
	)
	(segment
		(start 35.920934 -111.843058)
		(end 36.557458 -112.479582)
		(width 0.12065)
		(layer "B.Cu")
		(net "RMII_BMC_PHY_TXD0")
	)
	(segment
		(start 36.553648 -113.203228)
		(end 36.553648 -114.420904)
		(width 0.12065)
		(layer "B.Cu")
		(net "RMII_BMC_PHY_TXD0")
	)
	(segment
		(start 24.08174 -77.081888)
		(end 24.08174 -79.071978)
		(width 0.12065)
		(layer "B.Cu")
		(net "RMII_BMC_PHY_TXD0")
	)
	(segment
		(start 37.193474 -115.196112)
		(end 37.391086 -115.196112)
		(width 0.12065)
		(layer "F.Cu")
		(net "RMII_BMC_CRS_DV")
	)
	(segment
		(start 38.252908 -114.31905)
		(end 38.252908 -113.79835)
		(width 0.12065)
		(layer "F.Cu")
		(net "RMII_BMC_CRS_DV")
	)
	(segment
		(start 38.525704 -112.040924)
		(end 35.115246 -108.630466)
		(width 0.12065)
		(layer "F.Cu")
		(net "RMII_BMC_CRS_DV")
	)
	(segment
		(start 24.073104 -73.033128)
		(end 23.956518 -72.916542)
		(width 0.12065)
		(layer "F.Cu")
		(net "RMII_BMC_CRS_DV")
	)
	(segment
		(start 38.260528 -114.32667)
		(end 38.252908 -114.31905)
		(width 0.12065)
		(layer "F.Cu")
		(net "RMII_BMC_CRS_DV")
	)
	(segment
		(start 23.956518 -72.916542)
		(end 22.584918 -72.916542)
		(width 0.12065)
		(layer "F.Cu")
		(net "RMII_BMC_CRS_DV")
	)
	(segment
		(start 38.525704 -113.525554)
		(end 38.525704 -112.040924)
		(width 0.12065)
		(layer "F.Cu")
		(net "RMII_BMC_CRS_DV")
	)
	(segment
		(start 35.115246 -108.630466)
		(end 35.115246 -108.1532)
		(width 0.12065)
		(layer "F.Cu")
		(net "RMII_BMC_CRS_DV")
	)
	(segment
		(start 35.115246 -108.1532)
		(end 33.351216 -106.38917)
		(width 0.12065)
		(layer "F.Cu")
		(net "RMII_BMC_CRS_DV")
	)
	(segment
		(start 37.391086 -115.196112)
		(end 38.260528 -114.32667)
		(width 0.12065)
		(layer "F.Cu")
		(net "RMII_BMC_CRS_DV")
	)
	(segment
		(start 38.252908 -113.79835)
		(end 38.525704 -113.525554)
		(width 0.12065)
		(layer "F.Cu")
		(net "RMII_BMC_CRS_DV")
	)
	(segment
		(start 24.960072 -73.033128)
		(end 24.073104 -73.033128)
		(width 0.12065)
		(layer "F.Cu")
		(net "RMII_BMC_CRS_DV")
	)
	(segment
		(start 25.527 -72.4662)
		(end 24.960072 -73.033128)
		(width 0.12065)
		(layer "F.Cu")
		(net "RMII_BMC_CRS_DV")
	)
	(via
		(at 33.351216 -106.38917)
		(size 0.508)
		(drill 0.254)
		(layers "F.Cu" "B.Cu")
		(net "RMII_BMC_CRS_DV")
	)
	(via
		(at 18.467832 -97.04197)
		(size 0.508)
		(drill 0.254)
		(layers "F.Cu" "B.Cu")
		(net "RMII_BMC_CRS_DV")
	)
	(via
		(at 24.461216 -73.054464)
		(size 0.7112)
		(drill 0.3556)
		(layers "F.Cu" "B.Cu")
		(net "RMII_BMC_CRS_DV")
	)
	(via
		(at 25.527 -72.4662)
		(size 0.508)
		(drill 0.254)
		(layers "F.Cu" "B.Cu")
		(net "RMII_BMC_CRS_DV")
	)
	(segment
		(start 23.733252 -74.876152)
		(end 23.733252 -74.539348)
		(width 0.12065)
		(layer "B.Cu")
		(net "RMII_BMC_CRS_DV")
	)
	(segment
		(start 23.331932 -92.134182)
		(end 23.331932 -79.973932)
		(width 0.12065)
		(layer "B.Cu")
		(net "RMII_BMC_CRS_DV")
	)
	(segment
		(start 18.798032 -96.71177)
		(end 18.798032 -96.668082)
		(width 0.12065)
		(layer "B.Cu")
		(net "RMII_BMC_CRS_DV")
	)
	(segment
		(start 18.467832 -97.04197)
		(end 18.798032 -96.71177)
		(width 0.12065)
		(layer "B.Cu")
		(net "RMII_BMC_CRS_DV")
	)
	(segment
		(start 25.527 -72.4662)
		(end 25.04948 -72.4662)
		(width 0.12065)
		(layer "B.Cu")
		(net "RMII_BMC_CRS_DV")
	)
	(segment
		(start 22.6822 -75.927204)
		(end 23.733252 -74.876152)
		(width 0.12065)
		(layer "B.Cu")
		(net "RMII_BMC_CRS_DV")
	)
	(segment
		(start 18.798032 -96.668082)
		(end 23.331932 -92.134182)
		(width 0.12065)
		(layer "B.Cu")
		(net "RMII_BMC_CRS_DV")
	)
	(segment
		(start 23.733252 -74.539348)
		(end 24.205438 -74.067162)
		(width 0.12065)
		(layer "B.Cu")
		(net "RMII_BMC_CRS_DV")
	)
	(segment
		(start 23.331932 -79.973932)
		(end 22.6822 -79.3242)
		(width 0.12065)
		(layer "B.Cu")
		(net "RMII_BMC_CRS_DV")
	)
	(segment
		(start 24.205438 -73.310242)
		(end 24.461216 -73.054464)
		(width 0.12065)
		(layer "B.Cu")
		(net "RMII_BMC_CRS_DV")
	)
	(segment
		(start 25.04948 -72.4662)
		(end 24.461216 -73.054464)
		(width 0.12065)
		(layer "B.Cu")
		(net "RMII_BMC_CRS_DV")
	)
	(segment
		(start 24.205438 -74.067162)
		(end 24.205438 -73.310242)
		(width 0.12065)
		(layer "B.Cu")
		(net "RMII_BMC_CRS_DV")
	)
	(segment
		(start 22.6822 -79.3242)
		(end 22.6822 -75.927204)
		(width 0.12065)
		(layer "B.Cu")
		(net "RMII_BMC_CRS_DV")
	)
	(segment
		(start 18.467832 -97.04197)
		(end 20.104862 -98.679)
		(width 0.127)
		(layer "In5.Cu")
		(net "RMII_BMC_CRS_DV")
	)
	(segment
		(start 25.641046 -98.679)
		(end 33.351216 -106.38917)
		(width 0.127)
		(layer "In5.Cu")
		(net "RMII_BMC_CRS_DV")
	)
	(segment
		(start 20.104862 -98.679)
		(end 25.641046 -98.679)
		(width 0.127)
		(layer "In5.Cu")
		(net "RMII_BMC_CRS_DV")
	)
	(segment
		(start 143.136874 -94.572074)
		(end 143.136874 -94.82582)
		(width 0.12065)
		(layer "F.Cu")
		(net "PWRGD_P1V8_STBY")
	)
	(segment
		(start 65.2526 -165.5826)
		(end 65.1764 -165.6588)
		(width 0.12065)
		(layer "F.Cu")
		(net "PWRGD_P1V8_STBY")
	)
	(segment
		(start 142.374874 -92.50172)
		(end 142.374874 -93.657674)
		(width 0.12065)
		(layer "F.Cu")
		(net "PWRGD_P1V8_STBY")
	)
	(segment
		(start 142.5702 -94.0054)
		(end 143.136874 -94.572074)
		(width 0.12065)
		(layer "F.Cu")
		(net "PWRGD_P1V8_STBY")
	)
	(segment
		(start 142.5702 -93.853)
		(end 142.5702 -94.0054)
		(width 0.12065)
		(layer "F.Cu")
		(net "PWRGD_P1V8_STBY")
	)
	(segment
		(start 142.374874 -93.657674)
		(end 142.5702 -93.853)
		(width 0.12065)
		(layer "F.Cu")
		(net "PWRGD_P1V8_STBY")
	)
	(segment
		(start 66.2432 -165.5826)
		(end 65.2526 -165.5826)
		(width 0.12065)
		(layer "F.Cu")
		(net "PWRGD_P1V8_STBY")
	)
	(via
		(at 133.54939 -92.150184)
		(size 0.7112)
		(drill 0.3556)
		(layers "F.Cu" "B.Cu")
		(net "PWRGD_P1V8_STBY")
	)
	(via
		(at 65.1764 -165.6588)
		(size 0.508)
		(drill 0.254)
		(layers "F.Cu" "B.Cu")
		(net "PWRGD_P1V8_STBY")
	)
	(via
		(at 252.6411 -10.12952)
		(size 0.508)
		(drill 0.254)
		(layers "F.Cu" "B.Cu")
		(net "PWRGD_P1V8_STBY")
	)
	(via
		(at 142.5702 -93.853)
		(size 0.508)
		(drill 0.254)
		(layers "F.Cu" "B.Cu")
		(net "PWRGD_P1V8_STBY")
	)
	(via
		(at 135.376412 -94.239842)
		(size 0.508)
		(drill 0.254)
		(layers "F.Cu" "B.Cu")
		(net "PWRGD_P1V8_STBY")
	)
	(via
		(at 264.221214 -15.504922)
		(size 0.508)
		(drill 0.254)
		(layers "F.Cu" "B.Cu")
		(net "PWRGD_P1V8_STBY")
	)
	(segment
		(start 131.064 -44.6024)
		(end 143.369538 -44.6024)
		(width 0.12065)
		(layer "B.Cu")
		(net "PWRGD_P1V8_STBY")
	)
	(segment
		(start 198.570596 2.102358)
		(end 209.356452 2.102358)
		(width 0.12065)
		(layer "B.Cu")
		(net "PWRGD_P1V8_STBY")
	)
	(segment
		(start 145.114264 -42.857674)
		(end 161.569146 -42.857674)
		(width 0.12065)
		(layer "B.Cu")
		(net "PWRGD_P1V8_STBY")
	)
	(segment
		(start 126.650496 -64.344296)
		(end 124.1552 -61.849)
		(width 0.12065)
		(layer "B.Cu")
		(net "PWRGD_P1V8_STBY")
	)
	(segment
		(start 161.569146 -42.857674)
		(end 177.857404 -26.569416)
		(width 0.12065)
		(layer "B.Cu")
		(net "PWRGD_P1V8_STBY")
	)
	(segment
		(start 127.3048 -48.3616)
		(end 131.064 -44.6024)
		(width 0.12065)
		(layer "B.Cu")
		(net "PWRGD_P1V8_STBY")
	)
	(segment
		(start 230.698548 -6.070854)
		(end 243.687346 -6.070854)
		(width 0.12065)
		(layer "B.Cu")
		(net "PWRGD_P1V8_STBY")
	)
	(segment
		(start 229.206552 -3.489198)
		(end 229.043484 -3.652266)
		(width 0.12065)
		(layer "B.Cu")
		(net "PWRGD_P1V8_STBY")
	)
	(segment
		(start 243.687346 -6.070854)
		(end 244.485922 -6.86943)
		(width 0.12065)
		(layer "B.Cu")
		(net "PWRGD_P1V8_STBY")
	)
	(segment
		(start 186.027568 -13.671296)
		(end 186.027568 -12.63523)
		(width 0.12065)
		(layer "B.Cu")
		(net "PWRGD_P1V8_STBY")
	)
	(segment
		(start 124.1552 -52.8066)
		(end 127.3048 -49.657)
		(width 0.12065)
		(layer "B.Cu")
		(net "PWRGD_P1V8_STBY")
	)
	(segment
		(start 177.857404 -26.569416)
		(end 177.857404 -19.424396)
		(width 0.12065)
		(layer "B.Cu")
		(net "PWRGD_P1V8_STBY")
	)
	(segment
		(start 226.04095 2.054352)
		(end 229.206552 -1.11125)
		(width 0.12065)
		(layer "B.Cu")
		(net "PWRGD_P1V8_STBY")
	)
	(segment
		(start 133.54939 -92.150184)
		(end 126.304548 -84.905342)
		(width 0.12065)
		(layer "B.Cu")
		(net "PWRGD_P1V8_STBY")
	)
	(segment
		(start 209.404458 2.054352)
		(end 226.04095 2.054352)
		(width 0.12065)
		(layer "B.Cu")
		(net "PWRGD_P1V8_STBY")
	)
	(segment
		(start 261.18439 -15.43939)
		(end 260.63575 -14.89075)
		(width 0.12065)
		(layer "B.Cu")
		(net "PWRGD_P1V8_STBY")
	)
	(segment
		(start 251.069094 -8.810752)
		(end 252.387862 -10.12952)
		(width 0.12065)
		(layer "B.Cu")
		(net "PWRGD_P1V8_STBY")
	)
	(segment
		(start 181.6608 -15.621)
		(end 184.077864 -15.621)
		(width 0.12065)
		(layer "B.Cu")
		(net "PWRGD_P1V8_STBY")
	)
	(segment
		(start 246.122444 -8.810752)
		(end 251.069094 -8.810752)
		(width 0.12065)
		(layer "B.Cu")
		(net "PWRGD_P1V8_STBY")
	)
	(segment
		(start 262.995664 -15.43939)
		(end 261.18439 -15.43939)
		(width 0.12065)
		(layer "B.Cu")
		(net "PWRGD_P1V8_STBY")
	)
	(segment
		(start 209.356452 2.102358)
		(end 209.404458 2.054352)
		(width 0.12065)
		(layer "B.Cu")
		(net "PWRGD_P1V8_STBY")
	)
	(segment
		(start 196.722238 0.254)
		(end 198.570596 2.102358)
		(width 0.12065)
		(layer "B.Cu")
		(net "PWRGD_P1V8_STBY")
	)
	(segment
		(start 126.857252 -67.437)
		(end 126.650496 -67.230244)
		(width 0.12065)
		(layer "B.Cu")
		(net "PWRGD_P1V8_STBY")
	)
	(segment
		(start 184.077864 -15.621)
		(end 186.027568 -13.671296)
		(width 0.12065)
		(layer "B.Cu")
		(net "PWRGD_P1V8_STBY")
	)
	(segment
		(start 264.033 -14.351)
		(end 264.033 -14.402054)
		(width 0.12065)
		(layer "B.Cu")
		(net "PWRGD_P1V8_STBY")
	)
	(segment
		(start 264.033 -15.316708)
		(end 264.221214 -15.504922)
		(width 0.12065)
		(layer "B.Cu")
		(net "PWRGD_P1V8_STBY")
	)
	(segment
		(start 142.374874 -92.66682)
		(end 142.374874 -93.657674)
		(width 0.12065)
		(layer "B.Cu")
		(net "PWRGD_P1V8_STBY")
	)
	(segment
		(start 244.485922 -7.17423)
		(end 246.122444 -8.810752)
		(width 0.12065)
		(layer "B.Cu")
		(net "PWRGD_P1V8_STBY")
	)
	(segment
		(start 135.376412 -93.977206)
		(end 133.54939 -92.150184)
		(width 0.12065)
		(layer "B.Cu")
		(net "PWRGD_P1V8_STBY")
	)
	(segment
		(start 126.650496 -67.230244)
		(end 126.650496 -64.344296)
		(width 0.12065)
		(layer "B.Cu")
		(net "PWRGD_P1V8_STBY")
	)
	(segment
		(start 192.964054 0.254)
		(end 196.722238 0.254)
		(width 0.12065)
		(layer "B.Cu")
		(net "PWRGD_P1V8_STBY")
	)
	(segment
		(start 260.63575 -14.89075)
		(end 260.63575 -14.6431)
		(width 0.12065)
		(layer "B.Cu")
		(net "PWRGD_P1V8_STBY")
	)
	(segment
		(start 124.1552 -61.849)
		(end 124.1552 -52.8066)
		(width 0.12065)
		(layer "B.Cu")
		(net "PWRGD_P1V8_STBY")
	)
	(segment
		(start 229.043484 -3.652266)
		(end 229.043484 -4.41579)
		(width 0.12065)
		(layer "B.Cu")
		(net "PWRGD_P1V8_STBY")
	)
	(segment
		(start 126.304548 -71.515224)
		(end 126.857252 -70.96252)
		(width 0.12065)
		(layer "B.Cu")
		(net "PWRGD_P1V8_STBY")
	)
	(segment
		(start 126.857252 -70.96252)
		(end 126.857252 -67.437)
		(width 0.12065)
		(layer "B.Cu")
		(net "PWRGD_P1V8_STBY")
	)
	(segment
		(start 264.033 -14.402054)
		(end 262.995664 -15.43939)
		(width 0.12065)
		(layer "B.Cu")
		(net "PWRGD_P1V8_STBY")
	)
	(segment
		(start 142.374874 -93.657674)
		(end 142.5702 -93.853)
		(width 0.12065)
		(layer "B.Cu")
		(net "PWRGD_P1V8_STBY")
	)
	(segment
		(start 186.027568 -12.63523)
		(end 186.623452 -12.039346)
		(width 0.12065)
		(layer "B.Cu")
		(net "PWRGD_P1V8_STBY")
	)
	(segment
		(start 177.857404 -19.424396)
		(end 181.6608 -15.621)
		(width 0.12065)
		(layer "B.Cu")
		(net "PWRGD_P1V8_STBY")
	)
	(segment
		(start 244.485922 -6.86943)
		(end 244.485922 -7.17423)
		(width 0.12065)
		(layer "B.Cu")
		(net "PWRGD_P1V8_STBY")
	)
	(segment
		(start 127.3048 -49.657)
		(end 127.3048 -48.3616)
		(width 0.12065)
		(layer "B.Cu")
		(net "PWRGD_P1V8_STBY")
	)
	(segment
		(start 229.043484 -4.41579)
		(end 230.698548 -6.070854)
		(width 0.12065)
		(layer "B.Cu")
		(net "PWRGD_P1V8_STBY")
	)
	(segment
		(start 186.623452 -6.086602)
		(end 192.964054 0.254)
		(width 0.12065)
		(layer "B.Cu")
		(net "PWRGD_P1V8_STBY")
	)
	(segment
		(start 126.304548 -84.905342)
		(end 126.304548 -71.515224)
		(width 0.12065)
		(layer "B.Cu")
		(net "PWRGD_P1V8_STBY")
	)
	(segment
		(start 252.387862 -10.12952)
		(end 252.6411 -10.12952)
		(width 0.12065)
		(layer "B.Cu")
		(net "PWRGD_P1V8_STBY")
	)
	(segment
		(start 143.369538 -44.6024)
		(end 145.114264 -42.857674)
		(width 0.12065)
		(layer "B.Cu")
		(net "PWRGD_P1V8_STBY")
	)
	(segment
		(start 229.206552 -1.11125)
		(end 229.206552 -3.489198)
		(width 0.12065)
		(layer "B.Cu")
		(net "PWRGD_P1V8_STBY")
	)
	(segment
		(start 135.376412 -94.239842)
		(end 135.376412 -93.977206)
		(width 0.12065)
		(layer "B.Cu")
		(net "PWRGD_P1V8_STBY")
	)
	(segment
		(start 264.033 -14.402054)
		(end 264.033 -15.316708)
		(width 0.12065)
		(layer "B.Cu")
		(net "PWRGD_P1V8_STBY")
	)
	(segment
		(start 186.623452 -12.039346)
		(end 186.623452 -6.086602)
		(width 0.12065)
		(layer "B.Cu")
		(net "PWRGD_P1V8_STBY")
	)
	(segment
		(start 135.376412 -94.239842)
		(end 135.763254 -93.853)
		(width 0.127)
		(layer "In2.Cu")
		(net "PWRGD_P1V8_STBY")
	)
	(segment
		(start 135.763254 -93.853)
		(end 142.5702 -93.853)
		(width 0.127)
		(layer "In2.Cu")
		(net "PWRGD_P1V8_STBY")
	)
	(segment
		(start 253.01702 -11.378438)
		(end 257.027934 -11.378438)
		(width 0.127)
		(layer "In5.Cu")
		(net "PWRGD_P1V8_STBY")
	)
	(segment
		(start 69.8627 -160.9725)
		(end 69.8627 -164.4015)
		(width 0.127)
		(layer "In5.Cu")
		(net "PWRGD_P1V8_STBY")
	)
	(segment
		(start 142.5702 -93.853)
		(end 141.86789 -94.55531)
		(width 0.127)
		(layer "In5.Cu")
		(net "PWRGD_P1V8_STBY")
	)
	(segment
		(start 257.027934 -11.378438)
		(end 261.154418 -15.504922)
		(width 0.127)
		(layer "In5.Cu")
		(net "PWRGD_P1V8_STBY")
	)
	(segment
		(start 141.86789 -94.55531)
		(end 136.27989 -94.55531)
		(width 0.127)
		(layer "In5.Cu")
		(net "PWRGD_P1V8_STBY")
	)
	(segment
		(start 68.6054 -165.6588)
		(end 65.1764 -165.6588)
		(width 0.127)
		(layer "In5.Cu")
		(net "PWRGD_P1V8_STBY")
	)
	(segment
		(start 252.6411 -10.12952)
		(end 252.6411 -11.002518)
		(width 0.127)
		(layer "In5.Cu")
		(net "PWRGD_P1V8_STBY")
	)
	(segment
		(start 136.27989 -94.55531)
		(end 69.8627 -160.9725)
		(width 0.127)
		(layer "In5.Cu")
		(net "PWRGD_P1V8_STBY")
	)
	(segment
		(start 261.154418 -15.504922)
		(end 264.221214 -15.504922)
		(width 0.127)
		(layer "In5.Cu")
		(net "PWRGD_P1V8_STBY")
	)
	(segment
		(start 252.6411 -11.002518)
		(end 253.01702 -11.378438)
		(width 0.127)
		(layer "In5.Cu")
		(net "PWRGD_P1V8_STBY")
	)
	(segment
		(start 69.8627 -164.4015)
		(end 68.6054 -165.6588)
		(width 0.127)
		(layer "In5.Cu")
		(net "PWRGD_P1V8_STBY")
	)
	(segment
		(start 4.334002 -118.359682)
		(end 4.334002 -106.521758)
		(width 0.12065)
		(layer "F.Cu")
		(net "PWRGD_P1V538_STBY")
	)
	(segment
		(start 6.979412 -103.876348)
		(end 8.500872 -103.876348)
		(width 0.12065)
		(layer "F.Cu")
		(net "PWRGD_P1V538_STBY")
	)
	(segment
		(start 9.525 -104.900476)
		(end 9.525 -105.156)
		(width 0.12065)
		(layer "F.Cu")
		(net "PWRGD_P1V538_STBY")
	)
	(segment
		(start 69.5833 -162.433)
		(end 68.961 -162.433)
		(width 0.12065)
		(layer "F.Cu")
		(net "PWRGD_P1V538_STBY")
	)
	(segment
		(start 6.02488 -120.05056)
		(end 4.334002 -118.359682)
		(width 0.12065)
		(layer "F.Cu")
		(net "PWRGD_P1V538_STBY")
	)
	(segment
		(start 69.7357 -161.2646)
		(end 69.4817 -161.5186)
		(width 0.12065)
		(layer "F.Cu")
		(net "PWRGD_P1V538_STBY")
	)
	(segment
		(start 69.4817 -161.5186)
		(end 67.4116 -161.5186)
		(width 0.12065)
		(layer "F.Cu")
		(net "PWRGD_P1V538_STBY")
	)
	(segment
		(start 4.334002 -106.521758)
		(end 6.979412 -103.876348)
		(width 0.12065)
		(layer "F.Cu")
		(net "PWRGD_P1V538_STBY")
	)
	(segment
		(start 69.7357 -162.2806)
		(end 69.5833 -162.433)
		(width 0.12065)
		(layer "F.Cu")
		(net "PWRGD_P1V538_STBY")
	)
	(segment
		(start 69.7357 -162.2806)
		(end 69.7357 -161.2646)
		(width 0.12065)
		(layer "F.Cu")
		(net "PWRGD_P1V538_STBY")
	)
	(segment
		(start 8.500872 -103.876348)
		(end 9.525 -104.900476)
		(width 0.12065)
		(layer "F.Cu")
		(net "PWRGD_P1V538_STBY")
	)
	(via
		(at 6.02488 -120.05056)
		(size 0.508)
		(drill 0.254)
		(layers "F.Cu" "B.Cu")
		(net "PWRGD_P1V538_STBY")
	)
	(via
		(at 61.346334 -166.121334)
		(size 0.7112)
		(drill 0.3556)
		(layers "F.Cu" "B.Cu")
		(net "PWRGD_P1V538_STBY")
	)
	(via
		(at 6.096 -167.386)
		(size 0.508)
		(drill 0.254)
		(layers "F.Cu" "B.Cu")
		(net "PWRGD_P1V538_STBY")
	)
	(via
		(at 68.961 -162.433)
		(size 0.508)
		(drill 0.254)
		(layers "F.Cu" "B.Cu")
		(net "PWRGD_P1V538_STBY")
	)
	(segment
		(start 61.346334 -166.121334)
		(end 61.5315 -166.3065)
		(width 0.12065)
		(layer "B.Cu")
		(net "PWRGD_P1V538_STBY")
	)
	(segment
		(start 6.35 -167.64)
		(end 6.096 -167.386)
		(width 0.12065)
		(layer "B.Cu")
		(net "PWRGD_P1V538_STBY")
	)
	(segment
		(start 61.5315 -166.3065)
		(end 65.30594 -166.3065)
		(width 0.12065)
		(layer "B.Cu")
		(net "PWRGD_P1V538_STBY")
	)
	(segment
		(start 60.750196 -165.525196)
		(end 45.929804 -165.525196)
		(width 0.12065)
		(layer "B.Cu")
		(net "PWRGD_P1V538_STBY")
	)
	(segment
		(start 65.30594 -166.3065)
		(end 68.961 -162.65144)
		(width 0.12065)
		(layer "B.Cu")
		(net "PWRGD_P1V538_STBY")
	)
	(segment
		(start 34.29 -167.64)
		(end 6.35 -167.64)
		(width 0.12065)
		(layer "B.Cu")
		(net "PWRGD_P1V538_STBY")
	)
	(segment
		(start 45.929804 -165.525196)
		(end 44.831 -166.624)
		(width 0.12065)
		(layer "B.Cu")
		(net "PWRGD_P1V538_STBY")
	)
	(segment
		(start 44.831 -166.624)
		(end 35.306 -166.624)
		(width 0.12065)
		(layer "B.Cu")
		(net "PWRGD_P1V538_STBY")
	)
	(segment
		(start 68.961 -162.65144)
		(end 68.961 -162.433)
		(width 0.12065)
		(layer "B.Cu")
		(net "PWRGD_P1V538_STBY")
	)
	(segment
		(start 61.346334 -166.121334)
		(end 60.750196 -165.525196)
		(width 0.12065)
		(layer "B.Cu")
		(net "PWRGD_P1V538_STBY")
	)
	(segment
		(start 35.306 -166.624)
		(end 34.29 -167.64)
		(width 0.12065)
		(layer "B.Cu")
		(net "PWRGD_P1V538_STBY")
	)
	(segment
		(start 5.715 -167.005)
		(end 6.096 -167.386)
		(width 0.127)
		(layer "In5.Cu")
		(net "PWRGD_P1V538_STBY")
	)
	(segment
		(start 5.715 -120.36044)
		(end 5.715 -167.005)
		(width 0.127)
		(layer "In5.Cu")
		(net "PWRGD_P1V538_STBY")
	)
	(segment
		(start 6.02488 -120.05056)
		(end 5.715 -120.36044)
		(width 0.127)
		(layer "In5.Cu")
		(net "PWRGD_P1V538_STBY")
	)
	(segment
		(start 160.366202 -58.002932)
		(end 160.366202 -57.329832)
		(width 0.12065)
		(layer "F.Cu")
		(net "PWRGD_P1V26_STBY")
	)
	(segment
		(start 8.3185 -108.966)
		(end 8.547354 -108.966)
		(width 0.12065)
		(layer "F.Cu")
		(net "PWRGD_P1V26_STBY")
	)
	(segment
		(start 160.366202 -57.329832)
		(end 160.642046 -57.053988)
		(width 0.12065)
		(layer "F.Cu")
		(net "PWRGD_P1V26_STBY")
	)
	(segment
		(start 161.856166 -53.20792)
		(end 163.791646 -53.20792)
		(width 0.12065)
		(layer "F.Cu")
		(net "PWRGD_P1V26_STBY")
	)
	(segment
		(start 9.309354 -108.204)
		(end 10.6426 -108.204)
		(width 0.12065)
		(layer "F.Cu")
		(net "PWRGD_P1V26_STBY")
	)
	(segment
		(start 162.720782 -56.336946)
		(end 161.359088 -56.336946)
		(width 0.12065)
		(layer "F.Cu")
		(net "PWRGD_P1V26_STBY")
	)
	(segment
		(start 21.5646 -147.8915)
		(end 21.5646 -146.963892)
		(width 0.12065)
		(layer "F.Cu")
		(net "PWRGD_P1V26_STBY")
	)
	(segment
		(start 21.5646 -146.963892)
		(end 21.393404 -146.792696)
		(width 0.12065)
		(layer "F.Cu")
		(net "PWRGD_P1V26_STBY")
	)
	(segment
		(start 163.791646 -53.20792)
		(end 163.8808 -53.297074)
		(width 0.12065)
		(layer "F.Cu")
		(net "PWRGD_P1V26_STBY")
	)
	(segment
		(start 161.359088 -56.336946)
		(end 160.642046 -57.053988)
		(width 0.12065)
		(layer "F.Cu")
		(net "PWRGD_P1V26_STBY")
	)
	(segment
		(start 9.070086 -108.443268)
		(end 9.309354 -108.204)
		(width 0.12065)
		(layer "F.Cu")
		(net "PWRGD_P1V26_STBY")
	)
	(segment
		(start 8.547354 -108.966)
		(end 9.070086 -108.443268)
		(width 0.12065)
		(layer "F.Cu")
		(net "PWRGD_P1V26_STBY")
	)
	(segment
		(start 163.8808 -55.176928)
		(end 162.720782 -56.336946)
		(width 0.12065)
		(layer "F.Cu")
		(net "PWRGD_P1V26_STBY")
	)
	(segment
		(start 161.412428 -52.764182)
		(end 161.856166 -53.20792)
		(width 0.12065)
		(layer "F.Cu")
		(net "PWRGD_P1V26_STBY")
	)
	(segment
		(start 163.8808 -53.297074)
		(end 163.8808 -55.176928)
		(width 0.12065)
		(layer "F.Cu")
		(net "PWRGD_P1V26_STBY")
	)
	(via
		(at 9.070086 -108.443268)
		(size 0.508)
		(drill 0.254)
		(layers "F.Cu" "B.Cu")
		(net "PWRGD_P1V26_STBY")
	)
	(via
		(at 161.412428 -52.764182)
		(size 0.508)
		(drill 0.254)
		(layers "F.Cu" "B.Cu")
		(net "PWRGD_P1V26_STBY")
	)
	(via
		(at 21.393404 -146.792696)
		(size 0.508)
		(drill 0.254)
		(layers "F.Cu" "B.Cu")
		(net "PWRGD_P1V26_STBY")
	)
	(via
		(at 160.642046 -57.053988)
		(size 0.7112)
		(drill 0.3556)
		(layers "F.Cu" "B.Cu")
		(net "PWRGD_P1V26_STBY")
	)
	(via
		(at 68.066666 -86.995)
		(size 0.508)
		(drill 0.254)
		(layers "F.Cu" "B.Cu")
		(net "PWRGD_P1V26_STBY")
	)
	(segment
		(start 9.309354 -108.204)
		(end 10.4775 -108.204)
		(width 0.12065)
		(layer "B.Cu")
		(net "PWRGD_P1V26_STBY")
	)
	(segment
		(start 9.070086 -108.443268)
		(end 9.309354 -108.204)
		(width 0.12065)
		(layer "B.Cu")
		(net "PWRGD_P1V26_STBY")
	)
	(segment
		(start 12.700508 -138.811254)
		(end 13.180822 -138.811254)
		(width 0.127)
		(layer "In2.Cu")
		(net "PWRGD_P1V26_STBY")
	)
	(segment
		(start 24.207978 -91.896946)
		(end 23.727918 -91.896946)
		(width 0.127)
		(layer "In2.Cu")
		(net "PWRGD_P1V26_STBY")
	)
	(segment
		(start 66.1924 -86.995)
		(end 65.027048 -88.160352)
		(width 0.127)
		(layer "In2.Cu")
		(net "PWRGD_P1V26_STBY")
	)
	(segment
		(start 10.596118 -103.828596)
		(end 10.596118 -104.42575)
		(width 0.127)
		(layer "In2.Cu")
		(net "PWRGD_P1V26_STBY")
	)
	(segment
		(start 18.754344 -140.771626)
		(end 19.407378 -141.42466)
		(width 0.127)
		(layer "In2.Cu")
		(net "PWRGD_P1V26_STBY")
	)
	(segment
		(start 68.066666 -86.995)
		(end 66.1924 -86.995)
		(width 0.127)
		(layer "In2.Cu")
		(net "PWRGD_P1V26_STBY")
	)
	(segment
		(start 5.712206 -121.38406)
		(end 5.712206 -131.822952)
		(width 0.127)
		(layer "In2.Cu")
		(net "PWRGD_P1V26_STBY")
	)
	(segment
		(start 44.680378 -87.143336)
		(end 44.674282 -87.149432)
		(width 0.127)
		(layer "In2.Cu")
		(net "PWRGD_P1V26_STBY")
	)
	(segment
		(start 6.49478 -111.31042)
		(end 6.49478 -120.601486)
		(width 0.127)
		(layer "In2.Cu")
		(net "PWRGD_P1V26_STBY")
	)
	(segment
		(start 6.49478 -120.601486)
		(end 5.712206 -121.38406)
		(width 0.127)
		(layer "In2.Cu")
		(net "PWRGD_P1V26_STBY")
	)
	(segment
		(start 9.070086 -108.735114)
		(end 6.49478 -111.31042)
		(width 0.127)
		(layer "In2.Cu")
		(net "PWRGD_P1V26_STBY")
	)
	(segment
		(start 29.758132 -88.12022)
		(end 29.757878 -88.119966)
		(width 0.127)
		(layer "In2.Cu")
		(net "PWRGD_P1V26_STBY")
	)
	(segment
		(start 20.651216 -144.428972)
		(end 21.355304 -145.13306)
		(width 0.127)
		(layer "In2.Cu")
		(net "PWRGD_P1V26_STBY")
	)
	(segment
		(start 20.314666 -95.255334)
		(end 18.23593 -95.255334)
		(width 0.127)
		(layer "In2.Cu")
		(net "PWRGD_P1V26_STBY")
	)
	(segment
		(start 16.691356 -97.733358)
		(end 10.596118 -103.828596)
		(width 0.127)
		(layer "In2.Cu")
		(net "PWRGD_P1V26_STBY")
	)
	(segment
		(start 15.141194 -140.771626)
		(end 18.754344 -140.771626)
		(width 0.127)
		(layer "In2.Cu")
		(net "PWRGD_P1V26_STBY")
	)
	(segment
		(start 19.762978 -141.42466)
		(end 20.651216 -142.312898)
		(width 0.127)
		(layer "In2.Cu")
		(net "PWRGD_P1V26_STBY")
	)
	(segment
		(start 26.671524 -89.4334)
		(end 24.207978 -91.896946)
		(width 0.127)
		(layer "In2.Cu")
		(net "PWRGD_P1V26_STBY")
	)
	(segment
		(start 65.027048 -88.160352)
		(end 54.124352 -88.160352)
		(width 0.127)
		(layer "In2.Cu")
		(net "PWRGD_P1V26_STBY")
	)
	(segment
		(start 23.727918 -91.896946)
		(end 23.727664 -91.8972)
		(width 0.127)
		(layer "In2.Cu")
		(net "PWRGD_P1V26_STBY")
	)
	(segment
		(start 53.107336 -87.143336)
		(end 44.680378 -87.143336)
		(width 0.127)
		(layer "In2.Cu")
		(net "PWRGD_P1V26_STBY")
	)
	(segment
		(start 19.407378 -141.42466)
		(end 19.762978 -141.42466)
		(width 0.127)
		(layer "In2.Cu")
		(net "PWRGD_P1V26_STBY")
	)
	(segment
		(start 10.596118 -104.42575)
		(end 9.070086 -105.951782)
		(width 0.127)
		(layer "In2.Cu")
		(net "PWRGD_P1V26_STBY")
	)
	(segment
		(start 27.813 -89.4334)
		(end 26.671524 -89.4334)
		(width 0.127)
		(layer "In2.Cu")
		(net "PWRGD_P1V26_STBY")
	)
	(segment
		(start 18.23593 -95.255334)
		(end 16.691356 -96.799908)
		(width 0.127)
		(layer "In2.Cu")
		(net "PWRGD_P1V26_STBY")
	)
	(segment
		(start 44.674282 -87.149432)
		(end 44.625768 -87.149432)
		(width 0.127)
		(layer "In2.Cu")
		(net "PWRGD_P1V26_STBY")
	)
	(segment
		(start 29.757878 -88.119966)
		(end 29.126434 -88.119966)
		(width 0.127)
		(layer "In2.Cu")
		(net "PWRGD_P1V26_STBY")
	)
	(segment
		(start 13.180822 -138.811254)
		(end 15.141194 -140.771626)
		(width 0.127)
		(layer "In2.Cu")
		(net "PWRGD_P1V26_STBY")
	)
	(segment
		(start 23.6728 -91.8972)
		(end 20.314666 -95.255334)
		(width 0.127)
		(layer "In2.Cu")
		(net "PWRGD_P1V26_STBY")
	)
	(segment
		(start 9.070086 -105.951782)
		(end 9.070086 -108.443268)
		(width 0.127)
		(layer "In2.Cu")
		(net "PWRGD_P1V26_STBY")
	)
	(segment
		(start 44.625768 -87.149432)
		(end 43.65498 -88.12022)
		(width 0.127)
		(layer "In2.Cu")
		(net "PWRGD_P1V26_STBY")
	)
	(segment
		(start 54.124352 -88.160352)
		(end 53.107336 -87.143336)
		(width 0.127)
		(layer "In2.Cu")
		(net "PWRGD_P1V26_STBY")
	)
	(segment
		(start 20.651216 -142.312898)
		(end 20.651216 -144.428972)
		(width 0.127)
		(layer "In2.Cu")
		(net "PWRGD_P1V26_STBY")
	)
	(segment
		(start 43.65498 -88.12022)
		(end 29.758132 -88.12022)
		(width 0.127)
		(layer "In2.Cu")
		(net "PWRGD_P1V26_STBY")
	)
	(segment
		(start 16.691356 -96.799908)
		(end 16.691356 -97.733358)
		(width 0.127)
		(layer "In2.Cu")
		(net "PWRGD_P1V26_STBY")
	)
	(segment
		(start 29.126434 -88.119966)
		(end 27.813 -89.4334)
		(width 0.127)
		(layer "In2.Cu")
		(net "PWRGD_P1V26_STBY")
	)
	(segment
		(start 5.712206 -131.822952)
		(end 12.700508 -138.811254)
		(width 0.127)
		(layer "In2.Cu")
		(net "PWRGD_P1V26_STBY")
	)
	(segment
		(start 23.727664 -91.8972)
		(end 23.6728 -91.8972)
		(width 0.127)
		(layer "In2.Cu")
		(net "PWRGD_P1V26_STBY")
	)
	(segment
		(start 21.355304 -145.13306)
		(end 21.355304 -146.792696)
		(width 0.127)
		(layer "In2.Cu")
		(net "PWRGD_P1V26_STBY")
	)
	(segment
		(start 21.355304 -146.792696)
		(end 21.393404 -146.792696)
		(width 0.127)
		(layer "In2.Cu")
		(net "PWRGD_P1V26_STBY")
	)
	(segment
		(start 9.070086 -108.443268)
		(end 9.070086 -108.735114)
		(width 0.127)
		(layer "In2.Cu")
		(net "PWRGD_P1V26_STBY")
	)
	(segment
		(start 145.912586 -50.607468)
		(end 143.545814 -52.97424)
		(width 0.127)
		(layer "In5.Cu")
		(net "PWRGD_P1V26_STBY")
	)
	(segment
		(start 67.92468 -79.61884)
		(end 67.92468 -82.840322)
		(width 0.127)
		(layer "In5.Cu")
		(net "PWRGD_P1V26_STBY")
	)
	(segment
		(start 68.3641 -86.697566)
		(end 68.066666 -86.995)
		(width 0.127)
		(layer "In5.Cu")
		(net "PWRGD_P1V26_STBY")
	)
	(segment
		(start 96.8248 -68.961)
		(end 76.6064 -68.961)
		(width 0.127)
		(layer "In5.Cu")
		(net "PWRGD_P1V26_STBY")
	)
	(segment
		(start 161.212276 -52.764182)
		(end 159.055562 -50.607468)
		(width 0.127)
		(layer "In5.Cu")
		(net "PWRGD_P1V26_STBY")
	)
	(segment
		(start 143.545814 -52.97424)
		(end 125.537722 -52.97424)
		(width 0.127)
		(layer "In5.Cu")
		(net "PWRGD_P1V26_STBY")
	)
	(segment
		(start 159.055562 -50.607468)
		(end 145.912586 -50.607468)
		(width 0.127)
		(layer "In5.Cu")
		(net "PWRGD_P1V26_STBY")
	)
	(segment
		(start 69.011546 -78.531974)
		(end 67.92468 -79.61884)
		(width 0.127)
		(layer "In5.Cu")
		(net "PWRGD_P1V26_STBY")
	)
	(segment
		(start 68.3641 -83.279742)
		(end 68.3641 -86.697566)
		(width 0.127)
		(layer "In5.Cu")
		(net "PWRGD_P1V26_STBY")
	)
	(segment
		(start 111.5695 -54.2163)
		(end 96.8248 -68.961)
		(width 0.127)
		(layer "In5.Cu")
		(net "PWRGD_P1V26_STBY")
	)
	(segment
		(start 76.6064 -68.961)
		(end 69.8246 -75.7428)
		(width 0.127)
		(layer "In5.Cu")
		(net "PWRGD_P1V26_STBY")
	)
	(segment
		(start 125.537722 -52.97424)
		(end 124.295662 -54.2163)
		(width 0.127)
		(layer "In5.Cu")
		(net "PWRGD_P1V26_STBY")
	)
	(segment
		(start 69.011546 -77.741526)
		(end 69.011546 -78.531974)
		(width 0.127)
		(layer "In5.Cu")
		(net "PWRGD_P1V26_STBY")
	)
	(segment
		(start 161.412428 -52.764182)
		(end 161.212276 -52.764182)
		(width 0.127)
		(layer "In5.Cu")
		(net "PWRGD_P1V26_STBY")
	)
	(segment
		(start 67.92468 -82.840322)
		(end 68.3641 -83.279742)
		(width 0.127)
		(layer "In5.Cu")
		(net "PWRGD_P1V26_STBY")
	)
	(segment
		(start 69.8246 -75.7428)
		(end 69.8246 -76.928472)
		(width 0.127)
		(layer "In5.Cu")
		(net "PWRGD_P1V26_STBY")
	)
	(segment
		(start 124.295662 -54.2163)
		(end 111.5695 -54.2163)
		(width 0.127)
		(layer "In5.Cu")
		(net "PWRGD_P1V26_STBY")
	)
	(segment
		(start 69.8246 -76.928472)
		(end 69.011546 -77.741526)
		(width 0.127)
		(layer "In5.Cu")
		(net "PWRGD_P1V26_STBY")
	)
	(segment
		(start 74.676 -219.8878)
		(end 74.676 -210.82)
		(width 0.12065)
		(layer "F.Cu")
		(net "PWM_EXP_A")
	)
	(segment
		(start 84.648802 -200.847198)
		(end 75.080368 -210.415632)
		(width 0.12065)
		(layer "F.Cu")
		(net "PWM_EXP_A")
	)
	(segment
		(start 82.1944 -182.3212)
		(end 83.566 -183.6928)
		(width 0.12065)
		(layer "F.Cu")
		(net "PWM_EXP_A")
	)
	(segment
		(start 83.566 -183.6928)
		(end 83.566 -184.526936)
		(width 0.12065)
		(layer "F.Cu")
		(net "PWM_EXP_A")
	)
	(segment
		(start 73.300082 -224.559622)
		(end 72.43318 -223.69272)
		(width 0.12065)
		(layer "F.Cu")
		(net "PWM_EXP_A")
	)
	(segment
		(start 72.43318 -223.69272)
		(end 72.43318 -222.13062)
		(width 0.12065)
		(layer "F.Cu")
		(net "PWM_EXP_A")
	)
	(segment
		(start 72.43318 -222.13062)
		(end 74.676 -219.8878)
		(width 0.12065)
		(layer "F.Cu")
		(net "PWM_EXP_A")
	)
	(segment
		(start 73.300082 -225.54438)
		(end 73.300082 -224.559622)
		(width 0.12065)
		(layer "F.Cu")
		(net "PWM_EXP_A")
	)
	(segment
		(start 74.676 -210.82)
		(end 75.080368 -210.415632)
		(width 0.12065)
		(layer "F.Cu")
		(net "PWM_EXP_A")
	)
	(segment
		(start 84.648802 -185.609738)
		(end 84.648802 -200.847198)
		(width 0.12065)
		(layer "F.Cu")
		(net "PWM_EXP_A")
	)
	(segment
		(start 83.566 -184.526936)
		(end 84.648802 -185.609738)
		(width 0.12065)
		(layer "F.Cu")
		(net "PWM_EXP_A")
	)
	(via
		(at 46.784006 -143.384016)
		(size 0.508)
		(drill 0.254)
		(layers "F.Cu" "B.Cu")
		(net "PWM_EXP_A")
	)
	(via
		(at 82.1944 -182.3212)
		(size 0.508)
		(drill 0.254)
		(layers "F.Cu" "B.Cu")
		(net "PWM_EXP_A")
	)
	(via
		(at 75.080368 -210.415632)
		(size 0.7112)
		(drill 0.3556)
		(layers "F.Cu" "B.Cu")
		(net "PWM_EXP_A")
	)
	(via
		(at 41.1734 -172.1612)
		(size 0.508)
		(drill 0.254)
		(layers "F.Cu" "B.Cu")
		(net "PWM_EXP_A")
	)
	(segment
		(start 46.863 -139.3825)
		(end 46.863 -143.305022)
		(width 0.12065)
		(layer "B.Cu")
		(net "PWM_EXP_A")
	)
	(segment
		(start 46.863 -143.305022)
		(end 46.784006 -143.384016)
		(width 0.12065)
		(layer "B.Cu")
		(net "PWM_EXP_A")
	)
	(segment
		(start 79.558388 -170.2308)
		(end 56.141112 -170.2308)
		(width 0.127)
		(layer "In2.Cu")
		(net "PWM_EXP_A")
	)
	(segment
		(start 56.141112 -170.2308)
		(end 53.385212 -172.9867)
		(width 0.127)
		(layer "In2.Cu")
		(net "PWM_EXP_A")
	)
	(segment
		(start 41.9989 -172.9867)
		(end 41.1734 -172.1612)
		(width 0.127)
		(layer "In2.Cu")
		(net "PWM_EXP_A")
	)
	(segment
		(start 81.661 -172.333412)
		(end 79.558388 -170.2308)
		(width 0.127)
		(layer "In2.Cu")
		(net "PWM_EXP_A")
	)
	(segment
		(start 53.385212 -172.9867)
		(end 41.9989 -172.9867)
		(width 0.127)
		(layer "In2.Cu")
		(net "PWM_EXP_A")
	)
	(segment
		(start 81.661 -175.7934)
		(end 81.661 -172.333412)
		(width 0.127)
		(layer "In2.Cu")
		(net "PWM_EXP_A")
	)
	(segment
		(start 82.1944 -176.3268)
		(end 81.661 -175.7934)
		(width 0.127)
		(layer "In2.Cu")
		(net "PWM_EXP_A")
	)
	(segment
		(start 82.1944 -182.3212)
		(end 82.1944 -176.3268)
		(width 0.127)
		(layer "In2.Cu")
		(net "PWM_EXP_A")
	)
	(segment
		(start 46.6471 -144.000982)
		(end 46.784006 -143.864076)
		(width 0.127)
		(layer "In5.Cu")
		(net "PWM_EXP_A")
	)
	(segment
		(start 46.784006 -143.864076)
		(end 46.784006 -143.384016)
		(width 0.127)
		(layer "In5.Cu")
		(net "PWM_EXP_A")
	)
	(segment
		(start 41.1734 -172.1612)
		(end 46.6471 -166.6875)
		(width 0.127)
		(layer "In5.Cu")
		(net "PWM_EXP_A")
	)
	(segment
		(start 46.6471 -166.6875)
		(end 46.6471 -144.000982)
		(width 0.127)
		(layer "In5.Cu")
		(net "PWM_EXP_A")
	)
	(segment
		(start 31.304738 -123.684792)
		(end 30.914086 -124.075444)
		(width 0.12065)
		(layer "F.Cu")
		(net "PWGD_P0V9_E_PG_R")
	)
	(segment
		(start 24.663146 -121.219214)
		(end 25.631394 -121.219214)
		(width 0.12065)
		(layer "F.Cu")
		(net "PWGD_P0V9_E_PG_R")
	)
	(segment
		(start 26.202132 -121.285)
		(end 26.989532 -122.0724)
		(width 0.12065)
		(layer "F.Cu")
		(net "PWGD_P0V9_E_PG_R")
	)
	(segment
		(start 28.992576 -124.075444)
		(end 26.989532 -122.0724)
		(width 0.12065)
		(layer "F.Cu")
		(net "PWGD_P0V9_E_PG_R")
	)
	(segment
		(start 25.69718 -121.285)
		(end 26.202132 -121.285)
		(width 0.12065)
		(layer "F.Cu")
		(net "PWGD_P0V9_E_PG_R")
	)
	(segment
		(start 25.631394 -121.219214)
		(end 25.69718 -121.285)
		(width 0.12065)
		(layer "F.Cu")
		(net "PWGD_P0V9_E_PG_R")
	)
	(segment
		(start 30.914086 -124.075444)
		(end 28.992576 -124.075444)
		(width 0.12065)
		(layer "F.Cu")
		(net "PWGD_P0V9_E_PG_R")
	)
	(via
		(at 26.989532 -122.0724)
		(size 0.7112)
		(drill 0.3556)
		(layers "F.Cu" "B.Cu")
		(net "PWGD_P0V9_E_PG_R")
	)
	(segment
		(start 69.2912 -74.4601)
		(end 69.2912 -73.7362)
		(width 0.12065)
		(layer "F.Cu")
		(net "PU_IBMC_BT_HOLD_N")
	)
	(segment
		(start 69.3166 -74.4855)
		(end 69.2912 -74.4601)
		(width 0.12065)
		(layer "F.Cu")
		(net "PU_IBMC_BT_HOLD_N")
	)
	(segment
		(start 69.2912 -73.7362)
		(end 68.892674 -73.337674)
		(width 0.12065)
		(layer "F.Cu")
		(net "PU_IBMC_BT_HOLD_N")
	)
	(segment
		(start 68.892674 -73.337674)
		(end 68.892674 -72.023986)
		(width 0.12065)
		(layer "F.Cu")
		(net "PU_IBMC_BT_HOLD_N")
	)
	(segment
		(start 131.866386 -51.326288)
		(end 131.866386 -53.725826)
		(width 0.12065)
		(layer "F.Cu")
		(net "PMC_R_TXD5")
	)
	(segment
		(start 131.866386 -53.725826)
		(end 132.522468 -54.381908)
		(width 0.12065)
		(layer "F.Cu")
		(net "PMC_R_TXD5")
	)
	(segment
		(start 132.522468 -54.381908)
		(end 132.522468 -54.760876)
		(width 0.12065)
		(layer "F.Cu")
		(net "PMC_R_TXD5")
	)
	(segment
		(start 131.04749 -53.0733)
		(end 129.910586 -51.936396)
		(width 0.12065)
		(layer "F.Cu")
		(net "PMC_R_RXD5")
	)
	(segment
		(start 129.910586 -51.936396)
		(end 129.910586 -51.351688)
		(width 0.12065)
		(layer "F.Cu")
		(net "PMC_R_RXD5")
	)
	(segment
		(start 129.982468 -54.760876)
		(end 130.125724 -54.760876)
		(width 0.12065)
		(layer "F.Cu")
		(net "PMC_R_RXD5")
	)
	(segment
		(start 131.04749 -53.83911)
		(end 131.04749 -53.0733)
		(width 0.12065)
		(layer "F.Cu")
		(net "PMC_R_RXD5")
	)
	(segment
		(start 130.125724 -54.760876)
		(end 131.04749 -53.83911)
		(width 0.12065)
		(layer "F.Cu")
		(net "PMC_R_RXD5")
	)
	(segment
		(start 346.914216 -47.040038)
		(end 346.212414 -46.338236)
		(width 0.12065)
		(layer "F.Cu")
		(net "PM8536_RST#_AND")
	)
	(segment
		(start 346.212414 -46.338236)
		(end 345.188794 -46.338236)
		(width 0.12065)
		(layer "F.Cu")
		(net "PM8536_RST#_AND")
	)
	(via
		(at 346.914216 -48.192182)
		(size 0.7112)
		(drill 0.3556)
		(layers "F.Cu" "B.Cu")
		(net "PM8536_RST#_AND")
	)
	(via
		(at 346.914216 -47.040038)
		(size 0.508)
		(drill 0.254)
		(layers "F.Cu" "B.Cu")
		(net "PM8536_RST#_AND")
	)
	(segment
		(start 346.914216 -47.040038)
		(end 346.946982 -47.072804)
		(width 0.12065)
		(layer "B.Cu")
		(net "PM8536_RST#_AND")
	)
	(segment
		(start 346.914216 -47.040038)
		(end 346.914216 -48.192182)
		(width 0.12065)
		(layer "B.Cu")
		(net "PM8536_RST#_AND")
	)
	(segment
		(start 348.389956 -46.573694)
		(end 348.389956 -46.29023)
		(width 0.12065)
		(layer "B.Cu")
		(net "PM8536_RST#_AND")
	)
	(segment
		(start 347.890846 -47.072804)
		(end 348.389956 -46.573694)
		(width 0.12065)
		(layer "B.Cu")
		(net "PM8536_RST#_AND")
	)
	(segment
		(start 346.946982 -47.072804)
		(end 347.890846 -47.072804)
		(width 0.12065)
		(layer "B.Cu")
		(net "PM8536_RST#_AND")
	)
	(segment
		(start 265.293856 -5.75056)
		(end 256.630678 -5.75056)
		(width 0.12065)
		(layer "F.Cu")
		(net "PM8536_RST#")
	)
	(segment
		(start 251.309886 -8.546592)
		(end 251.309886 -12.313666)
		(width 0.12065)
		(layer "F.Cu")
		(net "PM8536_RST#")
	)
	(segment
		(start 265.685016 -5.3594)
		(end 265.293856 -5.75056)
		(width 0.12065)
		(layer "F.Cu")
		(net "PM8536_RST#")
	)
	(segment
		(start 253.125732 -6.730746)
		(end 251.309886 -8.546592)
		(width 0.12065)
		(layer "F.Cu")
		(net "PM8536_RST#")
	)
	(segment
		(start 251.309886 -12.313666)
		(end 251.619512 -12.623292)
		(width 0.12065)
		(layer "F.Cu")
		(net "PM8536_RST#")
	)
	(segment
		(start 266.7381 -5.3594)
		(end 265.685016 -5.3594)
		(width 0.12065)
		(layer "F.Cu")
		(net "PM8536_RST#")
	)
	(segment
		(start 256.630678 -5.75056)
		(end 255.650492 -6.730746)
		(width 0.12065)
		(layer "F.Cu")
		(net "PM8536_RST#")
	)
	(segment
		(start 267.0175 -5.6388)
		(end 266.7381 -5.3594)
		(width 0.12065)
		(layer "F.Cu")
		(net "PM8536_RST#")
	)
	(segment
		(start 255.650492 -6.730746)
		(end 253.125732 -6.730746)
		(width 0.12065)
		(layer "F.Cu")
		(net "PM8536_RST#")
	)
	(segment
		(start 232.599992 -34.99993)
		(end 232.10012 -34.500058)
		(width 0.12065)
		(layer "F.Cu")
		(net "PM8536_RST#")
	)
	(via
		(at 222.26778 -26.58618)
		(size 0.7112)
		(drill 0.3556)
		(layers "F.Cu" "B.Cu")
		(net "PM8536_RST#")
	)
	(via
		(at 251.619512 -12.623292)
		(size 0.508)
		(drill 0.254)
		(layers "F.Cu" "B.Cu")
		(net "PM8536_RST#")
	)
	(via
		(at 232.10012 -34.500058)
		(size 0.4572)
		(drill 0.2032)
		(layers "F.Cu" "B.Cu")
		(net "PM8536_RST#")
	)
	(segment
		(start 251.483114 -12.75969)
		(end 251.483114 -13.485622)
		(width 0.12065)
		(layer "B.Cu")
		(net "PM8536_RST#")
	)
	(segment
		(start 216.5096 -22.2377)
		(end 216.4842 -22.2631)
		(width 0.12065)
		(layer "B.Cu")
		(net "PM8536_RST#")
	)
	(segment
		(start 233.352086 -17.58315)
		(end 219.915486 -17.58315)
		(width 0.12065)
		(layer "B.Cu")
		(net "PM8536_RST#")
	)
	(segment
		(start 216.4842 -22.2631)
		(end 215.4174 -22.2631)
		(width 0.12065)
		(layer "B.Cu")
		(net "PM8536_RST#")
	)
	(segment
		(start 250.077986 -14.89075)
		(end 243.773452 -14.89075)
		(width 0.12065)
		(layer "B.Cu")
		(net "PM8536_RST#")
	)
	(segment
		(start 251.619512 -12.623292)
		(end 251.483114 -12.75969)
		(width 0.12065)
		(layer "B.Cu")
		(net "PM8536_RST#")
	)
	(segment
		(start 243.773452 -14.89075)
		(end 243.336318 -15.327884)
		(width 0.12065)
		(layer "B.Cu")
		(net "PM8536_RST#")
	)
	(segment
		(start 238.884714 -18.29435)
		(end 234.063286 -18.29435)
		(width 0.12065)
		(layer "B.Cu")
		(net "PM8536_RST#")
	)
	(segment
		(start 231.493822 -30.120082)
		(end 231.493822 -33.89376)
		(width 0.1016)
		(layer "B.Cu")
		(net "PM8536_RST#")
	)
	(segment
		(start 214.5157 -22.2631)
		(end 215.4174 -22.2631)
		(width 0.12065)
		(layer "B.Cu")
		(net "PM8536_RST#")
	)
	(segment
		(start 220.85808 -26.58618)
		(end 222.26778 -26.58618)
		(width 0.12065)
		(layer "B.Cu")
		(net "PM8536_RST#")
	)
	(segment
		(start 231.03332 -29.65958)
		(end 231.493822 -30.120082)
		(width 0.1016)
		(layer "B.Cu")
		(net "PM8536_RST#")
	)
	(segment
		(start 234.063286 -18.29435)
		(end 233.352086 -17.58315)
		(width 0.12065)
		(layer "B.Cu")
		(net "PM8536_RST#")
	)
	(segment
		(start 213.106 -18.39087)
		(end 213.106 -20.8534)
		(width 0.12065)
		(layer "B.Cu")
		(net "PM8536_RST#")
	)
	(segment
		(start 219.915486 -17.58315)
		(end 219.02039 -16.688054)
		(width 0.12065)
		(layer "B.Cu")
		(net "PM8536_RST#")
	)
	(segment
		(start 213.106 -20.8534)
		(end 214.5157 -22.2631)
		(width 0.12065)
		(layer "B.Cu")
		(net "PM8536_RST#")
	)
	(segment
		(start 243.336318 -15.327884)
		(end 243.336318 -15.696946)
		(width 0.12065)
		(layer "B.Cu")
		(net "PM8536_RST#")
	)
	(segment
		(start 219.02039 -16.688054)
		(end 214.808816 -16.688054)
		(width 0.12065)
		(layer "B.Cu")
		(net "PM8536_RST#")
	)
	(segment
		(start 242.485164 -16.5481)
		(end 240.630964 -16.5481)
		(width 0.12065)
		(layer "B.Cu")
		(net "PM8536_RST#")
	)
	(segment
		(start 214.808816 -16.688054)
		(end 213.106 -18.39087)
		(width 0.12065)
		(layer "B.Cu")
		(net "PM8536_RST#")
	)
	(segment
		(start 228.797866 -26.58618)
		(end 229.91572 -27.704034)
		(width 0.12065)
		(layer "B.Cu")
		(net "PM8536_RST#")
	)
	(segment
		(start 216.5096 -22.2377)
		(end 220.85808 -26.58618)
		(width 0.12065)
		(layer "B.Cu")
		(net "PM8536_RST#")
	)
	(segment
		(start 231.493822 -33.89376)
		(end 232.10012 -34.500058)
		(width 0.1016)
		(layer "B.Cu")
		(net "PM8536_RST#")
	)
	(segment
		(start 240.630964 -16.5481)
		(end 238.884714 -18.29435)
		(width 0.12065)
		(layer "B.Cu")
		(net "PM8536_RST#")
	)
	(segment
		(start 231.03332 -28.821634)
		(end 231.03332 -29.65958)
		(width 0.1016)
		(layer "B.Cu")
		(net "PM8536_RST#")
	)
	(segment
		(start 251.483114 -13.485622)
		(end 250.077986 -14.89075)
		(width 0.12065)
		(layer "B.Cu")
		(net "PM8536_RST#")
	)
	(segment
		(start 222.26778 -26.58618)
		(end 228.797866 -26.58618)
		(width 0.12065)
		(layer "B.Cu")
		(net "PM8536_RST#")
	)
	(segment
		(start 229.91572 -27.704034)
		(end 231.03332 -28.821634)
		(width 0.1016)
		(layer "B.Cu")
		(net "PM8536_RST#")
	)
	(segment
		(start 243.336318 -15.696946)
		(end 242.485164 -16.5481)
		(width 0.12065)
		(layer "B.Cu")
		(net "PM8536_RST#")
	)
	(via
		(at 351.323656 -42.911522)
		(size 0.7112)
		(drill 0.3556)
		(layers "F.Cu" "B.Cu")
		(net "PM8536_PG2_R")
	)
	(segment
		(start 350.085406 -42.98569)
		(end 349.040196 -44.0309)
		(width 0.12065)
		(layer "B.Cu")
		(net "PM8536_PG2_R")
	)
	(segment
		(start 349.040196 -44.0309)
		(end 349.040196 -44.63923)
		(width 0.12065)
		(layer "B.Cu")
		(net "PM8536_PG2_R")
	)
	(segment
		(start 350.085406 -42.98569)
		(end 350.159574 -42.911522)
		(width 0.12065)
		(layer "B.Cu")
		(net "PM8536_PG2_R")
	)
	(segment
		(start 350.159574 -42.911522)
		(end 351.323656 -42.911522)
		(width 0.12065)
		(layer "B.Cu")
		(net "PM8536_PG2_R")
	)
	(segment
		(start 243.5733 -17.5133)
		(end 243.6622 -17.4244)
		(width 0.12065)
		(layer "F.Cu")
		(net "PM8536_HB")
	)
	(segment
		(start 244.599968 -36.999926)
		(end 245.09984 -36.500054)
		(width 0.12065)
		(layer "F.Cu")
		(net "PM8536_HB")
	)
	(segment
		(start 243.6622 -16.533622)
		(end 243.6622 -17.4244)
		(width 0.12065)
		(layer "F.Cu")
		(net "PM8536_HB")
	)
	(segment
		(start 243.543074 -16.414496)
		(end 243.6622 -16.533622)
		(width 0.12065)
		(layer "F.Cu")
		(net "PM8536_HB")
	)
	(segment
		(start 242.6716 -17.5133)
		(end 243.5733 -17.5133)
		(width 0.12065)
		(layer "F.Cu")
		(net "PM8536_HB")
	)
	(via
		(at 243.901976 -16.481552)
		(size 0.7112)
		(drill 0.3556)
		(layers "F.Cu" "B.Cu")
		(net "PM8536_HB")
	)
	(via
		(at 243.6622 -17.4244)
		(size 0.508)
		(drill 0.254)
		(layers "F.Cu" "B.Cu")
		(net "PM8536_HB")
	)
	(via
		(at 245.09984 -36.500054)
		(size 0.4572)
		(drill 0.2032)
		(layers "F.Cu" "B.Cu")
		(net "PM8536_HB")
	)
	(segment
		(start 243.2304 -16.3576)
		(end 243.778024 -16.3576)
		(width 0.12065)
		(layer "B.Cu")
		(net "PM8536_HB")
	)
	(segment
		(start 243.901976 -17.184624)
		(end 243.901976 -16.481552)
		(width 0.12065)
		(layer "B.Cu")
		(net "PM8536_HB")
	)
	(segment
		(start 243.6622 -17.4244)
		(end 243.901976 -17.184624)
		(width 0.12065)
		(layer "B.Cu")
		(net "PM8536_HB")
	)
	(segment
		(start 242.8875 -17.2466)
		(end 242.8875 -16.7005)
		(width 0.12065)
		(layer "B.Cu")
		(net "PM8536_HB")
	)
	(segment
		(start 243.778024 -16.3576)
		(end 243.901976 -16.481552)
		(width 0.12065)
		(layer "B.Cu")
		(net "PM8536_HB")
	)
	(segment
		(start 242.8875 -16.7005)
		(end 243.2304 -16.3576)
		(width 0.12065)
		(layer "B.Cu")
		(net "PM8536_HB")
	)
	(segment
		(start 243.6622 -17.4244)
		(end 243.1923 -17.8943)
		(width 0.127)
		(layer "In5.Cu")
		(net "PM8536_HB")
	)
	(segment
		(start 245.669054 -35.889946)
		(end 245.09984 -36.45916)
		(width 0.127)
		(layer "In5.Cu")
		(net "PM8536_HB")
	)
	(segment
		(start 243.5479 -18.8722)
		(end 244.328188 -18.8722)
		(width 0.127)
		(layer "In5.Cu")
		(net "PM8536_HB")
	)
	(segment
		(start 243.1923 -17.8943)
		(end 243.1923 -18.5166)
		(width 0.127)
		(layer "In5.Cu")
		(net "PM8536_HB")
	)
	(segment
		(start 245.705884 -20.249896)
		(end 245.705884 -24.285448)
		(width 0.127)
		(layer "In5.Cu")
		(net "PM8536_HB")
	)
	(segment
		(start 244.328188 -18.8722)
		(end 245.705884 -20.249896)
		(width 0.127)
		(layer "In5.Cu")
		(net "PM8536_HB")
	)
	(segment
		(start 245.09984 -36.45916)
		(end 245.09984 -36.500054)
		(width 0.127)
		(layer "In5.Cu")
		(net "PM8536_HB")
	)
	(segment
		(start 243.1923 -18.5166)
		(end 243.5479 -18.8722)
		(width 0.127)
		(layer "In5.Cu")
		(net "PM8536_HB")
	)
	(segment
		(start 245.705884 -24.285448)
		(end 245.669054 -24.322278)
		(width 0.127)
		(layer "In5.Cu")
		(net "PM8536_HB")
	)
	(segment
		(start 245.669054 -24.322278)
		(end 245.669054 -35.889946)
		(width 0.127)
		(layer "In5.Cu")
		(net "PM8536_HB")
	)
	(segment
		(start 324.485 -101.0285)
		(end 324.485 -100.0125)
		(width 0.12065)
		(layer "F.Cu")
		(net "PEWAKE#")
	)
	(segment
		(start 323.469 -101.727)
		(end 324.1675 -101.0285)
		(width 0.12065)
		(layer "F.Cu")
		(net "PEWAKE#")
	)
	(segment
		(start 29.704792 -128.484884)
		(end 29.304742 -128.084834)
		(width 0.12065)
		(layer "F.Cu")
		(net "PEWAKE#")
	)
	(segment
		(start 324.1675 -101.0285)
		(end 324.485 -101.0285)
		(width 0.12065)
		(layer "F.Cu")
		(net "PEWAKE#")
	)
	(via
		(at 142.725648 -99.253548)
		(size 0.508)
		(drill 0.254)
		(layers "F.Cu" "B.Cu")
		(net "PEWAKE#")
	)
	(via
		(at 323.469 -103.251)
		(size 0.7112)
		(drill 0.3556)
		(layers "F.Cu" "B.Cu")
		(net "PEWAKE#")
	)
	(via
		(at 29.304742 -128.084834)
		(size 0.4572)
		(drill 0.2032)
		(layers "F.Cu" "B.Cu")
		(net "PEWAKE#")
	)
	(via
		(at 323.469 -101.727)
		(size 0.508)
		(drill 0.254)
		(layers "F.Cu" "B.Cu")
		(net "PEWAKE#")
	)
	(segment
		(start 319.55359 -108.03255)
		(end 323.469 -104.11714)
		(width 0.12065)
		(layer "B.Cu")
		(net "PEWAKE#")
	)
	(segment
		(start 323.469 -103.251)
		(end 323.469 -101.727)
		(width 0.12065)
		(layer "B.Cu")
		(net "PEWAKE#")
	)
	(segment
		(start 153.350214 -108.03255)
		(end 319.55359 -108.03255)
		(width 0.12065)
		(layer "B.Cu")
		(net "PEWAKE#")
	)
	(segment
		(start 323.469 -104.11714)
		(end 323.469 -103.251)
		(width 0.12065)
		(layer "B.Cu")
		(net "PEWAKE#")
	)
	(segment
		(start 142.725648 -99.253548)
		(end 142.818104 -99.161092)
		(width 0.12065)
		(layer "B.Cu")
		(net "PEWAKE#")
	)
	(segment
		(start 144.478756 -99.161092)
		(end 153.350214 -108.03255)
		(width 0.12065)
		(layer "B.Cu")
		(net "PEWAKE#")
	)
	(segment
		(start 142.818104 -99.161092)
		(end 144.478756 -99.161092)
		(width 0.12065)
		(layer "B.Cu")
		(net "PEWAKE#")
	)
	(segment
		(start 27.534362 -101.126544)
		(end 27.534108 -101.12629)
		(width 0.127)
		(layer "In2.Cu")
		(net "PEWAKE#")
	)
	(segment
		(start 31.191962 -98.291904)
		(end 28.357322 -101.126544)
		(width 0.127)
		(layer "In2.Cu")
		(net "PEWAKE#")
	)
	(segment
		(start 31.191962 -97.4344)
		(end 31.191962 -98.291904)
		(width 0.127)
		(layer "In2.Cu")
		(net "PEWAKE#")
	)
	(segment
		(start 28.276804 -129.112772)
		(end 29.304742 -128.084834)
		(width 0.127)
		(layer "In2.Cu")
		(net "PEWAKE#")
	)
	(segment
		(start 16.728694 -127.6858)
		(end 16.901414 -127.6858)
		(width 0.127)
		(layer "In2.Cu")
		(net "PEWAKE#")
	)
	(segment
		(start 28.357322 -101.126544)
		(end 27.534362 -101.126544)
		(width 0.127)
		(layer "In2.Cu")
		(net "PEWAKE#")
	)
	(segment
		(start 54.957726 -97.493328)
		(end 53.641244 -96.176846)
		(width 0.127)
		(layer "In2.Cu")
		(net "PEWAKE#")
	)
	(segment
		(start 18.061432 -120.292368)
		(end 18.061432 -122.248168)
		(width 0.127)
		(layer "In2.Cu")
		(net "PEWAKE#")
	)
	(segment
		(start 27.008328 -101.12629)
		(end 26.998676 -101.135942)
		(width 0.127)
		(layer "In2.Cu")
		(net "PEWAKE#")
	)
	(segment
		(start 25.625806 -102.390194)
		(end 24.681942 -102.390194)
		(width 0.127)
		(layer "In2.Cu")
		(net "PEWAKE#")
	)
	(segment
		(start 16.383 -124.574046)
		(end 15.709646 -125.2474)
		(width 0.127)
		(layer "In2.Cu")
		(net "PEWAKE#")
	)
	(segment
		(start 14.9987 -125.56617)
		(end 14.9987 -125.955806)
		(width 0.127)
		(layer "In2.Cu")
		(net "PEWAKE#")
	)
	(segment
		(start 142.725648 -99.253548)
		(end 133.59384 -99.253548)
		(width 0.127)
		(layer "In2.Cu")
		(net "PEWAKE#")
	)
	(segment
		(start 36.059872 -96.888808)
		(end 31.737554 -96.888808)
		(width 0.127)
		(layer "In2.Cu")
		(net "PEWAKE#")
	)
	(segment
		(start 75.116436 -97.493328)
		(end 54.957726 -97.493328)
		(width 0.127)
		(layer "In2.Cu")
		(net "PEWAKE#")
	)
	(segment
		(start 15.709646 -125.2474)
		(end 15.31747 -125.2474)
		(width 0.127)
		(layer "In2.Cu")
		(net "PEWAKE#")
	)
	(segment
		(start 22.710394 -104.361742)
		(end 22.710394 -104.872282)
		(width 0.127)
		(layer "In2.Cu")
		(net "PEWAKE#")
	)
	(segment
		(start 110.916212 -99.1616)
		(end 76.784708 -99.1616)
		(width 0.127)
		(layer "In2.Cu")
		(net "PEWAKE#")
	)
	(segment
		(start 24.314912 -102.75697)
		(end 22.710394 -104.361742)
		(width 0.127)
		(layer "In2.Cu")
		(net "PEWAKE#")
	)
	(segment
		(start 24.315166 -102.756462)
		(end 24.314912 -102.75697)
		(width 0.127)
		(layer "In2.Cu")
		(net "PEWAKE#")
	)
	(segment
		(start 26.998676 -101.135942)
		(end 26.880058 -101.135942)
		(width 0.127)
		(layer "In2.Cu")
		(net "PEWAKE#")
	)
	(segment
		(start 22.710394 -104.872282)
		(end 22.586442 -104.996234)
		(width 0.127)
		(layer "In2.Cu")
		(net "PEWAKE#")
	)
	(segment
		(start 18.99285 -108.591096)
		(end 18.99285 -112.938306)
		(width 0.127)
		(layer "In2.Cu")
		(net "PEWAKE#")
	)
	(segment
		(start 116.326412 -104.5718)
		(end 110.916212 -99.1616)
		(width 0.127)
		(layer "In2.Cu")
		(net "PEWAKE#")
	)
	(segment
		(start 16.901414 -127.6858)
		(end 18.328386 -129.112772)
		(width 0.127)
		(layer "In2.Cu")
		(net "PEWAKE#")
	)
	(segment
		(start 18.542 -119.8118)
		(end 18.061432 -120.292368)
		(width 0.127)
		(layer "In2.Cu")
		(net "PEWAKE#")
	)
	(segment
		(start 24.681942 -102.390194)
		(end 24.315166 -102.756462)
		(width 0.127)
		(layer "In2.Cu")
		(net "PEWAKE#")
	)
	(segment
		(start 76.784708 -99.1616)
		(end 75.116436 -97.493328)
		(width 0.127)
		(layer "In2.Cu")
		(net "PEWAKE#")
	)
	(segment
		(start 22.586442 -104.996234)
		(end 22.586442 -104.997504)
		(width 0.127)
		(layer "In2.Cu")
		(net "PEWAKE#")
	)
	(segment
		(start 18.328386 -129.112772)
		(end 28.276804 -129.112772)
		(width 0.127)
		(layer "In2.Cu")
		(net "PEWAKE#")
	)
	(segment
		(start 14.9987 -125.955806)
		(end 16.728694 -127.6858)
		(width 0.127)
		(layer "In2.Cu")
		(net "PEWAKE#")
	)
	(segment
		(start 26.880058 -101.135942)
		(end 25.625806 -102.390194)
		(width 0.127)
		(layer "In2.Cu")
		(net "PEWAKE#")
	)
	(segment
		(start 22.586442 -104.997504)
		(end 18.99285 -108.591096)
		(width 0.127)
		(layer "In2.Cu")
		(net "PEWAKE#")
	)
	(segment
		(start 128.275588 -104.5718)
		(end 116.326412 -104.5718)
		(width 0.127)
		(layer "In2.Cu")
		(net "PEWAKE#")
	)
	(segment
		(start 16.383 -123.9266)
		(end 16.383 -124.574046)
		(width 0.127)
		(layer "In2.Cu")
		(net "PEWAKE#")
	)
	(segment
		(start 18.99285 -112.938306)
		(end 18.542 -113.389156)
		(width 0.127)
		(layer "In2.Cu")
		(net "PEWAKE#")
	)
	(segment
		(start 27.534108 -101.12629)
		(end 27.008328 -101.12629)
		(width 0.127)
		(layer "In2.Cu")
		(net "PEWAKE#")
	)
	(segment
		(start 53.641244 -96.176846)
		(end 36.771834 -96.176846)
		(width 0.127)
		(layer "In2.Cu")
		(net "PEWAKE#")
	)
	(segment
		(start 133.59384 -99.253548)
		(end 128.275588 -104.5718)
		(width 0.127)
		(layer "In2.Cu")
		(net "PEWAKE#")
	)
	(segment
		(start 18.542 -113.389156)
		(end 18.542 -119.8118)
		(width 0.127)
		(layer "In2.Cu")
		(net "PEWAKE#")
	)
	(segment
		(start 36.771834 -96.176846)
		(end 36.059872 -96.888808)
		(width 0.127)
		(layer "In2.Cu")
		(net "PEWAKE#")
	)
	(segment
		(start 31.737554 -96.888808)
		(end 31.191962 -97.4344)
		(width 0.127)
		(layer "In2.Cu")
		(net "PEWAKE#")
	)
	(segment
		(start 15.31747 -125.2474)
		(end 14.9987 -125.56617)
		(width 0.127)
		(layer "In2.Cu")
		(net "PEWAKE#")
	)
	(segment
		(start 18.061432 -122.248168)
		(end 16.383 -123.9266)
		(width 0.127)
		(layer "In2.Cu")
		(net "PEWAKE#")
	)
	(via
		(at 55.609998 -200.930002)
		(size 0.7112)
		(drill 0.3556)
		(layers "F.Cu" "B.Cu")
		(net "PEER_TRAY_R")
	)
	(via
		(at 45.085 -115.3922)
		(size 0.508)
		(drill 0.254)
		(layers "F.Cu" "B.Cu")
		(net "PEER_TRAY_R")
	)
	(via
		(at 41.783 -176.149)
		(size 0.508)
		(drill 0.254)
		(layers "F.Cu" "B.Cu")
		(net "PEER_TRAY_R")
	)
	(segment
		(start 50.341784 -175.222408)
		(end 49.42459 -176.139602)
		(width 0.12065)
		(layer "B.Cu")
		(net "PEER_TRAY_R")
	)
	(segment
		(start 47.117 -117.1575)
		(end 46.327822 -116.368322)
		(width 0.12065)
		(layer "B.Cu")
		(net "PEER_TRAY_R")
	)
	(segment
		(start 55.93715 -200.60285)
		(end 55.93715 -177.73015)
		(width 0.12065)
		(layer "B.Cu")
		(net "PEER_TRAY_R")
	)
	(segment
		(start 55.609998 -200.930002)
		(end 55.93715 -200.60285)
		(width 0.12065)
		(layer "B.Cu")
		(net "PEER_TRAY_R")
	)
	(segment
		(start 53.429408 -175.222408)
		(end 50.341784 -175.222408)
		(width 0.12065)
		(layer "B.Cu")
		(net "PEER_TRAY_R")
	)
	(segment
		(start 38.9001 -225.92538)
		(end 38.9001 -212.611716)
		(width 0.12065)
		(layer "B.Cu")
		(net "PEER_TRAY_R")
	)
	(segment
		(start 38.9001 -212.611716)
		(end 47.549816 -203.962)
		(width 0.12065)
		(layer "B.Cu")
		(net "PEER_TRAY_R")
	)
	(segment
		(start 46.327822 -116.368322)
		(end 45.184822 -116.368322)
		(width 0.12065)
		(layer "B.Cu")
		(net "PEER_TRAY_R")
	)
	(segment
		(start 49.42459 -176.139602)
		(end 41.792398 -176.139602)
		(width 0.12065)
		(layer "B.Cu")
		(net "PEER_TRAY_R")
	)
	(segment
		(start 41.792398 -176.139602)
		(end 41.783 -176.149)
		(width 0.12065)
		(layer "B.Cu")
		(net "PEER_TRAY_R")
	)
	(segment
		(start 47.549816 -203.962)
		(end 52.578 -203.962)
		(width 0.12065)
		(layer "B.Cu")
		(net "PEER_TRAY_R")
	)
	(segment
		(start 52.578 -203.962)
		(end 55.609998 -200.930002)
		(width 0.12065)
		(layer "B.Cu")
		(net "PEER_TRAY_R")
	)
	(segment
		(start 55.93715 -177.73015)
		(end 53.429408 -175.222408)
		(width 0.12065)
		(layer "B.Cu")
		(net "PEER_TRAY_R")
	)
	(segment
		(start 45.085 -115.3922)
		(end 45.085 -116.2685)
		(width 0.12065)
		(layer "B.Cu")
		(net "PEER_TRAY_R")
	)
	(segment
		(start 45.184822 -116.368322)
		(end 45.085 -116.2685)
		(width 0.12065)
		(layer "B.Cu")
		(net "PEER_TRAY_R")
	)
	(segment
		(start 49.403254 -142.795244)
		(end 49.403254 -145.088102)
		(width 0.127)
		(layer "In5.Cu")
		(net "PEER_TRAY_R")
	)
	(segment
		(start 45.085 -117.337332)
		(end 48.884078 -121.13641)
		(width 0.127)
		(layer "In5.Cu")
		(net "PEER_TRAY_R")
	)
	(segment
		(start 49.6443 -145.329148)
		(end 49.6443 -168.1607)
		(width 0.127)
		(layer "In5.Cu")
		(net "PEER_TRAY_R")
	)
	(segment
		(start 41.783 -176.022)
		(end 41.783 -176.149)
		(width 0.127)
		(layer "In5.Cu")
		(net "PEER_TRAY_R")
	)
	(segment
		(start 45.085 -115.3922)
		(end 45.085 -117.337332)
		(width 0.127)
		(layer "In5.Cu")
		(net "PEER_TRAY_R")
	)
	(segment
		(start 49.6443 -168.1607)
		(end 41.783 -176.022)
		(width 0.127)
		(layer "In5.Cu")
		(net "PEER_TRAY_R")
	)
	(segment
		(start 48.884078 -142.276068)
		(end 49.403254 -142.795244)
		(width 0.127)
		(layer "In5.Cu")
		(net "PEER_TRAY_R")
	)
	(segment
		(start 48.884078 -121.13641)
		(end 48.884078 -142.276068)
		(width 0.127)
		(layer "In5.Cu")
		(net "PEER_TRAY_R")
	)
	(segment
		(start 49.403254 -145.088102)
		(end 49.6443 -145.329148)
		(width 0.127)
		(layer "In5.Cu")
		(net "PEER_TRAY_R")
	)
	(segment
		(start 42.504868 -124.484892)
		(end 42.105072 -124.085096)
		(width 0.12065)
		(layer "F.Cu")
		(net "PEER_TRAY_BMC")
	)
	(via
		(at 42.105072 -124.085096)
		(size 0.4572)
		(drill 0.2032)
		(layers "F.Cu" "B.Cu")
		(net "PEER_TRAY_BMC")
	)
	(via
		(at 46.057312 -117.018054)
		(size 0.7112)
		(drill 0.3556)
		(layers "F.Cu" "B.Cu")
		(net "PEER_TRAY_BMC")
	)
	(segment
		(start 42.1894 -121.395236)
		(end 44.339002 -119.245634)
		(width 0.12065)
		(layer "B.Cu")
		(net "PEER_TRAY_BMC")
	)
	(segment
		(start 44.339002 -119.245634)
		(end 44.339002 -117.903498)
		(width 0.12065)
		(layer "B.Cu")
		(net "PEER_TRAY_BMC")
	)
	(segment
		(start 45.19549 -117.04701)
		(end 45.085 -117.1575)
		(width 0.12065)
		(layer "B.Cu")
		(net "PEER_TRAY_BMC")
	)
	(segment
		(start 42.105072 -124.085096)
		(end 42.1894 -124.000768)
		(width 0.12065)
		(layer "B.Cu")
		(net "PEER_TRAY_BMC")
	)
	(segment
		(start 46.028356 -117.04701)
		(end 45.19549 -117.04701)
		(width 0.12065)
		(layer "B.Cu")
		(net "PEER_TRAY_BMC")
	)
	(segment
		(start 44.339002 -117.903498)
		(end 45.085 -117.1575)
		(width 0.12065)
		(layer "B.Cu")
		(net "PEER_TRAY_BMC")
	)
	(segment
		(start 42.1894 -124.000768)
		(end 42.1894 -121.395236)
		(width 0.12065)
		(layer "B.Cu")
		(net "PEER_TRAY_BMC")
	)
	(segment
		(start 46.057312 -117.018054)
		(end 46.028356 -117.04701)
		(width 0.12065)
		(layer "B.Cu")
		(net "PEER_TRAY_BMC")
	)
	(segment
		(start 21.78558 -141.458696)
		(end 21.78558 -141.47292)
		(width 0.12065)
		(layer "F.Cu")
		(net "PECI0_R")
	)
	(segment
		(start 21.78558 -141.47292)
		(end 21.3995 -141.859)
		(width 0.12065)
		(layer "F.Cu")
		(net "PECI0_R")
	)
	(segment
		(start 27.034744 -140.293344)
		(end 28.852622 -138.475466)
		(width 0.12065)
		(layer "F.Cu")
		(net "PECI0_R")
	)
	(segment
		(start 24.520398 -141.034262)
		(end 24.688038 -140.866622)
		(width 0.12065)
		(layer "F.Cu")
		(net "PECI0_R")
	)
	(segment
		(start 22.078696 -141.16558)
		(end 21.78558 -141.458696)
		(width 0.12065)
		(layer "F.Cu")
		(net "PECI0_R")
	)
	(segment
		(start 24.520398 -141.034262)
		(end 24.38908 -141.16558)
		(width 0.12065)
		(layer "F.Cu")
		(net "PECI0_R")
	)
	(segment
		(start 28.852622 -138.475466)
		(end 30.11424 -138.475466)
		(width 0.12065)
		(layer "F.Cu")
		(net "PECI0_R")
	)
	(segment
		(start 25.588468 -140.866622)
		(end 25.926542 -140.528548)
		(width 0.12065)
		(layer "F.Cu")
		(net "PECI0_R")
	)
	(segment
		(start 24.688038 -140.866622)
		(end 25.588468 -140.866622)
		(width 0.12065)
		(layer "F.Cu")
		(net "PECI0_R")
	)
	(segment
		(start 24.38908 -141.16558)
		(end 22.078696 -141.16558)
		(width 0.12065)
		(layer "F.Cu")
		(net "PECI0_R")
	)
	(segment
		(start 26.799794 -140.528548)
		(end 27.034744 -140.293344)
		(width 0.12065)
		(layer "F.Cu")
		(net "PECI0_R")
	)
	(segment
		(start 30.11424 -138.475466)
		(end 30.504892 -138.084814)
		(width 0.12065)
		(layer "F.Cu")
		(net "PECI0_R")
	)
	(segment
		(start 25.926542 -140.528548)
		(end 26.799794 -140.528548)
		(width 0.12065)
		(layer "F.Cu")
		(net "PECI0_R")
	)
	(via
		(at 24.520398 -141.034262)
		(size 0.7112)
		(drill 0.3556)
		(layers "F.Cu" "B.Cu")
		(net "PECI0_R")
	)
	(segment
		(start 349.874078 -45.119544)
		(end 348.152466 -45.119544)
		(width 0.12065)
		(layer "F.Cu")
		(net "PE1_PERST#_R")
	)
	(segment
		(start 351.287842 -44.947586)
		(end 351.363026 -45.02277)
		(width 0.12065)
		(layer "F.Cu")
		(net "PE1_PERST#_R")
	)
	(segment
		(start 351.363026 -45.012864)
		(end 351.908618 -45.558456)
		(width 0.12065)
		(layer "F.Cu")
		(net "PE1_PERST#_R")
	)
	(segment
		(start 350.046036 -44.947586)
		(end 349.874078 -45.119544)
		(width 0.12065)
		(layer "F.Cu")
		(net "PE1_PERST#_R")
	)
	(segment
		(start 351.363026 -45.012864)
		(end 351.36836 -45.012864)
		(width 0.12065)
		(layer "F.Cu")
		(net "PE1_PERST#_R")
	)
	(segment
		(start 351.363026 -45.02277)
		(end 351.363026 -45.012864)
		(width 0.12065)
		(layer "F.Cu")
		(net "PE1_PERST#_R")
	)
	(segment
		(start 348.152466 -45.119544)
		(end 347.527372 -45.744638)
		(width 0.12065)
		(layer "F.Cu")
		(net "PE1_PERST#_R")
	)
	(segment
		(start 350.046036 -44.947586)
		(end 351.287842 -44.947586)
		(width 0.12065)
		(layer "F.Cu")
		(net "PE1_PERST#_R")
	)
	(segment
		(start 347.527372 -45.744638)
		(end 347.527372 -46.063408)
		(width 0.12065)
		(layer "F.Cu")
		(net "PE1_PERST#_R")
	)
	(segment
		(start 351.908618 -45.558456)
		(end 351.908618 -45.857922)
		(width 0.12065)
		(layer "F.Cu")
		(net "PE1_PERST#_R")
	)
	(via
		(at 351.908618 -45.857922)
		(size 0.508)
		(drill 0.254)
		(layers "F.Cu" "B.Cu")
		(net "PE1_PERST#_R")
	)
	(via
		(at 351.36836 -45.012864)
		(size 0.7112)
		(drill 0.3556)
		(layers "F.Cu" "B.Cu")
		(net "PE1_PERST#_R")
	)
	(segment
		(start 351.908618 -45.857922)
		(end 350.689926 -44.63923)
		(width 0.12065)
		(layer "B.Cu")
		(net "PE1_PERST#_R")
	)
	(segment
		(start 350.689926 -44.63923)
		(end 349.690436 -44.63923)
		(width 0.12065)
		(layer "B.Cu")
		(net "PE1_PERST#_R")
	)
	(segment
		(start 30.504892 -128.482344)
		(end 30.099 -128.076452)
		(width 0.12065)
		(layer "F.Cu")
		(net "PE1_PERST#_BMC")
	)
	(segment
		(start 30.504892 -128.484884)
		(end 30.504892 -128.482344)
		(width 0.12065)
		(layer "F.Cu")
		(net "PE1_PERST#_BMC")
	)
	(via
		(at 16.980916 -128.987296)
		(size 0.7112)
		(drill 0.3556)
		(layers "F.Cu" "B.Cu")
		(net "PE1_PERST#_BMC")
	)
	(via
		(at 15.2781 -128.6383)
		(size 0.508)
		(drill 0.254)
		(layers "F.Cu" "B.Cu")
		(net "PE1_PERST#_BMC")
	)
	(via
		(at 30.099 -128.076452)
		(size 0.4572)
		(drill 0.2032)
		(layers "F.Cu" "B.Cu")
		(net "PE1_PERST#_BMC")
	)
	(segment
		(start 17.870932 -128.664208)
		(end 17.547844 -128.987296)
		(width 0.12065)
		(layer "B.Cu")
		(net "PE1_PERST#_BMC")
	)
	(segment
		(start 17.547844 -128.987296)
		(end 16.980916 -128.987296)
		(width 0.12065)
		(layer "B.Cu")
		(net "PE1_PERST#_BMC")
	)
	(segment
		(start 15.627096 -128.987296)
		(end 15.2781 -128.6383)
		(width 0.12065)
		(layer "B.Cu")
		(net "PE1_PERST#_BMC")
	)
	(segment
		(start 16.980916 -128.987296)
		(end 15.627096 -128.987296)
		(width 0.12065)
		(layer "B.Cu")
		(net "PE1_PERST#_BMC")
	)
	(segment
		(start 28.68168 -129.493772)
		(end 18.170398 -129.493772)
		(width 0.127)
		(layer "In2.Cu")
		(net "PE1_PERST#_BMC")
	)
	(segment
		(start 15.51432 -128.87452)
		(end 15.2781 -128.6383)
		(width 0.127)
		(layer "In2.Cu")
		(net "PE1_PERST#_BMC")
	)
	(segment
		(start 17.551146 -128.87452)
		(end 15.51432 -128.87452)
		(width 0.127)
		(layer "In2.Cu")
		(net "PE1_PERST#_BMC")
	)
	(segment
		(start 18.170398 -129.493772)
		(end 17.551146 -128.87452)
		(width 0.127)
		(layer "In2.Cu")
		(net "PE1_PERST#_BMC")
	)
	(segment
		(start 30.099 -128.076452)
		(end 28.68168 -129.493772)
		(width 0.127)
		(layer "In2.Cu")
		(net "PE1_PERST#_BMC")
	)
	(segment
		(start 18.010886 -127.56388)
		(end 17.022826 -127.56388)
		(width 0.12065)
		(layer "F.Cu")
		(net "PE1_PERST#")
	)
	(segment
		(start 349.78213 -42.729912)
		(end 350.265492 -42.729912)
		(width 0.12065)
		(layer "F.Cu")
		(net "PE1_PERST#")
	)
	(segment
		(start 350.841056 -42.729912)
		(end 352.347784 -44.23664)
		(width 0.12065)
		(layer "F.Cu")
		(net "PE1_PERST#")
	)
	(segment
		(start 18.01114 -127.563626)
		(end 18.010886 -127.56388)
		(width 0.12065)
		(layer "F.Cu")
		(net "PE1_PERST#")
	)
	(segment
		(start 350.265492 -42.729912)
		(end 350.841056 -42.729912)
		(width 0.12065)
		(layer "F.Cu")
		(net "PE1_PERST#")
	)
	(segment
		(start 348.511622 -44.00042)
		(end 349.78213 -42.729912)
		(width 0.12065)
		(layer "F.Cu")
		(net "PE1_PERST#")
	)
	(segment
		(start 348.511622 -44.158408)
		(end 348.511622 -44.00042)
		(width 0.12065)
		(layer "F.Cu")
		(net "PE1_PERST#")
	)
	(via
		(at 350.265492 -42.729912)
		(size 0.7112)
		(drill 0.3556)
		(layers "F.Cu" "B.Cu")
		(net "PE1_PERST#")
	)
	(via
		(at 134.3279 -100.2665)
		(size 0.508)
		(drill 0.254)
		(layers "F.Cu" "B.Cu")
		(net "PE1_PERST#")
	)
	(via
		(at 18.01114 -127.563626)
		(size 0.508)
		(drill 0.254)
		(layers "F.Cu" "B.Cu")
		(net "PE1_PERST#")
	)
	(via
		(at 352.347784 -44.23664)
		(size 0.508)
		(drill 0.254)
		(layers "F.Cu" "B.Cu")
		(net "PE1_PERST#")
	)
	(segment
		(start 352.533204 -47.77486)
		(end 352.53295 -95.174308)
		(width 0.12065)
		(layer "B.Cu")
		(net "PE1_PERST#")
	)
	(segment
		(start 142.715742 -106.299)
		(end 140.3604 -106.299)
		(width 0.12065)
		(layer "B.Cu")
		(net "PE1_PERST#")
	)
	(segment
		(start 149.456648 -113.039906)
		(end 142.715742 -106.299)
		(width 0.12065)
		(layer "B.Cu")
		(net "PE1_PERST#")
	)
	(segment
		(start 18.759932 -128.664208)
		(end 18.759932 -128.312418)
		(width 0.12065)
		(layer "B.Cu")
		(net "PE1_PERST#")
	)
	(segment
		(start 352.936302 -47.371762)
		(end 352.533204 -47.77486)
		(width 0.12065)
		(layer "B.Cu")
		(net "PE1_PERST#")
	)
	(segment
		(start 352.53295 -95.174308)
		(end 334.667352 -113.039906)
		(width 0.12065)
		(layer "B.Cu")
		(net "PE1_PERST#")
	)
	(segment
		(start 352.347784 -44.23664)
		(end 352.936302 -44.825158)
		(width 0.12065)
		(layer "B.Cu")
		(net "PE1_PERST#")
	)
	(segment
		(start 18.759932 -128.312418)
		(end 18.01114 -127.563626)
		(width 0.12065)
		(layer "B.Cu")
		(net "PE1_PERST#")
	)
	(segment
		(start 352.936302 -44.825158)
		(end 352.936302 -47.371762)
		(width 0.12065)
		(layer "B.Cu")
		(net "PE1_PERST#")
	)
	(segment
		(start 334.667352 -113.039906)
		(end 149.456648 -113.039906)
		(width 0.12065)
		(layer "B.Cu")
		(net "PE1_PERST#")
	)
	(segment
		(start 140.3604 -106.299)
		(end 134.3279 -100.2665)
		(width 0.12065)
		(layer "B.Cu")
		(net "PE1_PERST#")
	)
	(segment
		(start 106.999024 -99.5426)
		(end 76.62672 -99.5426)
		(width 0.127)
		(layer "In2.Cu")
		(net "PE1_PERST#")
	)
	(segment
		(start 128.433576 -104.9528)
		(end 112.409224 -104.9528)
		(width 0.127)
		(layer "In2.Cu")
		(net "PE1_PERST#")
	)
	(segment
		(start 38.890702 -96.558354)
		(end 38.890194 -96.557846)
		(width 0.127)
		(layer "In2.Cu")
		(net "PE1_PERST#")
	)
	(segment
		(start 39.522146 -96.558354)
		(end 38.890702 -96.558354)
		(width 0.127)
		(layer "In2.Cu")
		(net "PE1_PERST#")
	)
	(segment
		(start 76.62672 -99.5426)
		(end 74.958448 -97.874328)
		(width 0.127)
		(layer "In2.Cu")
		(net "PE1_PERST#")
	)
	(segment
		(start 134.3279 -100.2665)
		(end 133.119876 -100.2665)
		(width 0.127)
		(layer "In2.Cu")
		(net "PE1_PERST#")
	)
	(segment
		(start 24.62022 -104.791256)
		(end 21.312886 -108.09859)
		(width 0.127)
		(layer "In2.Cu")
		(net "PE1_PERST#")
	)
	(segment
		(start 112.409224 -104.9528)
		(end 106.999024 -99.5426)
		(width 0.127)
		(layer "In2.Cu")
		(net "PE1_PERST#")
	)
	(segment
		(start 17.318228 -127.563626)
		(end 18.01114 -127.563626)
		(width 0.127)
		(layer "In2.Cu")
		(net "PE1_PERST#")
	)
	(segment
		(start 25.20823 -103.660194)
		(end 24.62022 -104.248204)
		(width 0.127)
		(layer "In2.Cu")
		(net "PE1_PERST#")
	)
	(segment
		(start 20.26285 -113.464594)
		(end 19.812 -113.915444)
		(width 0.127)
		(layer "In2.Cu")
		(net "PE1_PERST#")
	)
	(segment
		(start 74.958448 -97.874328)
		(end 54.741064 -97.874328)
		(width 0.127)
		(layer "In2.Cu")
		(net "PE1_PERST#")
	)
	(segment
		(start 133.119876 -100.2665)
		(end 128.433576 -104.9528)
		(width 0.127)
		(layer "In2.Cu")
		(net "PE1_PERST#")
	)
	(segment
		(start 39.5224 -96.5581)
		(end 39.522146 -96.558354)
		(width 0.127)
		(layer "In2.Cu")
		(net "PE1_PERST#")
	)
	(segment
		(start 34.763202 -98.724466)
		(end 32.555688 -98.724466)
		(width 0.127)
		(layer "In2.Cu")
		(net "PE1_PERST#")
	)
	(segment
		(start 53.424582 -96.557846)
		(end 39.838122 -96.557846)
		(width 0.127)
		(layer "In2.Cu")
		(net "PE1_PERST#")
	)
	(segment
		(start 36.929822 -96.557846)
		(end 34.763202 -98.724466)
		(width 0.127)
		(layer "In2.Cu")
		(net "PE1_PERST#")
	)
	(segment
		(start 39.837868 -96.5581)
		(end 39.5224 -96.5581)
		(width 0.127)
		(layer "In2.Cu")
		(net "PE1_PERST#")
	)
	(segment
		(start 20.609306 -110.390432)
		(end 20.26285 -110.736888)
		(width 0.127)
		(layer "In2.Cu")
		(net "PE1_PERST#")
	)
	(segment
		(start 21.312886 -109.687106)
		(end 20.609306 -110.390432)
		(width 0.127)
		(layer "In2.Cu")
		(net "PE1_PERST#")
	)
	(segment
		(start 19.812 -121.116344)
		(end 16.7894 -124.138944)
		(width 0.127)
		(layer "In2.Cu")
		(net "PE1_PERST#")
	)
	(segment
		(start 54.741064 -97.874328)
		(end 53.424582 -96.557846)
		(width 0.127)
		(layer "In2.Cu")
		(net "PE1_PERST#")
	)
	(segment
		(start 21.312886 -108.09859)
		(end 21.312886 -109.687106)
		(width 0.127)
		(layer "In2.Cu")
		(net "PE1_PERST#")
	)
	(segment
		(start 20.26285 -110.736888)
		(end 20.26285 -113.464594)
		(width 0.127)
		(layer "In2.Cu")
		(net "PE1_PERST#")
	)
	(segment
		(start 32.555688 -98.724466)
		(end 28.874212 -102.405942)
		(width 0.127)
		(layer "In2.Cu")
		(net "PE1_PERST#")
	)
	(segment
		(start 38.890194 -96.557846)
		(end 36.929822 -96.557846)
		(width 0.127)
		(layer "In2.Cu")
		(net "PE1_PERST#")
	)
	(segment
		(start 19.812 -113.915444)
		(end 19.812 -121.116344)
		(width 0.127)
		(layer "In2.Cu")
		(net "PE1_PERST#")
	)
	(segment
		(start 16.7259 -126.971298)
		(end 17.318228 -127.563626)
		(width 0.127)
		(layer "In2.Cu")
		(net "PE1_PERST#")
	)
	(segment
		(start 39.838122 -96.557846)
		(end 39.837868 -96.5581)
		(width 0.127)
		(layer "In2.Cu")
		(net "PE1_PERST#")
	)
	(segment
		(start 16.7894 -124.138944)
		(end 16.7894 -124.853446)
		(width 0.127)
		(layer "In2.Cu")
		(net "PE1_PERST#")
	)
	(segment
		(start 26.152094 -103.660194)
		(end 25.20823 -103.660194)
		(width 0.127)
		(layer "In2.Cu")
		(net "PE1_PERST#")
	)
	(segment
		(start 24.62022 -104.248204)
		(end 24.62022 -104.791256)
		(width 0.127)
		(layer "In2.Cu")
		(net "PE1_PERST#")
	)
	(segment
		(start 16.7259 -124.916946)
		(end 16.7259 -126.971298)
		(width 0.127)
		(layer "In2.Cu")
		(net "PE1_PERST#")
	)
	(segment
		(start 27.406346 -102.405942)
		(end 26.152094 -103.660194)
		(width 0.127)
		(layer "In2.Cu")
		(net "PE1_PERST#")
	)
	(segment
		(start 16.7894 -124.853446)
		(end 16.7259 -124.916946)
		(width 0.127)
		(layer "In2.Cu")
		(net "PE1_PERST#")
	)
	(segment
		(start 28.874212 -102.405942)
		(end 27.406346 -102.405942)
		(width 0.127)
		(layer "In2.Cu")
		(net "PE1_PERST#")
	)
	(segment
		(start 33.402778 -150.943056)
		(end 33.402778 -150.09749)
		(width 0.12065)
		(layer "F.Cu")
		(net "PD_ZQ")
	)
	(segment
		(start 33.402778 -150.09749)
		(end 33.758378 -149.74189)
		(width 0.12065)
		(layer "F.Cu")
		(net "PD_ZQ")
	)
	(segment
		(start 34.739326 -147.43938)
		(end 35.247326 -146.93138)
		(width 0.12065)
		(layer "F.Cu")
		(net "PD_ZQ")
	)
	(segment
		(start 33.758378 -149.74189)
		(end 33.758378 -148.844)
		(width 0.12065)
		(layer "F.Cu")
		(net "PD_ZQ")
	)
	(segment
		(start 33.401 -147.711668)
		(end 33.676082 -147.436332)
		(width 0.12065)
		(layer "F.Cu")
		(net "PD_ZQ")
	)
	(segment
		(start 33.76803 -151.308308)
		(end 33.402778 -150.943056)
		(width 0.12065)
		(layer "F.Cu")
		(net "PD_ZQ")
	)
	(segment
		(start 33.76803 -151.579834)
		(end 33.76803 -151.308308)
		(width 0.12065)
		(layer "F.Cu")
		(net "PD_ZQ")
	)
	(segment
		(start 33.401 -148.486622)
		(end 33.401 -148.336)
		(width 0.12065)
		(layer "F.Cu")
		(net "PD_ZQ")
	)
	(segment
		(start 33.758378 -148.844)
		(end 33.401 -148.486622)
		(width 0.12065)
		(layer "F.Cu")
		(net "PD_ZQ")
	)
	(segment
		(start 34.736278 -147.436332)
		(end 34.739326 -147.43938)
		(width 0.12065)
		(layer "F.Cu")
		(net "PD_ZQ")
	)
	(segment
		(start 33.676082 -147.436332)
		(end 34.736278 -147.436332)
		(width 0.12065)
		(layer "F.Cu")
		(net "PD_ZQ")
	)
	(segment
		(start 33.401 -148.336)
		(end 33.401 -147.711668)
		(width 0.12065)
		(layer "F.Cu")
		(net "PD_ZQ")
	)
	(via
		(at 33.401 -148.336)
		(size 0.7112)
		(drill 0.3556)
		(layers "F.Cu" "B.Cu")
		(net "PD_ZQ")
	)
	(segment
		(start 31.304738 -138.084814)
		(end 30.904942 -138.48461)
		(width 0.12065)
		(layer "F.Cu")
		(net "PD_USB2VRES")
	)
	(via
		(at 30.904942 -138.48461)
		(size 0.4572)
		(drill 0.2032)
		(layers "F.Cu" "B.Cu")
		(net "PD_USB2VRES")
	)
	(via
		(at 29.575506 -138.944096)
		(size 0.7112)
		(drill 0.3556)
		(layers "F.Cu" "B.Cu")
		(net "PD_USB2VRES")
	)
	(segment
		(start 29.575506 -138.944096)
		(end 29.810202 -138.7094)
		(width 0.12065)
		(layer "B.Cu")
		(net "PD_USB2VRES")
	)
	(segment
		(start 26.434542 -141.501114)
		(end 28.877006 -139.05865)
		(width 0.12065)
		(layer "B.Cu")
		(net "PD_USB2VRES")
	)
	(segment
		(start 30.680152 -138.7094)
		(end 30.904942 -138.48461)
		(width 0.12065)
		(layer "B.Cu")
		(net "PD_USB2VRES")
	)
	(segment
		(start 28.877006 -139.05865)
		(end 29.460952 -139.05865)
		(width 0.12065)
		(layer "B.Cu")
		(net "PD_USB2VRES")
	)
	(segment
		(start 23.45944 -143.06804)
		(end 25.026366 -141.501114)
		(width 0.12065)
		(layer "B.Cu")
		(net "PD_USB2VRES")
	)
	(segment
		(start 25.026366 -141.501114)
		(end 26.434542 -141.501114)
		(width 0.12065)
		(layer "B.Cu")
		(net "PD_USB2VRES")
	)
	(segment
		(start 29.460952 -139.05865)
		(end 29.575506 -138.944096)
		(width 0.12065)
		(layer "B.Cu")
		(net "PD_USB2VRES")
	)
	(segment
		(start 29.810202 -138.7094)
		(end 30.680152 -138.7094)
		(width 0.12065)
		(layer "B.Cu")
		(net "PD_USB2VRES")
	)
	(segment
		(start 172.084238 -21.749258)
		(end 172.184314 -21.749258)
		(width 0.136652)
		(layer "F.Cu")
		(net "PCIE_TX_P95")
	)
	(segment
		(start 171.138342 -21.301456)
		(end 171.342812 -21.386292)
		(width 0.136652)
		(layer "F.Cu")
		(net "PCIE_TX_P95")
	)
	(segment
		(start 170.787314 -21.393404)
		(end 170.923966 -21.301456)
		(width 0.136652)
		(layer "F.Cu")
		(net "PCIE_TX_P95")
	)
	(segment
		(start 170.634406 -21.530056)
		(end 170.691048 -21.472906)
		(width 0.136652)
		(layer "F.Cu")
		(net "PCIE_TX_P95")
	)
	(segment
		(start 173.517306 -20.4089)
		(end 180.460396 -20.4089)
		(width 0.136652)
		(layer "F.Cu")
		(net "PCIE_TX_P95")
	)
	(segment
		(start 172.7835 -21.5011)
		(end 172.955712 -21.328888)
		(width 0.136652)
		(layer "F.Cu")
		(net "PCIE_TX_P95")
	)
	(segment
		(start 171.396152 -21.421852)
		(end 171.51985 -21.54555)
		(width 0.136652)
		(layer "F.Cu")
		(net "PCIE_TX_P95")
	)
	(segment
		(start 173.297088 -20.504404)
		(end 173.303946 -20.497546)
		(width 0.136652)
		(layer "F.Cu")
		(net "PCIE_TX_P95")
	)
	(segment
		(start 171.64685 -21.634958)
		(end 171.710858 -21.665438)
		(width 0.136652)
		(layer "F.Cu")
		(net "PCIE_TX_P95")
	)
	(arc
		(start 173.303946 -20.497546)
		(mid 173.401793 -20.431947)
		(end 173.517306 -20.4089)
		(width 0.136652)
		(layer "F.Cu")
		(net "PCIE_TX_P95")
	)
	(arc
		(start 172.184314 -21.749258)
		(mid 172.339329 -21.735005)
		(end 172.489114 -21.692616)
		(width 0.136652)
		(layer "F.Cu")
		(net "PCIE_TX_P95")
	)
	(arc
		(start 173.215554 -20.701)
		(mid 173.236793 -20.594604)
		(end 173.297088 -20.504404)
		(width 0.136652)
		(layer "F.Cu")
		(net "PCIE_TX_P95")
	)
	(arc
		(start 171.51985 -21.54555)
		(mid 171.579499 -21.595727)
		(end 171.64685 -21.634958)
		(width 0.136652)
		(layer "F.Cu")
		(net "PCIE_TX_P95")
	)
	(arc
		(start 171.710858 -21.665438)
		(mid 171.892878 -21.72816)
		(end 172.084238 -21.749258)
		(width 0.136652)
		(layer "F.Cu")
		(net "PCIE_TX_P95")
	)
	(arc
		(start 172.955712 -21.328888)
		(mid 173.148063 -21.040781)
		(end 173.215554 -20.701)
		(width 0.136652)
		(layer "F.Cu")
		(net "PCIE_TX_P95")
	)
	(arc
		(start 170.691048 -21.472906)
		(mid 170.737222 -21.430782)
		(end 170.787314 -21.393404)
		(width 0.136652)
		(layer "F.Cu")
		(net "PCIE_TX_P95")
	)
	(arc
		(start 171.37126 -21.401278)
		(mid 171.384195 -21.410974)
		(end 171.396152 -21.421852)
		(width 0.136652)
		(layer "F.Cu")
		(net "PCIE_TX_P95")
	)
	(arc
		(start 180.460396 -20.4089)
		(mid 180.842009 -20.484808)
		(end 181.1655 -20.701)
		(width 0.136652)
		(layer "F.Cu")
		(net "PCIE_TX_P95")
	)
	(arc
		(start 170.923966 -21.301456)
		(mid 171.031154 -21.28012)
		(end 171.138342 -21.301456)
		(width 0.136652)
		(layer "F.Cu")
		(net "PCIE_TX_P95")
	)
	(arc
		(start 171.342812 -21.386292)
		(mid 171.357404 -21.393086)
		(end 171.37126 -21.401278)
		(width 0.136652)
		(layer "F.Cu")
		(net "PCIE_TX_P95")
	)
	(arc
		(start 172.489114 -21.692616)
		(mid 172.64635 -21.612291)
		(end 172.7835 -21.5011)
		(width 0.136652)
		(layer "F.Cu")
		(net "PCIE_TX_P95")
	)
	(segment
		(start 171.109132 -25.146)
		(end 171.078906 -25.146)
		(width 0.136652)
		(layer "F.Cu")
		(net "PCIE_TX_P94")
	)
	(segment
		(start 173.719744 -24.3713)
		(end 172.787564 -25.30348)
		(width 0.136652)
		(layer "F.Cu")
		(net "PCIE_TX_P94")
	)
	(segment
		(start 180.6448 -24.185372)
		(end 174.168816 -24.185372)
		(width 0.136652)
		(layer "F.Cu")
		(net "PCIE_TX_P94")
	)
	(arc
		(start 171.512484 -25.312878)
		(mid 171.327396 -25.189333)
		(end 171.109132 -25.146)
		(width 0.136652)
		(layer "F.Cu")
		(net "PCIE_TX_P94")
	)
	(arc
		(start 172.787564 -25.30348)
		(mid 172.509207 -25.493681)
		(end 172.180758 -25.569672)
		(width 0.136652)
		(layer "F.Cu")
		(net "PCIE_TX_P94")
	)
	(arc
		(start 171.078906 -25.146)
		(mid 170.838332 -25.193853)
		(end 170.634406 -25.33015)
		(width 0.136652)
		(layer "F.Cu")
		(net "PCIE_TX_P94")
	)
	(arc
		(start 174.168816 -24.185372)
		(mid 173.925812 -24.233708)
		(end 173.719744 -24.3713)
		(width 0.136652)
		(layer "F.Cu")
		(net "PCIE_TX_P94")
	)
	(arc
		(start 181.1655 -24.511)
		(mid 180.951869 -24.273478)
		(end 180.6448 -24.185372)
		(width 0.136652)
		(layer "F.Cu")
		(net "PCIE_TX_P94")
	)
	(arc
		(start 172.180758 -25.569672)
		(mid 171.993038 -25.55807)
		(end 171.811696 -25.508204)
		(width 0.136652)
		(layer "F.Cu")
		(net "PCIE_TX_P94")
	)
	(arc
		(start 171.811696 -25.508204)
		(mid 171.667374 -25.435962)
		(end 171.5389 -25.338278)
		(width 0.136652)
		(layer "F.Cu")
		(net "PCIE_TX_P94")
	)
	(arc
		(start 171.5389 -25.338278)
		(mid 171.525558 -25.325718)
		(end 171.512484 -25.312878)
		(width 0.136652)
		(layer "F.Cu")
		(net "PCIE_TX_P94")
	)
	(segment
		(start 169.855896 -26.309828)
		(end 169.988738 -26.621486)
		(width 0.136652)
		(layer "F.Cu")
		(net "PCIE_TX_P93")
	)
	(segment
		(start 169.585894 -25.97404)
		(end 169.717974 -26.10612)
		(width 0.136652)
		(layer "F.Cu")
		(net "PCIE_TX_P93")
	)
	(segment
		(start 172.148246 -29.455618)
		(end 173.182026 -29.638244)
		(width 0.136652)
		(layer "F.Cu")
		(net "PCIE_TX_P93")
	)
	(segment
		(start 170.098466 -26.990294)
		(end 170.149774 -27.281632)
		(width 0.136652)
		(layer "F.Cu")
		(net "PCIE_TX_P93")
	)
	(segment
		(start 170.232578 -27.482292)
		(end 171.143676 -28.783534)
		(width 0.136652)
		(layer "F.Cu")
		(net "PCIE_TX_P93")
	)
	(segment
		(start 171.393866 -29.03347)
		(end 171.776136 -29.30144)
		(width 0.136652)
		(layer "F.Cu")
		(net "PCIE_TX_P93")
	)
	(segment
		(start 174.038006 -29.604462)
		(end 174.47006 -29.492194)
		(width 0.136652)
		(layer "F.Cu")
		(net "PCIE_TX_P93")
	)
	(segment
		(start 179.7558 -26.5049)
		(end 180.6194 -26.5049)
		(width 0.136652)
		(layer "F.Cu")
		(net "PCIE_TX_P93")
	)
	(segment
		(start 169.717974 -26.10612)
		(end 169.718228 -26.10612)
		(width 0.136652)
		(layer "F.Cu")
		(net "PCIE_TX_P93")
	)
	(segment
		(start 174.961296 -29.265626)
		(end 178.432714 -26.835354)
		(width 0.136652)
		(layer "F.Cu")
		(net "PCIE_TX_P93")
	)
	(segment
		(start 168.384474 -25.33015)
		(end 168.540684 -25.17394)
		(width 0.136652)
		(layer "F.Cu")
		(net "PCIE_TX_P93")
	)
	(arc
		(start 169.038524 -25.167336)
		(mid 169.0764 -25.251354)
		(end 169.117264 -25.33396)
		(width 0.136652)
		(layer "F.Cu")
		(net "PCIE_TX_P93")
	)
	(arc
		(start 174.47006 -29.492194)
		(mid 174.725802 -29.400861)
		(end 174.961296 -29.265626)
		(width 0.136652)
		(layer "F.Cu")
		(net "PCIE_TX_P93")
	)
	(arc
		(start 171.776136 -29.30144)
		(mid 171.953742 -29.398922)
		(end 172.148246 -29.455618)
		(width 0.136652)
		(layer "F.Cu")
		(net "PCIE_TX_P93")
	)
	(arc
		(start 168.540684 -25.17394)
		(mid 168.670389 -25.087274)
		(end 168.823386 -25.056846)
		(width 0.136652)
		(layer "F.Cu")
		(net "PCIE_TX_P93")
	)
	(arc
		(start 169.117264 -25.33396)
		(mid 169.326812 -25.672132)
		(end 169.585894 -25.97404)
		(width 0.136652)
		(layer "F.Cu")
		(net "PCIE_TX_P93")
	)
	(arc
		(start 169.718228 -26.10612)
		(mid 169.79689 -26.201334)
		(end 169.855896 -26.309828)
		(width 0.136652)
		(layer "F.Cu")
		(net "PCIE_TX_P93")
	)
	(arc
		(start 168.823386 -25.056846)
		(mid 168.939594 -25.095261)
		(end 169.038524 -25.167336)
		(width 0.136652)
		(layer "F.Cu")
		(net "PCIE_TX_P93")
	)
	(arc
		(start 169.988738 -26.621486)
		(mid 170.054149 -26.802753)
		(end 170.098466 -26.990294)
		(width 0.136652)
		(layer "F.Cu")
		(net "PCIE_TX_P93")
	)
	(arc
		(start 171.143676 -28.783534)
		(mid 171.257865 -28.919417)
		(end 171.393866 -29.03347)
		(width 0.136652)
		(layer "F.Cu")
		(net "PCIE_TX_P93")
	)
	(arc
		(start 170.149774 -27.281632)
		(mid 170.180173 -27.386505)
		(end 170.232578 -27.482292)
		(width 0.136652)
		(layer "F.Cu")
		(net "PCIE_TX_P93")
	)
	(arc
		(start 173.182026 -29.638244)
		(mid 173.611837 -29.667424)
		(end 174.038006 -29.604462)
		(width 0.136652)
		(layer "F.Cu")
		(net "PCIE_TX_P93")
	)
	(arc
		(start 178.432714 -26.835354)
		(mid 179.073941 -26.588796)
		(end 179.7558 -26.5049)
		(width 0.136652)
		(layer "F.Cu")
		(net "PCIE_TX_P93")
	)
	(arc
		(start 180.6194 -26.5049)
		(mid 180.929062 -26.582508)
		(end 181.1655 -26.797)
		(width 0.136652)
		(layer "F.Cu")
		(net "PCIE_TX_P93")
	)
	(segment
		(start 168.384474 -21.530056)
		(end 168.49725 -21.41728)
		(width 0.136652)
		(layer "F.Cu")
		(net "PCIE_TX_P92")
	)
	(segment
		(start 170.1292 -22.8854)
		(end 170.7642 -23.1394)
		(width 0.136652)
		(layer "F.Cu")
		(net "PCIE_TX_P92")
	)
	(segment
		(start 179.323746 -22.707346)
		(end 179.67325 -22.357842)
		(width 0.136652)
		(layer "F.Cu")
		(net "PCIE_TX_P92")
	)
	(segment
		(start 169.7482 -22.4536)
		(end 170.1292 -22.8854)
		(width 0.136652)
		(layer "F.Cu")
		(net "PCIE_TX_P92")
	)
	(segment
		(start 170.7642 -23.1394)
		(end 172.085 -22.97811)
		(width 0.136652)
		(layer "F.Cu")
		(net "PCIE_TX_P92")
	)
	(segment
		(start 169.102786 -21.378926)
		(end 169.11193 -21.387816)
		(width 0.136652)
		(layer "F.Cu")
		(net "PCIE_TX_P92")
	)
	(segment
		(start 169.11193 -21.387816)
		(end 169.46753 -21.743416)
		(width 0.136652)
		(layer "F.Cu")
		(net "PCIE_TX_P92")
	)
	(segment
		(start 172.085 -22.97811)
		(end 178.66995 -22.97811)
		(width 0.136652)
		(layer "F.Cu")
		(net "PCIE_TX_P92")
	)
	(segment
		(start 168.783 -21.298916)
		(end 168.91 -21.298916)
		(width 0.136652)
		(layer "F.Cu")
		(net "PCIE_TX_P92")
	)
	(segment
		(start 169.46753 -21.743416)
		(end 169.7482 -22.4536)
		(width 0.136652)
		(layer "F.Cu")
		(net "PCIE_TX_P92")
	)
	(segment
		(start 180.086 -22.1869)
		(end 180.46065 -22.1869)
		(width 0.136652)
		(layer "F.Cu")
		(net "PCIE_TX_P92")
	)
	(arc
		(start 168.49725 -21.41728)
		(mid 168.628353 -21.32968)
		(end 168.783 -21.298916)
		(width 0.136652)
		(layer "F.Cu")
		(net "PCIE_TX_P92")
	)
	(arc
		(start 179.67325 -22.357842)
		(mid 179.862621 -22.231308)
		(end 180.086 -22.1869)
		(width 0.136652)
		(layer "F.Cu")
		(net "PCIE_TX_P92")
	)
	(arc
		(start 168.91 -21.298916)
		(mid 169.014341 -21.319764)
		(end 169.102786 -21.378926)
		(width 0.136652)
		(layer "F.Cu")
		(net "PCIE_TX_P92")
	)
	(arc
		(start 180.46065 -22.1869)
		(mid 180.842127 -22.262856)
		(end 181.1655 -22.479)
		(width 0.136652)
		(layer "F.Cu")
		(net "PCIE_TX_P92")
	)
	(arc
		(start 178.66995 -22.97811)
		(mid 179.023778 -22.907747)
		(end 179.323746 -22.707346)
		(width 0.136652)
		(layer "F.Cu")
		(net "PCIE_TX_P92")
	)
	(segment
		(start 173.744382 -32.407352)
		(end 170.70832 -31.872174)
		(width 0.136652)
		(layer "F.Cu")
		(net "PCIE_TX_P91")
	)
	(segment
		(start 160.515554 -21.526246)
		(end 160.245298 -21.255736)
		(width 0.136652)
		(layer "F.Cu")
		(net "PCIE_TX_P91")
	)
	(segment
		(start 179.889404 -29.5529)
		(end 179.292504 -29.658056)
		(width 0.136652)
		(layer "F.Cu")
		(net "PCIE_TX_P91")
	)
	(segment
		(start 159.873442 -21.291042)
		(end 159.634428 -21.530056)
		(width 0.136652)
		(layer "F.Cu")
		(net "PCIE_TX_P91")
	)
	(segment
		(start 161.3662 -21.7678)
		(end 161.116772 -21.7678)
		(width 0.136652)
		(layer "F.Cu")
		(net "PCIE_TX_P91")
	)
	(segment
		(start 162.98164 -23.183342)
		(end 161.706814 -21.908516)
		(width 0.136652)
		(layer "F.Cu")
		(net "PCIE_TX_P91")
	)
	(segment
		(start 167.656002 -29.865066)
		(end 162.98164 -23.183342)
		(width 0.136652)
		(layer "F.Cu")
		(net "PCIE_TX_P91")
	)
	(segment
		(start 180.721 -29.5529)
		(end 179.889404 -29.5529)
		(width 0.136652)
		(layer "F.Cu")
		(net "PCIE_TX_P91")
	)
	(segment
		(start 170.254168 -31.684468)
		(end 167.656002 -29.865066)
		(width 0.136652)
		(layer "F.Cu")
		(net "PCIE_TX_P91")
	)
	(segment
		(start 160.740598 -21.682202)
		(end 160.725104 -21.674836)
		(width 0.136652)
		(layer "F.Cu")
		(net "PCIE_TX_P91")
	)
	(segment
		(start 179.011072 -29.774896)
		(end 175.826166 -32.005778)
		(width 0.136652)
		(layer "F.Cu")
		(net "PCIE_TX_P91")
	)
	(segment
		(start 175.267874 -32.237426)
		(end 174.315374 -32.407098)
		(width 0.136652)
		(layer "F.Cu")
		(net "PCIE_TX_P91")
	)
	(arc
		(start 174.315374 -32.407098)
		(mid 174.029888 -32.432335)
		(end 173.744382 -32.407352)
		(width 0.136652)
		(layer "F.Cu")
		(net "PCIE_TX_P91")
	)
	(arc
		(start 170.70832 -31.872174)
		(mid 170.470964 -31.803195)
		(end 170.254168 -31.684468)
		(width 0.136652)
		(layer "F.Cu")
		(net "PCIE_TX_P91")
	)
	(arc
		(start 160.725104 -21.674836)
		(mid 160.614038 -21.609413)
		(end 160.515554 -21.526246)
		(width 0.136652)
		(layer "F.Cu")
		(net "PCIE_TX_P91")
	)
	(arc
		(start 161.116772 -21.7678)
		(mid 160.923869 -21.746162)
		(end 160.740598 -21.682202)
		(width 0.136652)
		(layer "F.Cu")
		(net "PCIE_TX_P91")
	)
	(arc
		(start 179.292504 -29.658056)
		(mid 179.145394 -29.701069)
		(end 179.011072 -29.774896)
		(width 0.136652)
		(layer "F.Cu")
		(net "PCIE_TX_P91")
	)
	(arc
		(start 161.706814 -21.908516)
		(mid 161.550468 -21.804364)
		(end 161.3662 -21.7678)
		(width 0.136652)
		(layer "F.Cu")
		(net "PCIE_TX_P91")
	)
	(arc
		(start 160.245298 -21.255736)
		(mid 160.053013 -21.206478)
		(end 159.873442 -21.291042)
		(width 0.136652)
		(layer "F.Cu")
		(net "PCIE_TX_P91")
	)
	(arc
		(start 181.1655 -29.845)
		(mid 180.986923 -29.632511)
		(end 180.721 -29.5529)
		(width 0.136652)
		(layer "F.Cu")
		(net "PCIE_TX_P91")
	)
	(arc
		(start 175.826166 -32.005778)
		(mid 175.559655 -32.152052)
		(end 175.267874 -32.237426)
		(width 0.136652)
		(layer "F.Cu")
		(net "PCIE_TX_P91")
	)
	(segment
		(start 161.4551 -29.238448)
		(end 161.4551 -32.6644)
		(width 0.136652)
		(layer "F.Cu")
		(net "PCIE_TX_P90")
	)
	(segment
		(start 159.9311 -26.94559)
		(end 159.9311 -27.235658)
		(width 0.136652)
		(layer "F.Cu")
		(net "PCIE_TX_P90")
	)
	(segment
		(start 161.454846 -29.238702)
		(end 161.4551 -29.238448)
		(width 0.136652)
		(layer "F.Cu")
		(net "PCIE_TX_P90")
	)
	(segment
		(start 160.04921 -24.844756)
		(end 160.342072 -25.137364)
		(width 0.136652)
		(layer "F.Cu")
		(net "PCIE_TX_P90")
	)
	(segment
		(start 160.342072 -26.271728)
		(end 160.117028 -26.496772)
		(width 0.136652)
		(layer "F.Cu")
		(net "PCIE_TX_P90")
	)
	(segment
		(start 160.060386 -27.548078)
		(end 161.245804 -28.733496)
		(width 0.136652)
		(layer "F.Cu")
		(net "PCIE_TX_P90")
	)
	(segment
		(start 159.634428 -25.33015)
		(end 159.634428 -25.064466)
		(width 0.136652)
		(layer "F.Cu")
		(net "PCIE_TX_P90")
	)
	(segment
		(start 160.528 -25.586436)
		(end 160.528 -25.822656)
		(width 0.136652)
		(layer "F.Cu")
		(net "PCIE_TX_P90")
	)
	(arc
		(start 161.245804 -28.733496)
		(mid 161.400623 -28.965288)
		(end 161.454846 -29.238702)
		(width 0.136652)
		(layer "F.Cu")
		(net "PCIE_TX_P90")
	)
	(arc
		(start 160.528 -25.822656)
		(mid 160.479679 -26.065674)
		(end 160.342072 -26.271728)
		(width 0.136652)
		(layer "F.Cu")
		(net "PCIE_TX_P90")
	)
	(arc
		(start 159.726376 -24.84247)
		(mid 159.818908 -24.803595)
		(end 159.9184 -24.7904)
		(width 0.136652)
		(layer "F.Cu")
		(net "PCIE_TX_P90")
	)
	(arc
		(start 159.9311 -27.235658)
		(mid 159.96464 -27.404745)
		(end 160.060386 -27.548078)
		(width 0.136652)
		(layer "F.Cu")
		(net "PCIE_TX_P90")
	)
	(arc
		(start 161.4551 -32.6644)
		(mid 161.374877 -32.919839)
		(end 161.163 -33.0835)
		(width 0.136652)
		(layer "F.Cu")
		(net "PCIE_TX_P90")
	)
	(arc
		(start 159.634428 -25.064466)
		(mid 159.658326 -24.944325)
		(end 159.726376 -24.84247)
		(width 0.136652)
		(layer "F.Cu")
		(net "PCIE_TX_P90")
	)
	(arc
		(start 160.342072 -25.137364)
		(mid 160.479687 -25.343414)
		(end 160.528 -25.586436)
		(width 0.136652)
		(layer "F.Cu")
		(net "PCIE_TX_P90")
	)
	(arc
		(start 159.9184 -24.7904)
		(mid 159.989206 -24.804578)
		(end 160.04921 -24.844756)
		(width 0.136652)
		(layer "F.Cu")
		(net "PCIE_TX_P90")
	)
	(arc
		(start 160.117028 -26.496772)
		(mid 159.979461 -26.702705)
		(end 159.9311 -26.94559)
		(width 0.136652)
		(layer "F.Cu")
		(net "PCIE_TX_P90")
	)
	(segment
		(start 310.97474 -26.33345)
		(end 310.852566 -26.455624)
		(width 0.136652)
		(layer "F.Cu")
		(net "PCIE_TX_P9")
	)
	(segment
		(start 310.637936 -26.975816)
		(end 310.63819 -26.97607)
		(width 0.136652)
		(layer "F.Cu")
		(net "PCIE_TX_P9")
	)
	(segment
		(start 310.570372 -24.7777)
		(end 310.620156 -24.7777)
		(width 0.136652)
		(layer "F.Cu")
		(net "PCIE_TX_P9")
	)
	(segment
		(start 310.384444 -25.33015)
		(end 310.384444 -24.981154)
		(width 0.136652)
		(layer "F.Cu")
		(net "PCIE_TX_P9")
	)
	(segment
		(start 311.09539 -25.306782)
		(end 311.09539 -26.042112)
		(width 0.136652)
		(layer "F.Cu")
		(net "PCIE_TX_P9")
	)
	(segment
		(start 310.63819 -26.97607)
		(end 310.63819 -32.639)
		(width 0.136652)
		(layer "F.Cu")
		(net "PCIE_TX_P9")
	)
	(segment
		(start 310.63819 -26.975816)
		(end 310.637936 -26.975816)
		(width 0.136652)
		(layer "F.Cu")
		(net "PCIE_TX_P9")
	)
	(segment
		(start 310.803544 -24.853646)
		(end 310.981344 -25.031446)
		(width 0.136652)
		(layer "F.Cu")
		(net "PCIE_TX_P9")
	)
	(arc
		(start 310.44769 -24.8285)
		(mid 310.503977 -24.79089)
		(end 310.570372 -24.7777)
		(width 0.136652)
		(layer "F.Cu")
		(net "PCIE_TX_P9")
	)
	(arc
		(start 310.620156 -24.7777)
		(mid 310.717904 -24.796827)
		(end 310.801258 -24.85136)
		(width 0.136652)
		(layer "F.Cu")
		(net "PCIE_TX_P9")
	)
	(arc
		(start 310.852566 -26.455624)
		(mid 310.815015 -26.496153)
		(end 310.780684 -26.539444)
		(width 0.136652)
		(layer "F.Cu")
		(net "PCIE_TX_P9")
	)
	(arc
		(start 310.981344 -25.031446)
		(mid 311.065752 -25.157771)
		(end 311.09539 -25.306782)
		(width 0.136652)
		(layer "F.Cu")
		(net "PCIE_TX_P9")
	)
	(arc
		(start 310.801258 -24.85136)
		(mid 310.802405 -24.852499)
		(end 310.803544 -24.853646)
		(width 0.136652)
		(layer "F.Cu")
		(net "PCIE_TX_P9")
	)
	(arc
		(start 310.780684 -26.539444)
		(mid 310.674604 -26.746259)
		(end 310.63819 -26.975816)
		(width 0.136652)
		(layer "F.Cu")
		(net "PCIE_TX_P9")
	)
	(arc
		(start 311.09539 -26.042112)
		(mid 311.064029 -26.199773)
		(end 310.97474 -26.33345)
		(width 0.136652)
		(layer "F.Cu")
		(net "PCIE_TX_P9")
	)
	(arc
		(start 310.384444 -24.981154)
		(mid 310.400878 -24.898533)
		(end 310.44769 -24.8285)
		(width 0.136652)
		(layer "F.Cu")
		(net "PCIE_TX_P9")
	)
	(arc
		(start 310.63819 -32.639)
		(mid 310.567892 -32.909348)
		(end 310.374792 -33.111186)
		(width 0.136652)
		(layer "F.Cu")
		(net "PCIE_TX_P9")
	)
	(segment
		(start 158.170372 -25.226264)
		(end 158.170626 -25.226518)
		(width 0.136652)
		(layer "F.Cu")
		(net "PCIE_TX_P89")
	)
	(segment
		(start 158.170372 -25.226518)
		(end 158.170372 -25.226264)
		(width 0.136652)
		(layer "F.Cu")
		(net "PCIE_TX_P89")
	)
	(segment
		(start 157.806898 -24.862536)
		(end 158.170372 -25.226518)
		(width 0.136652)
		(layer "F.Cu")
		(net "PCIE_TX_P89")
	)
	(segment
		(start 157.384496 -25.33015)
		(end 157.384496 -25.071832)
		(width 0.136652)
		(layer "F.Cu")
		(net "PCIE_TX_P89")
	)
	(segment
		(start 158.408116 -30.251908)
		(end 158.792672 -30.636464)
		(width 0.136652)
		(layer "F.Cu")
		(net "PCIE_TX_P89")
	)
	(segment
		(start 158.2674 -25.459944)
		(end 158.2674 -29.911802)
		(width 0.136652)
		(layer "F.Cu")
		(net "PCIE_TX_P89")
	)
	(segment
		(start 158.83255 -30.733238)
		(end 158.832804 -30.732984)
		(width 0.136652)
		(layer "F.Cu")
		(net "PCIE_TX_P89")
	)
	(segment
		(start 158.832804 -30.732984)
		(end 158.832804 -32.6644)
		(width 0.136652)
		(layer "F.Cu")
		(net "PCIE_TX_P89")
	)
	(arc
		(start 157.484318 -24.830786)
		(mid 157.555658 -24.800695)
		(end 157.6324 -24.7904)
		(width 0.136652)
		(layer "F.Cu")
		(net "PCIE_TX_P89")
	)
	(arc
		(start 158.2674 -29.911802)
		(mid 158.303917 -30.095858)
		(end 158.408116 -30.251908)
		(width 0.136652)
		(layer "F.Cu")
		(net "PCIE_TX_P89")
	)
	(arc
		(start 157.384496 -25.071832)
		(mid 157.410443 -24.941387)
		(end 157.484318 -24.830786)
		(width 0.136652)
		(layer "F.Cu")
		(net "PCIE_TX_P89")
	)
	(arc
		(start 158.792672 -30.636464)
		(mid 158.822256 -30.680879)
		(end 158.83255 -30.733238)
		(width 0.136652)
		(layer "F.Cu")
		(net "PCIE_TX_P89")
	)
	(arc
		(start 158.832804 -32.6644)
		(mid 158.752581 -32.919839)
		(end 158.540704 -33.0835)
		(width 0.136652)
		(layer "F.Cu")
		(net "PCIE_TX_P89")
	)
	(arc
		(start 157.6324 -24.7904)
		(mid 157.726836 -24.809091)
		(end 157.806898 -24.862536)
		(width 0.136652)
		(layer "F.Cu")
		(net "PCIE_TX_P89")
	)
	(arc
		(start 158.170626 -25.226518)
		(mid 158.242215 -25.333614)
		(end 158.2674 -25.459944)
		(width 0.136652)
		(layer "F.Cu")
		(net "PCIE_TX_P89")
	)
	(segment
		(start 159.648398 -23.1394)
		(end 160.82391 -23.1394)
		(width 0.136652)
		(layer "F.Cu")
		(net "PCIE_TX_P88")
	)
	(segment
		(start 163.486846 -27.122882)
		(end 163.4871 -27.122628)
		(width 0.136652)
		(layer "F.Cu")
		(net "PCIE_TX_P88")
	)
	(segment
		(start 157.791658 -21.063204)
		(end 158.432754 -21.704046)
		(width 0.136652)
		(layer "F.Cu")
		(net "PCIE_TX_P88")
	)
	(segment
		(start 161.272728 -23.325328)
		(end 161.739072 -23.791672)
		(width 0.136652)
		(layer "F.Cu")
		(net "PCIE_TX_P88")
	)
	(segment
		(start 161.272728 -23.325582)
		(end 161.272728 -23.325328)
		(width 0.136652)
		(layer "F.Cu")
		(net "PCIE_TX_P88")
	)
	(segment
		(start 158.432754 -21.704046)
		(end 158.9532 -22.6314)
		(width 0.136652)
		(layer "F.Cu")
		(net "PCIE_TX_P88")
	)
	(segment
		(start 161.925 -24.24049)
		(end 161.925 -24.989282)
		(width 0.136652)
		(layer "F.Cu")
		(net "PCIE_TX_P88")
	)
	(segment
		(start 158.9532 -22.6314)
		(end 159.648398 -23.1394)
		(width 0.136652)
		(layer "F.Cu")
		(net "PCIE_TX_P88")
	)
	(segment
		(start 162.142932 -25.515824)
		(end 163.300918 -26.67381)
		(width 0.136652)
		(layer "F.Cu")
		(net "PCIE_TX_P88")
	)
	(segment
		(start 163.4871 -27.122628)
		(end 163.4871 -32.6644)
		(width 0.136652)
		(layer "F.Cu")
		(net "PCIE_TX_P88")
	)
	(segment
		(start 157.384496 -21.530056)
		(end 157.384496 -21.23186)
		(width 0.136652)
		(layer "F.Cu")
		(net "PCIE_TX_P88")
	)
	(arc
		(start 163.4871 -32.6644)
		(mid 163.406877 -32.919839)
		(end 163.195 -33.0835)
		(width 0.136652)
		(layer "F.Cu")
		(net "PCIE_TX_P88")
	)
	(arc
		(start 163.300918 -26.67381)
		(mid 163.438558 -26.879847)
		(end 163.486846 -27.122882)
		(width 0.136652)
		(layer "F.Cu")
		(net "PCIE_TX_P88")
	)
	(arc
		(start 160.82391 -23.1394)
		(mid 161.066821 -23.187887)
		(end 161.272728 -23.325582)
		(width 0.136652)
		(layer "F.Cu")
		(net "PCIE_TX_P88")
	)
	(arc
		(start 161.925 -24.989282)
		(mid 161.981587 -25.274234)
		(end 162.142932 -25.515824)
		(width 0.136652)
		(layer "F.Cu")
		(net "PCIE_TX_P88")
	)
	(arc
		(start 161.739072 -23.791672)
		(mid 161.876639 -23.997605)
		(end 161.925 -24.24049)
		(width 0.136652)
		(layer "F.Cu")
		(net "PCIE_TX_P88")
	)
	(arc
		(start 157.384496 -21.23186)
		(mid 157.53173 -21.011509)
		(end 157.791658 -21.063204)
		(width 0.136652)
		(layer "F.Cu")
		(net "PCIE_TX_P88")
	)
	(segment
		(start 149.58695 -21.62175)
		(end 149.5171 -21.551392)
		(width 0.136652)
		(layer "F.Cu")
		(net "PCIE_TX_P87")
	)
	(segment
		(start 149.81809 -21.772626)
		(end 149.804882 -21.767292)
		(width 0.136652)
		(layer "F.Cu")
		(net "PCIE_TX_P87")
	)
	(segment
		(start 149.047454 -21.081746)
		(end 149.018498 -21.052536)
		(width 0.136652)
		(layer "F.Cu")
		(net "PCIE_TX_P87")
	)
	(segment
		(start 152.8953 -32.639)
		(end 152.8953 -24.87422)
		(width 0.136652)
		(layer "F.Cu")
		(net "PCIE_TX_P87")
	)
	(segment
		(start 148.722842 -21.030438)
		(end 148.669756 -21.083778)
		(width 0.136652)
		(layer "F.Cu")
		(net "PCIE_TX_P87")
	)
	(segment
		(start 152.709372 -24.425148)
		(end 150.258526 -21.974302)
		(width 0.136652)
		(layer "F.Cu")
		(net "PCIE_TX_P87")
	)
	(segment
		(start 149.991318 -21.821394)
		(end 149.983444 -21.820124)
		(width 0.136652)
		(layer "F.Cu")
		(net "PCIE_TX_P87")
	)
	(segment
		(start 148.63445 -21.241004)
		(end 148.63445 -21.530056)
		(width 0.136652)
		(layer "F.Cu")
		(net "PCIE_TX_P87")
	)
	(segment
		(start 149.5171 -21.551392)
		(end 149.047454 -21.081746)
		(width 0.136652)
		(layer "F.Cu")
		(net "PCIE_TX_P87")
	)
	(arc
		(start 150.258526 -21.974302)
		(mid 150.199943 -21.921946)
		(end 150.135844 -21.876512)
		(width 0.136652)
		(layer "F.Cu")
		(net "PCIE_TX_P87")
	)
	(arc
		(start 150.135844 -21.876512)
		(mid 150.066294 -21.841839)
		(end 149.991318 -21.821394)
		(width 0.136652)
		(layer "F.Cu")
		(net "PCIE_TX_P87")
	)
	(arc
		(start 149.804882 -21.767292)
		(mid 149.688778 -21.705214)
		(end 149.58695 -21.62175)
		(width 0.136652)
		(layer "F.Cu")
		(net "PCIE_TX_P87")
	)
	(arc
		(start 152.6032 -33.0581)
		(mid 152.815036 -32.89441)
		(end 152.8953 -32.639)
		(width 0.136652)
		(layer "F.Cu")
		(net "PCIE_TX_P87")
	)
	(arc
		(start 148.669756 -21.083778)
		(mid 148.64339 -21.160436)
		(end 148.63445 -21.241004)
		(width 0.136652)
		(layer "F.Cu")
		(net "PCIE_TX_P87")
	)
	(arc
		(start 149.018498 -21.052536)
		(mid 148.938423 -20.999124)
		(end 148.844 -20.9804)
		(width 0.136652)
		(layer "F.Cu")
		(net "PCIE_TX_P87")
	)
	(arc
		(start 148.844 -20.9804)
		(mid 148.778432 -20.993348)
		(end 148.722842 -21.030438)
		(width 0.136652)
		(layer "F.Cu")
		(net "PCIE_TX_P87")
	)
	(arc
		(start 152.8953 -24.87422)
		(mid 152.846964 -24.631216)
		(end 152.709372 -24.425148)
		(width 0.136652)
		(layer "F.Cu")
		(net "PCIE_TX_P87")
	)
	(arc
		(start 149.983444 -21.820124)
		(mid 149.899422 -21.801058)
		(end 149.81809 -21.772626)
		(width 0.136652)
		(layer "F.Cu")
		(net "PCIE_TX_P87")
	)
	(segment
		(start 149.318472 -26.246328)
		(end 148.941028 -26.623772)
		(width 0.136652)
		(layer "F.Cu")
		(net "PCIE_TX_P86")
	)
	(segment
		(start 149.5044 -25.586436)
		(end 149.5044 -25.797256)
		(width 0.136652)
		(layer "F.Cu")
		(net "PCIE_TX_P86")
	)
	(segment
		(start 148.7551 -27.072844)
		(end 148.7551 -32.6644)
		(width 0.136652)
		(layer "F.Cu")
		(net "PCIE_TX_P86")
	)
	(segment
		(start 149.022054 -24.840946)
		(end 149.318472 -25.137364)
		(width 0.136652)
		(layer "F.Cu")
		(net "PCIE_TX_P86")
	)
	(segment
		(start 148.63445 -25.33015)
		(end 148.63445 -25.107392)
		(width 0.136652)
		(layer "F.Cu")
		(net "PCIE_TX_P86")
	)
	(arc
		(start 149.5044 -25.797256)
		(mid 149.456079 -26.040274)
		(end 149.318472 -26.246328)
		(width 0.136652)
		(layer "F.Cu")
		(net "PCIE_TX_P86")
	)
	(arc
		(start 148.761196 -24.801322)
		(mid 148.814028 -24.783688)
		(end 148.8694 -24.7777)
		(width 0.136652)
		(layer "F.Cu")
		(net "PCIE_TX_P86")
	)
	(arc
		(start 148.941028 -26.623772)
		(mid 148.803413 -26.829822)
		(end 148.7551 -27.072844)
		(width 0.136652)
		(layer "F.Cu")
		(net "PCIE_TX_P86")
	)
	(arc
		(start 149.318472 -25.137364)
		(mid 149.456087 -25.343414)
		(end 149.5044 -25.586436)
		(width 0.136652)
		(layer "F.Cu")
		(net "PCIE_TX_P86")
	)
	(arc
		(start 148.63445 -25.107392)
		(mid 148.667396 -24.94176)
		(end 148.761196 -24.801322)
		(width 0.136652)
		(layer "F.Cu")
		(net "PCIE_TX_P86")
	)
	(arc
		(start 148.7551 -32.6644)
		(mid 148.674877 -32.919839)
		(end 148.463 -33.0835)
		(width 0.136652)
		(layer "F.Cu")
		(net "PCIE_TX_P86")
	)
	(arc
		(start 148.8694 -24.7777)
		(mid 148.952021 -24.794134)
		(end 149.022054 -24.840946)
		(width 0.136652)
		(layer "F.Cu")
		(net "PCIE_TX_P86")
	)
	(segment
		(start 147.184618 -25.35047)
		(end 146.906996 -24.928576)
		(width 0.136652)
		(layer "F.Cu")
		(net "PCIE_TX_P85")
	)
	(segment
		(start 147.307046 -25.728168)
		(end 147.279614 -25.584404)
		(width 0.136652)
		(layer "F.Cu")
		(net "PCIE_TX_P85")
	)
	(segment
		(start 146.14652 -31.893002)
		(end 147.098512 -30.94101)
		(width 0.136652)
		(layer "F.Cu")
		(net "PCIE_TX_P85")
	)
	(segment
		(start 146.588988 -24.81453)
		(end 146.475704 -24.888952)
		(width 0.136652)
		(layer "F.Cu")
		(net "PCIE_TX_P85")
	)
	(segment
		(start 146.14652 -32.639)
		(end 146.14652 -31.893002)
		(width 0.136652)
		(layer "F.Cu")
		(net "PCIE_TX_P85")
	)
	(segment
		(start 147.30984 -30.431232)
		(end 147.30984 -25.75687)
		(width 0.136652)
		(layer "F.Cu")
		(net "PCIE_TX_P85")
	)
	(arc
		(start 146.475704 -24.888952)
		(mid 146.338626 -25.090658)
		(end 146.384518 -25.33015)
		(width 0.136652)
		(layer "F.Cu")
		(net "PCIE_TX_P85")
	)
	(arc
		(start 147.098512 -30.94101)
		(mid 147.25485 -30.707123)
		(end 147.30984 -30.431232)
		(width 0.136652)
		(layer "F.Cu")
		(net "PCIE_TX_P85")
	)
	(arc
		(start 146.906996 -24.928576)
		(mid 146.767021 -24.818481)
		(end 146.588988 -24.81453)
		(width 0.136652)
		(layer "F.Cu")
		(net "PCIE_TX_P85")
	)
	(arc
		(start 145.8722 -33.07842)
		(mid 146.072271 -32.897993)
		(end 146.14652 -32.639)
		(width 0.136652)
		(layer "F.Cu")
		(net "PCIE_TX_P85")
	)
	(arc
		(start 147.30984 -25.75687)
		(mid 147.309133 -25.742451)
		(end 147.307046 -25.728168)
		(width 0.136652)
		(layer "F.Cu")
		(net "PCIE_TX_P85")
	)
	(arc
		(start 147.279614 -25.584404)
		(mid 147.243649 -25.462753)
		(end 147.184618 -25.35047)
		(width 0.136652)
		(layer "F.Cu")
		(net "PCIE_TX_P85")
	)
	(segment
		(start 149.250146 -23.159974)
		(end 149.403308 -23.159974)
		(width 0.136652)
		(layer "F.Cu")
		(net "PCIE_TX_P84")
	)
	(segment
		(start 150.9141 -24.54529)
		(end 150.9141 -32.6644)
		(width 0.136652)
		(layer "F.Cu")
		(net "PCIE_TX_P84")
	)
	(segment
		(start 147.9804 -22.733)
		(end 148.6154 -23.1648)
		(width 0.136652)
		(layer "F.Cu")
		(net "PCIE_TX_P84")
	)
	(segment
		(start 150.066756 -23.434802)
		(end 150.728172 -24.096218)
		(width 0.136652)
		(layer "F.Cu")
		(net "PCIE_TX_P84")
	)
	(segment
		(start 147.447254 -21.716746)
		(end 147.9804 -22.733)
		(width 0.136652)
		(layer "F.Cu")
		(net "PCIE_TX_P84")
	)
	(segment
		(start 148.6154 -23.1648)
		(end 149.250146 -23.159974)
		(width 0.136652)
		(layer "F.Cu")
		(net "PCIE_TX_P84")
	)
	(segment
		(start 146.850354 -21.119846)
		(end 147.447254 -21.716746)
		(width 0.136652)
		(layer "F.Cu")
		(net "PCIE_TX_P84")
	)
	(arc
		(start 150.9141 -32.6644)
		(mid 150.833877 -32.919839)
		(end 150.622 -33.0835)
		(width 0.136652)
		(layer "F.Cu")
		(net "PCIE_TX_P84")
	)
	(arc
		(start 149.403308 -23.159974)
		(mid 149.762371 -23.231396)
		(end 150.066756 -23.434802)
		(width 0.136652)
		(layer "F.Cu")
		(net "PCIE_TX_P84")
	)
	(arc
		(start 146.384518 -21.530056)
		(mid 146.424941 -21.106492)
		(end 146.850354 -21.119846)
		(width 0.136652)
		(layer "F.Cu")
		(net "PCIE_TX_P84")
	)
	(arc
		(start 150.728172 -24.096218)
		(mid 150.865841 -24.302254)
		(end 150.9141 -24.54529)
		(width 0.136652)
		(layer "F.Cu")
		(net "PCIE_TX_P84")
	)
	(segment
		(start 141.224 -23.779734)
		(end 141.224 -27.269186)
		(width 0.136652)
		(layer "F.Cu")
		(net "PCIE_TX_P83")
	)
	(segment
		(start 138.09853 -21.04771)
		(end 138.213338 -21.162518)
		(width 0.136652)
		(layer "F.Cu")
		(net "PCIE_TX_P83")
	)
	(segment
		(start 140.706602 -22.736302)
		(end 140.852144 -22.881844)
		(width 0.136652)
		(layer "F.Cu")
		(net "PCIE_TX_P83")
	)
	(segment
		(start 137.8204 -31.724854)
		(end 137.8204 -32.6136)
		(width 0.136652)
		(layer "F.Cu")
		(net "PCIE_TX_P83")
	)
	(segment
		(start 139.886944 -22.278594)
		(end 139.888722 -22.27961)
		(width 0.136652)
		(layer "F.Cu")
		(net "PCIE_TX_P83")
	)
	(segment
		(start 139.168886 -22.040088)
		(end 139.886944 -22.278594)
		(width 0.136652)
		(layer "F.Cu")
		(net "PCIE_TX_P83")
	)
	(segment
		(start 138.381994 -21.384006)
		(end 138.826748 -21.82876)
		(width 0.136652)
		(layer "F.Cu")
		(net "PCIE_TX_P83")
	)
	(segment
		(start 140.941298 -27.95143)
		(end 138.28141 -30.611318)
		(width 0.136652)
		(layer "F.Cu")
		(net "PCIE_TX_P83")
	)
	(segment
		(start 139.888722 -22.27961)
		(end 140.327634 -22.475444)
		(width 0.136652)
		(layer "F.Cu")
		(net "PCIE_TX_P83")
	)
	(segment
		(start 137.634472 -21.530056)
		(end 137.634472 -21.330158)
		(width 0.136652)
		(layer "F.Cu")
		(net "PCIE_TX_P83")
	)
	(segment
		(start 137.738104 -21.079968)
		(end 137.770362 -21.04771)
		(width 0.136652)
		(layer "F.Cu")
		(net "PCIE_TX_P83")
	)
	(arc
		(start 138.213338 -21.162518)
		(mid 138.290179 -21.278962)
		(end 138.381994 -21.384006)
		(width 0.136652)
		(layer "F.Cu")
		(net "PCIE_TX_P83")
	)
	(arc
		(start 137.8204 -32.6136)
		(mid 137.741736 -32.89674)
		(end 137.5283 -33.09874)
		(width 0.136652)
		(layer "F.Cu")
		(net "PCIE_TX_P83")
	)
	(arc
		(start 138.28141 -30.611318)
		(mid 137.940178 -31.122242)
		(end 137.8204 -31.724854)
		(width 0.136652)
		(layer "F.Cu")
		(net "PCIE_TX_P83")
	)
	(arc
		(start 140.852144 -22.881844)
		(mid 141.12735 -23.293814)
		(end 141.224 -23.779734)
		(width 0.136652)
		(layer "F.Cu")
		(net "PCIE_TX_P83")
	)
	(arc
		(start 137.770362 -21.04771)
		(mid 137.934446 -20.979744)
		(end 138.09853 -21.04771)
		(width 0.136652)
		(layer "F.Cu")
		(net "PCIE_TX_P83")
	)
	(arc
		(start 141.224 -27.269186)
		(mid 141.15048 -27.638415)
		(end 140.941298 -27.95143)
		(width 0.136652)
		(layer "F.Cu")
		(net "PCIE_TX_P83")
	)
	(arc
		(start 140.327634 -22.475444)
		(mid 140.529032 -22.588566)
		(end 140.706602 -22.736302)
		(width 0.136652)
		(layer "F.Cu")
		(net "PCIE_TX_P83")
	)
	(arc
		(start 138.826748 -21.82876)
		(mid 138.985486 -21.954392)
		(end 139.168886 -22.040088)
		(width 0.136652)
		(layer "F.Cu")
		(net "PCIE_TX_P83")
	)
	(arc
		(start 137.634472 -21.330158)
		(mid 137.661405 -21.194756)
		(end 137.738104 -21.079968)
		(width 0.136652)
		(layer "F.Cu")
		(net "PCIE_TX_P83")
	)
	(segment
		(start 137.634472 -25.213056)
		(end 137.634472 -25.33015)
		(width 0.136652)
		(layer "F.Cu")
		(net "PCIE_TX_P82")
	)
	(segment
		(start 138.356594 -25.242774)
		(end 138.34237 -25.191212)
		(width 0.136652)
		(layer "F.Cu")
		(net "PCIE_TX_P82")
	)
	(segment
		(start 138.356848 -25.242774)
		(end 138.356594 -25.242774)
		(width 0.136652)
		(layer "F.Cu")
		(net "PCIE_TX_P82")
	)
	(segment
		(start 133.729984 -30.780482)
		(end 138.177016 -26.333958)
		(width 0.136652)
		(layer "F.Cu")
		(net "PCIE_TX_P82")
	)
	(segment
		(start 138.374882 -25.856692)
		(end 138.374882 -25.372822)
		(width 0.136652)
		(layer "F.Cu")
		(net "PCIE_TX_P82")
	)
	(segment
		(start 138.374882 -25.372822)
		(end 138.374628 -25.372822)
		(width 0.136652)
		(layer "F.Cu")
		(net "PCIE_TX_P82")
	)
	(segment
		(start 133.5024 -32.6136)
		(end 133.5024 -31.330646)
		(width 0.136652)
		(layer "F.Cu")
		(net "PCIE_TX_P82")
	)
	(arc
		(start 138.273282 -25.073864)
		(mid 138.206857 -24.996473)
		(end 138.15314 -24.90978)
		(width 0.136652)
		(layer "F.Cu")
		(net "PCIE_TX_P82")
	)
	(arc
		(start 133.2103 -33.09874)
		(mid 133.423751 -32.896749)
		(end 133.5024 -32.6136)
		(width 0.136652)
		(layer "F.Cu")
		(net "PCIE_TX_P82")
	)
	(arc
		(start 137.721594 -24.902414)
		(mid 137.656623 -25.051731)
		(end 137.634472 -25.213056)
		(width 0.136652)
		(layer "F.Cu")
		(net "PCIE_TX_P82")
	)
	(arc
		(start 138.34237 -25.191212)
		(mid 138.315331 -25.128122)
		(end 138.273282 -25.073864)
		(width 0.136652)
		(layer "F.Cu")
		(net "PCIE_TX_P82")
	)
	(arc
		(start 138.374628 -25.372822)
		(mid 138.370232 -25.307184)
		(end 138.356848 -25.242774)
		(width 0.136652)
		(layer "F.Cu")
		(net "PCIE_TX_P82")
	)
	(arc
		(start 133.5024 -31.330646)
		(mid 133.561437 -31.032907)
		(end 133.729984 -30.780482)
		(width 0.136652)
		(layer "F.Cu")
		(net "PCIE_TX_P82")
	)
	(arc
		(start 138.177016 -26.333958)
		(mid 138.323411 -26.115002)
		(end 138.374882 -25.856692)
		(width 0.136652)
		(layer "F.Cu")
		(net "PCIE_TX_P82")
	)
	(arc
		(start 138.15314 -24.90978)
		(mid 137.939607 -24.777434)
		(end 137.721594 -24.902414)
		(width 0.136652)
		(layer "F.Cu")
		(net "PCIE_TX_P82")
	)
	(segment
		(start 136.1694 -25.305004)
		(end 136.169146 -25.304496)
		(width 0.136652)
		(layer "F.Cu")
		(net "PCIE_TX_P81")
	)
	(segment
		(start 131.593336 -31.246064)
		(end 135.833612 -27.005788)
		(width 0.136652)
		(layer "F.Cu")
		(net "PCIE_TX_P81")
	)
	(segment
		(start 131.3434 -32.6136)
		(end 131.3434 -31.85033)
		(width 0.136652)
		(layer "F.Cu")
		(net "PCIE_TX_P81")
	)
	(segment
		(start 135.950706 -24.95296)
		(end 135.898382 -24.900382)
		(width 0.136652)
		(layer "F.Cu")
		(net "PCIE_TX_P81")
	)
	(segment
		(start 136.183116 -26.162)
		(end 136.183116 -25.413208)
		(width 0.136652)
		(layer "F.Cu")
		(net "PCIE_TX_P81")
	)
	(segment
		(start 135.38454 -25.062942)
		(end 135.38454 -25.33015)
		(width 0.136652)
		(layer "F.Cu")
		(net "PCIE_TX_P81")
	)
	(segment
		(start 135.384794 -25.062688)
		(end 135.38454 -25.062942)
		(width 0.136652)
		(layer "F.Cu")
		(net "PCIE_TX_P81")
	)
	(arc
		(start 131.0513 -33.09874)
		(mid 131.264751 -32.896749)
		(end 131.3434 -32.6136)
		(width 0.136652)
		(layer "F.Cu")
		(net "PCIE_TX_P81")
	)
	(arc
		(start 136.183116 -25.413208)
		(mid 136.179673 -25.358673)
		(end 136.1694 -25.305004)
		(width 0.136652)
		(layer "F.Cu")
		(net "PCIE_TX_P81")
	)
	(arc
		(start 136.169146 -25.304496)
		(mid 136.160303 -25.274549)
		(end 136.149334 -25.245314)
		(width 0.136652)
		(layer "F.Cu")
		(net "PCIE_TX_P81")
	)
	(arc
		(start 136.149334 -25.245314)
		(mid 136.129347 -25.204266)
		(end 136.105138 -25.165558)
		(width 0.136652)
		(layer "F.Cu")
		(net "PCIE_TX_P81")
	)
	(arc
		(start 136.105138 -25.165558)
		(mid 136.020929 -25.064338)
		(end 135.950706 -24.95296)
		(width 0.136652)
		(layer "F.Cu")
		(net "PCIE_TX_P81")
	)
	(arc
		(start 131.3434 -31.85033)
		(mid 131.408241 -31.523319)
		(end 131.593336 -31.246064)
		(width 0.136652)
		(layer "F.Cu")
		(net "PCIE_TX_P81")
	)
	(arc
		(start 135.833612 -27.005788)
		(mid 135.96257 -26.853174)
		(end 136.064244 -26.681176)
		(width 0.136652)
		(layer "F.Cu")
		(net "PCIE_TX_P81")
	)
	(arc
		(start 135.898382 -24.900382)
		(mid 135.764001 -24.810684)
		(end 135.60552 -24.779224)
		(width 0.136652)
		(layer "F.Cu")
		(net "PCIE_TX_P81")
	)
	(arc
		(start 136.064244 -26.681176)
		(mid 136.153011 -26.428304)
		(end 136.183116 -26.162)
		(width 0.136652)
		(layer "F.Cu")
		(net "PCIE_TX_P81")
	)
	(arc
		(start 135.60552 -24.779224)
		(mid 135.446502 -24.883086)
		(end 135.384794 -25.062688)
		(width 0.136652)
		(layer "F.Cu")
		(net "PCIE_TX_P81")
	)
	(segment
		(start 136.95045 -22.411944)
		(end 136.487662 -21.730208)
		(width 0.136652)
		(layer "F.Cu")
		(net "PCIE_TX_P80")
	)
	(segment
		(start 135.6614 -32.6136)
		(end 135.6614 -31.763716)
		(width 0.136652)
		(layer "F.Cu")
		(net "PCIE_TX_P80")
	)
	(segment
		(start 135.870188 -31.257748)
		(end 139.727178 -27.383232)
		(width 0.136652)
		(layer "F.Cu")
		(net "PCIE_TX_P80")
	)
	(segment
		(start 139.930886 -26.88971)
		(end 139.93114 -26.889964)
		(width 0.136652)
		(layer "F.Cu")
		(net "PCIE_TX_P80")
	)
	(segment
		(start 139.545314 -23.956772)
		(end 139.052046 -23.463758)
		(width 0.136652)
		(layer "F.Cu")
		(net "PCIE_TX_P80")
	)
	(segment
		(start 136.487662 -21.730208)
		(end 136.233154 -21.475192)
		(width 0.136652)
		(layer "F.Cu")
		(net "PCIE_TX_P80")
	)
	(segment
		(start 139.93114 -26.889964)
		(end 139.93114 -24.887428)
		(width 0.136652)
		(layer "F.Cu")
		(net "PCIE_TX_P80")
	)
	(segment
		(start 135.38454 -21.26488)
		(end 135.38454 -21.530056)
		(width 0.136652)
		(layer "F.Cu")
		(net "PCIE_TX_P80")
	)
	(segment
		(start 138.759438 -23.28291)
		(end 137.58291 -22.891242)
		(width 0.136652)
		(layer "F.Cu")
		(net "PCIE_TX_P80")
	)
	(segment
		(start 139.93114 -24.887428)
		(end 139.930886 -24.887682)
		(width 0.136652)
		(layer "F.Cu")
		(net "PCIE_TX_P80")
	)
	(arc
		(start 135.6614 -31.763716)
		(mid 135.71559 -31.490009)
		(end 135.870188 -31.257748)
		(width 0.136652)
		(layer "F.Cu")
		(net "PCIE_TX_P80")
	)
	(arc
		(start 135.868664 -21.052536)
		(mid 135.802496 -21.022994)
		(end 135.732774 -21.00326)
		(width 0.136652)
		(layer "F.Cu")
		(net "PCIE_TX_P80")
	)
	(arc
		(start 135.871966 -21.054314)
		(mid 135.870317 -21.053422)
		(end 135.868664 -21.052536)
		(width 0.136652)
		(layer "F.Cu")
		(net "PCIE_TX_P80")
	)
	(arc
		(start 139.727178 -27.383232)
		(mid 139.878016 -27.156688)
		(end 139.930886 -26.88971)
		(width 0.136652)
		(layer "F.Cu")
		(net "PCIE_TX_P80")
	)
	(arc
		(start 135.985758 -21.16582)
		(mid 135.933371 -21.105465)
		(end 135.871966 -21.054314)
		(width 0.136652)
		(layer "F.Cu")
		(net "PCIE_TX_P80")
	)
	(arc
		(start 135.637778 -21.006562)
		(mid 135.4953 -21.04951)
		(end 135.400288 -21.164042)
		(width 0.136652)
		(layer "F.Cu")
		(net "PCIE_TX_P80")
	)
	(arc
		(start 135.400288 -21.164042)
		(mid 135.388532 -21.213855)
		(end 135.38454 -21.26488)
		(width 0.136652)
		(layer "F.Cu")
		(net "PCIE_TX_P80")
	)
	(arc
		(start 136.233154 -21.475192)
		(mid 136.13706 -21.368645)
		(end 136.05256 -21.252688)
		(width 0.136652)
		(layer "F.Cu")
		(net "PCIE_TX_P80")
	)
	(arc
		(start 135.3693 -33.09874)
		(mid 135.582751 -32.896749)
		(end 135.6614 -32.6136)
		(width 0.136652)
		(layer "F.Cu")
		(net "PCIE_TX_P80")
	)
	(arc
		(start 139.052046 -23.463758)
		(mid 138.916295 -23.356255)
		(end 138.759438 -23.28291)
		(width 0.136652)
		(layer "F.Cu")
		(net "PCIE_TX_P80")
	)
	(arc
		(start 136.038082 -21.229828)
		(mid 136.011103 -21.198492)
		(end 135.985758 -21.16582)
		(width 0.136652)
		(layer "F.Cu")
		(net "PCIE_TX_P80")
	)
	(arc
		(start 137.58291 -22.891242)
		(mid 137.227248 -22.703641)
		(end 136.95045 -22.411944)
		(width 0.136652)
		(layer "F.Cu")
		(net "PCIE_TX_P80")
	)
	(arc
		(start 139.930886 -24.887682)
		(mid 139.927806 -24.798449)
		(end 139.918694 -24.709628)
		(width 0.136652)
		(layer "F.Cu")
		(net "PCIE_TX_P80")
	)
	(arc
		(start 136.05256 -21.252688)
		(mid 136.045265 -21.241293)
		(end 136.038082 -21.229828)
		(width 0.136652)
		(layer "F.Cu")
		(net "PCIE_TX_P80")
	)
	(arc
		(start 135.732774 -21.00326)
		(mid 135.685246 -21.004054)
		(end 135.637778 -21.006562)
		(width 0.136652)
		(layer "F.Cu")
		(net "PCIE_TX_P80")
	)
	(arc
		(start 139.918694 -24.709628)
		(mid 139.793707 -24.302596)
		(end 139.545314 -23.956772)
		(width 0.136652)
		(layer "F.Cu")
		(net "PCIE_TX_P80")
	)
	(segment
		(start 310.47309 -22.5933)
		(end 308.73954 -22.5933)
		(width 0.136652)
		(layer "F.Cu")
		(net "PCIE_TX_P8")
	)
	(segment
		(start 310.916066 -21.140674)
		(end 311.054242 -21.332698)
		(width 0.136652)
		(layer "F.Cu")
		(net "PCIE_TX_P8")
	)
	(segment
		(start 310.384444 -21.530056)
		(end 310.384444 -21.307806)
		(width 0.136652)
		(layer "F.Cu")
		(net "PCIE_TX_P8")
	)
	(segment
		(start 310.438546 -21.117306)
		(end 310.4642 -21.07565)
		(width 0.136652)
		(layer "F.Cu")
		(net "PCIE_TX_P8")
	)
	(segment
		(start 311.09539 -21.506688)
		(end 311.09539 -21.971)
		(width 0.136652)
		(layer "F.Cu")
		(net "PCIE_TX_P8")
	)
	(segment
		(start 306.221638 -25.067006)
		(end 306.221638 -32.5628)
		(width 0.136652)
		(layer "F.Cu")
		(net "PCIE_TX_P8")
	)
	(segment
		(start 307.672994 -23.035006)
		(end 306.632102 -24.075898)
		(width 0.136652)
		(layer "F.Cu")
		(net "PCIE_TX_P8")
	)
	(arc
		(start 308.73954 -22.5933)
		(mid 308.162343 -22.708094)
		(end 307.672994 -23.035006)
		(width 0.136652)
		(layer "F.Cu")
		(net "PCIE_TX_P8")
	)
	(arc
		(start 310.4642 -21.07565)
		(mid 310.560344 -20.994297)
		(end 310.685942 -20.985226)
		(width 0.136652)
		(layer "F.Cu")
		(net "PCIE_TX_P8")
	)
	(arc
		(start 311.09539 -21.971)
		(mid 310.913123 -22.411033)
		(end 310.47309 -22.5933)
		(width 0.136652)
		(layer "F.Cu")
		(net "PCIE_TX_P8")
	)
	(arc
		(start 306.221638 -32.5628)
		(mid 306.143457 -32.853453)
		(end 305.930046 -33.06572)
		(width 0.136652)
		(layer "F.Cu")
		(net "PCIE_TX_P8")
	)
	(arc
		(start 311.054242 -21.332698)
		(mid 311.084968 -21.417293)
		(end 311.09539 -21.506688)
		(width 0.136652)
		(layer "F.Cu")
		(net "PCIE_TX_P8")
	)
	(arc
		(start 310.384444 -21.307806)
		(mid 310.398231 -21.208789)
		(end 310.438546 -21.117306)
		(width 0.136652)
		(layer "F.Cu")
		(net "PCIE_TX_P8")
	)
	(arc
		(start 310.685942 -20.985226)
		(mid 310.814883 -21.042408)
		(end 310.916066 -21.140674)
		(width 0.136652)
		(layer "F.Cu")
		(net "PCIE_TX_P8")
	)
	(arc
		(start 306.632102 -24.075898)
		(mid 306.328294 -24.530623)
		(end 306.221638 -25.067006)
		(width 0.136652)
		(layer "F.Cu")
		(net "PCIE_TX_P8")
	)
	(segment
		(start 23.17369 -124.334016)
		(end 26.605992 -124.334016)
		(width 0.136652)
		(layer "F.Cu")
		(net "PCIE_TX_P76")
	)
	(segment
		(start 26.803858 -124.416058)
		(end 28.845764 -126.457964)
		(width 0.136652)
		(layer "F.Cu")
		(net "PCIE_TX_P76")
	)
	(segment
		(start 28.845764 -126.457964)
		(end 29.7434 -126.457964)
		(width 0.136652)
		(layer "F.Cu")
		(net "PCIE_TX_P76")
	)
	(arc
		(start 26.605992 -124.334016)
		(mid 26.713094 -124.355338)
		(end 26.803858 -124.416058)
		(width 0.136652)
		(layer "F.Cu")
		(net "PCIE_TX_P76")
	)
	(arc
		(start 29.7434 -126.457964)
		(mid 30.167403 -126.359674)
		(end 30.504892 -126.084838)
		(width 0.136652)
		(layer "F.Cu")
		(net "PCIE_TX_P76")
	)
	(segment
		(start 48.74768 -224.131378)
		(end 48.74768 -213.723474)
		(width 0.136652)
		(layer "F.Cu")
		(net "PCIE_TX_P75")
	)
	(segment
		(start 48.50003 -224.828608)
		(end 48.500284 -224.828354)
		(width 0.136652)
		(layer "F.Cu")
		(net "PCIE_TX_P75")
	)
	(segment
		(start 48.50003 -225.54438)
		(end 48.50003 -224.828608)
		(width 0.136652)
		(layer "F.Cu")
		(net "PCIE_TX_P75")
	)
	(arc
		(start 48.668432 -224.32264)
		(mid 48.727066 -224.234888)
		(end 48.74768 -224.131378)
		(width 0.136652)
		(layer "F.Cu")
		(net "PCIE_TX_P75")
	)
	(arc
		(start 48.74768 -213.723474)
		(mid 48.655261 -213.25885)
		(end 48.39208 -212.864954)
		(width 0.136652)
		(layer "F.Cu")
		(net "PCIE_TX_P75")
	)
	(arc
		(start 48.500284 -224.828354)
		(mid 48.543423 -224.561886)
		(end 48.668432 -224.32264)
		(width 0.136652)
		(layer "F.Cu")
		(net "PCIE_TX_P75")
	)
	(segment
		(start 51.700176 -225.54438)
		(end 51.700176 -224.828354)
		(width 0.136652)
		(layer "F.Cu")
		(net "PCIE_TX_P74")
	)
	(segment
		(start 51.947572 -224.131378)
		(end 51.947572 -213.723474)
		(width 0.136652)
		(layer "F.Cu")
		(net "PCIE_TX_P74")
	)
	(arc
		(start 51.947572 -213.723474)
		(mid 51.855153 -213.25885)
		(end 51.591972 -212.864954)
		(width 0.136652)
		(layer "F.Cu")
		(net "PCIE_TX_P74")
	)
	(arc
		(start 51.700176 -224.828354)
		(mid 51.743315 -224.561886)
		(end 51.868324 -224.32264)
		(width 0.136652)
		(layer "F.Cu")
		(net "PCIE_TX_P74")
	)
	(arc
		(start 51.868324 -224.32264)
		(mid 51.926958 -224.234888)
		(end 51.947572 -224.131378)
		(width 0.136652)
		(layer "F.Cu")
		(net "PCIE_TX_P74")
	)
	(segment
		(start 54.900068 -225.54438)
		(end 54.900068 -224.828608)
		(width 0.136652)
		(layer "F.Cu")
		(net "PCIE_TX_P73")
	)
	(segment
		(start 55.147718 -224.131378)
		(end 55.147718 -213.723474)
		(width 0.136652)
		(layer "F.Cu")
		(net "PCIE_TX_P73")
	)
	(segment
		(start 54.900068 -224.828608)
		(end 54.900322 -224.828354)
		(width 0.136652)
		(layer "F.Cu")
		(net "PCIE_TX_P73")
	)
	(arc
		(start 54.900322 -224.828354)
		(mid 54.943461 -224.561886)
		(end 55.06847 -224.32264)
		(width 0.136652)
		(layer "F.Cu")
		(net "PCIE_TX_P73")
	)
	(arc
		(start 55.06847 -224.32264)
		(mid 55.127104 -224.234888)
		(end 55.147718 -224.131378)
		(width 0.136652)
		(layer "F.Cu")
		(net "PCIE_TX_P73")
	)
	(arc
		(start 55.147718 -213.723474)
		(mid 55.055299 -213.25885)
		(end 54.792118 -212.864954)
		(width 0.136652)
		(layer "F.Cu")
		(net "PCIE_TX_P73")
	)
	(segment
		(start 58.09996 -224.828608)
		(end 58.100214 -224.828354)
		(width 0.136652)
		(layer "F.Cu")
		(net "PCIE_TX_P72")
	)
	(segment
		(start 58.09996 -225.54438)
		(end 58.09996 -224.828608)
		(width 0.136652)
		(layer "F.Cu")
		(net "PCIE_TX_P72")
	)
	(segment
		(start 58.34761 -224.131378)
		(end 58.34761 -213.723474)
		(width 0.136652)
		(layer "F.Cu")
		(net "PCIE_TX_P72")
	)
	(arc
		(start 58.268362 -224.32264)
		(mid 58.326996 -224.234888)
		(end 58.34761 -224.131378)
		(width 0.136652)
		(layer "F.Cu")
		(net "PCIE_TX_P72")
	)
	(arc
		(start 58.34761 -213.723474)
		(mid 58.255191 -213.25885)
		(end 57.99201 -212.864954)
		(width 0.136652)
		(layer "F.Cu")
		(net "PCIE_TX_P72")
	)
	(arc
		(start 58.100214 -224.828354)
		(mid 58.143353 -224.561886)
		(end 58.268362 -224.32264)
		(width 0.136652)
		(layer "F.Cu")
		(net "PCIE_TX_P72")
	)
	(segment
		(start 63.947548 -224.131378)
		(end 63.947548 -213.723474)
		(width 0.136652)
		(layer "F.Cu")
		(net "PCIE_TX_P71")
	)
	(segment
		(start 63.700152 -225.54438)
		(end 63.700152 -224.828354)
		(width 0.136652)
		(layer "F.Cu")
		(net "PCIE_TX_P71")
	)
	(arc
		(start 63.8683 -224.32264)
		(mid 63.926934 -224.234888)
		(end 63.947548 -224.131378)
		(width 0.136652)
		(layer "F.Cu")
		(net "PCIE_TX_P71")
	)
	(arc
		(start 63.947548 -213.723474)
		(mid 63.855129 -213.25885)
		(end 63.591948 -212.864954)
		(width 0.136652)
		(layer "F.Cu")
		(net "PCIE_TX_P71")
	)
	(arc
		(start 63.700152 -224.828354)
		(mid 63.743291 -224.561886)
		(end 63.8683 -224.32264)
		(width 0.136652)
		(layer "F.Cu")
		(net "PCIE_TX_P71")
	)
	(segment
		(start 67.147694 -224.131378)
		(end 67.147694 -213.723474)
		(width 0.136652)
		(layer "F.Cu")
		(net "PCIE_TX_P70")
	)
	(segment
		(start 66.900044 -224.828608)
		(end 66.900298 -224.828354)
		(width 0.136652)
		(layer "F.Cu")
		(net "PCIE_TX_P70")
	)
	(segment
		(start 66.900044 -225.54438)
		(end 66.900044 -224.828608)
		(width 0.136652)
		(layer "F.Cu")
		(net "PCIE_TX_P70")
	)
	(arc
		(start 67.147694 -213.723474)
		(mid 67.055275 -213.25885)
		(end 66.792094 -212.864954)
		(width 0.136652)
		(layer "F.Cu")
		(net "PCIE_TX_P70")
	)
	(arc
		(start 66.900298 -224.828354)
		(mid 66.943437 -224.561886)
		(end 67.068446 -224.32264)
		(width 0.136652)
		(layer "F.Cu")
		(net "PCIE_TX_P70")
	)
	(arc
		(start 67.068446 -224.32264)
		(mid 67.12708 -224.234888)
		(end 67.147694 -224.131378)
		(width 0.136652)
		(layer "F.Cu")
		(net "PCIE_TX_P70")
	)
	(segment
		(start 302.345344 -21.6916)
		(end 302.34509 -21.6916)
		(width 0.136652)
		(layer "F.Cu")
		(net "PCIE_TX_P7")
	)
	(segment
		(start 301.820326 -20.977606)
		(end 301.87011 -20.977606)
		(width 0.136652)
		(layer "F.Cu")
		(net "PCIE_TX_P7")
	)
	(segment
		(start 304.0634 -24.119332)
		(end 304.0634 -32.639)
		(width 0.136652)
		(layer "F.Cu")
		(net "PCIE_TX_P7")
	)
	(segment
		(start 302.6029 -22.3139)
		(end 303.819306 -23.530306)
		(width 0.136652)
		(layer "F.Cu")
		(net "PCIE_TX_P7")
	)
	(segment
		(start 302.34509 -21.691854)
		(end 302.344836 -21.6916)
		(width 0.136652)
		(layer "F.Cu")
		(net "PCIE_TX_P7")
	)
	(segment
		(start 301.634398 -21.530056)
		(end 301.634398 -21.18106)
		(width 0.136652)
		(layer "F.Cu")
		(net "PCIE_TX_P7")
	)
	(segment
		(start 302.345344 -21.506688)
		(end 302.345344 -21.6916)
		(width 0.136652)
		(layer "F.Cu")
		(net "PCIE_TX_P7")
	)
	(segment
		(start 302.34509 -21.6916)
		(end 302.34509 -21.691854)
		(width 0.136652)
		(layer "F.Cu")
		(net "PCIE_TX_P7")
	)
	(segment
		(start 302.053498 -21.053552)
		(end 302.231298 -21.231352)
		(width 0.136652)
		(layer "F.Cu")
		(net "PCIE_TX_P7")
	)
	(arc
		(start 302.051212 -21.051266)
		(mid 302.052359 -21.052405)
		(end 302.053498 -21.053552)
		(width 0.136652)
		(layer "F.Cu")
		(net "PCIE_TX_P7")
	)
	(arc
		(start 302.231298 -21.231352)
		(mid 302.315706 -21.357677)
		(end 302.345344 -21.506688)
		(width 0.136652)
		(layer "F.Cu")
		(net "PCIE_TX_P7")
	)
	(arc
		(start 302.344836 -21.6916)
		(mid 302.411948 -22.028433)
		(end 302.6029 -22.3139)
		(width 0.136652)
		(layer "F.Cu")
		(net "PCIE_TX_P7")
	)
	(arc
		(start 301.87011 -20.977606)
		(mid 301.967858 -20.996733)
		(end 302.051212 -21.051266)
		(width 0.136652)
		(layer "F.Cu")
		(net "PCIE_TX_P7")
	)
	(arc
		(start 301.697644 -21.028406)
		(mid 301.753931 -20.990796)
		(end 301.820326 -20.977606)
		(width 0.136652)
		(layer "F.Cu")
		(net "PCIE_TX_P7")
	)
	(arc
		(start 303.819306 -23.530306)
		(mid 303.999963 -23.800538)
		(end 304.0634 -24.119332)
		(width 0.136652)
		(layer "F.Cu")
		(net "PCIE_TX_P7")
	)
	(arc
		(start 304.0634 -32.639)
		(mid 303.987748 -32.901508)
		(end 303.784 -33.0835)
		(width 0.136652)
		(layer "F.Cu")
		(net "PCIE_TX_P7")
	)
	(arc
		(start 301.634398 -21.18106)
		(mid 301.650832 -21.098439)
		(end 301.697644 -21.028406)
		(width 0.136652)
		(layer "F.Cu")
		(net "PCIE_TX_P7")
	)
	(segment
		(start 70.10019 -225.54438)
		(end 70.10019 -224.828354)
		(width 0.136652)
		(layer "F.Cu")
		(net "PCIE_TX_P69")
	)
	(segment
		(start 70.347586 -224.131378)
		(end 70.347586 -213.723474)
		(width 0.136652)
		(layer "F.Cu")
		(net "PCIE_TX_P69")
	)
	(arc
		(start 70.10019 -224.828354)
		(mid 70.143329 -224.561886)
		(end 70.268338 -224.32264)
		(width 0.136652)
		(layer "F.Cu")
		(net "PCIE_TX_P69")
	)
	(arc
		(start 70.347586 -213.723474)
		(mid 70.255167 -213.25885)
		(end 69.991986 -212.864954)
		(width 0.136652)
		(layer "F.Cu")
		(net "PCIE_TX_P69")
	)
	(arc
		(start 70.268338 -224.32264)
		(mid 70.326972 -224.234888)
		(end 70.347586 -224.131378)
		(width 0.136652)
		(layer "F.Cu")
		(net "PCIE_TX_P69")
	)
	(segment
		(start 79.70012 -225.54438)
		(end 79.70012 -224.828354)
		(width 0.136652)
		(layer "F.Cu")
		(net "PCIE_TX_P68")
	)
	(segment
		(start 79.947516 -224.131378)
		(end 79.947516 -213.723474)
		(width 0.136652)
		(layer "F.Cu")
		(net "PCIE_TX_P68")
	)
	(arc
		(start 79.947516 -213.723474)
		(mid 79.855097 -213.25885)
		(end 79.591916 -212.864954)
		(width 0.136652)
		(layer "F.Cu")
		(net "PCIE_TX_P68")
	)
	(arc
		(start 79.70012 -224.828354)
		(mid 79.743259 -224.561886)
		(end 79.868268 -224.32264)
		(width 0.136652)
		(layer "F.Cu")
		(net "PCIE_TX_P68")
	)
	(arc
		(start 79.868268 -224.32264)
		(mid 79.926902 -224.234888)
		(end 79.947516 -224.131378)
		(width 0.136652)
		(layer "F.Cu")
		(net "PCIE_TX_P68")
	)
	(segment
		(start 82.900012 -224.828608)
		(end 82.900266 -224.828354)
		(width 0.136652)
		(layer "F.Cu")
		(net "PCIE_TX_P67")
	)
	(segment
		(start 82.900012 -225.54438)
		(end 82.900012 -224.828608)
		(width 0.136652)
		(layer "F.Cu")
		(net "PCIE_TX_P67")
	)
	(segment
		(start 83.147662 -224.131378)
		(end 83.147662 -213.723474)
		(width 0.136652)
		(layer "F.Cu")
		(net "PCIE_TX_P67")
	)
	(arc
		(start 83.068414 -224.32264)
		(mid 83.127048 -224.234888)
		(end 83.147662 -224.131378)
		(width 0.136652)
		(layer "F.Cu")
		(net "PCIE_TX_P67")
	)
	(arc
		(start 83.147662 -213.723474)
		(mid 83.055243 -213.25885)
		(end 82.792062 -212.864954)
		(width 0.136652)
		(layer "F.Cu")
		(net "PCIE_TX_P67")
	)
	(arc
		(start 82.900266 -224.828354)
		(mid 82.943405 -224.561886)
		(end 83.068414 -224.32264)
		(width 0.136652)
		(layer "F.Cu")
		(net "PCIE_TX_P67")
	)
	(segment
		(start 86.347554 -224.131378)
		(end 86.347554 -213.723474)
		(width 0.136652)
		(layer "F.Cu")
		(net "PCIE_TX_P66")
	)
	(segment
		(start 86.100158 -225.54438)
		(end 86.100158 -224.828354)
		(width 0.136652)
		(layer "F.Cu")
		(net "PCIE_TX_P66")
	)
	(arc
		(start 86.347554 -213.723474)
		(mid 86.255135 -213.25885)
		(end 85.991954 -212.864954)
		(width 0.136652)
		(layer "F.Cu")
		(net "PCIE_TX_P66")
	)
	(arc
		(start 86.100158 -224.828354)
		(mid 86.143297 -224.561886)
		(end 86.268306 -224.32264)
		(width 0.136652)
		(layer "F.Cu")
		(net "PCIE_TX_P66")
	)
	(arc
		(start 86.268306 -224.32264)
		(mid 86.32694 -224.234888)
		(end 86.347554 -224.131378)
		(width 0.136652)
		(layer "F.Cu")
		(net "PCIE_TX_P66")
	)
	(segment
		(start 89.30005 -224.828608)
		(end 89.300304 -224.828354)
		(width 0.136652)
		(layer "F.Cu")
		(net "PCIE_TX_P65")
	)
	(segment
		(start 89.30005 -225.54438)
		(end 89.30005 -224.828608)
		(width 0.136652)
		(layer "F.Cu")
		(net "PCIE_TX_P65")
	)
	(segment
		(start 89.5477 -224.131378)
		(end 89.5477 -213.723474)
		(width 0.136652)
		(layer "F.Cu")
		(net "PCIE_TX_P65")
	)
	(arc
		(start 89.468452 -224.32264)
		(mid 89.527086 -224.234888)
		(end 89.5477 -224.131378)
		(width 0.136652)
		(layer "F.Cu")
		(net "PCIE_TX_P65")
	)
	(arc
		(start 89.5477 -213.723474)
		(mid 89.455281 -213.25885)
		(end 89.1921 -212.864954)
		(width 0.136652)
		(layer "F.Cu")
		(net "PCIE_TX_P65")
	)
	(arc
		(start 89.300304 -224.828354)
		(mid 89.343443 -224.561886)
		(end 89.468452 -224.32264)
		(width 0.136652)
		(layer "F.Cu")
		(net "PCIE_TX_P65")
	)
	(segment
		(start 92.747592 -224.131378)
		(end 92.747592 -213.723474)
		(width 0.136652)
		(layer "F.Cu")
		(net "PCIE_TX_P64")
	)
	(segment
		(start 92.500196 -225.54438)
		(end 92.500196 -224.828354)
		(width 0.136652)
		(layer "F.Cu")
		(net "PCIE_TX_P64")
	)
	(arc
		(start 92.668344 -224.32264)
		(mid 92.726978 -224.234888)
		(end 92.747592 -224.131378)
		(width 0.136652)
		(layer "F.Cu")
		(net "PCIE_TX_P64")
	)
	(arc
		(start 92.500196 -224.828354)
		(mid 92.543335 -224.561886)
		(end 92.668344 -224.32264)
		(width 0.136652)
		(layer "F.Cu")
		(net "PCIE_TX_P64")
	)
	(arc
		(start 92.747592 -213.723474)
		(mid 92.655173 -213.25885)
		(end 92.391992 -212.864954)
		(width 0.136652)
		(layer "F.Cu")
		(net "PCIE_TX_P64")
	)
	(segment
		(start 98.100134 -225.54438)
		(end 98.100134 -224.828608)
		(width 0.136652)
		(layer "F.Cu")
		(net "PCIE_TX_P63")
	)
	(segment
		(start 98.100134 -224.828608)
		(end 98.100388 -224.828354)
		(width 0.136652)
		(layer "F.Cu")
		(net "PCIE_TX_P63")
	)
	(segment
		(start 98.347784 -224.131378)
		(end 98.347784 -213.723474)
		(width 0.136652)
		(layer "F.Cu")
		(net "PCIE_TX_P63")
	)
	(arc
		(start 98.100388 -224.828354)
		(mid 98.143527 -224.561886)
		(end 98.268536 -224.32264)
		(width 0.136652)
		(layer "F.Cu")
		(net "PCIE_TX_P63")
	)
	(arc
		(start 98.347784 -213.723474)
		(mid 98.255365 -213.25885)
		(end 97.992184 -212.864954)
		(width 0.136652)
		(layer "F.Cu")
		(net "PCIE_TX_P63")
	)
	(arc
		(start 98.268536 -224.32264)
		(mid 98.32717 -224.234888)
		(end 98.347784 -224.131378)
		(width 0.136652)
		(layer "F.Cu")
		(net "PCIE_TX_P63")
	)
	(segment
		(start 101.300026 -225.54438)
		(end 101.300026 -224.828608)
		(width 0.136652)
		(layer "F.Cu")
		(net "PCIE_TX_P62")
	)
	(segment
		(start 101.547676 -224.131378)
		(end 101.547676 -213.723474)
		(width 0.136652)
		(layer "F.Cu")
		(net "PCIE_TX_P62")
	)
	(segment
		(start 101.300026 -224.828608)
		(end 101.30028 -224.828354)
		(width 0.136652)
		(layer "F.Cu")
		(net "PCIE_TX_P62")
	)
	(arc
		(start 101.30028 -224.828354)
		(mid 101.343419 -224.561886)
		(end 101.468428 -224.32264)
		(width 0.136652)
		(layer "F.Cu")
		(net "PCIE_TX_P62")
	)
	(arc
		(start 101.547676 -213.723474)
		(mid 101.455257 -213.25885)
		(end 101.192076 -212.864954)
		(width 0.136652)
		(layer "F.Cu")
		(net "PCIE_TX_P62")
	)
	(arc
		(start 101.468428 -224.32264)
		(mid 101.527062 -224.234888)
		(end 101.547676 -224.131378)
		(width 0.136652)
		(layer "F.Cu")
		(net "PCIE_TX_P62")
	)
	(segment
		(start 104.747822 -224.131378)
		(end 104.747822 -213.723474)
		(width 0.136652)
		(layer "F.Cu")
		(net "PCIE_TX_P61")
	)
	(segment
		(start 104.500172 -224.828608)
		(end 104.500426 -224.828354)
		(width 0.136652)
		(layer "F.Cu")
		(net "PCIE_TX_P61")
	)
	(segment
		(start 104.500172 -225.54438)
		(end 104.500172 -224.828608)
		(width 0.136652)
		(layer "F.Cu")
		(net "PCIE_TX_P61")
	)
	(arc
		(start 104.668574 -224.32264)
		(mid 104.727208 -224.234888)
		(end 104.747822 -224.131378)
		(width 0.136652)
		(layer "F.Cu")
		(net "PCIE_TX_P61")
	)
	(arc
		(start 104.500426 -224.828354)
		(mid 104.543565 -224.561886)
		(end 104.668574 -224.32264)
		(width 0.136652)
		(layer "F.Cu")
		(net "PCIE_TX_P61")
	)
	(arc
		(start 104.747822 -213.723474)
		(mid 104.655403 -213.25885)
		(end 104.392222 -212.864954)
		(width 0.136652)
		(layer "F.Cu")
		(net "PCIE_TX_P61")
	)
	(segment
		(start 107.947714 -224.131378)
		(end 107.947714 -213.723474)
		(width 0.136652)
		(layer "F.Cu")
		(net "PCIE_TX_P60")
	)
	(segment
		(start 107.700064 -224.828608)
		(end 107.700318 -224.828354)
		(width 0.136652)
		(layer "F.Cu")
		(net "PCIE_TX_P60")
	)
	(segment
		(start 107.700064 -225.54438)
		(end 107.700064 -224.828608)
		(width 0.136652)
		(layer "F.Cu")
		(net "PCIE_TX_P60")
	)
	(arc
		(start 107.947714 -213.723474)
		(mid 107.855295 -213.25885)
		(end 107.592114 -212.864954)
		(width 0.136652)
		(layer "F.Cu")
		(net "PCIE_TX_P60")
	)
	(arc
		(start 107.868466 -224.32264)
		(mid 107.9271 -224.234888)
		(end 107.947714 -224.131378)
		(width 0.136652)
		(layer "F.Cu")
		(net "PCIE_TX_P60")
	)
	(arc
		(start 107.700318 -224.828354)
		(mid 107.743457 -224.561886)
		(end 107.868466 -224.32264)
		(width 0.136652)
		(layer "F.Cu")
		(net "PCIE_TX_P60")
	)
	(segment
		(start 302.345344 -25.306782)
		(end 302.345344 -26.042112)
		(width 0.136652)
		(layer "F.Cu")
		(net "PCIE_TX_P6")
	)
	(segment
		(start 301.888144 -26.97607)
		(end 301.888144 -32.7152)
		(width 0.136652)
		(layer "F.Cu")
		(net "PCIE_TX_P6")
	)
	(segment
		(start 301.88789 -26.975816)
		(end 301.888144 -26.97607)
		(width 0.136652)
		(layer "F.Cu")
		(net "PCIE_TX_P6")
	)
	(segment
		(start 302.224694 -26.33345)
		(end 302.10252 -26.455624)
		(width 0.136652)
		(layer "F.Cu")
		(net "PCIE_TX_P6")
	)
	(segment
		(start 301.888144 -26.975816)
		(end 301.88789 -26.975816)
		(width 0.136652)
		(layer "F.Cu")
		(net "PCIE_TX_P6")
	)
	(segment
		(start 301.634398 -25.33015)
		(end 301.634398 -24.981154)
		(width 0.136652)
		(layer "F.Cu")
		(net "PCIE_TX_P6")
	)
	(segment
		(start 301.820326 -24.7777)
		(end 301.87011 -24.7777)
		(width 0.136652)
		(layer "F.Cu")
		(net "PCIE_TX_P6")
	)
	(segment
		(start 302.053498 -24.853646)
		(end 302.231298 -25.031446)
		(width 0.136652)
		(layer "F.Cu")
		(net "PCIE_TX_P6")
	)
	(arc
		(start 302.231298 -25.031446)
		(mid 302.315706 -25.157771)
		(end 302.345344 -25.306782)
		(width 0.136652)
		(layer "F.Cu")
		(net "PCIE_TX_P6")
	)
	(arc
		(start 301.634398 -24.981154)
		(mid 301.650832 -24.898533)
		(end 301.697644 -24.8285)
		(width 0.136652)
		(layer "F.Cu")
		(net "PCIE_TX_P6")
	)
	(arc
		(start 302.051212 -24.85136)
		(mid 302.052359 -24.852499)
		(end 302.053498 -24.853646)
		(width 0.136652)
		(layer "F.Cu")
		(net "PCIE_TX_P6")
	)
	(arc
		(start 302.345344 -26.042112)
		(mid 302.313983 -26.199773)
		(end 302.224694 -26.33345)
		(width 0.136652)
		(layer "F.Cu")
		(net "PCIE_TX_P6")
	)
	(arc
		(start 301.697644 -24.8285)
		(mid 301.753931 -24.79089)
		(end 301.820326 -24.7777)
		(width 0.136652)
		(layer "F.Cu")
		(net "PCIE_TX_P6")
	)
	(arc
		(start 302.030638 -26.539444)
		(mid 301.924558 -26.746259)
		(end 301.888144 -26.975816)
		(width 0.136652)
		(layer "F.Cu")
		(net "PCIE_TX_P6")
	)
	(arc
		(start 301.888144 -32.7152)
		(mid 301.81072 -32.951326)
		(end 301.60849 -33.095692)
		(width 0.136652)
		(layer "F.Cu")
		(net "PCIE_TX_P6")
	)
	(arc
		(start 301.87011 -24.7777)
		(mid 301.967858 -24.796827)
		(end 302.051212 -24.85136)
		(width 0.136652)
		(layer "F.Cu")
		(net "PCIE_TX_P6")
	)
	(arc
		(start 302.10252 -26.455624)
		(mid 302.064969 -26.496153)
		(end 302.030638 -26.539444)
		(width 0.136652)
		(layer "F.Cu")
		(net "PCIE_TX_P6")
	)
	(segment
		(start 138.500104 -224.828608)
		(end 138.500358 -224.828354)
		(width 0.136652)
		(layer "F.Cu")
		(net "PCIE_TX_P59")
	)
	(segment
		(start 138.747754 -224.131378)
		(end 138.747754 -213.723474)
		(width 0.136652)
		(layer "F.Cu")
		(net "PCIE_TX_P59")
	)
	(segment
		(start 138.500104 -225.54438)
		(end 138.500104 -224.828608)
		(width 0.136652)
		(layer "F.Cu")
		(net "PCIE_TX_P59")
	)
	(arc
		(start 138.747754 -213.723474)
		(mid 138.655335 -213.25885)
		(end 138.392154 -212.864954)
		(width 0.136652)
		(layer "F.Cu")
		(net "PCIE_TX_P59")
	)
	(arc
		(start 138.500358 -224.828354)
		(mid 138.543497 -224.561886)
		(end 138.668506 -224.32264)
		(width 0.136652)
		(layer "F.Cu")
		(net "PCIE_TX_P59")
	)
	(arc
		(start 138.668506 -224.32264)
		(mid 138.72714 -224.234888)
		(end 138.747754 -224.131378)
		(width 0.136652)
		(layer "F.Cu")
		(net "PCIE_TX_P59")
	)
	(segment
		(start 141.9479 -224.131378)
		(end 141.9479 -213.723474)
		(width 0.136652)
		(layer "F.Cu")
		(net "PCIE_TX_P58")
	)
	(segment
		(start 141.699996 -225.54438)
		(end 141.699996 -224.828862)
		(width 0.136652)
		(layer "F.Cu")
		(net "PCIE_TX_P58")
	)
	(segment
		(start 141.592554 -212.865208)
		(end 141.592046 -212.864954)
		(width 0.136652)
		(layer "F.Cu")
		(net "PCIE_TX_P58")
	)
	(segment
		(start 141.699996 -224.828862)
		(end 141.700504 -224.828354)
		(width 0.136652)
		(layer "F.Cu")
		(net "PCIE_TX_P58")
	)
	(arc
		(start 141.9479 -213.723474)
		(mid 141.855602 -213.258991)
		(end 141.592554 -212.865208)
		(width 0.136652)
		(layer "F.Cu")
		(net "PCIE_TX_P58")
	)
	(arc
		(start 141.700504 -224.828354)
		(mid 141.743643 -224.561886)
		(end 141.868652 -224.32264)
		(width 0.136652)
		(layer "F.Cu")
		(net "PCIE_TX_P58")
	)
	(arc
		(start 141.868652 -224.32264)
		(mid 141.927286 -224.234888)
		(end 141.9479 -224.131378)
		(width 0.136652)
		(layer "F.Cu")
		(net "PCIE_TX_P58")
	)
	(segment
		(start 145.147792 -224.131378)
		(end 145.147792 -213.723474)
		(width 0.136652)
		(layer "F.Cu")
		(net "PCIE_TX_P57")
	)
	(segment
		(start 144.900142 -225.54438)
		(end 144.900142 -224.828608)
		(width 0.136652)
		(layer "F.Cu")
		(net "PCIE_TX_P57")
	)
	(segment
		(start 144.900142 -224.828608)
		(end 144.900396 -224.828354)
		(width 0.136652)
		(layer "F.Cu")
		(net "PCIE_TX_P57")
	)
	(arc
		(start 145.068544 -224.32264)
		(mid 145.127178 -224.234888)
		(end 145.147792 -224.131378)
		(width 0.136652)
		(layer "F.Cu")
		(net "PCIE_TX_P57")
	)
	(arc
		(start 144.900396 -224.828354)
		(mid 144.943535 -224.561886)
		(end 145.068544 -224.32264)
		(width 0.136652)
		(layer "F.Cu")
		(net "PCIE_TX_P57")
	)
	(arc
		(start 145.147792 -213.723474)
		(mid 145.055373 -213.25885)
		(end 144.792192 -212.864954)
		(width 0.136652)
		(layer "F.Cu")
		(net "PCIE_TX_P57")
	)
	(segment
		(start 148.347684 -224.131378)
		(end 148.347684 -213.723474)
		(width 0.136652)
		(layer "F.Cu")
		(net "PCIE_TX_P56")
	)
	(segment
		(start 148.100034 -225.54438)
		(end 148.100034 -224.828608)
		(width 0.136652)
		(layer "F.Cu")
		(net "PCIE_TX_P56")
	)
	(segment
		(start 148.100034 -224.828608)
		(end 148.100288 -224.828354)
		(width 0.136652)
		(layer "F.Cu")
		(net "PCIE_TX_P56")
	)
	(arc
		(start 148.347684 -213.723474)
		(mid 148.255265 -213.25885)
		(end 147.992084 -212.864954)
		(width 0.136652)
		(layer "F.Cu")
		(net "PCIE_TX_P56")
	)
	(arc
		(start 148.268436 -224.32264)
		(mid 148.32707 -224.234888)
		(end 148.347684 -224.131378)
		(width 0.136652)
		(layer "F.Cu")
		(net "PCIE_TX_P56")
	)
	(arc
		(start 148.100288 -224.828354)
		(mid 148.143427 -224.561886)
		(end 148.268436 -224.32264)
		(width 0.136652)
		(layer "F.Cu")
		(net "PCIE_TX_P56")
	)
	(segment
		(start 151.54783 -224.131378)
		(end 151.54783 -213.723474)
		(width 0.136652)
		(layer "F.Cu")
		(net "PCIE_TX_P55")
	)
	(segment
		(start 151.30018 -225.54438)
		(end 151.30018 -224.828608)
		(width 0.136652)
		(layer "F.Cu")
		(net "PCIE_TX_P55")
	)
	(segment
		(start 151.30018 -224.828608)
		(end 151.300434 -224.828354)
		(width 0.136652)
		(layer "F.Cu")
		(net "PCIE_TX_P55")
	)
	(arc
		(start 151.54783 -213.723474)
		(mid 151.455411 -213.25885)
		(end 151.19223 -212.864954)
		(width 0.136652)
		(layer "F.Cu")
		(net "PCIE_TX_P55")
	)
	(arc
		(start 151.300434 -224.828354)
		(mid 151.343573 -224.561886)
		(end 151.468582 -224.32264)
		(width 0.136652)
		(layer "F.Cu")
		(net "PCIE_TX_P55")
	)
	(arc
		(start 151.468582 -224.32264)
		(mid 151.527216 -224.234888)
		(end 151.54783 -224.131378)
		(width 0.136652)
		(layer "F.Cu")
		(net "PCIE_TX_P55")
	)
	(segment
		(start 154.747722 -224.131378)
		(end 154.747722 -213.723474)
		(width 0.136652)
		(layer "F.Cu")
		(net "PCIE_TX_P54")
	)
	(segment
		(start 154.500072 -224.828608)
		(end 154.500326 -224.828354)
		(width 0.136652)
		(layer "F.Cu")
		(net "PCIE_TX_P54")
	)
	(segment
		(start 154.500072 -225.54438)
		(end 154.500072 -224.828608)
		(width 0.136652)
		(layer "F.Cu")
		(net "PCIE_TX_P54")
	)
	(arc
		(start 154.668474 -224.32264)
		(mid 154.727108 -224.234888)
		(end 154.747722 -224.131378)
		(width 0.136652)
		(layer "F.Cu")
		(net "PCIE_TX_P54")
	)
	(arc
		(start 154.747722 -213.723474)
		(mid 154.655303 -213.25885)
		(end 154.392122 -212.864954)
		(width 0.136652)
		(layer "F.Cu")
		(net "PCIE_TX_P54")
	)
	(arc
		(start 154.500326 -224.828354)
		(mid 154.543465 -224.561886)
		(end 154.668474 -224.32264)
		(width 0.136652)
		(layer "F.Cu")
		(net "PCIE_TX_P54")
	)
	(segment
		(start 157.947868 -224.131378)
		(end 157.947868 -213.723474)
		(width 0.136652)
		(layer "F.Cu")
		(net "PCIE_TX_P53")
	)
	(segment
		(start 157.700218 -225.54438)
		(end 157.700218 -224.828608)
		(width 0.136652)
		(layer "F.Cu")
		(net "PCIE_TX_P53")
	)
	(segment
		(start 157.700218 -224.828608)
		(end 157.700472 -224.828354)
		(width 0.136652)
		(layer "F.Cu")
		(net "PCIE_TX_P53")
	)
	(arc
		(start 157.86862 -224.32264)
		(mid 157.927254 -224.234888)
		(end 157.947868 -224.131378)
		(width 0.136652)
		(layer "F.Cu")
		(net "PCIE_TX_P53")
	)
	(arc
		(start 157.700472 -224.828354)
		(mid 157.743611 -224.561886)
		(end 157.86862 -224.32264)
		(width 0.136652)
		(layer "F.Cu")
		(net "PCIE_TX_P53")
	)
	(arc
		(start 157.947868 -213.723474)
		(mid 157.855449 -213.25885)
		(end 157.592268 -212.864954)
		(width 0.136652)
		(layer "F.Cu")
		(net "PCIE_TX_P53")
	)
	(segment
		(start 160.90011 -225.54438)
		(end 160.90011 -224.828608)
		(width 0.136652)
		(layer "F.Cu")
		(net "PCIE_TX_P52")
	)
	(segment
		(start 161.14776 -224.131378)
		(end 161.14776 -213.723474)
		(width 0.136652)
		(layer "F.Cu")
		(net "PCIE_TX_P52")
	)
	(segment
		(start 160.90011 -224.828608)
		(end 160.900364 -224.828354)
		(width 0.136652)
		(layer "F.Cu")
		(net "PCIE_TX_P52")
	)
	(arc
		(start 160.900364 -224.828354)
		(mid 160.943503 -224.561886)
		(end 161.068512 -224.32264)
		(width 0.136652)
		(layer "F.Cu")
		(net "PCIE_TX_P52")
	)
	(arc
		(start 161.068512 -224.32264)
		(mid 161.127146 -224.234888)
		(end 161.14776 -224.131378)
		(width 0.136652)
		(layer "F.Cu")
		(net "PCIE_TX_P52")
	)
	(arc
		(start 161.14776 -213.723474)
		(mid 161.055341 -213.25885)
		(end 160.79216 -212.864954)
		(width 0.136652)
		(layer "F.Cu")
		(net "PCIE_TX_P52")
	)
	(segment
		(start 166.500048 -225.54438)
		(end 166.500048 -224.828608)
		(width 0.136652)
		(layer "F.Cu")
		(net "PCIE_TX_P51")
	)
	(segment
		(start 166.747698 -224.131378)
		(end 166.747698 -213.723474)
		(width 0.136652)
		(layer "F.Cu")
		(net "PCIE_TX_P51")
	)
	(segment
		(start 166.500048 -224.828608)
		(end 166.500302 -224.828354)
		(width 0.136652)
		(layer "F.Cu")
		(net "PCIE_TX_P51")
	)
	(arc
		(start 166.500302 -224.828354)
		(mid 166.543441 -224.561886)
		(end 166.66845 -224.32264)
		(width 0.136652)
		(layer "F.Cu")
		(net "PCIE_TX_P51")
	)
	(arc
		(start 166.66845 -224.32264)
		(mid 166.727084 -224.234888)
		(end 166.747698 -224.131378)
		(width 0.136652)
		(layer "F.Cu")
		(net "PCIE_TX_P51")
	)
	(arc
		(start 166.747698 -213.723474)
		(mid 166.655279 -213.25885)
		(end 166.392098 -212.864954)
		(width 0.136652)
		(layer "F.Cu")
		(net "PCIE_TX_P51")
	)
	(segment
		(start 169.700194 -225.54438)
		(end 169.700194 -224.828354)
		(width 0.136652)
		(layer "F.Cu")
		(net "PCIE_TX_P50")
	)
	(segment
		(start 169.94759 -224.131378)
		(end 169.94759 -213.723474)
		(width 0.136652)
		(layer "F.Cu")
		(net "PCIE_TX_P50")
	)
	(arc
		(start 169.868342 -224.32264)
		(mid 169.926976 -224.234888)
		(end 169.94759 -224.131378)
		(width 0.136652)
		(layer "F.Cu")
		(net "PCIE_TX_P50")
	)
	(arc
		(start 169.700194 -224.828354)
		(mid 169.743333 -224.561886)
		(end 169.868342 -224.32264)
		(width 0.136652)
		(layer "F.Cu")
		(net "PCIE_TX_P50")
	)
	(arc
		(start 169.94759 -213.723474)
		(mid 169.855171 -213.25885)
		(end 169.59199 -212.864954)
		(width 0.136652)
		(layer "F.Cu")
		(net "PCIE_TX_P50")
	)
	(segment
		(start 299.384466 -25.33015)
		(end 299.384466 -24.981154)
		(width 0.136652)
		(layer "F.Cu")
		(net "PCIE_TX_P5")
	)
	(segment
		(start 299.638212 -26.975816)
		(end 299.638212 -32.6898)
		(width 0.136652)
		(layer "F.Cu")
		(net "PCIE_TX_P5")
	)
	(segment
		(start 299.974762 -26.33345)
		(end 299.852588 -26.455624)
		(width 0.136652)
		(layer "F.Cu")
		(net "PCIE_TX_P5")
	)
	(segment
		(start 299.803566 -24.853646)
		(end 299.981366 -25.031446)
		(width 0.136652)
		(layer "F.Cu")
		(net "PCIE_TX_P5")
	)
	(segment
		(start 300.095412 -25.306782)
		(end 300.095412 -26.042112)
		(width 0.136652)
		(layer "F.Cu")
		(net "PCIE_TX_P5")
	)
	(arc
		(start 299.981366 -25.031446)
		(mid 300.065774 -25.157771)
		(end 300.095412 -25.306782)
		(width 0.136652)
		(layer "F.Cu")
		(net "PCIE_TX_P5")
	)
	(arc
		(start 299.852588 -26.455624)
		(mid 299.815037 -26.496153)
		(end 299.780706 -26.539444)
		(width 0.136652)
		(layer "F.Cu")
		(net "PCIE_TX_P5")
	)
	(arc
		(start 299.638212 -32.6898)
		(mid 299.568583 -32.938877)
		(end 299.379894 -33.115758)
		(width 0.136652)
		(layer "F.Cu")
		(net "PCIE_TX_P5")
	)
	(arc
		(start 299.384466 -24.981154)
		(mid 299.493303 -24.78153)
		(end 299.72 -24.765)
		(width 0.136652)
		(layer "F.Cu")
		(net "PCIE_TX_P5")
	)
	(arc
		(start 299.780706 -26.539444)
		(mid 299.674626 -26.746259)
		(end 299.638212 -26.975816)
		(width 0.136652)
		(layer "F.Cu")
		(net "PCIE_TX_P5")
	)
	(arc
		(start 300.095412 -26.042112)
		(mid 300.064051 -26.199773)
		(end 299.974762 -26.33345)
		(width 0.136652)
		(layer "F.Cu")
		(net "PCIE_TX_P5")
	)
	(arc
		(start 299.72 -24.765)
		(mid 299.759986 -24.808796)
		(end 299.80128 -24.85136)
		(width 0.136652)
		(layer "F.Cu")
		(net "PCIE_TX_P5")
	)
	(arc
		(start 299.80128 -24.85136)
		(mid 299.802427 -24.852499)
		(end 299.803566 -24.853646)
		(width 0.136652)
		(layer "F.Cu")
		(net "PCIE_TX_P5")
	)
	(segment
		(start 172.900086 -225.54438)
		(end 172.900086 -224.828608)
		(width 0.136652)
		(layer "F.Cu")
		(net "PCIE_TX_P49")
	)
	(segment
		(start 173.147736 -224.131378)
		(end 173.147736 -213.723474)
		(width 0.136652)
		(layer "F.Cu")
		(net "PCIE_TX_P49")
	)
	(segment
		(start 172.900086 -224.828608)
		(end 172.90034 -224.828354)
		(width 0.136652)
		(layer "F.Cu")
		(net "PCIE_TX_P49")
	)
	(arc
		(start 173.147736 -213.723474)
		(mid 173.055317 -213.25885)
		(end 172.792136 -212.864954)
		(width 0.136652)
		(layer "F.Cu")
		(net "PCIE_TX_P49")
	)
	(arc
		(start 172.90034 -224.828354)
		(mid 172.943479 -224.561886)
		(end 173.068488 -224.32264)
		(width 0.136652)
		(layer "F.Cu")
		(net "PCIE_TX_P49")
	)
	(arc
		(start 173.068488 -224.32264)
		(mid 173.127122 -224.234888)
		(end 173.147736 -224.131378)
		(width 0.136652)
		(layer "F.Cu")
		(net "PCIE_TX_P49")
	)
	(segment
		(start 176.347628 -224.131378)
		(end 176.347628 -213.723474)
		(width 0.136652)
		(layer "F.Cu")
		(net "PCIE_TX_P48")
	)
	(segment
		(start 176.100232 -225.54438)
		(end 176.100232 -224.828354)
		(width 0.136652)
		(layer "F.Cu")
		(net "PCIE_TX_P48")
	)
	(arc
		(start 176.347628 -213.723474)
		(mid 176.255209 -213.25885)
		(end 175.992028 -212.864954)
		(width 0.136652)
		(layer "F.Cu")
		(net "PCIE_TX_P48")
	)
	(arc
		(start 176.100232 -224.828354)
		(mid 176.143371 -224.561886)
		(end 176.26838 -224.32264)
		(width 0.136652)
		(layer "F.Cu")
		(net "PCIE_TX_P48")
	)
	(arc
		(start 176.26838 -224.32264)
		(mid 176.327014 -224.234888)
		(end 176.347628 -224.131378)
		(width 0.136652)
		(layer "F.Cu")
		(net "PCIE_TX_P48")
	)
	(segment
		(start 184.100216 -225.54438)
		(end 184.100216 -224.828354)
		(width 0.136652)
		(layer "F.Cu")
		(net "PCIE_TX_P47")
	)
	(segment
		(start 184.347612 -224.131378)
		(end 184.347612 -213.722712)
		(width 0.136652)
		(layer "F.Cu")
		(net "PCIE_TX_P47")
	)
	(arc
		(start 184.268364 -224.32264)
		(mid 184.326998 -224.234888)
		(end 184.347612 -224.131378)
		(width 0.136652)
		(layer "F.Cu")
		(net "PCIE_TX_P47")
	)
	(arc
		(start 184.347612 -213.722712)
		(mid 184.25527 -213.258477)
		(end 183.992266 -212.864954)
		(width 0.136652)
		(layer "F.Cu")
		(net "PCIE_TX_P47")
	)
	(arc
		(start 184.100216 -224.828354)
		(mid 184.143355 -224.561886)
		(end 184.268364 -224.32264)
		(width 0.136652)
		(layer "F.Cu")
		(net "PCIE_TX_P47")
	)
	(segment
		(start 187.547758 -224.131378)
		(end 187.547758 -213.723474)
		(width 0.136652)
		(layer "F.Cu")
		(net "PCIE_TX_P46")
	)
	(segment
		(start 187.300108 -224.828608)
		(end 187.300362 -224.828354)
		(width 0.136652)
		(layer "F.Cu")
		(net "PCIE_TX_P46")
	)
	(segment
		(start 187.300108 -225.54438)
		(end 187.300108 -224.828608)
		(width 0.136652)
		(layer "F.Cu")
		(net "PCIE_TX_P46")
	)
	(arc
		(start 187.300362 -224.828354)
		(mid 187.343501 -224.561886)
		(end 187.46851 -224.32264)
		(width 0.136652)
		(layer "F.Cu")
		(net "PCIE_TX_P46")
	)
	(arc
		(start 187.46851 -224.32264)
		(mid 187.527144 -224.234888)
		(end 187.547758 -224.131378)
		(width 0.136652)
		(layer "F.Cu")
		(net "PCIE_TX_P46")
	)
	(arc
		(start 187.547758 -213.723474)
		(mid 187.455339 -213.25885)
		(end 187.192158 -212.864954)
		(width 0.136652)
		(layer "F.Cu")
		(net "PCIE_TX_P46")
	)
	(segment
		(start 190.5 -225.54438)
		(end 190.5 -224.828608)
		(width 0.136652)
		(layer "F.Cu")
		(net "PCIE_TX_P45")
	)
	(segment
		(start 190.74765 -224.131378)
		(end 190.74765 -213.722712)
		(width 0.136652)
		(layer "F.Cu")
		(net "PCIE_TX_P45")
	)
	(segment
		(start 190.5 -224.828608)
		(end 190.500254 -224.828354)
		(width 0.136652)
		(layer "F.Cu")
		(net "PCIE_TX_P45")
	)
	(arc
		(start 190.74765 -213.722712)
		(mid 190.655308 -213.258477)
		(end 190.392304 -212.864954)
		(width 0.136652)
		(layer "F.Cu")
		(net "PCIE_TX_P45")
	)
	(arc
		(start 190.668402 -224.32264)
		(mid 190.727036 -224.234888)
		(end 190.74765 -224.131378)
		(width 0.136652)
		(layer "F.Cu")
		(net "PCIE_TX_P45")
	)
	(arc
		(start 190.500254 -224.828354)
		(mid 190.543393 -224.561886)
		(end 190.668402 -224.32264)
		(width 0.136652)
		(layer "F.Cu")
		(net "PCIE_TX_P45")
	)
	(segment
		(start 193.947796 -224.131378)
		(end 193.947796 -213.723474)
		(width 0.136652)
		(layer "F.Cu")
		(net "PCIE_TX_P44")
	)
	(segment
		(start 193.700146 -225.54438)
		(end 193.700146 -224.828608)
		(width 0.136652)
		(layer "F.Cu")
		(net "PCIE_TX_P44")
	)
	(segment
		(start 193.700146 -224.828608)
		(end 193.7004 -224.828354)
		(width 0.136652)
		(layer "F.Cu")
		(net "PCIE_TX_P44")
	)
	(arc
		(start 193.7004 -224.828354)
		(mid 193.743539 -224.561886)
		(end 193.868548 -224.32264)
		(width 0.136652)
		(layer "F.Cu")
		(net "PCIE_TX_P44")
	)
	(arc
		(start 193.947796 -213.723474)
		(mid 193.855377 -213.25885)
		(end 193.592196 -212.864954)
		(width 0.136652)
		(layer "F.Cu")
		(net "PCIE_TX_P44")
	)
	(arc
		(start 193.868548 -224.32264)
		(mid 193.927182 -224.234888)
		(end 193.947796 -224.131378)
		(width 0.136652)
		(layer "F.Cu")
		(net "PCIE_TX_P44")
	)
	(segment
		(start 196.900038 -224.828608)
		(end 196.900292 -224.828354)
		(width 0.136652)
		(layer "F.Cu")
		(net "PCIE_TX_P43")
	)
	(segment
		(start 197.147688 -224.131378)
		(end 197.147688 -213.723474)
		(width 0.136652)
		(layer "F.Cu")
		(net "PCIE_TX_P43")
	)
	(segment
		(start 196.900038 -225.54438)
		(end 196.900038 -224.828608)
		(width 0.136652)
		(layer "F.Cu")
		(net "PCIE_TX_P43")
	)
	(arc
		(start 197.147688 -213.723474)
		(mid 197.055269 -213.25885)
		(end 196.792088 -212.864954)
		(width 0.136652)
		(layer "F.Cu")
		(net "PCIE_TX_P43")
	)
	(arc
		(start 197.06844 -224.32264)
		(mid 197.127074 -224.234888)
		(end 197.147688 -224.131378)
		(width 0.136652)
		(layer "F.Cu")
		(net "PCIE_TX_P43")
	)
	(arc
		(start 196.900292 -224.828354)
		(mid 196.943431 -224.561886)
		(end 197.06844 -224.32264)
		(width 0.136652)
		(layer "F.Cu")
		(net "PCIE_TX_P43")
	)
	(segment
		(start 200.34758 -224.131378)
		(end 200.34758 -213.723474)
		(width 0.136652)
		(layer "F.Cu")
		(net "PCIE_TX_P42")
	)
	(segment
		(start 200.100184 -225.54438)
		(end 200.100184 -224.828354)
		(width 0.136652)
		(layer "F.Cu")
		(net "PCIE_TX_P42")
	)
	(arc
		(start 200.268332 -224.32264)
		(mid 200.326966 -224.234888)
		(end 200.34758 -224.131378)
		(width 0.136652)
		(layer "F.Cu")
		(net "PCIE_TX_P42")
	)
	(arc
		(start 200.100184 -224.828354)
		(mid 200.143323 -224.561886)
		(end 200.268332 -224.32264)
		(width 0.136652)
		(layer "F.Cu")
		(net "PCIE_TX_P42")
	)
	(arc
		(start 200.34758 -213.723474)
		(mid 200.255161 -213.25885)
		(end 199.99198 -212.864954)
		(width 0.136652)
		(layer "F.Cu")
		(net "PCIE_TX_P42")
	)
	(segment
		(start 203.547726 -224.131378)
		(end 203.547726 -213.723474)
		(width 0.136652)
		(layer "F.Cu")
		(net "PCIE_TX_P41")
	)
	(segment
		(start 203.300076 -225.54438)
		(end 203.300076 -224.828608)
		(width 0.136652)
		(layer "F.Cu")
		(net "PCIE_TX_P41")
	)
	(segment
		(start 203.300076 -224.828608)
		(end 203.30033 -224.828354)
		(width 0.136652)
		(layer "F.Cu")
		(net "PCIE_TX_P41")
	)
	(arc
		(start 203.547726 -213.723474)
		(mid 203.455307 -213.25885)
		(end 203.192126 -212.864954)
		(width 0.136652)
		(layer "F.Cu")
		(net "PCIE_TX_P41")
	)
	(arc
		(start 203.468478 -224.32264)
		(mid 203.527112 -224.234888)
		(end 203.547726 -224.131378)
		(width 0.136652)
		(layer "F.Cu")
		(net "PCIE_TX_P41")
	)
	(arc
		(start 203.30033 -224.828354)
		(mid 203.343469 -224.561886)
		(end 203.468478 -224.32264)
		(width 0.136652)
		(layer "F.Cu")
		(net "PCIE_TX_P41")
	)
	(segment
		(start 206.500222 -224.828862)
		(end 206.499968 -224.828608)
		(width 0.136652)
		(layer "F.Cu")
		(net "PCIE_TX_P40")
	)
	(segment
		(start 206.747618 -224.131378)
		(end 206.747618 -213.723474)
		(width 0.136652)
		(layer "F.Cu")
		(net "PCIE_TX_P40")
	)
	(segment
		(start 206.499968 -224.828608)
		(end 206.500222 -224.828354)
		(width 0.136652)
		(layer "F.Cu")
		(net "PCIE_TX_P40")
	)
	(segment
		(start 206.500222 -225.54438)
		(end 206.500222 -224.828862)
		(width 0.136652)
		(layer "F.Cu")
		(net "PCIE_TX_P40")
	)
	(arc
		(start 206.747618 -213.723474)
		(mid 206.655199 -213.25885)
		(end 206.392018 -212.864954)
		(width 0.136652)
		(layer "F.Cu")
		(net "PCIE_TX_P40")
	)
	(arc
		(start 206.500222 -224.828354)
		(mid 206.543361 -224.561886)
		(end 206.66837 -224.32264)
		(width 0.136652)
		(layer "F.Cu")
		(net "PCIE_TX_P40")
	)
	(arc
		(start 206.66837 -224.32264)
		(mid 206.727004 -224.234888)
		(end 206.747618 -224.131378)
		(width 0.136652)
		(layer "F.Cu")
		(net "PCIE_TX_P40")
	)
	(segment
		(start 296.851832 -23.010876)
		(end 294.588184 -25.273)
		(width 0.136652)
		(layer "F.Cu")
		(net "PCIE_TX_P4")
	)
	(segment
		(start 299.570394 -20.977606)
		(end 299.620178 -20.977606)
		(width 0.136652)
		(layer "F.Cu")
		(net "PCIE_TX_P4")
	)
	(segment
		(start 294.400478 -25.72639)
		(end 294.400478 -32.766)
		(width 0.136652)
		(layer "F.Cu")
		(net "PCIE_TX_P4")
	)
	(segment
		(start 299.1612 -22.650196)
		(end 297.722798 -22.650196)
		(width 0.136652)
		(layer "F.Cu")
		(net "PCIE_TX_P4")
	)
	(segment
		(start 299.915834 -22.150578)
		(end 299.596556 -22.469856)
		(width 0.136652)
		(layer "F.Cu")
		(net "PCIE_TX_P4")
	)
	(segment
		(start 299.384466 -21.530056)
		(end 299.384466 -21.18106)
		(width 0.136652)
		(layer "F.Cu")
		(net "PCIE_TX_P4")
	)
	(segment
		(start 300.095412 -21.506688)
		(end 300.095412 -21.717)
		(width 0.136652)
		(layer "F.Cu")
		(net "PCIE_TX_P4")
	)
	(segment
		(start 299.803566 -21.053552)
		(end 299.981366 -21.231352)
		(width 0.136652)
		(layer "F.Cu")
		(net "PCIE_TX_P4")
	)
	(arc
		(start 297.722798 -22.650196)
		(mid 297.251453 -22.743934)
		(end 296.851832 -23.010876)
		(width 0.136652)
		(layer "F.Cu")
		(net "PCIE_TX_P4")
	)
	(arc
		(start 294.588184 -25.273)
		(mid 294.449221 -25.481018)
		(end 294.400478 -25.72639)
		(width 0.136652)
		(layer "F.Cu")
		(net "PCIE_TX_P4")
	)
	(arc
		(start 299.447712 -21.028406)
		(mid 299.503999 -20.990796)
		(end 299.570394 -20.977606)
		(width 0.136652)
		(layer "F.Cu")
		(net "PCIE_TX_P4")
	)
	(arc
		(start 299.620178 -20.977606)
		(mid 299.701946 -20.990834)
		(end 299.775372 -21.029168)
		(width 0.136652)
		(layer "F.Cu")
		(net "PCIE_TX_P4")
	)
	(arc
		(start 299.596556 -22.469856)
		(mid 299.396813 -22.60332)
		(end 299.1612 -22.650196)
		(width 0.136652)
		(layer "F.Cu")
		(net "PCIE_TX_P4")
	)
	(arc
		(start 299.775372 -21.029168)
		(mid 299.788693 -21.039787)
		(end 299.80128 -21.051266)
		(width 0.136652)
		(layer "F.Cu")
		(net "PCIE_TX_P4")
	)
	(arc
		(start 299.80128 -21.051266)
		(mid 299.802427 -21.052405)
		(end 299.803566 -21.053552)
		(width 0.136652)
		(layer "F.Cu")
		(net "PCIE_TX_P4")
	)
	(arc
		(start 299.981366 -21.231352)
		(mid 300.065774 -21.357677)
		(end 300.095412 -21.506688)
		(width 0.136652)
		(layer "F.Cu")
		(net "PCIE_TX_P4")
	)
	(arc
		(start 294.400478 -32.766)
		(mid 294.321783 -33.048486)
		(end 294.108378 -33.249616)
		(width 0.136652)
		(layer "F.Cu")
		(net "PCIE_TX_P4")
	)
	(arc
		(start 299.384466 -21.18106)
		(mid 299.4009 -21.098439)
		(end 299.447712 -21.028406)
		(width 0.136652)
		(layer "F.Cu")
		(net "PCIE_TX_P4")
	)
	(arc
		(start 300.095412 -21.717)
		(mid 300.048738 -21.951645)
		(end 299.915834 -22.150578)
		(width 0.136652)
		(layer "F.Cu")
		(net "PCIE_TX_P4")
	)
	(segment
		(start 212.900006 -224.828608)
		(end 212.90026 -224.828354)
		(width 0.136652)
		(layer "F.Cu")
		(net "PCIE_TX_P39")
	)
	(segment
		(start 212.900006 -225.54438)
		(end 212.900006 -224.828608)
		(width 0.136652)
		(layer "F.Cu")
		(net "PCIE_TX_P39")
	)
	(segment
		(start 213.147656 -224.131378)
		(end 213.147656 -213.723474)
		(width 0.136652)
		(layer "F.Cu")
		(net "PCIE_TX_P39")
	)
	(arc
		(start 213.147656 -213.723474)
		(mid 213.055237 -213.25885)
		(end 212.792056 -212.864954)
		(width 0.136652)
		(layer "F.Cu")
		(net "PCIE_TX_P39")
	)
	(arc
		(start 212.90026 -224.828354)
		(mid 212.943399 -224.561886)
		(end 213.068408 -224.32264)
		(width 0.136652)
		(layer "F.Cu")
		(net "PCIE_TX_P39")
	)
	(arc
		(start 213.068408 -224.32264)
		(mid 213.127042 -224.234888)
		(end 213.147656 -224.131378)
		(width 0.136652)
		(layer "F.Cu")
		(net "PCIE_TX_P39")
	)
	(segment
		(start 216.347548 -224.131378)
		(end 216.347548 -213.723474)
		(width 0.136652)
		(layer "F.Cu")
		(net "PCIE_TX_P38")
	)
	(segment
		(start 216.100152 -225.54438)
		(end 216.100152 -224.828354)
		(width 0.136652)
		(layer "F.Cu")
		(net "PCIE_TX_P38")
	)
	(arc
		(start 216.347548 -213.723474)
		(mid 216.255129 -213.25885)
		(end 215.991948 -212.864954)
		(width 0.136652)
		(layer "F.Cu")
		(net "PCIE_TX_P38")
	)
	(arc
		(start 216.100152 -224.828354)
		(mid 216.143291 -224.561886)
		(end 216.2683 -224.32264)
		(width 0.136652)
		(layer "F.Cu")
		(net "PCIE_TX_P38")
	)
	(arc
		(start 216.2683 -224.32264)
		(mid 216.326934 -224.234888)
		(end 216.347548 -224.131378)
		(width 0.136652)
		(layer "F.Cu")
		(net "PCIE_TX_P38")
	)
	(segment
		(start 264.500106 -225.54438)
		(end 264.500106 -224.828608)
		(width 0.136652)
		(layer "F.Cu")
		(net "PCIE_TX_P37")
	)
	(segment
		(start 264.747756 -224.131378)
		(end 264.747756 -213.723474)
		(width 0.136652)
		(layer "F.Cu")
		(net "PCIE_TX_P37")
	)
	(segment
		(start 264.500106 -224.828608)
		(end 264.50036 -224.828354)
		(width 0.136652)
		(layer "F.Cu")
		(net "PCIE_TX_P37")
	)
	(arc
		(start 264.747756 -213.723474)
		(mid 264.655337 -213.25885)
		(end 264.392156 -212.864954)
		(width 0.136652)
		(layer "F.Cu")
		(net "PCIE_TX_P37")
	)
	(arc
		(start 264.668508 -224.32264)
		(mid 264.727142 -224.234888)
		(end 264.747756 -224.131378)
		(width 0.136652)
		(layer "F.Cu")
		(net "PCIE_TX_P37")
	)
	(arc
		(start 264.50036 -224.828354)
		(mid 264.543499 -224.561886)
		(end 264.668508 -224.32264)
		(width 0.136652)
		(layer "F.Cu")
		(net "PCIE_TX_P37")
	)
	(segment
		(start 267.947648 -224.131378)
		(end 267.947648 -213.723474)
		(width 0.136652)
		(layer "F.Cu")
		(net "PCIE_TX_P36")
	)
	(segment
		(start 267.699998 -225.54438)
		(end 267.699998 -224.828608)
		(width 0.136652)
		(layer "F.Cu")
		(net "PCIE_TX_P36")
	)
	(segment
		(start 267.699998 -224.828608)
		(end 267.700252 -224.828354)
		(width 0.136652)
		(layer "F.Cu")
		(net "PCIE_TX_P36")
	)
	(arc
		(start 267.8684 -224.32264)
		(mid 267.927034 -224.234888)
		(end 267.947648 -224.131378)
		(width 0.136652)
		(layer "F.Cu")
		(net "PCIE_TX_P36")
	)
	(arc
		(start 267.947648 -213.723474)
		(mid 267.855229 -213.25885)
		(end 267.592048 -212.864954)
		(width 0.136652)
		(layer "F.Cu")
		(net "PCIE_TX_P36")
	)
	(arc
		(start 267.700252 -224.828354)
		(mid 267.743391 -224.561886)
		(end 267.8684 -224.32264)
		(width 0.136652)
		(layer "F.Cu")
		(net "PCIE_TX_P36")
	)
	(segment
		(start 270.900144 -224.828608)
		(end 270.900398 -224.828354)
		(width 0.136652)
		(layer "F.Cu")
		(net "PCIE_TX_P35")
	)
	(segment
		(start 271.147794 -224.131378)
		(end 271.147794 -213.723474)
		(width 0.136652)
		(layer "F.Cu")
		(net "PCIE_TX_P35")
	)
	(segment
		(start 270.900144 -225.54438)
		(end 270.900144 -224.828608)
		(width 0.136652)
		(layer "F.Cu")
		(net "PCIE_TX_P35")
	)
	(arc
		(start 271.068546 -224.32264)
		(mid 271.12718 -224.234888)
		(end 271.147794 -224.131378)
		(width 0.136652)
		(layer "F.Cu")
		(net "PCIE_TX_P35")
	)
	(arc
		(start 271.147794 -213.723474)
		(mid 271.055375 -213.25885)
		(end 270.792194 -212.864954)
		(width 0.136652)
		(layer "F.Cu")
		(net "PCIE_TX_P35")
	)
	(arc
		(start 270.900398 -224.828354)
		(mid 270.943537 -224.561886)
		(end 271.068546 -224.32264)
		(width 0.136652)
		(layer "F.Cu")
		(net "PCIE_TX_P35")
	)
	(segment
		(start 274.347686 -224.131378)
		(end 274.347686 -213.723474)
		(width 0.136652)
		(layer "F.Cu")
		(net "PCIE_TX_P34")
	)
	(segment
		(start 274.100036 -224.828608)
		(end 274.10029 -224.828354)
		(width 0.136652)
		(layer "F.Cu")
		(net "PCIE_TX_P34")
	)
	(segment
		(start 274.100036 -225.54438)
		(end 274.100036 -224.828608)
		(width 0.136652)
		(layer "F.Cu")
		(net "PCIE_TX_P34")
	)
	(arc
		(start 274.268438 -224.32264)
		(mid 274.327072 -224.234888)
		(end 274.347686 -224.131378)
		(width 0.136652)
		(layer "F.Cu")
		(net "PCIE_TX_P34")
	)
	(arc
		(start 274.347686 -213.723474)
		(mid 274.255267 -213.25885)
		(end 273.992086 -212.864954)
		(width 0.136652)
		(layer "F.Cu")
		(net "PCIE_TX_P34")
	)
	(arc
		(start 274.10029 -224.828354)
		(mid 274.143429 -224.561886)
		(end 274.268438 -224.32264)
		(width 0.136652)
		(layer "F.Cu")
		(net "PCIE_TX_P34")
	)
	(segment
		(start 277.300182 -225.54438)
		(end 277.300182 -224.828354)
		(width 0.136652)
		(layer "F.Cu")
		(net "PCIE_TX_P33")
	)
	(segment
		(start 277.547578 -224.131378)
		(end 277.547578 -213.723474)
		(width 0.136652)
		(layer "F.Cu")
		(net "PCIE_TX_P33")
	)
	(arc
		(start 277.300182 -224.828354)
		(mid 277.343321 -224.561886)
		(end 277.46833 -224.32264)
		(width 0.136652)
		(layer "F.Cu")
		(net "PCIE_TX_P33")
	)
	(arc
		(start 277.547578 -213.723474)
		(mid 277.455159 -213.25885)
		(end 277.191978 -212.864954)
		(width 0.136652)
		(layer "F.Cu")
		(net "PCIE_TX_P33")
	)
	(arc
		(start 277.46833 -224.32264)
		(mid 277.526964 -224.234888)
		(end 277.547578 -224.131378)
		(width 0.136652)
		(layer "F.Cu")
		(net "PCIE_TX_P33")
	)
	(segment
		(start 280.747724 -224.131378)
		(end 280.747724 -213.723474)
		(width 0.136652)
		(layer "F.Cu")
		(net "PCIE_TX_P32")
	)
	(segment
		(start 280.500074 -225.54438)
		(end 280.500074 -224.828608)
		(width 0.136652)
		(layer "F.Cu")
		(net "PCIE_TX_P32")
	)
	(segment
		(start 280.500074 -224.828608)
		(end 280.500328 -224.828354)
		(width 0.136652)
		(layer "F.Cu")
		(net "PCIE_TX_P32")
	)
	(arc
		(start 280.500328 -224.828354)
		(mid 280.543467 -224.561886)
		(end 280.668476 -224.32264)
		(width 0.136652)
		(layer "F.Cu")
		(net "PCIE_TX_P32")
	)
	(arc
		(start 280.668476 -224.32264)
		(mid 280.72711 -224.234888)
		(end 280.747724 -224.131378)
		(width 0.136652)
		(layer "F.Cu")
		(net "PCIE_TX_P32")
	)
	(arc
		(start 280.747724 -213.723474)
		(mid 280.655305 -213.25885)
		(end 280.392124 -212.864954)
		(width 0.136652)
		(layer "F.Cu")
		(net "PCIE_TX_P32")
	)
	(segment
		(start 283.947616 -224.131378)
		(end 283.947616 -213.723474)
		(width 0.136652)
		(layer "F.Cu")
		(net "PCIE_TX_P31")
	)
	(segment
		(start 283.70022 -225.54438)
		(end 283.70022 -224.828354)
		(width 0.136652)
		(layer "F.Cu")
		(net "PCIE_TX_P31")
	)
	(arc
		(start 283.70022 -224.828354)
		(mid 283.743359 -224.561886)
		(end 283.868368 -224.32264)
		(width 0.136652)
		(layer "F.Cu")
		(net "PCIE_TX_P31")
	)
	(arc
		(start 283.868368 -224.32264)
		(mid 283.927002 -224.234888)
		(end 283.947616 -224.131378)
		(width 0.136652)
		(layer "F.Cu")
		(net "PCIE_TX_P31")
	)
	(arc
		(start 283.947616 -213.723474)
		(mid 283.855197 -213.25885)
		(end 283.592016 -212.864954)
		(width 0.136652)
		(layer "F.Cu")
		(net "PCIE_TX_P31")
	)
	(segment
		(start 286.900112 -224.828608)
		(end 286.900366 -224.828354)
		(width 0.136652)
		(layer "F.Cu")
		(net "PCIE_TX_P30")
	)
	(segment
		(start 286.900112 -225.54438)
		(end 286.900112 -224.828608)
		(width 0.136652)
		(layer "F.Cu")
		(net "PCIE_TX_P30")
	)
	(segment
		(start 287.147762 -224.131378)
		(end 287.147762 -213.723474)
		(width 0.136652)
		(layer "F.Cu")
		(net "PCIE_TX_P30")
	)
	(arc
		(start 286.900366 -224.828354)
		(mid 286.943505 -224.561886)
		(end 287.068514 -224.32264)
		(width 0.136652)
		(layer "F.Cu")
		(net "PCIE_TX_P30")
	)
	(arc
		(start 287.068514 -224.32264)
		(mid 287.127148 -224.234888)
		(end 287.147762 -224.131378)
		(width 0.136652)
		(layer "F.Cu")
		(net "PCIE_TX_P30")
	)
	(arc
		(start 287.147762 -213.723474)
		(mid 287.055343 -213.25885)
		(end 286.792162 -212.864954)
		(width 0.136652)
		(layer "F.Cu")
		(net "PCIE_TX_P30")
	)
	(segment
		(start 290.820348 -20.977606)
		(end 290.870132 -20.977606)
		(width 0.136652)
		(layer "F.Cu")
		(net "PCIE_TX_P3")
	)
	(segment
		(start 289.4584 -31.528766)
		(end 289.4584 -32.6136)
		(width 0.136652)
		(layer "F.Cu")
		(net "PCIE_TX_P3")
	)
	(segment
		(start 291.619686 -22.633686)
		(end 292.707822 -23.721822)
		(width 0.136652)
		(layer "F.Cu")
		(net "PCIE_TX_P3")
	)
	(segment
		(start 292.887146 -24.1554)
		(end 292.8874 -24.155146)
		(width 0.136652)
		(layer "F.Cu")
		(net "PCIE_TX_P3")
	)
	(segment
		(start 291.05352 -21.053552)
		(end 291.23132 -21.231352)
		(width 0.136652)
		(layer "F.Cu")
		(net "PCIE_TX_P3")
	)
	(segment
		(start 290.63442 -21.530056)
		(end 290.63442 -21.18106)
		(width 0.136652)
		(layer "F.Cu")
		(net "PCIE_TX_P3")
	)
	(segment
		(start 292.593522 -28.031186)
		(end 289.714432 -30.910276)
		(width 0.136652)
		(layer "F.Cu")
		(net "PCIE_TX_P3")
	)
	(segment
		(start 292.8874 -24.155146)
		(end 292.8874 -27.322018)
		(width 0.136652)
		(layer "F.Cu")
		(net "PCIE_TX_P3")
	)
	(segment
		(start 291.345366 -21.506434)
		(end 291.345366 -21.971)
		(width 0.136652)
		(layer "F.Cu")
		(net "PCIE_TX_P3")
	)
	(arc
		(start 291.051234 -21.051266)
		(mid 291.052381 -21.052405)
		(end 291.05352 -21.053552)
		(width 0.136652)
		(layer "F.Cu")
		(net "PCIE_TX_P3")
	)
	(arc
		(start 291.23132 -21.231352)
		(mid 291.315679 -21.35756)
		(end 291.345366 -21.506434)
		(width 0.136652)
		(layer "F.Cu")
		(net "PCIE_TX_P3")
	)
	(arc
		(start 289.714432 -30.910276)
		(mid 289.524909 -31.194057)
		(end 289.4584 -31.528766)
		(width 0.136652)
		(layer "F.Cu")
		(net "PCIE_TX_P3")
	)
	(arc
		(start 292.707822 -23.721822)
		(mid 292.840604 -23.920779)
		(end 292.887146 -24.1554)
		(width 0.136652)
		(layer "F.Cu")
		(net "PCIE_TX_P3")
	)
	(arc
		(start 291.041074 -21.041868)
		(mid 291.046218 -21.046498)
		(end 291.051234 -21.051266)
		(width 0.136652)
		(layer "F.Cu")
		(net "PCIE_TX_P3")
	)
	(arc
		(start 290.63442 -21.18106)
		(mid 290.650854 -21.098439)
		(end 290.697666 -21.028406)
		(width 0.136652)
		(layer "F.Cu")
		(net "PCIE_TX_P3")
	)
	(arc
		(start 290.870132 -20.977606)
		(mid 290.961436 -20.99421)
		(end 291.041074 -21.041868)
		(width 0.136652)
		(layer "F.Cu")
		(net "PCIE_TX_P3")
	)
	(arc
		(start 290.697666 -21.028406)
		(mid 290.753953 -20.990796)
		(end 290.820348 -20.977606)
		(width 0.136652)
		(layer "F.Cu")
		(net "PCIE_TX_P3")
	)
	(arc
		(start 291.345366 -21.971)
		(mid 291.416608 -22.32963)
		(end 291.619686 -22.633686)
		(width 0.136652)
		(layer "F.Cu")
		(net "PCIE_TX_P3")
	)
	(arc
		(start 289.4584 -32.6136)
		(mid 289.383281 -32.886956)
		(end 289.179 -33.0835)
		(width 0.136652)
		(layer "F.Cu")
		(net "PCIE_TX_P3")
	)
	(arc
		(start 292.8874 -27.322018)
		(mid 292.810965 -27.705813)
		(end 292.593522 -28.031186)
		(width 0.136652)
		(layer "F.Cu")
		(net "PCIE_TX_P3")
	)
	(segment
		(start 290.347654 -224.131378)
		(end 290.347654 -213.723474)
		(width 0.136652)
		(layer "F.Cu")
		(net "PCIE_TX_P29")
	)
	(segment
		(start 290.100004 -225.54438)
		(end 290.100004 -224.828608)
		(width 0.136652)
		(layer "F.Cu")
		(net "PCIE_TX_P29")
	)
	(segment
		(start 290.100004 -224.828608)
		(end 290.100258 -224.828354)
		(width 0.136652)
		(layer "F.Cu")
		(net "PCIE_TX_P29")
	)
	(arc
		(start 290.268406 -224.32264)
		(mid 290.32704 -224.234888)
		(end 290.347654 -224.131378)
		(width 0.136652)
		(layer "F.Cu")
		(net "PCIE_TX_P29")
	)
	(arc
		(start 290.347654 -213.723474)
		(mid 290.255235 -213.25885)
		(end 289.992054 -212.864954)
		(width 0.136652)
		(layer "F.Cu")
		(net "PCIE_TX_P29")
	)
	(arc
		(start 290.100258 -224.828354)
		(mid 290.143397 -224.561886)
		(end 290.268406 -224.32264)
		(width 0.136652)
		(layer "F.Cu")
		(net "PCIE_TX_P29")
	)
	(segment
		(start 293.30015 -225.54438)
		(end 293.30015 -224.828354)
		(width 0.136652)
		(layer "F.Cu")
		(net "PCIE_TX_P28")
	)
	(segment
		(start 293.547546 -224.131378)
		(end 293.547546 -213.723474)
		(width 0.136652)
		(layer "F.Cu")
		(net "PCIE_TX_P28")
	)
	(arc
		(start 293.547546 -213.723474)
		(mid 293.455127 -213.25885)
		(end 293.191946 -212.864954)
		(width 0.136652)
		(layer "F.Cu")
		(net "PCIE_TX_P28")
	)
	(arc
		(start 293.468298 -224.32264)
		(mid 293.526932 -224.234888)
		(end 293.547546 -224.131378)
		(width 0.136652)
		(layer "F.Cu")
		(net "PCIE_TX_P28")
	)
	(arc
		(start 293.30015 -224.828354)
		(mid 293.343289 -224.561886)
		(end 293.468298 -224.32264)
		(width 0.136652)
		(layer "F.Cu")
		(net "PCIE_TX_P28")
	)
	(segment
		(start 298.900088 -224.828608)
		(end 298.900342 -224.828354)
		(width 0.136652)
		(layer "F.Cu")
		(net "PCIE_TX_P27")
	)
	(segment
		(start 298.900088 -225.54438)
		(end 298.900088 -224.828608)
		(width 0.136652)
		(layer "F.Cu")
		(net "PCIE_TX_P27")
	)
	(segment
		(start 299.147738 -224.131378)
		(end 299.147738 -213.723474)
		(width 0.136652)
		(layer "F.Cu")
		(net "PCIE_TX_P27")
	)
	(arc
		(start 298.900342 -224.828354)
		(mid 298.943481 -224.561886)
		(end 299.06849 -224.32264)
		(width 0.136652)
		(layer "F.Cu")
		(net "PCIE_TX_P27")
	)
	(arc
		(start 299.06849 -224.32264)
		(mid 299.127124 -224.234888)
		(end 299.147738 -224.131378)
		(width 0.136652)
		(layer "F.Cu")
		(net "PCIE_TX_P27")
	)
	(arc
		(start 299.147738 -213.723474)
		(mid 299.055319 -213.25885)
		(end 298.792138 -212.864954)
		(width 0.136652)
		(layer "F.Cu")
		(net "PCIE_TX_P27")
	)
	(segment
		(start 302.100234 -225.54438)
		(end 302.100234 -224.828354)
		(width 0.136652)
		(layer "F.Cu")
		(net "PCIE_TX_P26")
	)
	(segment
		(start 302.34763 -224.131378)
		(end 302.34763 -213.723474)
		(width 0.136652)
		(layer "F.Cu")
		(net "PCIE_TX_P26")
	)
	(arc
		(start 302.268382 -224.32264)
		(mid 302.327016 -224.234888)
		(end 302.34763 -224.131378)
		(width 0.136652)
		(layer "F.Cu")
		(net "PCIE_TX_P26")
	)
	(arc
		(start 302.34763 -213.723474)
		(mid 302.255211 -213.25885)
		(end 301.99203 -212.864954)
		(width 0.136652)
		(layer "F.Cu")
		(net "PCIE_TX_P26")
	)
	(arc
		(start 302.100234 -224.828354)
		(mid 302.143373 -224.561886)
		(end 302.268382 -224.32264)
		(width 0.136652)
		(layer "F.Cu")
		(net "PCIE_TX_P26")
	)
	(segment
		(start 310.100218 -225.54438)
		(end 310.100218 -224.828608)
		(width 0.136652)
		(layer "F.Cu")
		(net "PCIE_TX_P25")
	)
	(segment
		(start 309.992522 -212.865208)
		(end 309.992014 -212.864954)
		(width 0.136652)
		(layer "F.Cu")
		(net "PCIE_TX_P25")
	)
	(segment
		(start 310.100218 -224.828608)
		(end 310.100472 -224.828354)
		(width 0.136652)
		(layer "F.Cu")
		(net "PCIE_TX_P25")
	)
	(segment
		(start 310.347868 -224.131378)
		(end 310.347868 -213.723474)
		(width 0.136652)
		(layer "F.Cu")
		(net "PCIE_TX_P25")
	)
	(arc
		(start 310.100472 -224.828354)
		(mid 310.143611 -224.561886)
		(end 310.26862 -224.32264)
		(width 0.136652)
		(layer "F.Cu")
		(net "PCIE_TX_P25")
	)
	(arc
		(start 310.26862 -224.32264)
		(mid 310.327254 -224.234888)
		(end 310.347868 -224.131378)
		(width 0.136652)
		(layer "F.Cu")
		(net "PCIE_TX_P25")
	)
	(arc
		(start 310.347868 -213.723474)
		(mid 310.25557 -213.258991)
		(end 309.992522 -212.865208)
		(width 0.136652)
		(layer "F.Cu")
		(net "PCIE_TX_P25")
	)
	(segment
		(start 313.30011 -224.828608)
		(end 313.300364 -224.828354)
		(width 0.136652)
		(layer "F.Cu")
		(net "PCIE_TX_P24")
	)
	(segment
		(start 313.30011 -225.54438)
		(end 313.30011 -224.828608)
		(width 0.136652)
		(layer "F.Cu")
		(net "PCIE_TX_P24")
	)
	(segment
		(start 313.54776 -224.131378)
		(end 313.54776 -213.723474)
		(width 0.136652)
		(layer "F.Cu")
		(net "PCIE_TX_P24")
	)
	(arc
		(start 313.468512 -224.32264)
		(mid 313.527146 -224.234888)
		(end 313.54776 -224.131378)
		(width 0.136652)
		(layer "F.Cu")
		(net "PCIE_TX_P24")
	)
	(arc
		(start 313.300364 -224.828354)
		(mid 313.343503 -224.561886)
		(end 313.468512 -224.32264)
		(width 0.136652)
		(layer "F.Cu")
		(net "PCIE_TX_P24")
	)
	(arc
		(start 313.54776 -213.723474)
		(mid 313.455341 -213.25885)
		(end 313.19216 -212.864954)
		(width 0.136652)
		(layer "F.Cu")
		(net "PCIE_TX_P24")
	)
	(segment
		(start 316.39256 -212.865208)
		(end 316.392052 -212.864954)
		(width 0.136652)
		(layer "F.Cu")
		(net "PCIE_TX_P23")
	)
	(segment
		(start 316.500002 -225.54438)
		(end 316.500002 -224.828862)
		(width 0.136652)
		(layer "F.Cu")
		(net "PCIE_TX_P23")
	)
	(segment
		(start 316.747906 -224.131378)
		(end 316.747906 -213.723474)
		(width 0.136652)
		(layer "F.Cu")
		(net "PCIE_TX_P23")
	)
	(segment
		(start 316.500002 -224.828862)
		(end 316.50051 -224.828354)
		(width 0.136652)
		(layer "F.Cu")
		(net "PCIE_TX_P23")
	)
	(arc
		(start 316.668658 -224.32264)
		(mid 316.727292 -224.234888)
		(end 316.747906 -224.131378)
		(width 0.136652)
		(layer "F.Cu")
		(net "PCIE_TX_P23")
	)
	(arc
		(start 316.747906 -213.723474)
		(mid 316.655608 -213.258991)
		(end 316.39256 -212.865208)
		(width 0.136652)
		(layer "F.Cu")
		(net "PCIE_TX_P23")
	)
	(arc
		(start 316.50051 -224.828354)
		(mid 316.543649 -224.561886)
		(end 316.668658 -224.32264)
		(width 0.136652)
		(layer "F.Cu")
		(net "PCIE_TX_P23")
	)
	(segment
		(start 319.700148 -225.54438)
		(end 319.700148 -224.828608)
		(width 0.136652)
		(layer "F.Cu")
		(net "PCIE_TX_P22")
	)
	(segment
		(start 319.700148 -224.828608)
		(end 319.700402 -224.828354)
		(width 0.136652)
		(layer "F.Cu")
		(net "PCIE_TX_P22")
	)
	(segment
		(start 319.947798 -224.131378)
		(end 319.947798 -213.723474)
		(width 0.136652)
		(layer "F.Cu")
		(net "PCIE_TX_P22")
	)
	(arc
		(start 319.700402 -224.828354)
		(mid 319.743541 -224.561886)
		(end 319.86855 -224.32264)
		(width 0.136652)
		(layer "F.Cu")
		(net "PCIE_TX_P22")
	)
	(arc
		(start 319.947798 -213.723474)
		(mid 319.855379 -213.25885)
		(end 319.592198 -212.864954)
		(width 0.136652)
		(layer "F.Cu")
		(net "PCIE_TX_P22")
	)
	(arc
		(start 319.86855 -224.32264)
		(mid 319.927184 -224.234888)
		(end 319.947798 -224.131378)
		(width 0.136652)
		(layer "F.Cu")
		(net "PCIE_TX_P22")
	)
	(segment
		(start 322.90004 -225.54438)
		(end 322.90004 -224.828608)
		(width 0.136652)
		(layer "F.Cu")
		(net "PCIE_TX_P21")
	)
	(segment
		(start 322.90004 -224.828608)
		(end 322.900294 -224.828354)
		(width 0.136652)
		(layer "F.Cu")
		(net "PCIE_TX_P21")
	)
	(segment
		(start 323.14769 -224.131378)
		(end 323.14769 -213.723474)
		(width 0.136652)
		(layer "F.Cu")
		(net "PCIE_TX_P21")
	)
	(arc
		(start 322.900294 -224.828354)
		(mid 322.943433 -224.561886)
		(end 323.068442 -224.32264)
		(width 0.136652)
		(layer "F.Cu")
		(net "PCIE_TX_P21")
	)
	(arc
		(start 323.068442 -224.32264)
		(mid 323.127076 -224.234888)
		(end 323.14769 -224.131378)
		(width 0.136652)
		(layer "F.Cu")
		(net "PCIE_TX_P21")
	)
	(arc
		(start 323.14769 -213.723474)
		(mid 323.055271 -213.25885)
		(end 322.79209 -212.864954)
		(width 0.136652)
		(layer "F.Cu")
		(net "PCIE_TX_P21")
	)
	(segment
		(start 326.100186 -225.54438)
		(end 326.100186 -224.828354)
		(width 0.136652)
		(layer "F.Cu")
		(net "PCIE_TX_P20")
	)
	(segment
		(start 326.347582 -224.131378)
		(end 326.347582 -213.723474)
		(width 0.136652)
		(layer "F.Cu")
		(net "PCIE_TX_P20")
	)
	(arc
		(start 326.100186 -224.828354)
		(mid 326.143325 -224.561886)
		(end 326.268334 -224.32264)
		(width 0.136652)
		(layer "F.Cu")
		(net "PCIE_TX_P20")
	)
	(arc
		(start 326.268334 -224.32264)
		(mid 326.326968 -224.234888)
		(end 326.347582 -224.131378)
		(width 0.136652)
		(layer "F.Cu")
		(net "PCIE_TX_P20")
	)
	(arc
		(start 326.347582 -213.723474)
		(mid 326.255163 -213.25885)
		(end 325.991982 -212.864954)
		(width 0.136652)
		(layer "F.Cu")
		(net "PCIE_TX_P20")
	)
	(segment
		(start 291.300154 -25.273)
		(end 291.300154 -25.781254)
		(width 0.136652)
		(layer "F.Cu")
		(net "PCIE_TX_P2")
	)
	(segment
		(start 290.63442 -25.33015)
		(end 290.551616 -24.983948)
		(width 0.136652)
		(layer "F.Cu")
		(net "PCIE_TX_P2")
	)
	(segment
		(start 291.300154 -25.781254)
		(end 291.2999 -25.781)
		(width 0.136652)
		(layer "F.Cu")
		(net "PCIE_TX_P2")
	)
	(segment
		(start 287.6423 -33.274)
		(end 287.401 -33.274)
		(width 0.136652)
		(layer "F.Cu")
		(net "PCIE_TX_P2")
	)
	(segment
		(start 287.119314 -33.15716)
		(end 286.9311 -32.9692)
		(width 0.136652)
		(layer "F.Cu")
		(net "PCIE_TX_P2")
	)
	(segment
		(start 288.036 -29.598366)
		(end 288.036 -32.808164)
		(width 0.136652)
		(layer "F.Cu")
		(net "PCIE_TX_P2")
	)
	(segment
		(start 291.16528 -26.106628)
		(end 288.292032 -28.979876)
		(width 0.136652)
		(layer "F.Cu")
		(net "PCIE_TX_P2")
	)
	(segment
		(start 287.921954 -33.0835)
		(end 287.794954 -33.210754)
		(width 0.136652)
		(layer "F.Cu")
		(net "PCIE_TX_P2")
	)
	(segment
		(start 291.018722 -24.662892)
		(end 291.067998 -24.712168)
		(width 0.136652)
		(layer "F.Cu")
		(net "PCIE_TX_P2")
	)
	(segment
		(start 287.921954 -33.083754)
		(end 287.921954 -33.0835)
		(width 0.136652)
		(layer "F.Cu")
		(net "PCIE_TX_P2")
	)
	(arc
		(start 287.794954 -33.210754)
		(mid 287.724916 -33.257552)
		(end 287.6423 -33.274)
		(width 0.136652)
		(layer "F.Cu")
		(net "PCIE_TX_P2")
	)
	(arc
		(start 291.217096 -24.919432)
		(mid 291.27914 -25.091397)
		(end 291.300154 -25.273)
		(width 0.136652)
		(layer "F.Cu")
		(net "PCIE_TX_P2")
	)
	(arc
		(start 288.292032 -28.979876)
		(mid 288.102509 -29.263657)
		(end 288.036 -29.598366)
		(width 0.136652)
		(layer "F.Cu")
		(net "PCIE_TX_P2")
	)
	(arc
		(start 287.401 -33.274)
		(mid 287.248544 -33.243581)
		(end 287.119314 -33.15716)
		(width 0.136652)
		(layer "F.Cu")
		(net "PCIE_TX_P2")
	)
	(arc
		(start 288.036 -32.808164)
		(mid 288.006409 -32.957311)
		(end 287.921954 -33.083754)
		(width 0.136652)
		(layer "F.Cu")
		(net "PCIE_TX_P2")
	)
	(arc
		(start 290.551616 -24.983948)
		(mid 290.563281 -24.790578)
		(end 290.680394 -24.636222)
		(width 0.136652)
		(layer "F.Cu")
		(net "PCIE_TX_P2")
	)
	(arc
		(start 291.067998 -24.712168)
		(mid 291.150957 -24.809752)
		(end 291.217096 -24.919432)
		(width 0.136652)
		(layer "F.Cu")
		(net "PCIE_TX_P2")
	)
	(arc
		(start 291.2999 -25.781)
		(mid 291.264964 -25.957197)
		(end 291.16528 -26.106628)
		(width 0.136652)
		(layer "F.Cu")
		(net "PCIE_TX_P2")
	)
	(arc
		(start 290.680394 -24.636222)
		(mid 290.854439 -24.58727)
		(end 291.018722 -24.662892)
		(width 0.136652)
		(layer "F.Cu")
		(net "PCIE_TX_P2")
	)
	(segment
		(start 332.392528 -212.865208)
		(end 332.39202 -212.864954)
		(width 0.136652)
		(layer "F.Cu")
		(net "PCIE_TX_P19")
	)
	(segment
		(start 332.500224 -224.828608)
		(end 332.500478 -224.828354)
		(width 0.136652)
		(layer "F.Cu")
		(net "PCIE_TX_P19")
	)
	(segment
		(start 332.747874 -224.131378)
		(end 332.747874 -213.723474)
		(width 0.136652)
		(layer "F.Cu")
		(net "PCIE_TX_P19")
	)
	(segment
		(start 332.500224 -225.54438)
		(end 332.500224 -224.828608)
		(width 0.136652)
		(layer "F.Cu")
		(net "PCIE_TX_P19")
	)
	(arc
		(start 332.747874 -213.723474)
		(mid 332.655576 -213.258991)
		(end 332.392528 -212.865208)
		(width 0.136652)
		(layer "F.Cu")
		(net "PCIE_TX_P19")
	)
	(arc
		(start 332.500478 -224.828354)
		(mid 332.543617 -224.561886)
		(end 332.668626 -224.32264)
		(width 0.136652)
		(layer "F.Cu")
		(net "PCIE_TX_P19")
	)
	(arc
		(start 332.668626 -224.32264)
		(mid 332.72726 -224.234888)
		(end 332.747874 -224.131378)
		(width 0.136652)
		(layer "F.Cu")
		(net "PCIE_TX_P19")
	)
	(segment
		(start 335.700116 -224.828608)
		(end 335.70037 -224.828354)
		(width 0.136652)
		(layer "F.Cu")
		(net "PCIE_TX_P18")
	)
	(segment
		(start 335.947766 -224.131378)
		(end 335.947766 -213.723474)
		(width 0.136652)
		(layer "F.Cu")
		(net "PCIE_TX_P18")
	)
	(segment
		(start 335.700116 -225.54438)
		(end 335.700116 -224.828608)
		(width 0.136652)
		(layer "F.Cu")
		(net "PCIE_TX_P18")
	)
	(arc
		(start 335.868518 -224.32264)
		(mid 335.927152 -224.234888)
		(end 335.947766 -224.131378)
		(width 0.136652)
		(layer "F.Cu")
		(net "PCIE_TX_P18")
	)
	(arc
		(start 335.70037 -224.828354)
		(mid 335.743509 -224.561886)
		(end 335.868518 -224.32264)
		(width 0.136652)
		(layer "F.Cu")
		(net "PCIE_TX_P18")
	)
	(arc
		(start 335.947766 -213.723474)
		(mid 335.855347 -213.25885)
		(end 335.592166 -212.864954)
		(width 0.136652)
		(layer "F.Cu")
		(net "PCIE_TX_P18")
	)
	(segment
		(start 339.147658 -224.131378)
		(end 339.147658 -213.723474)
		(width 0.136652)
		(layer "F.Cu")
		(net "PCIE_TX_P17")
	)
	(segment
		(start 338.900008 -224.828608)
		(end 338.900262 -224.828354)
		(width 0.136652)
		(layer "F.Cu")
		(net "PCIE_TX_P17")
	)
	(segment
		(start 338.900008 -225.54438)
		(end 338.900008 -224.828608)
		(width 0.136652)
		(layer "F.Cu")
		(net "PCIE_TX_P17")
	)
	(arc
		(start 338.900262 -224.828354)
		(mid 338.943401 -224.561886)
		(end 339.06841 -224.32264)
		(width 0.136652)
		(layer "F.Cu")
		(net "PCIE_TX_P17")
	)
	(arc
		(start 339.06841 -224.32264)
		(mid 339.127044 -224.234888)
		(end 339.147658 -224.131378)
		(width 0.136652)
		(layer "F.Cu")
		(net "PCIE_TX_P17")
	)
	(arc
		(start 339.147658 -213.723474)
		(mid 339.055239 -213.25885)
		(end 338.792058 -212.864954)
		(width 0.136652)
		(layer "F.Cu")
		(net "PCIE_TX_P17")
	)
	(segment
		(start 342.34755 -224.131378)
		(end 342.34755 -213.723474)
		(width 0.136652)
		(layer "F.Cu")
		(net "PCIE_TX_P16")
	)
	(segment
		(start 342.100154 -225.54438)
		(end 342.100154 -224.828354)
		(width 0.136652)
		(layer "F.Cu")
		(net "PCIE_TX_P16")
	)
	(arc
		(start 342.100154 -224.828354)
		(mid 342.143293 -224.561886)
		(end 342.268302 -224.32264)
		(width 0.136652)
		(layer "F.Cu")
		(net "PCIE_TX_P16")
	)
	(arc
		(start 342.268302 -224.32264)
		(mid 342.326936 -224.234888)
		(end 342.34755 -224.131378)
		(width 0.136652)
		(layer "F.Cu")
		(net "PCIE_TX_P16")
	)
	(arc
		(start 342.34755 -213.723474)
		(mid 342.255131 -213.25885)
		(end 341.99195 -212.864954)
		(width 0.136652)
		(layer "F.Cu")
		(net "PCIE_TX_P16")
	)
	(segment
		(start 324.3453 -22.0472)
		(end 324.3453 -21.506688)
		(width 0.136652)
		(layer "F.Cu")
		(net "PCIE_TX_P15")
	)
	(segment
		(start 324.231254 -21.231352)
		(end 324.053454 -21.053552)
		(width 0.136652)
		(layer "F.Cu")
		(net "PCIE_TX_P15")
	)
	(segment
		(start 323.870066 -20.977606)
		(end 323.820282 -20.977606)
		(width 0.136652)
		(layer "F.Cu")
		(net "PCIE_TX_P15")
	)
	(segment
		(start 328.284332 -26.379932)
		(end 324.623176 -22.71903)
		(width 0.136652)
		(layer "F.Cu")
		(net "PCIE_TX_P15")
	)
	(segment
		(start 328.603864 -32.397954)
		(end 328.603864 -27.150822)
		(width 0.136652)
		(layer "F.Cu")
		(net "PCIE_TX_P15")
	)
	(segment
		(start 323.634354 -21.18106)
		(end 323.634354 -21.530056)
		(width 0.136652)
		(layer "F.Cu")
		(net "PCIE_TX_P15")
	)
	(arc
		(start 324.051168 -21.051266)
		(mid 323.967827 -20.996699)
		(end 323.870066 -20.977606)
		(width 0.136652)
		(layer "F.Cu")
		(net "PCIE_TX_P15")
	)
	(arc
		(start 324.3453 -21.506688)
		(mid 324.31566 -21.357678)
		(end 324.231254 -21.231352)
		(width 0.136652)
		(layer "F.Cu")
		(net "PCIE_TX_P15")
	)
	(arc
		(start 328.324718 -32.988758)
		(mid 328.530562 -32.724669)
		(end 328.603864 -32.397954)
		(width 0.136652)
		(layer "F.Cu")
		(net "PCIE_TX_P15")
	)
	(arc
		(start 323.820282 -20.977606)
		(mid 323.753893 -20.990812)
		(end 323.6976 -21.028406)
		(width 0.136652)
		(layer "F.Cu")
		(net "PCIE_TX_P15")
	)
	(arc
		(start 324.053454 -21.053552)
		(mid 324.052315 -21.052405)
		(end 324.051168 -21.051266)
		(width 0.136652)
		(layer "F.Cu")
		(net "PCIE_TX_P15")
	)
	(arc
		(start 323.6976 -21.028406)
		(mid 323.650802 -21.098444)
		(end 323.634354 -21.18106)
		(width 0.136652)
		(layer "F.Cu")
		(net "PCIE_TX_P15")
	)
	(arc
		(start 324.623176 -22.71903)
		(mid 324.417491 -22.410733)
		(end 324.3453 -22.0472)
		(width 0.136652)
		(layer "F.Cu")
		(net "PCIE_TX_P15")
	)
	(arc
		(start 328.603864 -27.150822)
		(mid 328.520763 -26.733604)
		(end 328.284332 -26.379932)
		(width 0.136652)
		(layer "F.Cu")
		(net "PCIE_TX_P15")
	)
	(segment
		(start 325.876158 -29.76245)
		(end 324.120002 -28.006294)
		(width 0.136652)
		(layer "F.Cu")
		(net "PCIE_TX_P14")
	)
	(segment
		(start 323.8881 -27.446224)
		(end 323.8881 -26.975816)
		(width 0.136652)
		(layer "F.Cu")
		(net "PCIE_TX_P14")
	)
	(segment
		(start 323.870066 -24.7777)
		(end 323.820282 -24.7777)
		(width 0.136652)
		(layer "F.Cu")
		(net "PCIE_TX_P14")
	)
	(segment
		(start 324.102476 -26.455624)
		(end 324.22465 -26.33345)
		(width 0.136652)
		(layer "F.Cu")
		(net "PCIE_TX_P14")
	)
	(segment
		(start 324.231254 -25.031446)
		(end 324.053454 -24.853646)
		(width 0.136652)
		(layer "F.Cu")
		(net "PCIE_TX_P14")
	)
	(segment
		(start 323.634354 -24.981154)
		(end 323.634354 -25.33015)
		(width 0.136652)
		(layer "F.Cu")
		(net "PCIE_TX_P14")
	)
	(segment
		(start 324.3453 -26.042112)
		(end 324.3453 -25.306782)
		(width 0.136652)
		(layer "F.Cu")
		(net "PCIE_TX_P14")
	)
	(segment
		(start 326.199246 -32.470344)
		(end 326.199246 -30.541976)
		(width 0.136652)
		(layer "F.Cu")
		(net "PCIE_TX_P14")
	)
	(arc
		(start 324.120002 -28.006294)
		(mid 323.948335 -27.749331)
		(end 323.8881 -27.446224)
		(width 0.136652)
		(layer "F.Cu")
		(net "PCIE_TX_P14")
	)
	(arc
		(start 324.3453 -25.306782)
		(mid 324.31566 -25.157772)
		(end 324.231254 -25.031446)
		(width 0.136652)
		(layer "F.Cu")
		(net "PCIE_TX_P14")
	)
	(arc
		(start 324.22465 -26.33345)
		(mid 324.313963 -26.199783)
		(end 324.3453 -26.042112)
		(width 0.136652)
		(layer "F.Cu")
		(net "PCIE_TX_P14")
	)
	(arc
		(start 323.820282 -24.7777)
		(mid 323.753893 -24.790906)
		(end 323.6976 -24.8285)
		(width 0.136652)
		(layer "F.Cu")
		(net "PCIE_TX_P14")
	)
	(arc
		(start 323.8881 -26.975816)
		(mid 323.924559 -26.746274)
		(end 324.030594 -26.539444)
		(width 0.136652)
		(layer "F.Cu")
		(net "PCIE_TX_P14")
	)
	(arc
		(start 324.051168 -24.85136)
		(mid 323.967827 -24.796793)
		(end 323.870066 -24.7777)
		(width 0.136652)
		(layer "F.Cu")
		(net "PCIE_TX_P14")
	)
	(arc
		(start 323.6976 -24.8285)
		(mid 323.650802 -24.898538)
		(end 323.634354 -24.981154)
		(width 0.136652)
		(layer "F.Cu")
		(net "PCIE_TX_P14")
	)
	(arc
		(start 324.053454 -24.853646)
		(mid 324.052315 -24.852499)
		(end 324.051168 -24.85136)
		(width 0.136652)
		(layer "F.Cu")
		(net "PCIE_TX_P14")
	)
	(arc
		(start 325.918322 -33.01492)
		(mid 326.124884 -32.776729)
		(end 326.199246 -32.470344)
		(width 0.136652)
		(layer "F.Cu")
		(net "PCIE_TX_P14")
	)
	(arc
		(start 324.030594 -26.539444)
		(mid 324.064927 -26.496155)
		(end 324.102476 -26.455624)
		(width 0.136652)
		(layer "F.Cu")
		(net "PCIE_TX_P14")
	)
	(arc
		(start 326.199246 -30.541976)
		(mid 326.115216 -30.120092)
		(end 325.876158 -29.76245)
		(width 0.136652)
		(layer "F.Cu")
		(net "PCIE_TX_P14")
	)
	(segment
		(start 321.971924 -25.022048)
		(end 321.803522 -24.853646)
		(width 0.136652)
		(layer "F.Cu")
		(net "PCIE_TX_P13")
	)
	(segment
		(start 321.620134 -24.7777)
		(end 321.57035 -24.7777)
		(width 0.136652)
		(layer "F.Cu")
		(net "PCIE_TX_P13")
	)
	(segment
		(start 322.095368 -25.306528)
		(end 322.095114 -25.306782)
		(width 0.136652)
		(layer "F.Cu")
		(net "PCIE_TX_P13")
	)
	(segment
		(start 323.472048 -29.26334)
		(end 322.41744 -28.208732)
		(width 0.136652)
		(layer "F.Cu")
		(net "PCIE_TX_P13")
	)
	(segment
		(start 321.384422 -24.981154)
		(end 321.384422 -25.33015)
		(width 0.136652)
		(layer "F.Cu")
		(net "PCIE_TX_P13")
	)
	(segment
		(start 323.8246 -32.4358)
		(end 323.8246 -30.11424)
		(width 0.136652)
		(layer "F.Cu")
		(net "PCIE_TX_P13")
	)
	(segment
		(start 322.095368 -27.430984)
		(end 322.095368 -25.306528)
		(width 0.136652)
		(layer "F.Cu")
		(net "PCIE_TX_P13")
	)
	(arc
		(start 321.981068 -25.031446)
		(mid 321.976468 -25.026774)
		(end 321.971924 -25.022048)
		(width 0.136652)
		(layer "F.Cu")
		(net "PCIE_TX_P13")
	)
	(arc
		(start 321.801236 -24.85136)
		(mid 321.717895 -24.796793)
		(end 321.620134 -24.7777)
		(width 0.136652)
		(layer "F.Cu")
		(net "PCIE_TX_P13")
	)
	(arc
		(start 321.447668 -24.8285)
		(mid 321.40087 -24.898538)
		(end 321.384422 -24.981154)
		(width 0.136652)
		(layer "F.Cu")
		(net "PCIE_TX_P13")
	)
	(arc
		(start 322.095114 -25.306782)
		(mid 322.065459 -25.157786)
		(end 321.981068 -25.031446)
		(width 0.136652)
		(layer "F.Cu")
		(net "PCIE_TX_P13")
	)
	(arc
		(start 321.57035 -24.7777)
		(mid 321.503961 -24.790906)
		(end 321.447668 -24.8285)
		(width 0.136652)
		(layer "F.Cu")
		(net "PCIE_TX_P13")
	)
	(arc
		(start 323.8246 -30.11424)
		(mid 323.732978 -29.653713)
		(end 323.472048 -29.26334)
		(width 0.136652)
		(layer "F.Cu")
		(net "PCIE_TX_P13")
	)
	(arc
		(start 322.41744 -28.208732)
		(mid 322.179041 -27.851897)
		(end 322.095368 -27.430984)
		(width 0.136652)
		(layer "F.Cu")
		(net "PCIE_TX_P13")
	)
	(arc
		(start 321.803522 -24.853646)
		(mid 321.802383 -24.852499)
		(end 321.801236 -24.85136)
		(width 0.136652)
		(layer "F.Cu")
		(net "PCIE_TX_P13")
	)
	(arc
		(start 323.56171 -33.038288)
		(mid 323.75599 -32.764466)
		(end 323.8246 -32.4358)
		(width 0.136652)
		(layer "F.Cu")
		(net "PCIE_TX_P13")
	)
	(segment
		(start 321.620134 -20.977606)
		(end 321.57035 -20.977606)
		(width 0.136652)
		(layer "F.Cu")
		(net "PCIE_TX_P12")
	)
	(segment
		(start 317.7286 -28.080462)
		(end 317.7286 -24.530304)
		(width 0.136652)
		(layer "F.Cu")
		(net "PCIE_TX_P12")
	)
	(segment
		(start 319.937384 -32.497776)
		(end 319.937384 -30.92577)
		(width 0.136652)
		(layer "F.Cu")
		(net "PCIE_TX_P12")
	)
	(segment
		(start 322.095368 -21.7932)
		(end 322.095368 -21.506688)
		(width 0.136652)
		(layer "F.Cu")
		(net "PCIE_TX_P12")
	)
	(segment
		(start 318.002158 -23.86965)
		(end 318.936116 -22.935692)
		(width 0.136652)
		(layer "F.Cu")
		(net "PCIE_TX_P12")
	)
	(segment
		(start 321.981322 -21.231352)
		(end 321.803522 -21.053552)
		(width 0.136652)
		(layer "F.Cu")
		(net "PCIE_TX_P12")
	)
	(segment
		(start 319.787016 -30.563312)
		(end 318.028574 -28.80487)
		(width 0.136652)
		(layer "F.Cu")
		(net "PCIE_TX_P12")
	)
	(segment
		(start 319.625218 -22.65045)
		(end 321.238118 -22.65045)
		(width 0.136652)
		(layer "F.Cu")
		(net "PCIE_TX_P12")
	)
	(segment
		(start 321.384422 -21.18106)
		(end 321.384422 -21.530056)
		(width 0.136652)
		(layer "F.Cu")
		(net "PCIE_TX_P12")
	)
	(arc
		(start 319.670176 -33.062926)
		(mid 319.867213 -32.810343)
		(end 319.937384 -32.497776)
		(width 0.136652)
		(layer "F.Cu")
		(net "PCIE_TX_P12")
	)
	(arc
		(start 317.7286 -24.530304)
		(mid 317.799645 -24.172757)
		(end 318.002158 -23.86965)
		(width 0.136652)
		(layer "F.Cu")
		(net "PCIE_TX_P12")
	)
	(arc
		(start 322.095368 -21.506688)
		(mid 322.065728 -21.357678)
		(end 321.981322 -21.231352)
		(width 0.136652)
		(layer "F.Cu")
		(net "PCIE_TX_P12")
	)
	(arc
		(start 321.238118 -22.65045)
		(mid 321.844285 -22.399367)
		(end 322.095368 -21.7932)
		(width 0.136652)
		(layer "F.Cu")
		(net "PCIE_TX_P12")
	)
	(arc
		(start 321.57035 -20.977606)
		(mid 321.503961 -20.990812)
		(end 321.447668 -21.028406)
		(width 0.136652)
		(layer "F.Cu")
		(net "PCIE_TX_P12")
	)
	(arc
		(start 321.803522 -21.053552)
		(mid 321.802383 -21.052405)
		(end 321.801236 -21.051266)
		(width 0.136652)
		(layer "F.Cu")
		(net "PCIE_TX_P12")
	)
	(arc
		(start 318.936116 -22.935692)
		(mid 319.252308 -22.724576)
		(end 319.625218 -22.65045)
		(width 0.136652)
		(layer "F.Cu")
		(net "PCIE_TX_P12")
	)
	(arc
		(start 321.801236 -21.051266)
		(mid 321.717895 -20.996699)
		(end 321.620134 -20.977606)
		(width 0.136652)
		(layer "F.Cu")
		(net "PCIE_TX_P12")
	)
	(arc
		(start 321.447668 -21.028406)
		(mid 321.40087 -21.098444)
		(end 321.384422 -21.18106)
		(width 0.136652)
		(layer "F.Cu")
		(net "PCIE_TX_P12")
	)
	(arc
		(start 318.028574 -28.80487)
		(mid 317.806527 -28.472508)
		(end 317.7286 -28.080462)
		(width 0.136652)
		(layer "F.Cu")
		(net "PCIE_TX_P12")
	)
	(arc
		(start 319.937384 -30.92577)
		(mid 319.898249 -30.729588)
		(end 319.787016 -30.563312)
		(width 0.136652)
		(layer "F.Cu")
		(net "PCIE_TX_P12")
	)
	(segment
		(start 312.634376 -21.530056)
		(end 312.634376 -21.18106)
		(width 0.136652)
		(layer "F.Cu")
		(net "PCIE_TX_P11")
	)
	(segment
		(start 313.053476 -21.053552)
		(end 313.231276 -21.231352)
		(width 0.136652)
		(layer "F.Cu")
		(net "PCIE_TX_P11")
	)
	(segment
		(start 313.601354 -22.745446)
		(end 314.91682 -24.060912)
		(width 0.136652)
		(layer "F.Cu")
		(net "PCIE_TX_P11")
	)
	(segment
		(start 312.820304 -20.977606)
		(end 312.870088 -20.977606)
		(width 0.136652)
		(layer "F.Cu")
		(net "PCIE_TX_P11")
	)
	(segment
		(start 315.1124 -24.53259)
		(end 315.1124 -32.5628)
		(width 0.136652)
		(layer "F.Cu")
		(net "PCIE_TX_P11")
	)
	(segment
		(start 313.345322 -21.506688)
		(end 313.345322 -22.12721)
		(width 0.136652)
		(layer "F.Cu")
		(net "PCIE_TX_P11")
	)
	(arc
		(start 313.345322 -22.12721)
		(mid 313.411857 -22.461792)
		(end 313.601354 -22.745446)
		(width 0.136652)
		(layer "F.Cu")
		(net "PCIE_TX_P11")
	)
	(arc
		(start 313.231276 -21.231352)
		(mid 313.315684 -21.357677)
		(end 313.345322 -21.506688)
		(width 0.136652)
		(layer "F.Cu")
		(net "PCIE_TX_P11")
	)
	(arc
		(start 314.91682 -24.060912)
		(mid 315.061556 -24.27729)
		(end 315.1124 -24.53259)
		(width 0.136652)
		(layer "F.Cu")
		(net "PCIE_TX_P11")
	)
	(arc
		(start 312.634376 -21.18106)
		(mid 312.65081 -21.098439)
		(end 312.697622 -21.028406)
		(width 0.136652)
		(layer "F.Cu")
		(net "PCIE_TX_P11")
	)
	(arc
		(start 312.870088 -20.977606)
		(mid 312.967836 -20.996733)
		(end 313.05119 -21.051266)
		(width 0.136652)
		(layer "F.Cu")
		(net "PCIE_TX_P11")
	)
	(arc
		(start 312.697622 -21.028406)
		(mid 312.753909 -20.990796)
		(end 312.820304 -20.977606)
		(width 0.136652)
		(layer "F.Cu")
		(net "PCIE_TX_P11")
	)
	(arc
		(start 313.05119 -21.051266)
		(mid 313.052337 -21.052405)
		(end 313.053476 -21.053552)
		(width 0.136652)
		(layer "F.Cu")
		(net "PCIE_TX_P11")
	)
	(arc
		(start 315.1124 -32.5628)
		(mid 315.038133 -32.858257)
		(end 314.833 -33.0835)
		(width 0.136652)
		(layer "F.Cu")
		(net "PCIE_TX_P11")
	)
	(segment
		(start 312.888122 -26.975816)
		(end 312.887868 -26.975816)
		(width 0.136652)
		(layer "F.Cu")
		(net "PCIE_TX_P10")
	)
	(segment
		(start 312.887868 -26.975816)
		(end 312.888122 -26.97607)
		(width 0.136652)
		(layer "F.Cu")
		(net "PCIE_TX_P10")
	)
	(segment
		(start 313.224672 -26.33345)
		(end 313.102498 -26.455624)
		(width 0.136652)
		(layer "F.Cu")
		(net "PCIE_TX_P10")
	)
	(segment
		(start 313.053476 -24.853646)
		(end 313.231276 -25.031446)
		(width 0.136652)
		(layer "F.Cu")
		(net "PCIE_TX_P10")
	)
	(segment
		(start 313.345322 -25.306782)
		(end 313.345322 -26.042112)
		(width 0.136652)
		(layer "F.Cu")
		(net "PCIE_TX_P10")
	)
	(segment
		(start 312.634376 -25.33015)
		(end 312.634376 -24.981154)
		(width 0.136652)
		(layer "F.Cu")
		(net "PCIE_TX_P10")
	)
	(segment
		(start 312.888122 -26.97607)
		(end 312.888122 -32.5882)
		(width 0.136652)
		(layer "F.Cu")
		(net "PCIE_TX_P10")
	)
	(arc
		(start 312.634376 -24.981154)
		(mid 312.746766 -24.777603)
		(end 312.9788 -24.7904)
		(width 0.136652)
		(layer "F.Cu")
		(net "PCIE_TX_P10")
	)
	(arc
		(start 313.345322 -26.042112)
		(mid 313.313961 -26.199773)
		(end 313.224672 -26.33345)
		(width 0.136652)
		(layer "F.Cu")
		(net "PCIE_TX_P10")
	)
	(arc
		(start 313.05119 -24.85136)
		(mid 313.052337 -24.852499)
		(end 313.053476 -24.853646)
		(width 0.136652)
		(layer "F.Cu")
		(net "PCIE_TX_P10")
	)
	(arc
		(start 313.102498 -26.455624)
		(mid 313.064947 -26.496153)
		(end 313.030616 -26.539444)
		(width 0.136652)
		(layer "F.Cu")
		(net "PCIE_TX_P10")
	)
	(arc
		(start 313.030616 -26.539444)
		(mid 312.924536 -26.746259)
		(end 312.888122 -26.975816)
		(width 0.136652)
		(layer "F.Cu")
		(net "PCIE_TX_P10")
	)
	(arc
		(start 312.9788 -24.7904)
		(mid 313.016309 -24.81932)
		(end 313.05119 -24.85136)
		(width 0.136652)
		(layer "F.Cu")
		(net "PCIE_TX_P10")
	)
	(arc
		(start 313.231276 -25.031446)
		(mid 313.315684 -25.157771)
		(end 313.345322 -25.306782)
		(width 0.136652)
		(layer "F.Cu")
		(net "PCIE_TX_P10")
	)
	(arc
		(start 312.888122 -32.5882)
		(mid 312.818785 -32.881154)
		(end 312.625486 -33.111948)
		(width 0.136652)
		(layer "F.Cu")
		(net "PCIE_TX_P10")
	)
	(segment
		(start 278.25827 -24.774652)
		(end 278.139652 -24.48814)
		(width 0.136652)
		(layer "F.Cu")
		(net "PCIE_TX_P1")
	)
	(segment
		(start 275.759672 -14.7828)
		(end 274.890738 -14.7828)
		(width 0.136652)
		(layer "F.Cu")
		(net "PCIE_TX_P1")
	)
	(segment
		(start 288.763456 -24.657812)
		(end 288.818066 -24.712168)
		(width 0.136652)
		(layer "F.Cu")
		(net "PCIE_TX_P1")
	)
	(segment
		(start 274.545298 -14.639544)
		(end 274.3835 -14.478)
		(width 0.136652)
		(layer "F.Cu")
		(net "PCIE_TX_P1")
	)
	(segment
		(start 288.344102 -24.673306)
		(end 288.373566 -24.643842)
		(width 0.136652)
		(layer "F.Cu")
		(net "PCIE_TX_P1")
	)
	(segment
		(start 288.483294 -24.598376)
		(end 288.619946 -24.598376)
		(width 0.136652)
		(layer "F.Cu")
		(net "PCIE_TX_P1")
	)
	(segment
		(start 279.807162 -25.822148)
		(end 278.816562 -25.358852)
		(width 0.136652)
		(layer "F.Cu")
		(net "PCIE_TX_P1")
	)
	(segment
		(start 288.59353 -26.065988)
		(end 280.903426 -26.065988)
		(width 0.136652)
		(layer "F.Cu")
		(net "PCIE_TX_P1")
	)
	(segment
		(start 277.964392 -23.607776)
		(end 277.964392 -16.609314)
		(width 0.136652)
		(layer "F.Cu")
		(net "PCIE_TX_P1")
	)
	(segment
		(start 289.050222 -25.272746)
		(end 289.050222 -25.609296)
		(width 0.136652)
		(layer "F.Cu")
		(net "PCIE_TX_P1")
	)
	(segment
		(start 289.049968 -25.272746)
		(end 289.050222 -25.272746)
		(width 0.136652)
		(layer "F.Cu")
		(net "PCIE_TX_P1")
	)
	(segment
		(start 288.384488 -25.33015)
		(end 288.285682 -24.916638)
		(width 0.136652)
		(layer "F.Cu")
		(net "PCIE_TX_P1")
	)
	(segment
		(start 288.967164 -24.919432)
		(end 288.967164 -24.919178)
		(width 0.136652)
		(layer "F.Cu")
		(net "PCIE_TX_P1")
	)
	(segment
		(start 288.285682 -24.916638)
		(end 288.285682 -24.814276)
		(width 0.136652)
		(layer "F.Cu")
		(net "PCIE_TX_P1")
	)
	(arc
		(start 288.818066 -24.712168)
		(mid 288.901025 -24.809752)
		(end 288.967164 -24.919432)
		(width 0.136652)
		(layer "F.Cu")
		(net "PCIE_TX_P1")
	)
	(arc
		(start 288.916364 -25.93213)
		(mid 288.768262 -26.031182)
		(end 288.59353 -26.065988)
		(width 0.136652)
		(layer "F.Cu")
		(net "PCIE_TX_P1")
	)
	(arc
		(start 278.816562 -25.358852)
		(mid 278.482699 -25.119035)
		(end 278.25827 -24.774652)
		(width 0.136652)
		(layer "F.Cu")
		(net "PCIE_TX_P1")
	)
	(arc
		(start 288.285682 -24.814276)
		(mid 288.30086 -24.737973)
		(end 288.344102 -24.673306)
		(width 0.136652)
		(layer "F.Cu")
		(net "PCIE_TX_P1")
	)
	(arc
		(start 289.010344 -25.02408)
		(mid 289.040107 -25.146829)
		(end 289.049968 -25.272746)
		(width 0.136652)
		(layer "F.Cu")
		(net "PCIE_TX_P1")
	)
	(arc
		(start 277.964392 -16.609314)
		(mid 277.845712 -16.012579)
		(end 277.5077 -15.5067)
		(width 0.136652)
		(layer "F.Cu")
		(net "PCIE_TX_P1")
	)
	(arc
		(start 289.050222 -25.609296)
		(mid 289.015375 -25.784011)
		(end 288.916364 -25.93213)
		(width 0.136652)
		(layer "F.Cu")
		(net "PCIE_TX_P1")
	)
	(arc
		(start 288.619946 -24.598376)
		(mid 288.69761 -24.613824)
		(end 288.763456 -24.657812)
		(width 0.136652)
		(layer "F.Cu")
		(net "PCIE_TX_P1")
	)
	(arc
		(start 288.373566 -24.643842)
		(mid 288.42391 -24.610203)
		(end 288.483294 -24.598376)
		(width 0.136652)
		(layer "F.Cu")
		(net "PCIE_TX_P1")
	)
	(arc
		(start 280.903426 -26.065988)
		(mid 280.341906 -26.004262)
		(end 279.807162 -25.822148)
		(width 0.136652)
		(layer "F.Cu")
		(net "PCIE_TX_P1")
	)
	(arc
		(start 274.890738 -14.7828)
		(mid 274.703776 -14.745517)
		(end 274.545298 -14.639544)
		(width 0.136652)
		(layer "F.Cu")
		(net "PCIE_TX_P1")
	)
	(arc
		(start 278.139652 -24.48814)
		(mid 278.00864 -24.056593)
		(end 277.964392 -23.607776)
		(width 0.136652)
		(layer "F.Cu")
		(net "PCIE_TX_P1")
	)
	(arc
		(start 288.967164 -24.919178)
		(mid 288.990632 -24.970856)
		(end 289.010344 -25.02408)
		(width 0.136652)
		(layer "F.Cu")
		(net "PCIE_TX_P1")
	)
	(arc
		(start 277.5077 -15.5067)
		(mid 276.705683 -14.970902)
		(end 275.759672 -14.7828)
		(width 0.136652)
		(layer "F.Cu")
		(net "PCIE_TX_P1")
	)
	(segment
		(start 283.089858 -18.81505)
		(end 277.702518 -13.42771)
		(width 0.136652)
		(layer "F.Cu")
		(net "PCIE_TX_P0")
	)
	(segment
		(start 287.149032 -19.18462)
		(end 283.982414 -19.18462)
		(width 0.136652)
		(layer "F.Cu")
		(net "PCIE_TX_P0")
	)
	(segment
		(start 288.433002 -20.72767)
		(end 288.111946 -20.406614)
		(width 0.136652)
		(layer "F.Cu")
		(net "PCIE_TX_P0")
	)
	(segment
		(start 287.757108 -19.547078)
		(end 287.568386 -19.358356)
		(width 0.136652)
		(layer "F.Cu")
		(net "PCIE_TX_P0")
	)
	(segment
		(start 277.386542 -13.2969)
		(end 275.088604 -13.2969)
		(width 0.136652)
		(layer "F.Cu")
		(net "PCIE_TX_P0")
	)
	(segment
		(start 287.960816 -20.041616)
		(end 287.960816 -20.038822)
		(width 0.136652)
		(layer "F.Cu")
		(net "PCIE_TX_P0")
	)
	(arc
		(start 283.982414 -19.18462)
		(mid 283.499366 -19.088629)
		(end 283.089858 -18.81505)
		(width 0.136652)
		(layer "F.Cu")
		(net "PCIE_TX_P0")
	)
	(arc
		(start 287.568386 -19.358356)
		(mid 287.375985 -19.229798)
		(end 287.149032 -19.18462)
		(width 0.136652)
		(layer "F.Cu")
		(net "PCIE_TX_P0")
	)
	(arc
		(start 288.384488 -21.530056)
		(mid 288.589269 -21.139788)
		(end 288.433002 -20.72767)
		(width 0.136652)
		(layer "F.Cu")
		(net "PCIE_TX_P0")
	)
	(arc
		(start 275.088604 -13.2969)
		(mid 274.706991 -13.372808)
		(end 274.3835 -13.589)
		(width 0.136652)
		(layer "F.Cu")
		(net "PCIE_TX_P0")
	)
	(arc
		(start 287.960816 -20.038822)
		(mid 287.907878 -19.772684)
		(end 287.757108 -19.547078)
		(width 0.136652)
		(layer "F.Cu")
		(net "PCIE_TX_P0")
	)
	(arc
		(start 288.111946 -20.406614)
		(mid 288.000105 -20.239137)
		(end 287.960816 -20.041616)
		(width 0.136652)
		(layer "F.Cu")
		(net "PCIE_TX_P0")
	)
	(arc
		(start 277.702518 -13.42771)
		(mid 277.557533 -13.330897)
		(end 277.386542 -13.2969)
		(width 0.136652)
		(layer "F.Cu")
		(net "PCIE_TX_P0")
	)
	(segment
		(start 173.081442 -20.288758)
		(end 173.0883 -20.2819)
		(width 0.136652)
		(layer "F.Cu")
		(net "PCIE_TX_N95")
	)
	(segment
		(start 172.18406 -21.444458)
		(end 172.18406 -21.444204)
		(width 0.136652)
		(layer "F.Cu")
		(net "PCIE_TX_N95")
	)
	(segment
		(start 171.384468 -20.130008)
		(end 171.384468 -20.554188)
		(width 0.136652)
		(layer "F.Cu")
		(net "PCIE_TX_N95")
	)
	(segment
		(start 173.517306 -20.1041)
		(end 180.460396 -20.1041)
		(width 0.136652)
		(layer "F.Cu")
		(net "PCIE_TX_N95")
	)
	(segment
		(start 172.083984 -21.444458)
		(end 172.18406 -21.444458)
		(width 0.136652)
		(layer "F.Cu")
		(net "PCIE_TX_N95")
	)
	(segment
		(start 172.567854 -21.285454)
		(end 172.740066 -21.113242)
		(width 0.136652)
		(layer "F.Cu")
		(net "PCIE_TX_N95")
	)
	(arc
		(start 171.684696 -21.279104)
		(mid 171.758453 -21.341068)
		(end 171.841668 -21.389594)
		(width 0.136652)
		(layer "F.Cu")
		(net "PCIE_TX_N95")
	)
	(arc
		(start 171.527724 -21.077174)
		(mid 171.599879 -21.183062)
		(end 171.684696 -21.279104)
		(width 0.136652)
		(layer "F.Cu")
		(net "PCIE_TX_N95")
	)
	(arc
		(start 172.18406 -21.444204)
		(mid 172.283394 -21.435037)
		(end 172.379386 -21.407882)
		(width 0.136652)
		(layer "F.Cu")
		(net "PCIE_TX_N95")
	)
	(arc
		(start 172.740066 -21.113242)
		(mid 172.86639 -20.92409)
		(end 172.910754 -20.701)
		(width 0.136652)
		(layer "F.Cu")
		(net "PCIE_TX_N95")
	)
	(arc
		(start 172.379386 -21.407882)
		(mid 172.480019 -21.356521)
		(end 172.567854 -21.285454)
		(width 0.136652)
		(layer "F.Cu")
		(net "PCIE_TX_N95")
	)
	(arc
		(start 172.910754 -20.701)
		(mid 172.955112 -20.477908)
		(end 173.081442 -20.288758)
		(width 0.136652)
		(layer "F.Cu")
		(net "PCIE_TX_N95")
	)
	(arc
		(start 171.384468 -20.554188)
		(mid 171.420903 -20.825319)
		(end 171.527724 -21.077174)
		(width 0.136652)
		(layer "F.Cu")
		(net "PCIE_TX_N95")
	)
	(arc
		(start 171.841668 -21.389594)
		(mid 171.95977 -21.430526)
		(end 172.083984 -21.444458)
		(width 0.136652)
		(layer "F.Cu")
		(net "PCIE_TX_N95")
	)
	(arc
		(start 180.460396 -20.1041)
		(mid 180.842009 -20.028192)
		(end 181.1655 -19.812)
		(width 0.136652)
		(layer "F.Cu")
		(net "PCIE_TX_N95")
	)
	(arc
		(start 173.0883 -20.2819)
		(mid 173.285115 -20.150329)
		(end 173.517306 -20.1041)
		(width 0.136652)
		(layer "F.Cu")
		(net "PCIE_TX_N95")
	)
	(segment
		(start 180.6448 -23.880572)
		(end 174.168562 -23.880572)
		(width 0.136652)
		(layer "F.Cu")
		(net "PCIE_TX_N94")
	)
	(segment
		(start 171.384468 -24.242268)
		(end 171.384468 -23.930102)
		(width 0.136652)
		(layer "F.Cu")
		(net "PCIE_TX_N94")
	)
	(segment
		(start 173.503844 -24.155908)
		(end 172.572426 -25.087326)
		(width 0.136652)
		(layer "F.Cu")
		(net "PCIE_TX_N94")
	)
	(arc
		(start 181.1655 -23.622)
		(mid 180.935486 -23.812377)
		(end 180.6448 -23.880572)
		(width 0.136652)
		(layer "F.Cu")
		(net "PCIE_TX_N94")
	)
	(arc
		(start 171.922186 -25.223978)
		(mid 171.828838 -25.177294)
		(end 171.745656 -25.11425)
		(width 0.136652)
		(layer "F.Cu")
		(net "PCIE_TX_N94")
	)
	(arc
		(start 171.745656 -25.11425)
		(mid 171.478339 -24.714181)
		(end 171.384468 -24.242268)
		(width 0.136652)
		(layer "F.Cu")
		(net "PCIE_TX_N94")
	)
	(arc
		(start 174.168562 -23.880572)
		(mid 173.808833 -23.952144)
		(end 173.503844 -24.155908)
		(width 0.136652)
		(layer "F.Cu")
		(net "PCIE_TX_N94")
	)
	(arc
		(start 172.572426 -25.087326)
		(mid 172.386931 -25.214094)
		(end 172.168058 -25.264872)
		(width 0.136652)
		(layer "F.Cu")
		(net "PCIE_TX_N94")
	)
	(arc
		(start 172.168058 -25.264872)
		(mid 172.042999 -25.257178)
		(end 171.922186 -25.223978)
		(width 0.136652)
		(layer "F.Cu")
		(net "PCIE_TX_N94")
	)
	(segment
		(start 178.272694 -26.575258)
		(end 174.78629 -29.01569)
		(width 0.136652)
		(layer "F.Cu")
		(net "PCIE_TX_N93")
	)
	(segment
		(start 171.393612 -28.608528)
		(end 170.482514 -27.30754)
		(width 0.136652)
		(layer "F.Cu")
		(net "PCIE_TX_N93")
	)
	(segment
		(start 174.393352 -29.197046)
		(end 173.961298 -29.309314)
		(width 0.136652)
		(layer "F.Cu")
		(net "PCIE_TX_N93")
	)
	(segment
		(start 169.134536 -24.151336)
		(end 169.134536 -23.930102)
		(width 0.136652)
		(layer "F.Cu")
		(net "PCIE_TX_N93")
	)
	(segment
		(start 169.93362 -25.89022)
		(end 169.801286 -25.75814)
		(width 0.136652)
		(layer "F.Cu")
		(net "PCIE_TX_N93")
	)
	(segment
		(start 180.6194 -26.2001)
		(end 179.7558 -26.2001)
		(width 0.136652)
		(layer "F.Cu")
		(net "PCIE_TX_N93")
	)
	(segment
		(start 173.235112 -29.338016)
		(end 172.201332 -29.15539)
		(width 0.136652)
		(layer "F.Cu")
		(net "PCIE_TX_N93")
	)
	(segment
		(start 170.269408 -26.501852)
		(end 170.136566 -26.190194)
		(width 0.136652)
		(layer "F.Cu")
		(net "PCIE_TX_N93")
	)
	(segment
		(start 170.450002 -27.2288)
		(end 170.398694 -26.937462)
		(width 0.136652)
		(layer "F.Cu")
		(net "PCIE_TX_N93")
	)
	(segment
		(start 171.951142 -29.051758)
		(end 171.568872 -28.783788)
		(width 0.136652)
		(layer "F.Cu")
		(net "PCIE_TX_N93")
	)
	(arc
		(start 170.482514 -27.30754)
		(mid 170.461927 -27.269956)
		(end 170.450002 -27.2288)
		(width 0.136652)
		(layer "F.Cu")
		(net "PCIE_TX_N93")
	)
	(arc
		(start 169.24782 -24.859234)
		(mid 169.163047 -24.509787)
		(end 169.134536 -24.151336)
		(width 0.136652)
		(layer "F.Cu")
		(net "PCIE_TX_N93")
	)
	(arc
		(start 172.201332 -29.15539)
		(mid 172.070557 -29.117286)
		(end 171.951142 -29.051758)
		(width 0.136652)
		(layer "F.Cu")
		(net "PCIE_TX_N93")
	)
	(arc
		(start 173.961298 -29.309314)
		(mid 173.599749 -29.362712)
		(end 173.235112 -29.338016)
		(width 0.136652)
		(layer "F.Cu")
		(net "PCIE_TX_N93")
	)
	(arc
		(start 171.568872 -28.783788)
		(mid 171.473585 -28.703815)
		(end 171.393612 -28.608528)
		(width 0.136652)
		(layer "F.Cu")
		(net "PCIE_TX_N93")
	)
	(arc
		(start 169.388028 -25.193752)
		(mid 169.330953 -25.075163)
		(end 169.28084 -24.953468)
		(width 0.136652)
		(layer "F.Cu")
		(net "PCIE_TX_N93")
	)
	(arc
		(start 170.398694 -26.937462)
		(mid 170.346505 -26.71596)
		(end 170.269408 -26.501852)
		(width 0.136652)
		(layer "F.Cu")
		(net "PCIE_TX_N93")
	)
	(arc
		(start 181.1655 -25.908)
		(mid 180.92905 -26.12247)
		(end 180.6194 -26.2001)
		(width 0.136652)
		(layer "F.Cu")
		(net "PCIE_TX_N93")
	)
	(arc
		(start 174.78629 -29.01569)
		(mid 174.597921 -29.123915)
		(end 174.393352 -29.197046)
		(width 0.136652)
		(layer "F.Cu")
		(net "PCIE_TX_N93")
	)
	(arc
		(start 169.262298 -24.902922)
		(mid 169.254948 -24.881115)
		(end 169.24782 -24.859234)
		(width 0.136652)
		(layer "F.Cu")
		(net "PCIE_TX_N93")
	)
	(arc
		(start 169.28084 -24.953468)
		(mid 169.271418 -24.92825)
		(end 169.262298 -24.902922)
		(width 0.136652)
		(layer "F.Cu")
		(net "PCIE_TX_N93")
	)
	(arc
		(start 170.136566 -26.190194)
		(mid 170.04952 -26.030449)
		(end 169.93362 -25.89022)
		(width 0.136652)
		(layer "F.Cu")
		(net "PCIE_TX_N93")
	)
	(arc
		(start 179.7558 -26.2001)
		(mid 178.990891 -26.295344)
		(end 178.272694 -26.575258)
		(width 0.136652)
		(layer "F.Cu")
		(net "PCIE_TX_N93")
	)
	(arc
		(start 169.801286 -25.75814)
		(mid 169.5728 -25.491949)
		(end 169.388028 -25.193752)
		(width 0.136652)
		(layer "F.Cu")
		(net "PCIE_TX_N93")
	)
	(segment
		(start 179.1081 -22.4917)
		(end 179.457604 -22.142196)
		(width 0.136652)
		(layer "F.Cu")
		(net "PCIE_TX_N92")
	)
	(segment
		(start 169.72788 -21.572474)
		(end 170.01236 -22.291802)
		(width 0.136652)
		(layer "F.Cu")
		(net "PCIE_TX_N92")
	)
	(segment
		(start 170.80484 -22.827234)
		(end 172.066458 -22.67331)
		(width 0.136652)
		(layer "F.Cu")
		(net "PCIE_TX_N92")
	)
	(segment
		(start 169.403776 -21.24837)
		(end 169.72788 -21.572474)
		(width 0.136652)
		(layer "F.Cu")
		(net "PCIE_TX_N92")
	)
	(segment
		(start 180.086 -21.8821)
		(end 180.460396 -21.8821)
		(width 0.136652)
		(layer "F.Cu")
		(net "PCIE_TX_N92")
	)
	(segment
		(start 170.309794 -22.629114)
		(end 170.80484 -22.827234)
		(width 0.136652)
		(layer "F.Cu")
		(net "PCIE_TX_N92")
	)
	(segment
		(start 170.01236 -22.291802)
		(end 170.309794 -22.629114)
		(width 0.136652)
		(layer "F.Cu")
		(net "PCIE_TX_N92")
	)
	(segment
		(start 172.066458 -22.67331)
		(end 178.669696 -22.67331)
		(width 0.136652)
		(layer "F.Cu")
		(net "PCIE_TX_N92")
	)
	(segment
		(start 169.134536 -20.130008)
		(end 169.134536 -20.598384)
		(width 0.136652)
		(layer "F.Cu")
		(net "PCIE_TX_N92")
	)
	(arc
		(start 169.134536 -20.598384)
		(mid 169.163474 -20.827471)
		(end 169.248582 -21.042122)
		(width 0.136652)
		(layer "F.Cu")
		(net "PCIE_TX_N92")
	)
	(arc
		(start 169.269664 -21.078444)
		(mid 169.331701 -21.167368)
		(end 169.403776 -21.24837)
		(width 0.136652)
		(layer "F.Cu")
		(net "PCIE_TX_N92")
	)
	(arc
		(start 179.457604 -22.142196)
		(mid 179.745944 -21.94969)
		(end 180.086 -21.8821)
		(width 0.136652)
		(layer "F.Cu")
		(net "PCIE_TX_N92")
	)
	(arc
		(start 169.248582 -21.042122)
		(mid 169.258916 -21.060403)
		(end 169.269664 -21.078444)
		(width 0.136652)
		(layer "F.Cu")
		(net "PCIE_TX_N92")
	)
	(arc
		(start 180.460396 -21.8821)
		(mid 180.842009 -21.806192)
		(end 181.1655 -21.59)
		(width 0.136652)
		(layer "F.Cu")
		(net "PCIE_TX_N92")
	)
	(arc
		(start 178.669696 -22.67331)
		(mid 178.906965 -22.626114)
		(end 179.1081 -22.4917)
		(width 0.136652)
		(layer "F.Cu")
		(net "PCIE_TX_N92")
	)
	(segment
		(start 175.65116 -31.755842)
		(end 178.836066 -29.52496)
		(width 0.136652)
		(layer "F.Cu")
		(net "PCIE_TX_N91")
	)
	(segment
		(start 161.92246 -21.692616)
		(end 163.216336 -22.986492)
		(width 0.136652)
		(layer "F.Cu")
		(net "PCIE_TX_N91")
	)
	(segment
		(start 167.875204 -29.646118)
		(end 170.429174 -31.434532)
		(width 0.136652)
		(layer "F.Cu")
		(net "PCIE_TX_N91")
	)
	(segment
		(start 179.862734 -29.2481)
		(end 180.721 -29.2481)
		(width 0.136652)
		(layer "F.Cu")
		(net "PCIE_TX_N91")
	)
	(segment
		(start 170.761152 -31.571946)
		(end 173.797468 -32.107124)
		(width 0.136652)
		(layer "F.Cu")
		(net "PCIE_TX_N91")
	)
	(segment
		(start 174.262034 -32.10687)
		(end 175.21428 -31.937198)
		(width 0.136652)
		(layer "F.Cu")
		(net "PCIE_TX_N91")
	)
	(segment
		(start 179.239672 -29.357828)
		(end 179.862734 -29.2481)
		(width 0.136652)
		(layer "F.Cu")
		(net "PCIE_TX_N91")
	)
	(segment
		(start 161.117026 -21.463)
		(end 161.3662 -21.463)
		(width 0.136652)
		(layer "F.Cu")
		(net "PCIE_TX_N91")
	)
	(segment
		(start 160.274 -20.396708)
		(end 160.274 -20.574)
		(width 0.136652)
		(layer "F.Cu")
		(net "PCIE_TX_N91")
	)
	(segment
		(start 163.216336 -22.986492)
		(end 167.875204 -29.646118)
		(width 0.136652)
		(layer "F.Cu")
		(net "PCIE_TX_N91")
	)
	(segment
		(start 161.92246 -21.69287)
		(end 161.92246 -21.692616)
		(width 0.136652)
		(layer "F.Cu")
		(net "PCIE_TX_N91")
	)
	(segment
		(start 160.471612 -21.051012)
		(end 160.7185 -21.2979)
		(width 0.136652)
		(layer "F.Cu")
		(net "PCIE_TX_N91")
	)
	(arc
		(start 160.872678 -21.407374)
		(mid 160.991723 -21.448927)
		(end 161.117026 -21.463)
		(width 0.136652)
		(layer "F.Cu")
		(net "PCIE_TX_N91")
	)
	(arc
		(start 161.3662 -21.463)
		(mid 161.522051 -21.47847)
		(end 161.671762 -21.524468)
		(width 0.136652)
		(layer "F.Cu")
		(net "PCIE_TX_N91")
	)
	(arc
		(start 170.429174 -31.434532)
		(mid 170.587645 -31.521394)
		(end 170.761152 -31.571946)
		(width 0.136652)
		(layer "F.Cu")
		(net "PCIE_TX_N91")
	)
	(arc
		(start 175.21428 -31.937198)
		(mid 175.442626 -31.870376)
		(end 175.65116 -31.755842)
		(width 0.136652)
		(layer "F.Cu")
		(net "PCIE_TX_N91")
	)
	(arc
		(start 173.797468 -32.107124)
		(mid 174.029763 -32.127434)
		(end 174.262034 -32.10687)
		(width 0.136652)
		(layer "F.Cu")
		(net "PCIE_TX_N91")
	)
	(arc
		(start 160.7185 -21.2979)
		(mid 160.790963 -21.359153)
		(end 160.872678 -21.407374)
		(width 0.136652)
		(layer "F.Cu")
		(net "PCIE_TX_N91")
	)
	(arc
		(start 161.671762 -21.524468)
		(mid 161.805284 -21.596499)
		(end 161.92246 -21.69287)
		(width 0.136652)
		(layer "F.Cu")
		(net "PCIE_TX_N91")
	)
	(arc
		(start 178.836066 -29.52496)
		(mid 179.028702 -29.419247)
		(end 179.239672 -29.357828)
		(width 0.136652)
		(layer "F.Cu")
		(net "PCIE_TX_N91")
	)
	(arc
		(start 160.274 -20.574)
		(mid 160.325353 -20.832167)
		(end 160.471612 -21.051012)
		(width 0.136652)
		(layer "F.Cu")
		(net "PCIE_TX_N91")
	)
	(arc
		(start 180.721 -29.2481)
		(mid 180.986963 -29.16855)
		(end 181.1655 -28.956)
		(width 0.136652)
		(layer "F.Cu")
		(net "PCIE_TX_N91")
	)
	(arc
		(start 160.38449 -20.130008)
		(mid 160.30273 -20.252371)
		(end 160.274 -20.396708)
		(width 0.136652)
		(layer "F.Cu")
		(net "PCIE_TX_N91")
	)
	(segment
		(start 160.38449 -24.503634)
		(end 160.38449 -23.930102)
		(width 0.136652)
		(layer "F.Cu")
		(net "PCIE_TX_N90")
	)
	(segment
		(start 160.2359 -27.235658)
		(end 160.2359 -26.945844)
		(width 0.136652)
		(layer "F.Cu")
		(net "PCIE_TX_N90")
	)
	(segment
		(start 160.332674 -26.712418)
		(end 160.557718 -26.487374)
		(width 0.136652)
		(layer "F.Cu")
		(net "PCIE_TX_N90")
	)
	(segment
		(start 160.8328 -25.822656)
		(end 160.8328 -25.586436)
		(width 0.136652)
		(layer "F.Cu")
		(net "PCIE_TX_N90")
	)
	(segment
		(start 161.46145 -28.51785)
		(end 160.276032 -27.332432)
		(width 0.136652)
		(layer "F.Cu")
		(net "PCIE_TX_N90")
	)
	(segment
		(start 161.7599 -32.6644)
		(end 161.7599 -29.238702)
		(width 0.136652)
		(layer "F.Cu")
		(net "PCIE_TX_N90")
	)
	(arc
		(start 160.557718 -24.921718)
		(mid 160.429549 -24.729899)
		(end 160.38449 -24.503634)
		(width 0.136652)
		(layer "F.Cu")
		(net "PCIE_TX_N90")
	)
	(arc
		(start 160.8328 -25.586436)
		(mid 160.76136 -25.226722)
		(end 160.557718 -24.921718)
		(width 0.136652)
		(layer "F.Cu")
		(net "PCIE_TX_N90")
	)
	(arc
		(start 161.7599 -29.238702)
		(mid 161.682431 -28.848567)
		(end 161.46145 -28.51785)
		(width 0.136652)
		(layer "F.Cu")
		(net "PCIE_TX_N90")
	)
	(arc
		(start 162.052 -33.0835)
		(mid 161.840164 -32.91981)
		(end 161.7599 -32.6644)
		(width 0.136652)
		(layer "F.Cu")
		(net "PCIE_TX_N90")
	)
	(arc
		(start 160.2359 -26.945844)
		(mid 160.261103 -26.819521)
		(end 160.332674 -26.712418)
		(width 0.136652)
		(layer "F.Cu")
		(net "PCIE_TX_N90")
	)
	(arc
		(start 160.557718 -26.487374)
		(mid 160.761359 -26.18237)
		(end 160.8328 -25.822656)
		(width 0.136652)
		(layer "F.Cu")
		(net "PCIE_TX_N90")
	)
	(arc
		(start 160.276032 -27.332432)
		(mid 160.246311 -27.288046)
		(end 160.2359 -27.235658)
		(width 0.136652)
		(layer "F.Cu")
		(net "PCIE_TX_N90")
	)
	(segment
		(start 310.94299 -26.975816)
		(end 310.94299 -32.639)
		(width 0.136652)
		(layer "F.Cu")
		(net "PCIE_TX_N9")
	)
	(segment
		(start 311.190386 -26.549096)
		(end 311.069736 -26.669746)
		(width 0.136652)
		(layer "F.Cu")
		(net "PCIE_TX_N9")
	)
	(segment
		(start 311.134506 -23.930102)
		(end 311.134506 -24.664924)
		(width 0.136652)
		(layer "F.Cu")
		(net "PCIE_TX_N9")
	)
	(segment
		(start 311.40019 -25.306782)
		(end 311.40019 -26.042112)
		(width 0.136652)
		(layer "F.Cu")
		(net "PCIE_TX_N9")
	)
	(arc
		(start 310.94299 -32.639)
		(mid 311.030769 -32.924444)
		(end 311.263792 -33.111186)
		(width 0.136652)
		(layer "F.Cu")
		(net "PCIE_TX_N9")
	)
	(arc
		(start 311.204102 -26.535126)
		(mid 311.197291 -26.542158)
		(end 311.190386 -26.549096)
		(width 0.136652)
		(layer "F.Cu")
		(net "PCIE_TX_N9")
	)
	(arc
		(start 311.069736 -26.669746)
		(mid 311.047316 -26.693944)
		(end 311.02681 -26.719784)
		(width 0.136652)
		(layer "F.Cu")
		(net "PCIE_TX_N9")
	)
	(arc
		(start 311.40019 -26.042112)
		(mid 311.349392 -26.307399)
		(end 311.204102 -26.535126)
		(width 0.136652)
		(layer "F.Cu")
		(net "PCIE_TX_N9")
	)
	(arc
		(start 311.134506 -24.664924)
		(mid 311.150747 -24.746573)
		(end 311.19699 -24.8158)
		(width 0.136652)
		(layer "F.Cu")
		(net "PCIE_TX_N9")
	)
	(arc
		(start 311.19699 -24.8158)
		(mid 311.347424 -25.041079)
		(end 311.40019 -25.306782)
		(width 0.136652)
		(layer "F.Cu")
		(net "PCIE_TX_N9")
	)
	(arc
		(start 311.02681 -26.719784)
		(mid 310.964461 -26.841111)
		(end 310.94299 -26.975816)
		(width 0.136652)
		(layer "F.Cu")
		(net "PCIE_TX_N9")
	)
	(segment
		(start 158.623762 -30.036262)
		(end 159.008318 -30.420818)
		(width 0.136652)
		(layer "F.Cu")
		(net "PCIE_TX_N89")
	)
	(segment
		(start 158.386018 -25.010618)
		(end 158.386272 -25.010872)
		(width 0.136652)
		(layer "F.Cu")
		(net "PCIE_TX_N89")
	)
	(segment
		(start 158.5722 -25.459944)
		(end 158.5722 -29.911802)
		(width 0.136652)
		(layer "F.Cu")
		(net "PCIE_TX_N89")
	)
	(segment
		(start 158.134558 -23.930102)
		(end 158.134558 -24.403304)
		(width 0.136652)
		(layer "F.Cu")
		(net "PCIE_TX_N89")
	)
	(segment
		(start 159.137604 -30.733238)
		(end 159.137604 -32.6644)
		(width 0.136652)
		(layer "F.Cu")
		(net "PCIE_TX_N89")
	)
	(arc
		(start 159.008318 -30.420818)
		(mid 159.104011 -30.564173)
		(end 159.137604 -30.733238)
		(width 0.136652)
		(layer "F.Cu")
		(net "PCIE_TX_N89")
	)
	(arc
		(start 159.137604 -32.6644)
		(mid 159.217827 -32.919839)
		(end 159.429704 -33.0835)
		(width 0.136652)
		(layer "F.Cu")
		(net "PCIE_TX_N89")
	)
	(arc
		(start 158.386272 -25.010872)
		(mid 158.523887 -25.216922)
		(end 158.5722 -25.459944)
		(width 0.136652)
		(layer "F.Cu")
		(net "PCIE_TX_N89")
	)
	(arc
		(start 158.134558 -24.403304)
		(mid 158.199898 -24.731971)
		(end 158.386018 -25.010618)
		(width 0.136652)
		(layer "F.Cu")
		(net "PCIE_TX_N89")
	)
	(arc
		(start 158.5722 -29.911802)
		(mid 158.585599 -29.979163)
		(end 158.623762 -30.036262)
		(width 0.136652)
		(layer "F.Cu")
		(net "PCIE_TX_N89")
	)
	(segment
		(start 158.678118 -21.518118)
		(end 159.186626 -22.42439)
		(width 0.136652)
		(layer "F.Cu")
		(net "PCIE_TX_N88")
	)
	(segment
		(start 159.186626 -22.42439)
		(end 159.747966 -22.8346)
		(width 0.136652)
		(layer "F.Cu")
		(net "PCIE_TX_N88")
	)
	(segment
		(start 162.358578 -25.300178)
		(end 163.516564 -26.458164)
		(width 0.136652)
		(layer "F.Cu")
		(net "PCIE_TX_N88")
	)
	(segment
		(start 158.4579 -21.2979)
		(end 158.678118 -21.518118)
		(width 0.136652)
		(layer "F.Cu")
		(net "PCIE_TX_N88")
	)
	(segment
		(start 158.134558 -20.130008)
		(end 158.134558 -20.517358)
		(width 0.136652)
		(layer "F.Cu")
		(net "PCIE_TX_N88")
	)
	(segment
		(start 163.7919 -27.122882)
		(end 163.7919 -32.6644)
		(width 0.136652)
		(layer "F.Cu")
		(net "PCIE_TX_N88")
	)
	(segment
		(start 159.747966 -22.8346)
		(end 160.823656 -22.8346)
		(width 0.136652)
		(layer "F.Cu")
		(net "PCIE_TX_N88")
	)
	(segment
		(start 162.2298 -24.240236)
		(end 162.2298 -24.989282)
		(width 0.136652)
		(layer "F.Cu")
		(net "PCIE_TX_N88")
	)
	(segment
		(start 161.488374 -23.109682)
		(end 161.954718 -23.576026)
		(width 0.136652)
		(layer "F.Cu")
		(net "PCIE_TX_N88")
	)
	(arc
		(start 161.954718 -23.576026)
		(mid 162.158262 -23.880796)
		(end 162.2298 -24.240236)
		(width 0.136652)
		(layer "F.Cu")
		(net "PCIE_TX_N88")
	)
	(arc
		(start 163.516564 -26.458164)
		(mid 163.720396 -26.763125)
		(end 163.7919 -27.122882)
		(width 0.136652)
		(layer "F.Cu")
		(net "PCIE_TX_N88")
	)
	(arc
		(start 158.169102 -20.79117)
		(mid 158.173655 -20.808735)
		(end 158.1785 -20.826222)
		(width 0.136652)
		(layer "F.Cu")
		(net "PCIE_TX_N88")
	)
	(arc
		(start 158.1785 -20.826222)
		(mid 158.189932 -20.862754)
		(end 158.20263 -20.898866)
		(width 0.136652)
		(layer "F.Cu")
		(net "PCIE_TX_N88")
	)
	(arc
		(start 158.20263 -20.898866)
		(mid 158.308614 -21.112232)
		(end 158.4579 -21.2979)
		(width 0.136652)
		(layer "F.Cu")
		(net "PCIE_TX_N88")
	)
	(arc
		(start 160.823656 -22.8346)
		(mid 161.18337 -22.90604)
		(end 161.488374 -23.109682)
		(width 0.136652)
		(layer "F.Cu")
		(net "PCIE_TX_N88")
	)
	(arc
		(start 158.134558 -20.517358)
		(mid 158.143248 -20.655346)
		(end 158.169102 -20.79117)
		(width 0.136652)
		(layer "F.Cu")
		(net "PCIE_TX_N88")
	)
	(arc
		(start 162.2298 -24.989282)
		(mid 162.263268 -25.157538)
		(end 162.358578 -25.300178)
		(width 0.136652)
		(layer "F.Cu")
		(net "PCIE_TX_N88")
	)
	(arc
		(start 163.7919 -32.6644)
		(mid 163.872123 -32.919839)
		(end 164.084 -33.0835)
		(width 0.136652)
		(layer "F.Cu")
		(net "PCIE_TX_N88")
	)
	(segment
		(start 152.924764 -24.209248)
		(end 150.474172 -21.758656)
		(width 0.136652)
		(layer "F.Cu")
		(net "PCIE_TX_N87")
	)
	(segment
		(start 149.933406 -21.490432)
		(end 149.931374 -21.48967)
		(width 0.136652)
		(layer "F.Cu")
		(net "PCIE_TX_N87")
	)
	(segment
		(start 149.733 -21.336)
		(end 149.6441 -21.2471)
		(width 0.136652)
		(layer "F.Cu")
		(net "PCIE_TX_N87")
	)
	(segment
		(start 149.80285 -21.406104)
		(end 149.733 -21.336)
		(width 0.136652)
		(layer "F.Cu")
		(net "PCIE_TX_N87")
	)
	(segment
		(start 149.931374 -21.48967)
		(end 149.926802 -21.487638)
		(width 0.136652)
		(layer "F.Cu")
		(net "PCIE_TX_N87")
	)
	(segment
		(start 149.384512 -20.620482)
		(end 149.384512 -20.130008)
		(width 0.136652)
		(layer "F.Cu")
		(net "PCIE_TX_N87")
	)
	(segment
		(start 149.934676 -21.49094)
		(end 149.933406 -21.490432)
		(width 0.136652)
		(layer "F.Cu")
		(net "PCIE_TX_N87")
	)
	(segment
		(start 150.040848 -21.520404)
		(end 150.033228 -21.519388)
		(width 0.136652)
		(layer "F.Cu")
		(net "PCIE_TX_N87")
	)
	(segment
		(start 153.2001 -32.639)
		(end 153.2001 -24.873966)
		(width 0.136652)
		(layer "F.Cu")
		(net "PCIE_TX_N87")
	)
	(arc
		(start 150.474172 -21.758656)
		(mid 150.38999 -21.683461)
		(end 150.297896 -21.618194)
		(width 0.136652)
		(layer "F.Cu")
		(net "PCIE_TX_N87")
	)
	(arc
		(start 150.033228 -21.519388)
		(mid 149.983155 -21.507927)
		(end 149.934676 -21.49094)
		(width 0.136652)
		(layer "F.Cu")
		(net "PCIE_TX_N87")
	)
	(arc
		(start 149.411436 -20.837144)
		(mid 149.391291 -20.729644)
		(end 149.384512 -20.620482)
		(width 0.136652)
		(layer "F.Cu")
		(net "PCIE_TX_N87")
	)
	(arc
		(start 149.926802 -21.487638)
		(mid 149.924258 -21.486632)
		(end 149.921722 -21.485606)
		(width 0.136652)
		(layer "F.Cu")
		(net "PCIE_TX_N87")
	)
	(arc
		(start 149.6441 -21.2471)
		(mid 149.500012 -21.057875)
		(end 149.411436 -20.837144)
		(width 0.136652)
		(layer "F.Cu")
		(net "PCIE_TX_N87")
	)
	(arc
		(start 149.921722 -21.485606)
		(mid 149.858382 -21.451691)
		(end 149.80285 -21.406104)
		(width 0.136652)
		(layer "F.Cu")
		(net "PCIE_TX_N87")
	)
	(arc
		(start 150.297896 -21.618194)
		(mid 150.174216 -21.556562)
		(end 150.040848 -21.520404)
		(width 0.136652)
		(layer "F.Cu")
		(net "PCIE_TX_N87")
	)
	(arc
		(start 153.4922 -33.0581)
		(mid 153.280364 -32.89441)
		(end 153.2001 -32.639)
		(width 0.136652)
		(layer "F.Cu")
		(net "PCIE_TX_N87")
	)
	(arc
		(start 153.2001 -24.873966)
		(mid 153.128528 -24.514237)
		(end 152.924764 -24.209248)
		(width 0.136652)
		(layer "F.Cu")
		(net "PCIE_TX_N87")
	)
	(segment
		(start 149.384512 -24.56053)
		(end 149.384512 -23.930102)
		(width 0.136652)
		(layer "F.Cu")
		(net "PCIE_TX_N86")
	)
	(segment
		(start 149.0599 -32.6644)
		(end 149.0599 -27.072844)
		(width 0.136652)
		(layer "F.Cu")
		(net "PCIE_TX_N86")
	)
	(segment
		(start 149.156928 -26.839418)
		(end 149.534118 -26.461974)
		(width 0.136652)
		(layer "F.Cu")
		(net "PCIE_TX_N86")
	)
	(segment
		(start 149.8092 -25.797256)
		(end 149.8092 -25.586436)
		(width 0.136652)
		(layer "F.Cu")
		(net "PCIE_TX_N86")
	)
	(arc
		(start 149.8092 -25.586436)
		(mid 149.73776 -25.226722)
		(end 149.534118 -24.921718)
		(width 0.136652)
		(layer "F.Cu")
		(net "PCIE_TX_N86")
	)
	(arc
		(start 149.395434 -24.666194)
		(mid 149.394923 -24.664417)
		(end 149.394418 -24.662638)
		(width 0.136652)
		(layer "F.Cu")
		(net "PCIE_TX_N86")
	)
	(arc
		(start 149.393402 -24.656796)
		(mid 149.386668 -24.608874)
		(end 149.384512 -24.56053)
		(width 0.136652)
		(layer "F.Cu")
		(net "PCIE_TX_N86")
	)
	(arc
		(start 149.0599 -27.072844)
		(mid 149.085235 -26.946506)
		(end 149.156928 -26.839418)
		(width 0.136652)
		(layer "F.Cu")
		(net "PCIE_TX_N86")
	)
	(arc
		(start 149.394418 -24.662638)
		(mid 149.393902 -24.659718)
		(end 149.393402 -24.656796)
		(width 0.136652)
		(layer "F.Cu")
		(net "PCIE_TX_N86")
	)
	(arc
		(start 149.352 -33.0835)
		(mid 149.140164 -32.91981)
		(end 149.0599 -32.6644)
		(width 0.136652)
		(layer "F.Cu")
		(net "PCIE_TX_N86")
	)
	(arc
		(start 149.534118 -26.461974)
		(mid 149.737759 -26.15697)
		(end 149.8092 -25.797256)
		(width 0.136652)
		(layer "F.Cu")
		(net "PCIE_TX_N86")
	)
	(arc
		(start 149.534118 -24.921718)
		(mid 149.446216 -24.804029)
		(end 149.395434 -24.666194)
		(width 0.136652)
		(layer "F.Cu")
		(net "PCIE_TX_N86")
	)
	(segment
		(start 147.237196 -24.87549)
		(end 147.43938 -25.18283)
		(width 0.136652)
		(layer "F.Cu")
		(net "PCIE_TX_N85")
	)
	(segment
		(start 146.45132 -32.019494)
		(end 146.45132 -32.639)
		(width 0.136652)
		(layer "F.Cu")
		(net "PCIE_TX_N85")
	)
	(segment
		(start 147.314158 -31.156656)
		(end 146.45132 -32.019494)
		(width 0.136652)
		(layer "F.Cu")
		(net "PCIE_TX_N85")
	)
	(segment
		(start 147.57908 -25.527254)
		(end 147.606512 -25.671018)
		(width 0.136652)
		(layer "F.Cu")
		(net "PCIE_TX_N85")
	)
	(segment
		(start 147.61464 -25.75687)
		(end 147.61464 -30.431486)
		(width 0.136652)
		(layer "F.Cu")
		(net "PCIE_TX_N85")
	)
	(arc
		(start 147.134326 -23.930102)
		(mid 147.16012 -24.405586)
		(end 147.237196 -24.87549)
		(width 0.136652)
		(layer "F.Cu")
		(net "PCIE_TX_N85")
	)
	(arc
		(start 146.45132 -32.639)
		(mid 146.531013 -32.902813)
		(end 146.74342 -33.07842)
		(width 0.136652)
		(layer "F.Cu")
		(net "PCIE_TX_N85")
	)
	(arc
		(start 147.606512 -25.671018)
		(mid 147.612604 -25.713752)
		(end 147.61464 -25.75687)
		(width 0.136652)
		(layer "F.Cu")
		(net "PCIE_TX_N85")
	)
	(arc
		(start 147.43938 -25.18283)
		(mid 147.526205 -25.348156)
		(end 147.57908 -25.527254)
		(width 0.136652)
		(layer "F.Cu")
		(net "PCIE_TX_N85")
	)
	(arc
		(start 147.61464 -30.431486)
		(mid 147.536446 -30.823921)
		(end 147.314158 -31.156656)
		(width 0.136652)
		(layer "F.Cu")
		(net "PCIE_TX_N85")
	)
	(segment
		(start 151.2189 -32.6644)
		(end 151.2189 -24.545036)
		(width 0.136652)
		(layer "F.Cu")
		(net "PCIE_TX_N84")
	)
	(segment
		(start 148.70811 -22.859238)
		(end 148.215096 -22.523704)
		(width 0.136652)
		(layer "F.Cu")
		(net "PCIE_TX_N84")
	)
	(segment
		(start 147.134326 -20.530312)
		(end 147.134326 -20.130008)
		(width 0.136652)
		(layer "F.Cu")
		(net "PCIE_TX_N84")
	)
	(segment
		(start 148.215096 -22.523704)
		(end 147.956016 -22.029674)
		(width 0.136652)
		(layer "F.Cu")
		(net "PCIE_TX_N84")
	)
	(segment
		(start 147.69592 -21.533866)
		(end 147.6121 -21.4503)
		(width 0.136652)
		(layer "F.Cu")
		(net "PCIE_TX_N84")
	)
	(segment
		(start 147.6121 -21.4503)
		(end 147.447 -21.2852)
		(width 0.136652)
		(layer "F.Cu")
		(net "PCIE_TX_N84")
	)
	(segment
		(start 149.403562 -22.855174)
		(end 149.248876 -22.855174)
		(width 0.136652)
		(layer "F.Cu")
		(net "PCIE_TX_N84")
	)
	(segment
		(start 150.943564 -23.880318)
		(end 150.282402 -23.219156)
		(width 0.136652)
		(layer "F.Cu")
		(net "PCIE_TX_N84")
	)
	(segment
		(start 149.248876 -22.855174)
		(end 148.978874 -22.857206)
		(width 0.136652)
		(layer "F.Cu")
		(net "PCIE_TX_N84")
	)
	(segment
		(start 147.956016 -22.029674)
		(end 147.69592 -21.533866)
		(width 0.136652)
		(layer "F.Cu")
		(net "PCIE_TX_N84")
	)
	(segment
		(start 148.978874 -22.857206)
		(end 148.70811 -22.859238)
		(width 0.136652)
		(layer "F.Cu")
		(net "PCIE_TX_N84")
	)
	(arc
		(start 151.511 -33.0835)
		(mid 151.299164 -32.91981)
		(end 151.2189 -32.6644)
		(width 0.136652)
		(layer "F.Cu")
		(net "PCIE_TX_N84")
	)
	(arc
		(start 147.18284 -20.848828)
		(mid 147.179084 -20.836531)
		(end 147.175474 -20.82419)
		(width 0.136652)
		(layer "F.Cu")
		(net "PCIE_TX_N84")
	)
	(arc
		(start 150.282402 -23.219156)
		(mid 149.879173 -22.94979)
		(end 149.403562 -22.855174)
		(width 0.136652)
		(layer "F.Cu")
		(net "PCIE_TX_N84")
	)
	(arc
		(start 147.172426 -20.813014)
		(mid 147.169312 -20.801347)
		(end 147.16633 -20.789646)
		(width 0.136652)
		(layer "F.Cu")
		(net "PCIE_TX_N84")
	)
	(arc
		(start 151.2189 -24.545036)
		(mid 151.147328 -24.185307)
		(end 150.943564 -23.880318)
		(width 0.136652)
		(layer "F.Cu")
		(net "PCIE_TX_N84")
	)
	(arc
		(start 147.16633 -20.789646)
		(mid 147.142376 -20.660961)
		(end 147.134326 -20.530312)
		(width 0.136652)
		(layer "F.Cu")
		(net "PCIE_TX_N84")
	)
	(arc
		(start 147.175474 -20.82419)
		(mid 147.174452 -20.820509)
		(end 147.173442 -20.816824)
		(width 0.136652)
		(layer "F.Cu")
		(net "PCIE_TX_N84")
	)
	(arc
		(start 147.447 -21.2852)
		(mid 147.288474 -21.083023)
		(end 147.18284 -20.848828)
		(width 0.136652)
		(layer "F.Cu")
		(net "PCIE_TX_N84")
	)
	(arc
		(start 147.173442 -20.816824)
		(mid 147.172932 -20.814919)
		(end 147.172426 -20.813014)
		(width 0.136652)
		(layer "F.Cu")
		(net "PCIE_TX_N84")
	)
	(segment
		(start 141.5288 -23.779734)
		(end 141.5288 -27.26944)
		(width 0.136652)
		(layer "F.Cu")
		(net "PCIE_TX_N83")
	)
	(segment
		(start 138.59764 -21.16836)
		(end 139.042394 -21.613114)
		(width 0.136652)
		(layer "F.Cu")
		(net "PCIE_TX_N83")
	)
	(segment
		(start 138.1252 -31.724854)
		(end 138.1252 -32.6136)
		(width 0.136652)
		(layer "F.Cu")
		(net "PCIE_TX_N83")
	)
	(segment
		(start 139.265152 -21.750782)
		(end 139.997434 -21.994114)
		(width 0.136652)
		(layer "F.Cu")
		(net "PCIE_TX_N83")
	)
	(segment
		(start 141.156944 -28.167076)
		(end 138.497056 -30.826964)
		(width 0.136652)
		(layer "F.Cu")
		(net "PCIE_TX_N83")
	)
	(segment
		(start 138.384534 -20.130008)
		(end 138.384534 -20.653756)
		(width 0.136652)
		(layer "F.Cu")
		(net "PCIE_TX_N83")
	)
	(segment
		(start 140.922248 -22.520656)
		(end 141.06779 -22.666198)
		(width 0.136652)
		(layer "F.Cu")
		(net "PCIE_TX_N83")
	)
	(segment
		(start 139.997434 -21.994114)
		(end 140.452348 -22.19706)
		(width 0.136652)
		(layer "F.Cu")
		(net "PCIE_TX_N83")
	)
	(arc
		(start 141.5288 -27.26944)
		(mid 141.432113 -27.755228)
		(end 141.156944 -28.167076)
		(width 0.136652)
		(layer "F.Cu")
		(net "PCIE_TX_N83")
	)
	(arc
		(start 138.384534 -20.653756)
		(mid 138.391568 -20.755455)
		(end 138.412728 -20.855178)
		(width 0.136652)
		(layer "F.Cu")
		(net "PCIE_TX_N83")
	)
	(arc
		(start 139.042394 -21.613114)
		(mid 139.145749 -21.694927)
		(end 139.265152 -21.750782)
		(width 0.136652)
		(layer "F.Cu")
		(net "PCIE_TX_N83")
	)
	(arc
		(start 138.1252 -32.6136)
		(mid 138.203864 -32.89674)
		(end 138.4173 -33.09874)
		(width 0.136652)
		(layer "F.Cu")
		(net "PCIE_TX_N83")
	)
	(arc
		(start 140.452348 -22.19706)
		(mid 140.702059 -22.33742)
		(end 140.922248 -22.520656)
		(width 0.136652)
		(layer "F.Cu")
		(net "PCIE_TX_N83")
	)
	(arc
		(start 138.478768 -21.01215)
		(mid 138.532922 -21.094273)
		(end 138.59764 -21.16836)
		(width 0.136652)
		(layer "F.Cu")
		(net "PCIE_TX_N83")
	)
	(arc
		(start 141.06779 -22.666198)
		(mid 141.409022 -23.177122)
		(end 141.5288 -23.779734)
		(width 0.136652)
		(layer "F.Cu")
		(net "PCIE_TX_N83")
	)
	(arc
		(start 138.412728 -20.855178)
		(mid 138.441153 -20.935596)
		(end 138.478768 -21.01215)
		(width 0.136652)
		(layer "F.Cu")
		(net "PCIE_TX_N83")
	)
	(arc
		(start 138.497056 -30.826964)
		(mid 138.22185 -31.238934)
		(end 138.1252 -31.724854)
		(width 0.136652)
		(layer "F.Cu")
		(net "PCIE_TX_N83")
	)
	(segment
		(start 138.392662 -26.549604)
		(end 133.94563 -30.996128)
		(width 0.136652)
		(layer "F.Cu")
		(net "PCIE_TX_N82")
	)
	(segment
		(start 133.8072 -31.330646)
		(end 133.8072 -32.6136)
		(width 0.136652)
		(layer "F.Cu")
		(net "PCIE_TX_N82")
	)
	(segment
		(start 138.679682 -25.373076)
		(end 138.679682 -25.856946)
		(width 0.136652)
		(layer "F.Cu")
		(net "PCIE_TX_N82")
	)
	(segment
		(start 138.384534 -23.930102)
		(end 138.384534 -24.60625)
		(width 0.136652)
		(layer "F.Cu")
		(net "PCIE_TX_N82")
	)
	(segment
		(start 138.63574 -25.108408)
		(end 138.650218 -25.15997)
		(width 0.136652)
		(layer "F.Cu")
		(net "PCIE_TX_N82")
	)
	(arc
		(start 138.424158 -24.769572)
		(mid 138.453097 -24.816414)
		(end 138.488928 -24.858218)
		(width 0.136652)
		(layer "F.Cu")
		(net "PCIE_TX_N82")
	)
	(arc
		(start 138.650218 -25.15997)
		(mid 138.672314 -25.265505)
		(end 138.679682 -25.373076)
		(width 0.136652)
		(layer "F.Cu")
		(net "PCIE_TX_N82")
	)
	(arc
		(start 138.391138 -24.675084)
		(mid 138.391638 -24.677499)
		(end 138.392154 -24.67991)
		(width 0.136652)
		(layer "F.Cu")
		(net "PCIE_TX_N82")
	)
	(arc
		(start 138.398504 -24.705564)
		(mid 138.409787 -24.738186)
		(end 138.424158 -24.769572)
		(width 0.136652)
		(layer "F.Cu")
		(net "PCIE_TX_N82")
	)
	(arc
		(start 138.384534 -24.60625)
		(mid 138.386166 -24.640827)
		(end 138.391138 -24.675084)
		(width 0.136652)
		(layer "F.Cu")
		(net "PCIE_TX_N82")
	)
	(arc
		(start 138.488928 -24.858218)
		(mid 138.578375 -24.9739)
		(end 138.63574 -25.108408)
		(width 0.136652)
		(layer "F.Cu")
		(net "PCIE_TX_N82")
	)
	(arc
		(start 138.679682 -25.856946)
		(mid 138.605041 -26.231813)
		(end 138.392662 -26.549604)
		(width 0.136652)
		(layer "F.Cu")
		(net "PCIE_TX_N82")
	)
	(arc
		(start 138.392154 -24.67991)
		(mid 138.395087 -24.692797)
		(end 138.398504 -24.705564)
		(width 0.136652)
		(layer "F.Cu")
		(net "PCIE_TX_N82")
	)
	(arc
		(start 133.94563 -30.996128)
		(mid 133.843162 -31.149621)
		(end 133.8072 -31.330646)
		(width 0.136652)
		(layer "F.Cu")
		(net "PCIE_TX_N82")
	)
	(arc
		(start 133.8072 -32.6136)
		(mid 133.885864 -32.89674)
		(end 134.0993 -33.09874)
		(width 0.136652)
		(layer "F.Cu")
		(net "PCIE_TX_N82")
	)
	(segment
		(start 131.6482 -31.85033)
		(end 131.6482 -32.6136)
		(width 0.136652)
		(layer "F.Cu")
		(net "PCIE_TX_N81")
	)
	(segment
		(start 136.487916 -25.412954)
		(end 136.487916 -26.162)
		(width 0.136652)
		(layer "F.Cu")
		(net "PCIE_TX_N81")
	)
	(segment
		(start 136.134348 -23.930102)
		(end 136.134348 -24.474678)
		(width 0.136652)
		(layer "F.Cu")
		(net "PCIE_TX_N81")
	)
	(segment
		(start 136.049766 -27.220926)
		(end 131.808982 -31.46171)
		(width 0.136652)
		(layer "F.Cu")
		(net "PCIE_TX_N81")
	)
	(arc
		(start 131.6482 -32.6136)
		(mid 131.726864 -32.89674)
		(end 131.9403 -33.09874)
		(width 0.136652)
		(layer "F.Cu")
		(net "PCIE_TX_N81")
	)
	(arc
		(start 136.196832 -24.763984)
		(mid 136.258661 -24.872463)
		(end 136.338818 -24.9682)
		(width 0.136652)
		(layer "F.Cu")
		(net "PCIE_TX_N81")
	)
	(arc
		(start 136.487916 -26.162)
		(mid 136.450231 -26.496441)
		(end 136.338818 -26.814018)
		(width 0.136652)
		(layer "F.Cu")
		(net "PCIE_TX_N81")
	)
	(arc
		(start 136.338818 -24.9682)
		(mid 136.389649 -25.04496)
		(end 136.430512 -25.127458)
		(width 0.136652)
		(layer "F.Cu")
		(net "PCIE_TX_N81")
	)
	(arc
		(start 136.154668 -24.642572)
		(mid 136.157494 -24.653899)
		(end 136.16051 -24.665178)
		(width 0.136652)
		(layer "F.Cu")
		(net "PCIE_TX_N81")
	)
	(arc
		(start 136.464548 -25.229058)
		(mid 136.48204 -25.320269)
		(end 136.487916 -25.412954)
		(width 0.136652)
		(layer "F.Cu")
		(net "PCIE_TX_N81")
	)
	(arc
		(start 136.338818 -26.814018)
		(mid 136.211409 -27.029633)
		(end 136.049766 -27.220926)
		(width 0.136652)
		(layer "F.Cu")
		(net "PCIE_TX_N81")
	)
	(arc
		(start 131.808982 -31.46171)
		(mid 131.689928 -31.640025)
		(end 131.6482 -31.85033)
		(width 0.136652)
		(layer "F.Cu")
		(net "PCIE_TX_N81")
	)
	(arc
		(start 136.134348 -24.474678)
		(mid 136.139397 -24.559244)
		(end 136.154668 -24.642572)
		(width 0.136652)
		(layer "F.Cu")
		(net "PCIE_TX_N81")
	)
	(arc
		(start 136.16051 -24.665178)
		(mid 136.176803 -24.715268)
		(end 136.196832 -24.763984)
		(width 0.136652)
		(layer "F.Cu")
		(net "PCIE_TX_N81")
	)
	(arc
		(start 136.430512 -25.127458)
		(mid 136.449377 -25.177639)
		(end 136.464548 -25.229058)
		(width 0.136652)
		(layer "F.Cu")
		(net "PCIE_TX_N81")
	)
	(segment
		(start 136.134348 -20.499578)
		(end 136.156446 -20.743672)
		(width 0.136652)
		(layer "F.Cu")
		(net "PCIE_TX_N80")
	)
	(segment
		(start 137.67943 -22.601936)
		(end 138.855704 -22.993604)
		(width 0.136652)
		(layer "F.Cu")
		(net "PCIE_TX_N80")
	)
	(segment
		(start 140.221208 -24.66848)
		(end 140.23594 -24.683466)
		(width 0.136652)
		(layer "F.Cu")
		(net "PCIE_TX_N80")
	)
	(segment
		(start 136.156446 -20.743672)
		(end 136.170416 -20.757642)
		(width 0.136652)
		(layer "F.Cu")
		(net "PCIE_TX_N80")
	)
	(segment
		(start 139.267692 -23.247858)
		(end 139.76096 -23.741126)
		(width 0.136652)
		(layer "F.Cu")
		(net "PCIE_TX_N80")
	)
	(segment
		(start 136.134348 -20.130008)
		(end 136.134348 -20.499578)
		(width 0.136652)
		(layer "F.Cu")
		(net "PCIE_TX_N80")
	)
	(segment
		(start 136.723882 -21.535136)
		(end 137.202672 -22.240748)
		(width 0.136652)
		(layer "F.Cu")
		(net "PCIE_TX_N80")
	)
	(segment
		(start 135.9662 -31.763716)
		(end 135.9662 -32.6136)
		(width 0.136652)
		(layer "F.Cu")
		(net "PCIE_TX_N80")
	)
	(segment
		(start 140.23594 -24.683466)
		(end 140.23594 -26.88971)
		(width 0.136652)
		(layer "F.Cu")
		(net "PCIE_TX_N80")
	)
	(segment
		(start 139.943332 -27.59837)
		(end 136.086342 -31.472886)
		(width 0.136652)
		(layer "F.Cu")
		(net "PCIE_TX_N80")
	)
	(segment
		(start 136.4488 -21.259546)
		(end 136.723882 -21.535136)
		(width 0.136652)
		(layer "F.Cu")
		(net "PCIE_TX_N80")
	)
	(arc
		(start 137.202672 -22.240748)
		(mid 137.411293 -22.460625)
		(end 137.67943 -22.601936)
		(width 0.136652)
		(layer "F.Cu")
		(net "PCIE_TX_N80")
	)
	(arc
		(start 136.086342 -31.472886)
		(mid 135.997399 -31.606377)
		(end 135.9662 -31.763716)
		(width 0.136652)
		(layer "F.Cu")
		(net "PCIE_TX_N80")
	)
	(arc
		(start 136.182608 -20.859496)
		(mid 136.183356 -20.862928)
		(end 136.184132 -20.866354)
		(width 0.136652)
		(layer "F.Cu")
		(net "PCIE_TX_N80")
	)
	(arc
		(start 136.18591 -20.87245)
		(mid 136.186164 -20.872958)
		(end 136.186418 -20.873466)
		(width 0.136652)
		(layer "F.Cu")
		(net "PCIE_TX_N80")
	)
	(arc
		(start 139.76096 -23.741126)
		(mid 140.067133 -24.167067)
		(end 140.221208 -24.66848)
		(width 0.136652)
		(layer "F.Cu")
		(net "PCIE_TX_N80")
	)
	(arc
		(start 136.308338 -21.086572)
		(mid 136.374076 -21.176707)
		(end 136.4488 -21.259546)
		(width 0.136652)
		(layer "F.Cu")
		(net "PCIE_TX_N80")
	)
	(arc
		(start 140.23594 -26.88971)
		(mid 140.159956 -27.273075)
		(end 139.943332 -27.59837)
		(width 0.136652)
		(layer "F.Cu")
		(net "PCIE_TX_N80")
	)
	(arc
		(start 136.282176 -21.044154)
		(mid 136.29501 -21.065516)
		(end 136.308338 -21.086572)
		(width 0.136652)
		(layer "F.Cu")
		(net "PCIE_TX_N80")
	)
	(arc
		(start 138.855704 -22.993604)
		(mid 139.076523 -23.096712)
		(end 139.267692 -23.247858)
		(width 0.136652)
		(layer "F.Cu")
		(net "PCIE_TX_N80")
	)
	(arc
		(start 135.9662 -32.6136)
		(mid 136.044864 -32.89674)
		(end 136.2583 -33.09874)
		(width 0.136652)
		(layer "F.Cu")
		(net "PCIE_TX_N80")
	)
	(arc
		(start 136.182354 -20.857718)
		(mid 136.18248 -20.858607)
		(end 136.182608 -20.859496)
		(width 0.136652)
		(layer "F.Cu")
		(net "PCIE_TX_N80")
	)
	(arc
		(start 136.184132 -20.866354)
		(mid 136.18501 -20.869405)
		(end 136.18591 -20.87245)
		(width 0.136652)
		(layer "F.Cu")
		(net "PCIE_TX_N80")
	)
	(arc
		(start 136.186418 -20.873466)
		(mid 136.224293 -20.964422)
		(end 136.282176 -21.044154)
		(width 0.136652)
		(layer "F.Cu")
		(net "PCIE_TX_N80")
	)
	(arc
		(start 136.170416 -20.757642)
		(mid 136.173397 -20.808036)
		(end 136.182354 -20.857718)
		(width 0.136652)
		(layer "F.Cu")
		(net "PCIE_TX_N80")
	)
	(segment
		(start 306.526438 -25.066752)
		(end 306.526692 -25.067006)
		(width 0.136652)
		(layer "F.Cu")
		(net "PCIE_TX_N8")
	)
	(segment
		(start 311.40019 -21.971)
		(end 311.40019 -21.506688)
		(width 0.136652)
		(layer "F.Cu")
		(net "PCIE_TX_N8")
	)
	(segment
		(start 308.73954 -22.8981)
		(end 310.47309 -22.8981)
		(width 0.136652)
		(layer "F.Cu")
		(net "PCIE_TX_N8")
	)
	(segment
		(start 306.847748 -24.291544)
		(end 307.88864 -23.250652)
		(width 0.136652)
		(layer "F.Cu")
		(net "PCIE_TX_N8")
	)
	(segment
		(start 306.526438 -32.5628)
		(end 306.526438 -25.066752)
		(width 0.136652)
		(layer "F.Cu")
		(net "PCIE_TX_N8")
	)
	(arc
		(start 311.174892 -20.790662)
		(mid 311.122637 -20.462293)
		(end 311.134506 -20.130008)
		(width 0.136652)
		(layer "F.Cu")
		(net "PCIE_TX_N8")
	)
	(arc
		(start 310.47309 -22.8981)
		(mid 311.128649 -22.626559)
		(end 311.40019 -21.971)
		(width 0.136652)
		(layer "F.Cu")
		(net "PCIE_TX_N8")
	)
	(arc
		(start 306.819046 -33.06572)
		(mid 306.604952 -32.85371)
		(end 306.526438 -32.5628)
		(width 0.136652)
		(layer "F.Cu")
		(net "PCIE_TX_N8")
	)
	(arc
		(start 311.200292 -20.880832)
		(mid 311.187084 -20.83589)
		(end 311.174892 -20.790662)
		(width 0.136652)
		(layer "F.Cu")
		(net "PCIE_TX_N8")
	)
	(arc
		(start 311.40019 -21.506688)
		(mid 311.381665 -21.34736)
		(end 311.327038 -21.196554)
		(width 0.136652)
		(layer "F.Cu")
		(net "PCIE_TX_N8")
	)
	(arc
		(start 306.526692 -25.067006)
		(mid 306.610092 -24.647347)
		(end 306.847748 -24.291544)
		(width 0.136652)
		(layer "F.Cu")
		(net "PCIE_TX_N8")
	)
	(arc
		(start 307.88864 -23.250652)
		(mid 308.279035 -22.989768)
		(end 308.73954 -22.8981)
		(width 0.136652)
		(layer "F.Cu")
		(net "PCIE_TX_N8")
	)
	(arc
		(start 311.327038 -21.196554)
		(mid 311.257217 -21.041282)
		(end 311.200292 -20.880832)
		(width 0.136652)
		(layer "F.Cu")
		(net "PCIE_TX_N8")
	)
	(segment
		(start 24.765254 -123.841764)
		(end 24.355298 -123.841764)
		(width 0.136652)
		(layer "F.Cu")
		(net "PCIE_TX_N76")
	)
	(segment
		(start 27.31897 -124.499878)
		(end 27.019504 -124.200412)
		(width 0.136652)
		(layer "F.Cu")
		(net "PCIE_TX_N76")
	)
	(segment
		(start 28.657042 -125.532642)
		(end 28.438094 -125.313694)
		(width 0.136652)
		(layer "F.Cu")
		(net "PCIE_TX_N76")
	)
	(segment
		(start 25.362662 -124.029216)
		(end 24.952706 -124.029216)
		(width 0.136652)
		(layer "F.Cu")
		(net "PCIE_TX_N76")
	)
	(segment
		(start 28.438094 -125.313694)
		(end 28.132786 -125.313694)
		(width 0.136652)
		(layer "F.Cu")
		(net "PCIE_TX_N76")
	)
	(segment
		(start 24.952706 -124.029216)
		(end 24.765254 -123.841764)
		(width 0.136652)
		(layer "F.Cu")
		(net "PCIE_TX_N76")
	)
	(segment
		(start 28.972256 -126.153164)
		(end 28.657042 -125.83795)
		(width 0.136652)
		(layer "F.Cu")
		(net "PCIE_TX_N76")
	)
	(segment
		(start 25.96007 -123.841764)
		(end 25.550114 -123.841764)
		(width 0.136652)
		(layer "F.Cu")
		(net "PCIE_TX_N76")
	)
	(segment
		(start 27.842972 -125.02388)
		(end 27.842972 -124.718572)
		(width 0.136652)
		(layer "F.Cu")
		(net "PCIE_TX_N76")
	)
	(segment
		(start 28.132786 -125.313694)
		(end 27.842972 -125.02388)
		(width 0.136652)
		(layer "F.Cu")
		(net "PCIE_TX_N76")
	)
	(segment
		(start 26.605992 -124.029216)
		(end 26.147522 -124.029216)
		(width 0.136652)
		(layer "F.Cu")
		(net "PCIE_TX_N76")
	)
	(segment
		(start 27.624278 -124.499878)
		(end 27.31897 -124.499878)
		(width 0.136652)
		(layer "F.Cu")
		(net "PCIE_TX_N76")
	)
	(segment
		(start 23.75789 -124.029216)
		(end 23.17369 -123.445016)
		(width 0.136652)
		(layer "F.Cu")
		(net "PCIE_TX_N76")
	)
	(segment
		(start 29.539946 -126.153164)
		(end 28.972256 -126.153164)
		(width 0.136652)
		(layer "F.Cu")
		(net "PCIE_TX_N76")
	)
	(segment
		(start 24.167846 -124.029216)
		(end 23.75789 -124.029216)
		(width 0.136652)
		(layer "F.Cu")
		(net "PCIE_TX_N76")
	)
	(segment
		(start 26.147522 -124.029216)
		(end 25.96007 -123.841764)
		(width 0.136652)
		(layer "F.Cu")
		(net "PCIE_TX_N76")
	)
	(segment
		(start 24.355298 -123.841764)
		(end 24.167846 -124.029216)
		(width 0.136652)
		(layer "F.Cu")
		(net "PCIE_TX_N76")
	)
	(segment
		(start 27.842972 -124.718572)
		(end 27.624278 -124.499878)
		(width 0.136652)
		(layer "F.Cu")
		(net "PCIE_TX_N76")
	)
	(segment
		(start 28.657042 -125.83795)
		(end 28.657042 -125.532642)
		(width 0.136652)
		(layer "F.Cu")
		(net "PCIE_TX_N76")
	)
	(segment
		(start 25.550114 -123.841764)
		(end 25.362662 -124.029216)
		(width 0.136652)
		(layer "F.Cu")
		(net "PCIE_TX_N76")
	)
	(arc
		(start 29.704792 -126.084838)
		(mid 29.62916 -126.135374)
		(end 29.539946 -126.153164)
		(width 0.136652)
		(layer "F.Cu")
		(net "PCIE_TX_N76")
	)
	(arc
		(start 27.019504 -124.200412)
		(mid 26.829782 -124.073674)
		(end 26.605992 -124.029216)
		(width 0.136652)
		(layer "F.Cu")
		(net "PCIE_TX_N76")
	)
	(segment
		(start 49.30013 -225.54438)
		(end 49.30013 -224.828354)
		(width 0.136652)
		(layer "F.Cu")
		(net "PCIE_TX_N75")
	)
	(segment
		(start 49.052734 -224.133664)
		(end 49.052734 -213.722712)
		(width 0.136652)
		(layer "F.Cu")
		(net "PCIE_TX_N75")
	)
	(arc
		(start 49.30013 -224.828354)
		(mid 49.256493 -224.560646)
		(end 49.130204 -224.320608)
		(width 0.136652)
		(layer "F.Cu")
		(net "PCIE_TX_N75")
	)
	(arc
		(start 49.130204 -224.320608)
		(mid 49.072894 -224.234837)
		(end 49.052734 -224.133664)
		(width 0.136652)
		(layer "F.Cu")
		(net "PCIE_TX_N75")
	)
	(arc
		(start 49.052734 -213.722712)
		(mid 49.145076 -213.258477)
		(end 49.40808 -212.864954)
		(width 0.136652)
		(layer "F.Cu")
		(net "PCIE_TX_N75")
	)
	(segment
		(start 52.252626 -224.133664)
		(end 52.252626 -213.722712)
		(width 0.136652)
		(layer "F.Cu")
		(net "PCIE_TX_N74")
	)
	(segment
		(start 52.500022 -225.54438)
		(end 52.500022 -224.828354)
		(width 0.136652)
		(layer "F.Cu")
		(net "PCIE_TX_N74")
	)
	(arc
		(start 52.252626 -213.722712)
		(mid 52.344968 -213.258477)
		(end 52.607972 -212.864954)
		(width 0.136652)
		(layer "F.Cu")
		(net "PCIE_TX_N74")
	)
	(arc
		(start 52.500022 -224.828354)
		(mid 52.456385 -224.560646)
		(end 52.330096 -224.320608)
		(width 0.136652)
		(layer "F.Cu")
		(net "PCIE_TX_N74")
	)
	(arc
		(start 52.330096 -224.320608)
		(mid 52.272786 -224.234837)
		(end 52.252626 -224.133664)
		(width 0.136652)
		(layer "F.Cu")
		(net "PCIE_TX_N74")
	)
	(segment
		(start 55.700168 -225.54438)
		(end 55.700168 -224.828354)
		(width 0.136652)
		(layer "F.Cu")
		(net "PCIE_TX_N73")
	)
	(segment
		(start 55.452772 -224.133664)
		(end 55.452772 -213.722712)
		(width 0.136652)
		(layer "F.Cu")
		(net "PCIE_TX_N73")
	)
	(arc
		(start 55.530242 -224.320608)
		(mid 55.472932 -224.234837)
		(end 55.452772 -224.133664)
		(width 0.136652)
		(layer "F.Cu")
		(net "PCIE_TX_N73")
	)
	(arc
		(start 55.700168 -224.828354)
		(mid 55.656531 -224.560646)
		(end 55.530242 -224.320608)
		(width 0.136652)
		(layer "F.Cu")
		(net "PCIE_TX_N73")
	)
	(arc
		(start 55.452772 -213.722712)
		(mid 55.545114 -213.258477)
		(end 55.808118 -212.864954)
		(width 0.136652)
		(layer "F.Cu")
		(net "PCIE_TX_N73")
	)
	(segment
		(start 58.90006 -225.54438)
		(end 58.90006 -224.828354)
		(width 0.136652)
		(layer "F.Cu")
		(net "PCIE_TX_N72")
	)
	(segment
		(start 58.652664 -224.133664)
		(end 58.652664 -213.722712)
		(width 0.136652)
		(layer "F.Cu")
		(net "PCIE_TX_N72")
	)
	(arc
		(start 58.90006 -224.828354)
		(mid 58.856423 -224.560646)
		(end 58.730134 -224.320608)
		(width 0.136652)
		(layer "F.Cu")
		(net "PCIE_TX_N72")
	)
	(arc
		(start 58.730134 -224.320608)
		(mid 58.672824 -224.234837)
		(end 58.652664 -224.133664)
		(width 0.136652)
		(layer "F.Cu")
		(net "PCIE_TX_N72")
	)
	(arc
		(start 58.652664 -213.722712)
		(mid 58.745006 -213.258477)
		(end 59.00801 -212.864954)
		(width 0.136652)
		(layer "F.Cu")
		(net "PCIE_TX_N72")
	)
	(segment
		(start 64.252602 -224.133664)
		(end 64.252602 -213.722712)
		(width 0.136652)
		(layer "F.Cu")
		(net "PCIE_TX_N71")
	)
	(segment
		(start 64.499998 -225.54438)
		(end 64.499998 -224.828354)
		(width 0.136652)
		(layer "F.Cu")
		(net "PCIE_TX_N71")
	)
	(arc
		(start 64.252602 -213.722712)
		(mid 64.344944 -213.258477)
		(end 64.607948 -212.864954)
		(width 0.136652)
		(layer "F.Cu")
		(net "PCIE_TX_N71")
	)
	(arc
		(start 64.499998 -224.828354)
		(mid 64.456361 -224.560646)
		(end 64.330072 -224.320608)
		(width 0.136652)
		(layer "F.Cu")
		(net "PCIE_TX_N71")
	)
	(arc
		(start 64.330072 -224.320608)
		(mid 64.272762 -224.234837)
		(end 64.252602 -224.133664)
		(width 0.136652)
		(layer "F.Cu")
		(net "PCIE_TX_N71")
	)
	(segment
		(start 67.452748 -224.133664)
		(end 67.452748 -213.722712)
		(width 0.136652)
		(layer "F.Cu")
		(net "PCIE_TX_N70")
	)
	(segment
		(start 67.700144 -225.54438)
		(end 67.700144 -224.828354)
		(width 0.136652)
		(layer "F.Cu")
		(net "PCIE_TX_N70")
	)
	(arc
		(start 67.530218 -224.320608)
		(mid 67.472908 -224.234837)
		(end 67.452748 -224.133664)
		(width 0.136652)
		(layer "F.Cu")
		(net "PCIE_TX_N70")
	)
	(arc
		(start 67.452748 -213.722712)
		(mid 67.54509 -213.258477)
		(end 67.808094 -212.864954)
		(width 0.136652)
		(layer "F.Cu")
		(net "PCIE_TX_N70")
	)
	(arc
		(start 67.700144 -224.828354)
		(mid 67.656507 -224.560646)
		(end 67.530218 -224.320608)
		(width 0.136652)
		(layer "F.Cu")
		(net "PCIE_TX_N70")
	)
	(segment
		(start 302.650144 -21.6916)
		(end 302.64989 -21.6916)
		(width 0.136652)
		(layer "F.Cu")
		(net "PCIE_TX_N7")
	)
	(segment
		(start 302.650144 -21.506688)
		(end 302.650144 -21.6916)
		(width 0.136652)
		(layer "F.Cu")
		(net "PCIE_TX_N7")
	)
	(segment
		(start 302.38446 -20.130008)
		(end 302.38446 -20.86483)
		(width 0.136652)
		(layer "F.Cu")
		(net "PCIE_TX_N7")
	)
	(segment
		(start 304.3682 -24.119332)
		(end 304.3682 -32.639)
		(width 0.136652)
		(layer "F.Cu")
		(net "PCIE_TX_N7")
	)
	(segment
		(start 302.818546 -22.098254)
		(end 304.034952 -23.31466)
		(width 0.136652)
		(layer "F.Cu")
		(net "PCIE_TX_N7")
	)
	(arc
		(start 304.3682 -32.639)
		(mid 304.45172 -32.908481)
		(end 304.673 -33.0835)
		(width 0.136652)
		(layer "F.Cu")
		(net "PCIE_TX_N7")
	)
	(arc
		(start 302.387762 -20.90293)
		(mid 302.408757 -20.963827)
		(end 302.446944 -21.015706)
		(width 0.136652)
		(layer "F.Cu")
		(net "PCIE_TX_N7")
	)
	(arc
		(start 302.64989 -21.6916)
		(mid 302.693781 -21.911694)
		(end 302.818546 -22.098254)
		(width 0.136652)
		(layer "F.Cu")
		(net "PCIE_TX_N7")
	)
	(arc
		(start 302.386746 -20.89785)
		(mid 302.387239 -20.900393)
		(end 302.387762 -20.90293)
		(width 0.136652)
		(layer "F.Cu")
		(net "PCIE_TX_N7")
	)
	(arc
		(start 302.446944 -21.015706)
		(mid 302.597378 -21.240985)
		(end 302.650144 -21.506688)
		(width 0.136652)
		(layer "F.Cu")
		(net "PCIE_TX_N7")
	)
	(arc
		(start 304.034952 -23.31466)
		(mid 304.281581 -23.683861)
		(end 304.3682 -24.119332)
		(width 0.136652)
		(layer "F.Cu")
		(net "PCIE_TX_N7")
	)
	(arc
		(start 302.38446 -20.86483)
		(mid 302.384964 -20.881384)
		(end 302.386746 -20.89785)
		(width 0.136652)
		(layer "F.Cu")
		(net "PCIE_TX_N7")
	)
	(segment
		(start 70.65264 -224.133664)
		(end 70.65264 -213.722712)
		(width 0.136652)
		(layer "F.Cu")
		(net "PCIE_TX_N69")
	)
	(segment
		(start 70.900036 -225.54438)
		(end 70.900036 -224.828354)
		(width 0.136652)
		(layer "F.Cu")
		(net "PCIE_TX_N69")
	)
	(arc
		(start 70.900036 -224.828354)
		(mid 70.856399 -224.560646)
		(end 70.73011 -224.320608)
		(width 0.136652)
		(layer "F.Cu")
		(net "PCIE_TX_N69")
	)
	(arc
		(start 70.73011 -224.320608)
		(mid 70.6728 -224.234837)
		(end 70.65264 -224.133664)
		(width 0.136652)
		(layer "F.Cu")
		(net "PCIE_TX_N69")
	)
	(arc
		(start 70.65264 -213.722712)
		(mid 70.744982 -213.258477)
		(end 71.007986 -212.864954)
		(width 0.136652)
		(layer "F.Cu")
		(net "PCIE_TX_N69")
	)
	(segment
		(start 80.499966 -225.54438)
		(end 80.499966 -224.828354)
		(width 0.136652)
		(layer "F.Cu")
		(net "PCIE_TX_N68")
	)
	(segment
		(start 80.25257 -224.133664)
		(end 80.25257 -213.722712)
		(width 0.136652)
		(layer "F.Cu")
		(net "PCIE_TX_N68")
	)
	(arc
		(start 80.499966 -224.828354)
		(mid 80.456329 -224.560646)
		(end 80.33004 -224.320608)
		(width 0.136652)
		(layer "F.Cu")
		(net "PCIE_TX_N68")
	)
	(arc
		(start 80.33004 -224.320608)
		(mid 80.27273 -224.234837)
		(end 80.25257 -224.133664)
		(width 0.136652)
		(layer "F.Cu")
		(net "PCIE_TX_N68")
	)
	(arc
		(start 80.25257 -213.722712)
		(mid 80.344912 -213.258477)
		(end 80.607916 -212.864954)
		(width 0.136652)
		(layer "F.Cu")
		(net "PCIE_TX_N68")
	)
	(segment
		(start 83.700112 -225.54438)
		(end 83.700112 -224.828354)
		(width 0.136652)
		(layer "F.Cu")
		(net "PCIE_TX_N67")
	)
	(segment
		(start 83.452716 -224.133664)
		(end 83.452716 -213.722712)
		(width 0.136652)
		(layer "F.Cu")
		(net "PCIE_TX_N67")
	)
	(arc
		(start 83.452716 -213.722712)
		(mid 83.545058 -213.258477)
		(end 83.808062 -212.864954)
		(width 0.136652)
		(layer "F.Cu")
		(net "PCIE_TX_N67")
	)
	(arc
		(start 83.530186 -224.320608)
		(mid 83.472876 -224.234837)
		(end 83.452716 -224.133664)
		(width 0.136652)
		(layer "F.Cu")
		(net "PCIE_TX_N67")
	)
	(arc
		(start 83.700112 -224.828354)
		(mid 83.656475 -224.560646)
		(end 83.530186 -224.320608)
		(width 0.136652)
		(layer "F.Cu")
		(net "PCIE_TX_N67")
	)
	(segment
		(start 86.900004 -225.54438)
		(end 86.900004 -224.828354)
		(width 0.136652)
		(layer "F.Cu")
		(net "PCIE_TX_N66")
	)
	(segment
		(start 86.652608 -224.133664)
		(end 86.652608 -213.722712)
		(width 0.136652)
		(layer "F.Cu")
		(net "PCIE_TX_N66")
	)
	(arc
		(start 86.900004 -224.828354)
		(mid 86.856367 -224.560646)
		(end 86.730078 -224.320608)
		(width 0.136652)
		(layer "F.Cu")
		(net "PCIE_TX_N66")
	)
	(arc
		(start 86.652608 -213.722712)
		(mid 86.74495 -213.258477)
		(end 87.007954 -212.864954)
		(width 0.136652)
		(layer "F.Cu")
		(net "PCIE_TX_N66")
	)
	(arc
		(start 86.730078 -224.320608)
		(mid 86.672768 -224.234837)
		(end 86.652608 -224.133664)
		(width 0.136652)
		(layer "F.Cu")
		(net "PCIE_TX_N66")
	)
	(segment
		(start 90.10015 -225.54438)
		(end 90.10015 -224.828354)
		(width 0.136652)
		(layer "F.Cu")
		(net "PCIE_TX_N65")
	)
	(segment
		(start 89.852754 -224.133664)
		(end 89.852754 -213.722712)
		(width 0.136652)
		(layer "F.Cu")
		(net "PCIE_TX_N65")
	)
	(arc
		(start 90.10015 -224.828354)
		(mid 90.056513 -224.560646)
		(end 89.930224 -224.320608)
		(width 0.136652)
		(layer "F.Cu")
		(net "PCIE_TX_N65")
	)
	(arc
		(start 89.852754 -213.722712)
		(mid 89.945096 -213.258477)
		(end 90.2081 -212.864954)
		(width 0.136652)
		(layer "F.Cu")
		(net "PCIE_TX_N65")
	)
	(arc
		(start 89.930224 -224.320608)
		(mid 89.872914 -224.234837)
		(end 89.852754 -224.133664)
		(width 0.136652)
		(layer "F.Cu")
		(net "PCIE_TX_N65")
	)
	(segment
		(start 93.300042 -225.54438)
		(end 93.300042 -224.828354)
		(width 0.136652)
		(layer "F.Cu")
		(net "PCIE_TX_N64")
	)
	(segment
		(start 93.052646 -224.133664)
		(end 93.052646 -213.722712)
		(width 0.136652)
		(layer "F.Cu")
		(net "PCIE_TX_N64")
	)
	(arc
		(start 93.130116 -224.320608)
		(mid 93.072806 -224.234837)
		(end 93.052646 -224.133664)
		(width 0.136652)
		(layer "F.Cu")
		(net "PCIE_TX_N64")
	)
	(arc
		(start 93.300042 -224.828354)
		(mid 93.256405 -224.560646)
		(end 93.130116 -224.320608)
		(width 0.136652)
		(layer "F.Cu")
		(net "PCIE_TX_N64")
	)
	(arc
		(start 93.052646 -213.722712)
		(mid 93.144988 -213.258477)
		(end 93.407992 -212.864954)
		(width 0.136652)
		(layer "F.Cu")
		(net "PCIE_TX_N64")
	)
	(segment
		(start 98.89998 -225.54438)
		(end 98.89998 -224.828608)
		(width 0.136652)
		(layer "F.Cu")
		(net "PCIE_TX_N63")
	)
	(segment
		(start 98.652838 -224.133664)
		(end 98.652838 -213.722712)
		(width 0.136652)
		(layer "F.Cu")
		(net "PCIE_TX_N63")
	)
	(segment
		(start 98.89998 -224.828608)
		(end 98.900234 -224.828354)
		(width 0.136652)
		(layer "F.Cu")
		(net "PCIE_TX_N63")
	)
	(arc
		(start 98.730308 -224.320608)
		(mid 98.672998 -224.234837)
		(end 98.652838 -224.133664)
		(width 0.136652)
		(layer "F.Cu")
		(net "PCIE_TX_N63")
	)
	(arc
		(start 98.652838 -213.722712)
		(mid 98.74518 -213.258477)
		(end 99.008184 -212.864954)
		(width 0.136652)
		(layer "F.Cu")
		(net "PCIE_TX_N63")
	)
	(arc
		(start 98.900234 -224.828354)
		(mid 98.856597 -224.560646)
		(end 98.730308 -224.320608)
		(width 0.136652)
		(layer "F.Cu")
		(net "PCIE_TX_N63")
	)
	(segment
		(start 102.100126 -225.54438)
		(end 102.100126 -224.828354)
		(width 0.136652)
		(layer "F.Cu")
		(net "PCIE_TX_N62")
	)
	(segment
		(start 101.85273 -224.133664)
		(end 101.85273 -213.722712)
		(width 0.136652)
		(layer "F.Cu")
		(net "PCIE_TX_N62")
	)
	(arc
		(start 101.9302 -224.320608)
		(mid 101.87289 -224.234837)
		(end 101.85273 -224.133664)
		(width 0.136652)
		(layer "F.Cu")
		(net "PCIE_TX_N62")
	)
	(arc
		(start 101.85273 -213.722712)
		(mid 101.945072 -213.258477)
		(end 102.208076 -212.864954)
		(width 0.136652)
		(layer "F.Cu")
		(net "PCIE_TX_N62")
	)
	(arc
		(start 102.100126 -224.828354)
		(mid 102.056489 -224.560646)
		(end 101.9302 -224.320608)
		(width 0.136652)
		(layer "F.Cu")
		(net "PCIE_TX_N62")
	)
	(segment
		(start 105.300018 -225.54438)
		(end 105.300018 -224.828608)
		(width 0.136652)
		(layer "F.Cu")
		(net "PCIE_TX_N61")
	)
	(segment
		(start 105.300018 -224.828608)
		(end 105.300272 -224.828354)
		(width 0.136652)
		(layer "F.Cu")
		(net "PCIE_TX_N61")
	)
	(segment
		(start 105.052876 -224.133664)
		(end 105.052876 -213.722712)
		(width 0.136652)
		(layer "F.Cu")
		(net "PCIE_TX_N61")
	)
	(arc
		(start 105.130346 -224.320608)
		(mid 105.073036 -224.234837)
		(end 105.052876 -224.133664)
		(width 0.136652)
		(layer "F.Cu")
		(net "PCIE_TX_N61")
	)
	(arc
		(start 105.052876 -213.722712)
		(mid 105.145218 -213.258477)
		(end 105.408222 -212.864954)
		(width 0.136652)
		(layer "F.Cu")
		(net "PCIE_TX_N61")
	)
	(arc
		(start 105.300272 -224.828354)
		(mid 105.256635 -224.560646)
		(end 105.130346 -224.320608)
		(width 0.136652)
		(layer "F.Cu")
		(net "PCIE_TX_N61")
	)
	(segment
		(start 108.252768 -224.133664)
		(end 108.252768 -213.722712)
		(width 0.136652)
		(layer "F.Cu")
		(net "PCIE_TX_N60")
	)
	(segment
		(start 108.500164 -225.54438)
		(end 108.500164 -224.828354)
		(width 0.136652)
		(layer "F.Cu")
		(net "PCIE_TX_N60")
	)
	(arc
		(start 108.500164 -224.828354)
		(mid 108.456527 -224.560646)
		(end 108.330238 -224.320608)
		(width 0.136652)
		(layer "F.Cu")
		(net "PCIE_TX_N60")
	)
	(arc
		(start 108.330238 -224.320608)
		(mid 108.272928 -224.234837)
		(end 108.252768 -224.133664)
		(width 0.136652)
		(layer "F.Cu")
		(net "PCIE_TX_N60")
	)
	(arc
		(start 108.252768 -213.722712)
		(mid 108.34511 -213.258477)
		(end 108.608114 -212.864954)
		(width 0.136652)
		(layer "F.Cu")
		(net "PCIE_TX_N60")
	)
	(segment
		(start 302.192944 -26.975816)
		(end 302.192944 -32.7152)
		(width 0.136652)
		(layer "F.Cu")
		(net "PCIE_TX_N6")
	)
	(segment
		(start 302.44034 -26.549096)
		(end 302.31969 -26.669746)
		(width 0.136652)
		(layer "F.Cu")
		(net "PCIE_TX_N6")
	)
	(segment
		(start 302.38446 -23.930102)
		(end 302.38446 -24.664924)
		(width 0.136652)
		(layer "F.Cu")
		(net "PCIE_TX_N6")
	)
	(segment
		(start 302.650144 -25.306782)
		(end 302.650144 -26.042112)
		(width 0.136652)
		(layer "F.Cu")
		(net "PCIE_TX_N6")
	)
	(arc
		(start 302.650144 -26.042112)
		(mid 302.599346 -26.307399)
		(end 302.454056 -26.535126)
		(width 0.136652)
		(layer "F.Cu")
		(net "PCIE_TX_N6")
	)
	(arc
		(start 302.192944 -32.7152)
		(mid 302.278462 -32.958864)
		(end 302.49749 -33.095692)
		(width 0.136652)
		(layer "F.Cu")
		(net "PCIE_TX_N6")
	)
	(arc
		(start 302.38446 -24.664924)
		(mid 302.400701 -24.746573)
		(end 302.446944 -24.8158)
		(width 0.136652)
		(layer "F.Cu")
		(net "PCIE_TX_N6")
	)
	(arc
		(start 302.31969 -26.669746)
		(mid 302.29727 -26.693944)
		(end 302.276764 -26.719784)
		(width 0.136652)
		(layer "F.Cu")
		(net "PCIE_TX_N6")
	)
	(arc
		(start 302.454056 -26.535126)
		(mid 302.447245 -26.542158)
		(end 302.44034 -26.549096)
		(width 0.136652)
		(layer "F.Cu")
		(net "PCIE_TX_N6")
	)
	(arc
		(start 302.446944 -24.8158)
		(mid 302.597378 -25.041079)
		(end 302.650144 -25.306782)
		(width 0.136652)
		(layer "F.Cu")
		(net "PCIE_TX_N6")
	)
	(arc
		(start 302.276764 -26.719784)
		(mid 302.214415 -26.841111)
		(end 302.192944 -26.975816)
		(width 0.136652)
		(layer "F.Cu")
		(net "PCIE_TX_N6")
	)
	(segment
		(start 139.052808 -224.133664)
		(end 139.052808 -213.722712)
		(width 0.136652)
		(layer "F.Cu")
		(net "PCIE_TX_N59")
	)
	(segment
		(start 139.300204 -225.54438)
		(end 139.300204 -224.828354)
		(width 0.136652)
		(layer "F.Cu")
		(net "PCIE_TX_N59")
	)
	(arc
		(start 139.300204 -224.828354)
		(mid 139.256567 -224.560646)
		(end 139.130278 -224.320608)
		(width 0.136652)
		(layer "F.Cu")
		(net "PCIE_TX_N59")
	)
	(arc
		(start 139.052808 -213.722712)
		(mid 139.14515 -213.258477)
		(end 139.408154 -212.864954)
		(width 0.136652)
		(layer "F.Cu")
		(net "PCIE_TX_N59")
	)
	(arc
		(start 139.130278 -224.320608)
		(mid 139.072968 -224.234837)
		(end 139.052808 -224.133664)
		(width 0.136652)
		(layer "F.Cu")
		(net "PCIE_TX_N59")
	)
	(segment
		(start 142.500096 -225.54438)
		(end 142.500096 -224.828608)
		(width 0.136652)
		(layer "F.Cu")
		(net "PCIE_TX_N58")
	)
	(segment
		(start 142.500096 -224.828608)
		(end 142.50035 -224.828354)
		(width 0.136652)
		(layer "F.Cu")
		(net "PCIE_TX_N58")
	)
	(segment
		(start 142.252954 -224.133664)
		(end 142.252954 -213.722204)
		(width 0.136652)
		(layer "F.Cu")
		(net "PCIE_TX_N58")
	)
	(arc
		(start 142.50035 -224.828354)
		(mid 142.456713 -224.560646)
		(end 142.330424 -224.320608)
		(width 0.136652)
		(layer "F.Cu")
		(net "PCIE_TX_N58")
	)
	(arc
		(start 142.330424 -224.320608)
		(mid 142.273114 -224.234837)
		(end 142.252954 -224.133664)
		(width 0.136652)
		(layer "F.Cu")
		(net "PCIE_TX_N58")
	)
	(arc
		(start 142.252954 -213.722204)
		(mid 142.345238 -213.258261)
		(end 142.608046 -212.864954)
		(width 0.136652)
		(layer "F.Cu")
		(net "PCIE_TX_N58")
	)
	(segment
		(start 145.700242 -225.54438)
		(end 145.700242 -224.828354)
		(width 0.136652)
		(layer "F.Cu")
		(net "PCIE_TX_N57")
	)
	(segment
		(start 145.452846 -224.133664)
		(end 145.452846 -213.722712)
		(width 0.136652)
		(layer "F.Cu")
		(net "PCIE_TX_N57")
	)
	(arc
		(start 145.530316 -224.320608)
		(mid 145.473006 -224.234837)
		(end 145.452846 -224.133664)
		(width 0.136652)
		(layer "F.Cu")
		(net "PCIE_TX_N57")
	)
	(arc
		(start 145.700242 -224.828354)
		(mid 145.656605 -224.560646)
		(end 145.530316 -224.320608)
		(width 0.136652)
		(layer "F.Cu")
		(net "PCIE_TX_N57")
	)
	(arc
		(start 145.452846 -213.722712)
		(mid 145.545188 -213.258477)
		(end 145.808192 -212.864954)
		(width 0.136652)
		(layer "F.Cu")
		(net "PCIE_TX_N57")
	)
	(segment
		(start 148.652738 -224.133664)
		(end 148.652738 -213.722712)
		(width 0.136652)
		(layer "F.Cu")
		(net "PCIE_TX_N56")
	)
	(segment
		(start 148.900134 -225.54438)
		(end 148.900134 -224.828354)
		(width 0.136652)
		(layer "F.Cu")
		(net "PCIE_TX_N56")
	)
	(arc
		(start 148.730208 -224.320608)
		(mid 148.672898 -224.234837)
		(end 148.652738 -224.133664)
		(width 0.136652)
		(layer "F.Cu")
		(net "PCIE_TX_N56")
	)
	(arc
		(start 148.900134 -224.828354)
		(mid 148.856497 -224.560646)
		(end 148.730208 -224.320608)
		(width 0.136652)
		(layer "F.Cu")
		(net "PCIE_TX_N56")
	)
	(arc
		(start 148.652738 -213.722712)
		(mid 148.74508 -213.258477)
		(end 149.008084 -212.864954)
		(width 0.136652)
		(layer "F.Cu")
		(net "PCIE_TX_N56")
	)
	(segment
		(start 152.100026 -225.54438)
		(end 152.100026 -224.828608)
		(width 0.136652)
		(layer "F.Cu")
		(net "PCIE_TX_N55")
	)
	(segment
		(start 152.100026 -224.828608)
		(end 152.10028 -224.828354)
		(width 0.136652)
		(layer "F.Cu")
		(net "PCIE_TX_N55")
	)
	(segment
		(start 151.852884 -224.133664)
		(end 151.852884 -213.722712)
		(width 0.136652)
		(layer "F.Cu")
		(net "PCIE_TX_N55")
	)
	(arc
		(start 151.852884 -213.722712)
		(mid 151.945226 -213.258477)
		(end 152.20823 -212.864954)
		(width 0.136652)
		(layer "F.Cu")
		(net "PCIE_TX_N55")
	)
	(arc
		(start 151.930354 -224.320608)
		(mid 151.873044 -224.234837)
		(end 151.852884 -224.133664)
		(width 0.136652)
		(layer "F.Cu")
		(net "PCIE_TX_N55")
	)
	(arc
		(start 152.10028 -224.828354)
		(mid 152.056643 -224.560646)
		(end 151.930354 -224.320608)
		(width 0.136652)
		(layer "F.Cu")
		(net "PCIE_TX_N55")
	)
	(segment
		(start 155.052776 -224.133664)
		(end 155.052776 -213.722712)
		(width 0.136652)
		(layer "F.Cu")
		(net "PCIE_TX_N54")
	)
	(segment
		(start 155.300172 -225.54438)
		(end 155.300172 -224.828354)
		(width 0.136652)
		(layer "F.Cu")
		(net "PCIE_TX_N54")
	)
	(arc
		(start 155.300172 -224.828354)
		(mid 155.256535 -224.560646)
		(end 155.130246 -224.320608)
		(width 0.136652)
		(layer "F.Cu")
		(net "PCIE_TX_N54")
	)
	(arc
		(start 155.130246 -224.320608)
		(mid 155.072936 -224.234837)
		(end 155.052776 -224.133664)
		(width 0.136652)
		(layer "F.Cu")
		(net "PCIE_TX_N54")
	)
	(arc
		(start 155.052776 -213.722712)
		(mid 155.145118 -213.258477)
		(end 155.408122 -212.864954)
		(width 0.136652)
		(layer "F.Cu")
		(net "PCIE_TX_N54")
	)
	(segment
		(start 158.500064 -224.828608)
		(end 158.500318 -224.828354)
		(width 0.136652)
		(layer "F.Cu")
		(net "PCIE_TX_N53")
	)
	(segment
		(start 158.500064 -225.54438)
		(end 158.500064 -224.828608)
		(width 0.136652)
		(layer "F.Cu")
		(net "PCIE_TX_N53")
	)
	(segment
		(start 158.252922 -224.133664)
		(end 158.252922 -213.722712)
		(width 0.136652)
		(layer "F.Cu")
		(net "PCIE_TX_N53")
	)
	(arc
		(start 158.330392 -224.320608)
		(mid 158.273082 -224.234837)
		(end 158.252922 -224.133664)
		(width 0.136652)
		(layer "F.Cu")
		(net "PCIE_TX_N53")
	)
	(arc
		(start 158.500318 -224.828354)
		(mid 158.456681 -224.560646)
		(end 158.330392 -224.320608)
		(width 0.136652)
		(layer "F.Cu")
		(net "PCIE_TX_N53")
	)
	(arc
		(start 158.252922 -213.722712)
		(mid 158.345264 -213.258477)
		(end 158.608268 -212.864954)
		(width 0.136652)
		(layer "F.Cu")
		(net "PCIE_TX_N53")
	)
	(segment
		(start 161.70021 -225.54438)
		(end 161.70021 -224.828354)
		(width 0.136652)
		(layer "F.Cu")
		(net "PCIE_TX_N52")
	)
	(segment
		(start 161.452814 -224.133664)
		(end 161.452814 -213.722712)
		(width 0.136652)
		(layer "F.Cu")
		(net "PCIE_TX_N52")
	)
	(arc
		(start 161.70021 -224.828354)
		(mid 161.656573 -224.560646)
		(end 161.530284 -224.320608)
		(width 0.136652)
		(layer "F.Cu")
		(net "PCIE_TX_N52")
	)
	(arc
		(start 161.452814 -213.722712)
		(mid 161.545156 -213.258477)
		(end 161.80816 -212.864954)
		(width 0.136652)
		(layer "F.Cu")
		(net "PCIE_TX_N52")
	)
	(arc
		(start 161.530284 -224.320608)
		(mid 161.472974 -224.234837)
		(end 161.452814 -224.133664)
		(width 0.136652)
		(layer "F.Cu")
		(net "PCIE_TX_N52")
	)
	(segment
		(start 167.052752 -224.133664)
		(end 167.052752 -213.722712)
		(width 0.136652)
		(layer "F.Cu")
		(net "PCIE_TX_N51")
	)
	(segment
		(start 167.300148 -225.54438)
		(end 167.300148 -224.828354)
		(width 0.136652)
		(layer "F.Cu")
		(net "PCIE_TX_N51")
	)
	(arc
		(start 167.300148 -224.828354)
		(mid 167.256511 -224.560646)
		(end 167.130222 -224.320608)
		(width 0.136652)
		(layer "F.Cu")
		(net "PCIE_TX_N51")
	)
	(arc
		(start 167.052752 -213.722712)
		(mid 167.145094 -213.258477)
		(end 167.408098 -212.864954)
		(width 0.136652)
		(layer "F.Cu")
		(net "PCIE_TX_N51")
	)
	(arc
		(start 167.130222 -224.320608)
		(mid 167.072912 -224.234837)
		(end 167.052752 -224.133664)
		(width 0.136652)
		(layer "F.Cu")
		(net "PCIE_TX_N51")
	)
	(segment
		(start 170.50004 -225.54438)
		(end 170.50004 -224.828354)
		(width 0.136652)
		(layer "F.Cu")
		(net "PCIE_TX_N50")
	)
	(segment
		(start 170.252644 -224.133664)
		(end 170.252644 -213.722712)
		(width 0.136652)
		(layer "F.Cu")
		(net "PCIE_TX_N50")
	)
	(arc
		(start 170.252644 -213.722712)
		(mid 170.344986 -213.258477)
		(end 170.60799 -212.864954)
		(width 0.136652)
		(layer "F.Cu")
		(net "PCIE_TX_N50")
	)
	(arc
		(start 170.50004 -224.828354)
		(mid 170.456403 -224.560646)
		(end 170.330114 -224.320608)
		(width 0.136652)
		(layer "F.Cu")
		(net "PCIE_TX_N50")
	)
	(arc
		(start 170.330114 -224.320608)
		(mid 170.272804 -224.234837)
		(end 170.252644 -224.133664)
		(width 0.136652)
		(layer "F.Cu")
		(net "PCIE_TX_N50")
	)
	(segment
		(start 300.400212 -26.042112)
		(end 300.400212 -25.306782)
		(width 0.136652)
		(layer "F.Cu")
		(net "PCIE_TX_N5")
	)
	(segment
		(start 300.134274 -24.66467)
		(end 300.134274 -23.930102)
		(width 0.136652)
		(layer "F.Cu")
		(net "PCIE_TX_N5")
	)
	(segment
		(start 299.943012 -32.6898)
		(end 299.943012 -26.975816)
		(width 0.136652)
		(layer "F.Cu")
		(net "PCIE_TX_N5")
	)
	(segment
		(start 300.134528 -24.664924)
		(end 300.134274 -24.66467)
		(width 0.136652)
		(layer "F.Cu")
		(net "PCIE_TX_N5")
	)
	(segment
		(start 300.069758 -26.669746)
		(end 300.190408 -26.549096)
		(width 0.136652)
		(layer "F.Cu")
		(net "PCIE_TX_N5")
	)
	(arc
		(start 300.268894 -33.115758)
		(mid 300.033763 -32.957988)
		(end 299.943012 -32.6898)
		(width 0.136652)
		(layer "F.Cu")
		(net "PCIE_TX_N5")
	)
	(arc
		(start 300.026832 -26.719784)
		(mid 300.047344 -26.693949)
		(end 300.069758 -26.669746)
		(width 0.136652)
		(layer "F.Cu")
		(net "PCIE_TX_N5")
	)
	(arc
		(start 299.943012 -26.975816)
		(mid 299.964506 -26.841118)
		(end 300.026832 -26.719784)
		(width 0.136652)
		(layer "F.Cu")
		(net "PCIE_TX_N5")
	)
	(arc
		(start 300.400212 -25.306782)
		(mid 300.347454 -25.041076)
		(end 300.197012 -24.8158)
		(width 0.136652)
		(layer "F.Cu")
		(net "PCIE_TX_N5")
	)
	(arc
		(start 300.190408 -26.549096)
		(mid 300.197314 -26.542158)
		(end 300.204124 -26.535126)
		(width 0.136652)
		(layer "F.Cu")
		(net "PCIE_TX_N5")
	)
	(arc
		(start 300.197012 -24.8158)
		(mid 300.150759 -24.746578)
		(end 300.134528 -24.664924)
		(width 0.136652)
		(layer "F.Cu")
		(net "PCIE_TX_N5")
	)
	(arc
		(start 300.204124 -26.535126)
		(mid 300.349515 -26.307439)
		(end 300.400212 -26.042112)
		(width 0.136652)
		(layer "F.Cu")
		(net "PCIE_TX_N5")
	)
	(segment
		(start 173.45279 -224.133664)
		(end 173.45279 -213.722712)
		(width 0.136652)
		(layer "F.Cu")
		(net "PCIE_TX_N49")
	)
	(segment
		(start 173.700186 -225.54438)
		(end 173.700186 -224.828354)
		(width 0.136652)
		(layer "F.Cu")
		(net "PCIE_TX_N49")
	)
	(arc
		(start 173.700186 -224.828354)
		(mid 173.656549 -224.560646)
		(end 173.53026 -224.320608)
		(width 0.136652)
		(layer "F.Cu")
		(net "PCIE_TX_N49")
	)
	(arc
		(start 173.45279 -213.722712)
		(mid 173.545132 -213.258477)
		(end 173.808136 -212.864954)
		(width 0.136652)
		(layer "F.Cu")
		(net "PCIE_TX_N49")
	)
	(arc
		(start 173.53026 -224.320608)
		(mid 173.47295 -224.234837)
		(end 173.45279 -224.133664)
		(width 0.136652)
		(layer "F.Cu")
		(net "PCIE_TX_N49")
	)
	(segment
		(start 176.900078 -225.54438)
		(end 176.900078 -224.828354)
		(width 0.136652)
		(layer "F.Cu")
		(net "PCIE_TX_N48")
	)
	(segment
		(start 176.652682 -224.133664)
		(end 176.652682 -213.722712)
		(width 0.136652)
		(layer "F.Cu")
		(net "PCIE_TX_N48")
	)
	(arc
		(start 176.652682 -213.722712)
		(mid 176.745024 -213.258477)
		(end 177.008028 -212.864954)
		(width 0.136652)
		(layer "F.Cu")
		(net "PCIE_TX_N48")
	)
	(arc
		(start 176.730152 -224.320608)
		(mid 176.672842 -224.234837)
		(end 176.652682 -224.133664)
		(width 0.136652)
		(layer "F.Cu")
		(net "PCIE_TX_N48")
	)
	(arc
		(start 176.900078 -224.828354)
		(mid 176.856441 -224.560646)
		(end 176.730152 -224.320608)
		(width 0.136652)
		(layer "F.Cu")
		(net "PCIE_TX_N48")
	)
	(segment
		(start 184.900062 -225.54438)
		(end 184.900062 -224.828354)
		(width 0.136652)
		(layer "F.Cu")
		(net "PCIE_TX_N47")
	)
	(segment
		(start 185.007758 -212.865462)
		(end 185.008266 -212.864954)
		(width 0.136652)
		(layer "F.Cu")
		(net "PCIE_TX_N47")
	)
	(segment
		(start 184.652666 -224.133664)
		(end 184.652666 -213.722712)
		(width 0.136652)
		(layer "F.Cu")
		(net "PCIE_TX_N47")
	)
	(arc
		(start 184.900062 -224.828354)
		(mid 184.856425 -224.560646)
		(end 184.730136 -224.320608)
		(width 0.136652)
		(layer "F.Cu")
		(net "PCIE_TX_N47")
	)
	(arc
		(start 184.652666 -213.722712)
		(mid 184.74495 -213.258769)
		(end 185.007758 -212.865462)
		(width 0.136652)
		(layer "F.Cu")
		(net "PCIE_TX_N47")
	)
	(arc
		(start 184.730136 -224.320608)
		(mid 184.672826 -224.234837)
		(end 184.652666 -224.133664)
		(width 0.136652)
		(layer "F.Cu")
		(net "PCIE_TX_N47")
	)
	(segment
		(start 188.100208 -225.54438)
		(end 188.100208 -224.828354)
		(width 0.136652)
		(layer "F.Cu")
		(net "PCIE_TX_N46")
	)
	(segment
		(start 187.852812 -224.133664)
		(end 187.852812 -213.722712)
		(width 0.136652)
		(layer "F.Cu")
		(net "PCIE_TX_N46")
	)
	(arc
		(start 187.852812 -213.722712)
		(mid 187.945154 -213.258477)
		(end 188.208158 -212.864954)
		(width 0.136652)
		(layer "F.Cu")
		(net "PCIE_TX_N46")
	)
	(arc
		(start 188.100208 -224.828354)
		(mid 188.056571 -224.560646)
		(end 187.930282 -224.320608)
		(width 0.136652)
		(layer "F.Cu")
		(net "PCIE_TX_N46")
	)
	(arc
		(start 187.930282 -224.320608)
		(mid 187.872972 -224.234837)
		(end 187.852812 -224.133664)
		(width 0.136652)
		(layer "F.Cu")
		(net "PCIE_TX_N46")
	)
	(segment
		(start 191.052704 -224.133664)
		(end 191.052704 -213.722712)
		(width 0.136652)
		(layer "F.Cu")
		(net "PCIE_TX_N45")
	)
	(segment
		(start 191.3001 -225.54438)
		(end 191.3001 -224.828354)
		(width 0.136652)
		(layer "F.Cu")
		(net "PCIE_TX_N45")
	)
	(segment
		(start 191.407796 -212.865462)
		(end 191.408304 -212.864954)
		(width 0.136652)
		(layer "F.Cu")
		(net "PCIE_TX_N45")
	)
	(arc
		(start 191.130174 -224.320608)
		(mid 191.072864 -224.234837)
		(end 191.052704 -224.133664)
		(width 0.136652)
		(layer "F.Cu")
		(net "PCIE_TX_N45")
	)
	(arc
		(start 191.3001 -224.828354)
		(mid 191.256463 -224.560646)
		(end 191.130174 -224.320608)
		(width 0.136652)
		(layer "F.Cu")
		(net "PCIE_TX_N45")
	)
	(arc
		(start 191.052704 -213.722712)
		(mid 191.144988 -213.258769)
		(end 191.407796 -212.865462)
		(width 0.136652)
		(layer "F.Cu")
		(net "PCIE_TX_N45")
	)
	(segment
		(start 194.500246 -225.54438)
		(end 194.500246 -224.828354)
		(width 0.136652)
		(layer "F.Cu")
		(net "PCIE_TX_N44")
	)
	(segment
		(start 194.25285 -224.133664)
		(end 194.25285 -213.722712)
		(width 0.136652)
		(layer "F.Cu")
		(net "PCIE_TX_N44")
	)
	(arc
		(start 194.33032 -224.320608)
		(mid 194.27301 -224.234837)
		(end 194.25285 -224.133664)
		(width 0.136652)
		(layer "F.Cu")
		(net "PCIE_TX_N44")
	)
	(arc
		(start 194.500246 -224.828354)
		(mid 194.456609 -224.560646)
		(end 194.33032 -224.320608)
		(width 0.136652)
		(layer "F.Cu")
		(net "PCIE_TX_N44")
	)
	(arc
		(start 194.25285 -213.722712)
		(mid 194.345192 -213.258477)
		(end 194.608196 -212.864954)
		(width 0.136652)
		(layer "F.Cu")
		(net "PCIE_TX_N44")
	)
	(segment
		(start 197.452742 -224.133664)
		(end 197.452742 -213.722712)
		(width 0.136652)
		(layer "F.Cu")
		(net "PCIE_TX_N43")
	)
	(segment
		(start 197.700138 -225.54438)
		(end 197.700138 -224.828354)
		(width 0.136652)
		(layer "F.Cu")
		(net "PCIE_TX_N43")
	)
	(arc
		(start 197.700138 -224.828354)
		(mid 197.656501 -224.560646)
		(end 197.530212 -224.320608)
		(width 0.136652)
		(layer "F.Cu")
		(net "PCIE_TX_N43")
	)
	(arc
		(start 197.452742 -213.722712)
		(mid 197.545084 -213.258477)
		(end 197.808088 -212.864954)
		(width 0.136652)
		(layer "F.Cu")
		(net "PCIE_TX_N43")
	)
	(arc
		(start 197.530212 -224.320608)
		(mid 197.472902 -224.234837)
		(end 197.452742 -224.133664)
		(width 0.136652)
		(layer "F.Cu")
		(net "PCIE_TX_N43")
	)
	(segment
		(start 200.90003 -225.54438)
		(end 200.90003 -224.828354)
		(width 0.136652)
		(layer "F.Cu")
		(net "PCIE_TX_N42")
	)
	(segment
		(start 200.652634 -224.133664)
		(end 200.652634 -213.722712)
		(width 0.136652)
		(layer "F.Cu")
		(net "PCIE_TX_N42")
	)
	(arc
		(start 200.730104 -224.320608)
		(mid 200.672794 -224.234837)
		(end 200.652634 -224.133664)
		(width 0.136652)
		(layer "F.Cu")
		(net "PCIE_TX_N42")
	)
	(arc
		(start 200.90003 -224.828354)
		(mid 200.856393 -224.560646)
		(end 200.730104 -224.320608)
		(width 0.136652)
		(layer "F.Cu")
		(net "PCIE_TX_N42")
	)
	(arc
		(start 200.652634 -213.722712)
		(mid 200.744976 -213.258477)
		(end 201.00798 -212.864954)
		(width 0.136652)
		(layer "F.Cu")
		(net "PCIE_TX_N42")
	)
	(segment
		(start 204.100176 -225.54438)
		(end 204.100176 -224.828354)
		(width 0.136652)
		(layer "F.Cu")
		(net "PCIE_TX_N41")
	)
	(segment
		(start 203.85278 -224.133664)
		(end 203.85278 -213.722712)
		(width 0.136652)
		(layer "F.Cu")
		(net "PCIE_TX_N41")
	)
	(arc
		(start 204.100176 -224.828354)
		(mid 204.056539 -224.560646)
		(end 203.93025 -224.320608)
		(width 0.136652)
		(layer "F.Cu")
		(net "PCIE_TX_N41")
	)
	(arc
		(start 203.93025 -224.320608)
		(mid 203.87294 -224.234837)
		(end 203.85278 -224.133664)
		(width 0.136652)
		(layer "F.Cu")
		(net "PCIE_TX_N41")
	)
	(arc
		(start 203.85278 -213.722712)
		(mid 203.945122 -213.258477)
		(end 204.208126 -212.864954)
		(width 0.136652)
		(layer "F.Cu")
		(net "PCIE_TX_N41")
	)
	(segment
		(start 207.300068 -225.54438)
		(end 207.300068 -224.828354)
		(width 0.136652)
		(layer "F.Cu")
		(net "PCIE_TX_N40")
	)
	(segment
		(start 207.052672 -224.133664)
		(end 207.052672 -213.722712)
		(width 0.136652)
		(layer "F.Cu")
		(net "PCIE_TX_N40")
	)
	(arc
		(start 207.300068 -224.828354)
		(mid 207.256431 -224.560646)
		(end 207.130142 -224.320608)
		(width 0.136652)
		(layer "F.Cu")
		(net "PCIE_TX_N40")
	)
	(arc
		(start 207.052672 -213.722712)
		(mid 207.145014 -213.258477)
		(end 207.408018 -212.864954)
		(width 0.136652)
		(layer "F.Cu")
		(net "PCIE_TX_N40")
	)
	(arc
		(start 207.130142 -224.320608)
		(mid 207.072832 -224.234837)
		(end 207.052672 -224.133664)
		(width 0.136652)
		(layer "F.Cu")
		(net "PCIE_TX_N40")
	)
	(segment
		(start 300.134274 -20.130008)
		(end 300.134528 -20.130262)
		(width 0.136652)
		(layer "F.Cu")
		(net "PCIE_TX_N4")
	)
	(segment
		(start 299.161454 -22.954996)
		(end 297.722798 -22.954996)
		(width 0.136652)
		(layer "F.Cu")
		(net "PCIE_TX_N4")
	)
	(segment
		(start 300.134528 -20.130262)
		(end 300.134528 -20.86483)
		(width 0.136652)
		(layer "F.Cu")
		(net "PCIE_TX_N4")
	)
	(segment
		(start 294.705532 -25.72639)
		(end 294.705278 -25.726136)
		(width 0.136652)
		(layer "F.Cu")
		(net "PCIE_TX_N4")
	)
	(segment
		(start 300.400212 -21.506688)
		(end 300.400212 -21.717)
		(width 0.136652)
		(layer "F.Cu")
		(net "PCIE_TX_N4")
	)
	(segment
		(start 297.067478 -23.226776)
		(end 294.80383 -25.488646)
		(width 0.136652)
		(layer "F.Cu")
		(net "PCIE_TX_N4")
	)
	(segment
		(start 294.705278 -25.726136)
		(end 294.705278 -32.766)
		(width 0.136652)
		(layer "F.Cu")
		(net "PCIE_TX_N4")
	)
	(segment
		(start 300.13148 -22.366224)
		(end 299.812202 -22.685502)
		(width 0.136652)
		(layer "F.Cu")
		(net "PCIE_TX_N4")
	)
	(arc
		(start 300.400212 -21.717)
		(mid 300.330435 -22.068354)
		(end 300.13148 -22.366224)
		(width 0.136652)
		(layer "F.Cu")
		(net "PCIE_TX_N4")
	)
	(arc
		(start 300.134528 -20.86483)
		(mid 300.150769 -20.946479)
		(end 300.197012 -21.015706)
		(width 0.136652)
		(layer "F.Cu")
		(net "PCIE_TX_N4")
	)
	(arc
		(start 297.722798 -22.954996)
		(mid 297.368134 -23.025748)
		(end 297.067478 -23.226776)
		(width 0.136652)
		(layer "F.Cu")
		(net "PCIE_TX_N4")
	)
	(arc
		(start 299.812202 -22.685502)
		(mid 299.513622 -22.884944)
		(end 299.161454 -22.954996)
		(width 0.136652)
		(layer "F.Cu")
		(net "PCIE_TX_N4")
	)
	(arc
		(start 300.197012 -21.015706)
		(mid 300.347446 -21.240985)
		(end 300.400212 -21.506688)
		(width 0.136652)
		(layer "F.Cu")
		(net "PCIE_TX_N4")
	)
	(arc
		(start 294.80383 -25.488646)
		(mid 294.731029 -25.597739)
		(end 294.705532 -25.72639)
		(width 0.136652)
		(layer "F.Cu")
		(net "PCIE_TX_N4")
	)
	(arc
		(start 294.705278 -32.766)
		(mid 294.783973 -33.048486)
		(end 294.997378 -33.249616)
		(width 0.136652)
		(layer "F.Cu")
		(net "PCIE_TX_N4")
	)
	(segment
		(start 213.45271 -224.133664)
		(end 213.45271 -213.722712)
		(width 0.136652)
		(layer "F.Cu")
		(net "PCIE_TX_N39")
	)
	(segment
		(start 213.700106 -225.54438)
		(end 213.700106 -224.828354)
		(width 0.136652)
		(layer "F.Cu")
		(net "PCIE_TX_N39")
	)
	(arc
		(start 213.45271 -213.722712)
		(mid 213.545052 -213.258477)
		(end 213.808056 -212.864954)
		(width 0.136652)
		(layer "F.Cu")
		(net "PCIE_TX_N39")
	)
	(arc
		(start 213.700106 -224.828354)
		(mid 213.656469 -224.560646)
		(end 213.53018 -224.320608)
		(width 0.136652)
		(layer "F.Cu")
		(net "PCIE_TX_N39")
	)
	(arc
		(start 213.53018 -224.320608)
		(mid 213.47287 -224.234837)
		(end 213.45271 -224.133664)
		(width 0.136652)
		(layer "F.Cu")
		(net "PCIE_TX_N39")
	)
	(segment
		(start 216.652602 -224.133664)
		(end 216.652602 -213.722712)
		(width 0.136652)
		(layer "F.Cu")
		(net "PCIE_TX_N38")
	)
	(segment
		(start 216.899998 -225.54438)
		(end 216.899998 -224.828354)
		(width 0.136652)
		(layer "F.Cu")
		(net "PCIE_TX_N38")
	)
	(arc
		(start 216.652602 -213.722712)
		(mid 216.744944 -213.258477)
		(end 217.007948 -212.864954)
		(width 0.136652)
		(layer "F.Cu")
		(net "PCIE_TX_N38")
	)
	(arc
		(start 216.899998 -224.828354)
		(mid 216.856361 -224.560646)
		(end 216.730072 -224.320608)
		(width 0.136652)
		(layer "F.Cu")
		(net "PCIE_TX_N38")
	)
	(arc
		(start 216.730072 -224.320608)
		(mid 216.672762 -224.234837)
		(end 216.652602 -224.133664)
		(width 0.136652)
		(layer "F.Cu")
		(net "PCIE_TX_N38")
	)
	(segment
		(start 265.300206 -225.54438)
		(end 265.300206 -224.828354)
		(width 0.136652)
		(layer "F.Cu")
		(net "PCIE_TX_N37")
	)
	(segment
		(start 265.05281 -224.133664)
		(end 265.05281 -213.722712)
		(width 0.136652)
		(layer "F.Cu")
		(net "PCIE_TX_N37")
	)
	(arc
		(start 265.300206 -224.828354)
		(mid 265.256569 -224.560646)
		(end 265.13028 -224.320608)
		(width 0.136652)
		(layer "F.Cu")
		(net "PCIE_TX_N37")
	)
	(arc
		(start 265.13028 -224.320608)
		(mid 265.07297 -224.234837)
		(end 265.05281 -224.133664)
		(width 0.136652)
		(layer "F.Cu")
		(net "PCIE_TX_N37")
	)
	(arc
		(start 265.05281 -213.722712)
		(mid 265.145152 -213.258477)
		(end 265.408156 -212.864954)
		(width 0.136652)
		(layer "F.Cu")
		(net "PCIE_TX_N37")
	)
	(segment
		(start 268.500098 -225.54438)
		(end 268.500098 -224.828354)
		(width 0.136652)
		(layer "F.Cu")
		(net "PCIE_TX_N36")
	)
	(segment
		(start 268.252702 -224.133664)
		(end 268.252702 -213.722712)
		(width 0.136652)
		(layer "F.Cu")
		(net "PCIE_TX_N36")
	)
	(arc
		(start 268.252702 -213.722712)
		(mid 268.345044 -213.258477)
		(end 268.608048 -212.864954)
		(width 0.136652)
		(layer "F.Cu")
		(net "PCIE_TX_N36")
	)
	(arc
		(start 268.330172 -224.320608)
		(mid 268.272862 -224.234837)
		(end 268.252702 -224.133664)
		(width 0.136652)
		(layer "F.Cu")
		(net "PCIE_TX_N36")
	)
	(arc
		(start 268.500098 -224.828354)
		(mid 268.456461 -224.560646)
		(end 268.330172 -224.320608)
		(width 0.136652)
		(layer "F.Cu")
		(net "PCIE_TX_N36")
	)
	(segment
		(start 271.700244 -225.54438)
		(end 271.700244 -224.828354)
		(width 0.136652)
		(layer "F.Cu")
		(net "PCIE_TX_N35")
	)
	(segment
		(start 271.452848 -224.133664)
		(end 271.452848 -213.722712)
		(width 0.136652)
		(layer "F.Cu")
		(net "PCIE_TX_N35")
	)
	(arc
		(start 271.530318 -224.320608)
		(mid 271.473008 -224.234837)
		(end 271.452848 -224.133664)
		(width 0.136652)
		(layer "F.Cu")
		(net "PCIE_TX_N35")
	)
	(arc
		(start 271.452848 -213.722712)
		(mid 271.54519 -213.258477)
		(end 271.808194 -212.864954)
		(width 0.136652)
		(layer "F.Cu")
		(net "PCIE_TX_N35")
	)
	(arc
		(start 271.700244 -224.828354)
		(mid 271.656607 -224.560646)
		(end 271.530318 -224.320608)
		(width 0.136652)
		(layer "F.Cu")
		(net "PCIE_TX_N35")
	)
	(segment
		(start 274.65274 -224.133664)
		(end 274.65274 -213.722712)
		(width 0.136652)
		(layer "F.Cu")
		(net "PCIE_TX_N34")
	)
	(segment
		(start 274.900136 -225.54438)
		(end 274.900136 -224.828354)
		(width 0.136652)
		(layer "F.Cu")
		(net "PCIE_TX_N34")
	)
	(arc
		(start 274.900136 -224.828354)
		(mid 274.856499 -224.560646)
		(end 274.73021 -224.320608)
		(width 0.136652)
		(layer "F.Cu")
		(net "PCIE_TX_N34")
	)
	(arc
		(start 274.65274 -213.722712)
		(mid 274.745082 -213.258477)
		(end 275.008086 -212.864954)
		(width 0.136652)
		(layer "F.Cu")
		(net "PCIE_TX_N34")
	)
	(arc
		(start 274.73021 -224.320608)
		(mid 274.6729 -224.234837)
		(end 274.65274 -224.133664)
		(width 0.136652)
		(layer "F.Cu")
		(net "PCIE_TX_N34")
	)
	(segment
		(start 277.852632 -224.133664)
		(end 277.852632 -213.722712)
		(width 0.136652)
		(layer "F.Cu")
		(net "PCIE_TX_N33")
	)
	(segment
		(start 278.100028 -225.54438)
		(end 278.100028 -224.828354)
		(width 0.136652)
		(layer "F.Cu")
		(net "PCIE_TX_N33")
	)
	(arc
		(start 278.100028 -224.828354)
		(mid 278.056391 -224.560646)
		(end 277.930102 -224.320608)
		(width 0.136652)
		(layer "F.Cu")
		(net "PCIE_TX_N33")
	)
	(arc
		(start 277.852632 -213.722712)
		(mid 277.944974 -213.258477)
		(end 278.207978 -212.864954)
		(width 0.136652)
		(layer "F.Cu")
		(net "PCIE_TX_N33")
	)
	(arc
		(start 277.930102 -224.320608)
		(mid 277.872792 -224.234837)
		(end 277.852632 -224.133664)
		(width 0.136652)
		(layer "F.Cu")
		(net "PCIE_TX_N33")
	)
	(segment
		(start 281.052778 -224.133664)
		(end 281.052778 -213.722712)
		(width 0.136652)
		(layer "F.Cu")
		(net "PCIE_TX_N32")
	)
	(segment
		(start 281.300174 -225.54438)
		(end 281.300174 -224.828354)
		(width 0.136652)
		(layer "F.Cu")
		(net "PCIE_TX_N32")
	)
	(arc
		(start 281.300174 -224.828354)
		(mid 281.256537 -224.560646)
		(end 281.130248 -224.320608)
		(width 0.136652)
		(layer "F.Cu")
		(net "PCIE_TX_N32")
	)
	(arc
		(start 281.130248 -224.320608)
		(mid 281.072938 -224.234837)
		(end 281.052778 -224.133664)
		(width 0.136652)
		(layer "F.Cu")
		(net "PCIE_TX_N32")
	)
	(arc
		(start 281.052778 -213.722712)
		(mid 281.14512 -213.258477)
		(end 281.408124 -212.864954)
		(width 0.136652)
		(layer "F.Cu")
		(net "PCIE_TX_N32")
	)
	(segment
		(start 284.500066 -225.54438)
		(end 284.500066 -224.828354)
		(width 0.136652)
		(layer "F.Cu")
		(net "PCIE_TX_N31")
	)
	(segment
		(start 284.25267 -224.133664)
		(end 284.25267 -213.722712)
		(width 0.136652)
		(layer "F.Cu")
		(net "PCIE_TX_N31")
	)
	(arc
		(start 284.500066 -224.828354)
		(mid 284.456429 -224.560646)
		(end 284.33014 -224.320608)
		(width 0.136652)
		(layer "F.Cu")
		(net "PCIE_TX_N31")
	)
	(arc
		(start 284.33014 -224.320608)
		(mid 284.27283 -224.234837)
		(end 284.25267 -224.133664)
		(width 0.136652)
		(layer "F.Cu")
		(net "PCIE_TX_N31")
	)
	(arc
		(start 284.25267 -213.722712)
		(mid 284.345012 -213.258477)
		(end 284.608016 -212.864954)
		(width 0.136652)
		(layer "F.Cu")
		(net "PCIE_TX_N31")
	)
	(segment
		(start 287.452816 -224.133664)
		(end 287.452816 -213.722712)
		(width 0.136652)
		(layer "F.Cu")
		(net "PCIE_TX_N30")
	)
	(segment
		(start 287.700212 -225.54438)
		(end 287.700212 -224.828354)
		(width 0.136652)
		(layer "F.Cu")
		(net "PCIE_TX_N30")
	)
	(arc
		(start 287.452816 -213.722712)
		(mid 287.545158 -213.258477)
		(end 287.808162 -212.864954)
		(width 0.136652)
		(layer "F.Cu")
		(net "PCIE_TX_N30")
	)
	(arc
		(start 287.530286 -224.320608)
		(mid 287.472976 -224.234837)
		(end 287.452816 -224.133664)
		(width 0.136652)
		(layer "F.Cu")
		(net "PCIE_TX_N30")
	)
	(arc
		(start 287.700212 -224.828354)
		(mid 287.656575 -224.560646)
		(end 287.530286 -224.320608)
		(width 0.136652)
		(layer "F.Cu")
		(net "PCIE_TX_N30")
	)
	(segment
		(start 292.809168 -28.246832)
		(end 289.930078 -31.125922)
		(width 0.136652)
		(layer "F.Cu")
		(net "PCIE_TX_N3")
	)
	(segment
		(start 291.835332 -22.41804)
		(end 292.923468 -23.506176)
		(width 0.136652)
		(layer "F.Cu")
		(net "PCIE_TX_N3")
	)
	(segment
		(start 291.650166 -21.506688)
		(end 291.650166 -21.971)
		(width 0.136652)
		(layer "F.Cu")
		(net "PCIE_TX_N3")
	)
	(segment
		(start 291.384482 -20.130008)
		(end 291.384482 -20.86483)
		(width 0.136652)
		(layer "F.Cu")
		(net "PCIE_TX_N3")
	)
	(segment
		(start 289.7632 -31.528766)
		(end 289.7632 -32.6136)
		(width 0.136652)
		(layer "F.Cu")
		(net "PCIE_TX_N3")
	)
	(segment
		(start 293.1922 -24.1554)
		(end 293.1922 -27.322018)
		(width 0.136652)
		(layer "F.Cu")
		(net "PCIE_TX_N3")
	)
	(arc
		(start 291.446966 -21.015706)
		(mid 291.5974 -21.240985)
		(end 291.650166 -21.506688)
		(width 0.136652)
		(layer "F.Cu")
		(net "PCIE_TX_N3")
	)
	(arc
		(start 289.7632 -32.6136)
		(mid 289.846074 -32.893647)
		(end 290.068 -33.0835)
		(width 0.136652)
		(layer "F.Cu")
		(net "PCIE_TX_N3")
	)
	(arc
		(start 292.923468 -23.506176)
		(mid 293.122359 -23.804072)
		(end 293.1922 -24.1554)
		(width 0.136652)
		(layer "F.Cu")
		(net "PCIE_TX_N3")
	)
	(arc
		(start 291.384482 -20.86483)
		(mid 291.384957 -20.880106)
		(end 291.386514 -20.89531)
		(width 0.136652)
		(layer "F.Cu")
		(net "PCIE_TX_N3")
	)
	(arc
		(start 289.930078 -31.125922)
		(mid 289.806581 -31.310748)
		(end 289.7632 -31.528766)
		(width 0.136652)
		(layer "F.Cu")
		(net "PCIE_TX_N3")
	)
	(arc
		(start 291.650166 -21.971)
		(mid 291.69829 -22.212935)
		(end 291.835332 -22.41804)
		(width 0.136652)
		(layer "F.Cu")
		(net "PCIE_TX_N3")
	)
	(arc
		(start 293.1922 -27.322018)
		(mid 293.092661 -27.822523)
		(end 292.809168 -28.246832)
		(width 0.136652)
		(layer "F.Cu")
		(net "PCIE_TX_N3")
	)
	(arc
		(start 291.386514 -20.89531)
		(mid 291.407016 -20.960384)
		(end 291.446966 -21.015706)
		(width 0.136652)
		(layer "F.Cu")
		(net "PCIE_TX_N3")
	)
	(segment
		(start 290.652708 -224.133664)
		(end 290.652708 -213.722712)
		(width 0.136652)
		(layer "F.Cu")
		(net "PCIE_TX_N29")
	)
	(segment
		(start 290.900104 -225.54438)
		(end 290.900104 -224.828354)
		(width 0.136652)
		(layer "F.Cu")
		(net "PCIE_TX_N29")
	)
	(arc
		(start 290.900104 -224.828354)
		(mid 290.856467 -224.560646)
		(end 290.730178 -224.320608)
		(width 0.136652)
		(layer "F.Cu")
		(net "PCIE_TX_N29")
	)
	(arc
		(start 290.730178 -224.320608)
		(mid 290.672868 -224.234837)
		(end 290.652708 -224.133664)
		(width 0.136652)
		(layer "F.Cu")
		(net "PCIE_TX_N29")
	)
	(arc
		(start 290.652708 -213.722712)
		(mid 290.74505 -213.258477)
		(end 291.008054 -212.864954)
		(width 0.136652)
		(layer "F.Cu")
		(net "PCIE_TX_N29")
	)
	(segment
		(start 294.099996 -225.54438)
		(end 294.099996 -224.828354)
		(width 0.136652)
		(layer "F.Cu")
		(net "PCIE_TX_N28")
	)
	(segment
		(start 293.8526 -224.133664)
		(end 293.8526 -213.722712)
		(width 0.136652)
		(layer "F.Cu")
		(net "PCIE_TX_N28")
	)
	(arc
		(start 293.8526 -213.722712)
		(mid 293.944942 -213.258477)
		(end 294.207946 -212.864954)
		(width 0.136652)
		(layer "F.Cu")
		(net "PCIE_TX_N28")
	)
	(arc
		(start 294.099996 -224.828354)
		(mid 294.056359 -224.560646)
		(end 293.93007 -224.320608)
		(width 0.136652)
		(layer "F.Cu")
		(net "PCIE_TX_N28")
	)
	(arc
		(start 293.93007 -224.320608)
		(mid 293.87276 -224.234837)
		(end 293.8526 -224.133664)
		(width 0.136652)
		(layer "F.Cu")
		(net "PCIE_TX_N28")
	)
	(segment
		(start 299.700188 -225.54438)
		(end 299.700188 -224.828354)
		(width 0.136652)
		(layer "F.Cu")
		(net "PCIE_TX_N27")
	)
	(segment
		(start 299.452792 -224.133664)
		(end 299.452792 -213.722712)
		(width 0.136652)
		(layer "F.Cu")
		(net "PCIE_TX_N27")
	)
	(arc
		(start 299.452792 -213.722712)
		(mid 299.545134 -213.258477)
		(end 299.808138 -212.864954)
		(width 0.136652)
		(layer "F.Cu")
		(net "PCIE_TX_N27")
	)
	(arc
		(start 299.530262 -224.320608)
		(mid 299.472952 -224.234837)
		(end 299.452792 -224.133664)
		(width 0.136652)
		(layer "F.Cu")
		(net "PCIE_TX_N27")
	)
	(arc
		(start 299.700188 -224.828354)
		(mid 299.656551 -224.560646)
		(end 299.530262 -224.320608)
		(width 0.136652)
		(layer "F.Cu")
		(net "PCIE_TX_N27")
	)
	(segment
		(start 302.652684 -224.133664)
		(end 302.652684 -213.722712)
		(width 0.136652)
		(layer "F.Cu")
		(net "PCIE_TX_N26")
	)
	(segment
		(start 302.90008 -225.54438)
		(end 302.90008 -224.828354)
		(width 0.136652)
		(layer "F.Cu")
		(net "PCIE_TX_N26")
	)
	(arc
		(start 302.730154 -224.320608)
		(mid 302.672844 -224.234837)
		(end 302.652684 -224.133664)
		(width 0.136652)
		(layer "F.Cu")
		(net "PCIE_TX_N26")
	)
	(arc
		(start 302.652684 -213.722712)
		(mid 302.745026 -213.258477)
		(end 303.00803 -212.864954)
		(width 0.136652)
		(layer "F.Cu")
		(net "PCIE_TX_N26")
	)
	(arc
		(start 302.90008 -224.828354)
		(mid 302.856443 -224.560646)
		(end 302.730154 -224.320608)
		(width 0.136652)
		(layer "F.Cu")
		(net "PCIE_TX_N26")
	)
	(segment
		(start 310.900064 -224.828608)
		(end 310.900318 -224.828354)
		(width 0.136652)
		(layer "F.Cu")
		(net "PCIE_TX_N25")
	)
	(segment
		(start 310.900064 -225.54438)
		(end 310.900064 -224.828608)
		(width 0.136652)
		(layer "F.Cu")
		(net "PCIE_TX_N25")
	)
	(segment
		(start 310.652922 -224.133664)
		(end 310.652922 -213.722204)
		(width 0.136652)
		(layer "F.Cu")
		(net "PCIE_TX_N25")
	)
	(arc
		(start 310.900318 -224.828354)
		(mid 310.856681 -224.560646)
		(end 310.730392 -224.320608)
		(width 0.136652)
		(layer "F.Cu")
		(net "PCIE_TX_N25")
	)
	(arc
		(start 310.652922 -213.722204)
		(mid 310.745206 -213.258261)
		(end 311.008014 -212.864954)
		(width 0.136652)
		(layer "F.Cu")
		(net "PCIE_TX_N25")
	)
	(arc
		(start 310.730392 -224.320608)
		(mid 310.673082 -224.234837)
		(end 310.652922 -224.133664)
		(width 0.136652)
		(layer "F.Cu")
		(net "PCIE_TX_N25")
	)
	(segment
		(start 314.10021 -225.54438)
		(end 314.10021 -224.828354)
		(width 0.136652)
		(layer "F.Cu")
		(net "PCIE_TX_N24")
	)
	(segment
		(start 313.852814 -224.133664)
		(end 313.852814 -213.722712)
		(width 0.136652)
		(layer "F.Cu")
		(net "PCIE_TX_N24")
	)
	(arc
		(start 313.930284 -224.320608)
		(mid 313.872974 -224.234837)
		(end 313.852814 -224.133664)
		(width 0.136652)
		(layer "F.Cu")
		(net "PCIE_TX_N24")
	)
	(arc
		(start 314.10021 -224.828354)
		(mid 314.056573 -224.560646)
		(end 313.930284 -224.320608)
		(width 0.136652)
		(layer "F.Cu")
		(net "PCIE_TX_N24")
	)
	(arc
		(start 313.852814 -213.722712)
		(mid 313.945156 -213.258477)
		(end 314.20816 -212.864954)
		(width 0.136652)
		(layer "F.Cu")
		(net "PCIE_TX_N24")
	)
	(segment
		(start 317.300102 -225.54438)
		(end 317.300102 -224.828608)
		(width 0.136652)
		(layer "F.Cu")
		(net "PCIE_TX_N23")
	)
	(segment
		(start 317.05296 -224.133664)
		(end 317.05296 -213.722204)
		(width 0.136652)
		(layer "F.Cu")
		(net "PCIE_TX_N23")
	)
	(segment
		(start 317.300102 -224.828608)
		(end 317.300356 -224.828354)
		(width 0.136652)
		(layer "F.Cu")
		(net "PCIE_TX_N23")
	)
	(arc
		(start 317.05296 -213.722204)
		(mid 317.145244 -213.258261)
		(end 317.408052 -212.864954)
		(width 0.136652)
		(layer "F.Cu")
		(net "PCIE_TX_N23")
	)
	(arc
		(start 317.300356 -224.828354)
		(mid 317.256719 -224.560646)
		(end 317.13043 -224.320608)
		(width 0.136652)
		(layer "F.Cu")
		(net "PCIE_TX_N23")
	)
	(arc
		(start 317.13043 -224.320608)
		(mid 317.07312 -224.234837)
		(end 317.05296 -224.133664)
		(width 0.136652)
		(layer "F.Cu")
		(net "PCIE_TX_N23")
	)
	(segment
		(start 320.500248 -225.54438)
		(end 320.500248 -224.828354)
		(width 0.136652)
		(layer "F.Cu")
		(net "PCIE_TX_N22")
	)
	(segment
		(start 320.252852 -224.133664)
		(end 320.252852 -213.722712)
		(width 0.136652)
		(layer "F.Cu")
		(net "PCIE_TX_N22")
	)
	(arc
		(start 320.500248 -224.828354)
		(mid 320.456611 -224.560646)
		(end 320.330322 -224.320608)
		(width 0.136652)
		(layer "F.Cu")
		(net "PCIE_TX_N22")
	)
	(arc
		(start 320.252852 -213.722712)
		(mid 320.345194 -213.258477)
		(end 320.608198 -212.864954)
		(width 0.136652)
		(layer "F.Cu")
		(net "PCIE_TX_N22")
	)
	(arc
		(start 320.330322 -224.320608)
		(mid 320.273012 -224.234837)
		(end 320.252852 -224.133664)
		(width 0.136652)
		(layer "F.Cu")
		(net "PCIE_TX_N22")
	)
	(segment
		(start 323.70014 -225.54438)
		(end 323.70014 -224.828354)
		(width 0.136652)
		(layer "F.Cu")
		(net "PCIE_TX_N21")
	)
	(segment
		(start 323.452744 -224.133664)
		(end 323.452744 -213.722712)
		(width 0.136652)
		(layer "F.Cu")
		(net "PCIE_TX_N21")
	)
	(arc
		(start 323.70014 -224.828354)
		(mid 323.656503 -224.560646)
		(end 323.530214 -224.320608)
		(width 0.136652)
		(layer "F.Cu")
		(net "PCIE_TX_N21")
	)
	(arc
		(start 323.452744 -213.722712)
		(mid 323.545086 -213.258477)
		(end 323.80809 -212.864954)
		(width 0.136652)
		(layer "F.Cu")
		(net "PCIE_TX_N21")
	)
	(arc
		(start 323.530214 -224.320608)
		(mid 323.472904 -224.234837)
		(end 323.452744 -224.133664)
		(width 0.136652)
		(layer "F.Cu")
		(net "PCIE_TX_N21")
	)
	(segment
		(start 326.652636 -224.133664)
		(end 326.652636 -213.722712)
		(width 0.136652)
		(layer "F.Cu")
		(net "PCIE_TX_N20")
	)
	(segment
		(start 326.900032 -225.54438)
		(end 326.900032 -224.828354)
		(width 0.136652)
		(layer "F.Cu")
		(net "PCIE_TX_N20")
	)
	(arc
		(start 326.730106 -224.320608)
		(mid 326.672796 -224.234837)
		(end 326.652636 -224.133664)
		(width 0.136652)
		(layer "F.Cu")
		(net "PCIE_TX_N20")
	)
	(arc
		(start 326.900032 -224.828354)
		(mid 326.856395 -224.560646)
		(end 326.730106 -224.320608)
		(width 0.136652)
		(layer "F.Cu")
		(net "PCIE_TX_N20")
	)
	(arc
		(start 326.652636 -213.722712)
		(mid 326.744978 -213.258477)
		(end 327.007982 -212.864954)
		(width 0.136652)
		(layer "F.Cu")
		(net "PCIE_TX_N20")
	)
	(segment
		(start 288.1376 -33.299146)
		(end 288.1376 -33.2994)
		(width 0.136652)
		(layer "F.Cu")
		(net "PCIE_TX_N2")
	)
	(segment
		(start 291.384482 -23.930102)
		(end 291.384482 -24.333708)
		(width 0.136652)
		(layer "F.Cu")
		(net "PCIE_TX_N2")
	)
	(segment
		(start 288.3408 -29.598366)
		(end 288.3408 -32.808418)
		(width 0.136652)
		(layer "F.Cu")
		(net "PCIE_TX_N2")
	)
	(segment
		(start 288.0106 -33.4264)
		(end 288.010346 -33.4264)
		(width 0.136652)
		(layer "F.Cu")
		(net "PCIE_TX_N2")
	)
	(segment
		(start 288.1376 -33.2994)
		(end 288.0106 -33.4264)
		(width 0.136652)
		(layer "F.Cu")
		(net "PCIE_TX_N2")
	)
	(segment
		(start 287.5026 -33.5788)
		(end 287.5026 -33.578546)
		(width 0.136652)
		(layer "F.Cu")
		(net "PCIE_TX_N2")
	)
	(segment
		(start 287.642554 -33.5788)
		(end 287.5026 -33.5788)
		(width 0.136652)
		(layer "F.Cu")
		(net "PCIE_TX_N2")
	)
	(segment
		(start 287.004252 -33.784794)
		(end 286.9311 -33.8582)
		(width 0.136652)
		(layer "F.Cu")
		(net "PCIE_TX_N2")
	)
	(segment
		(start 291.380926 -26.322274)
		(end 288.507678 -29.195522)
		(width 0.136652)
		(layer "F.Cu")
		(net "PCIE_TX_N2")
	)
	(segment
		(start 291.604954 -25.273)
		(end 291.604954 -25.781)
		(width 0.136652)
		(layer "F.Cu")
		(net "PCIE_TX_N2")
	)
	(arc
		(start 291.490146 -24.783542)
		(mid 291.575912 -25.021615)
		(end 291.604954 -25.273)
		(width 0.136652)
		(layer "F.Cu")
		(net "PCIE_TX_N2")
	)
	(arc
		(start 288.507678 -29.195522)
		(mid 288.384181 -29.380348)
		(end 288.3408 -29.598366)
		(width 0.136652)
		(layer "F.Cu")
		(net "PCIE_TX_N2")
	)
	(arc
		(start 291.604954 -25.781)
		(mid 291.546782 -26.073922)
		(end 291.380926 -26.322274)
		(width 0.136652)
		(layer "F.Cu")
		(net "PCIE_TX_N2")
	)
	(arc
		(start 291.384482 -24.333708)
		(mid 291.411294 -24.564734)
		(end 291.490146 -24.783542)
		(width 0.136652)
		(layer "F.Cu")
		(net "PCIE_TX_N2")
	)
	(arc
		(start 288.010346 -33.4264)
		(mid 287.841588 -33.539127)
		(end 287.642554 -33.5788)
		(width 0.136652)
		(layer "F.Cu")
		(net "PCIE_TX_N2")
	)
	(arc
		(start 288.3408 -32.808418)
		(mid 288.287993 -33.073987)
		(end 288.1376 -33.299146)
		(width 0.136652)
		(layer "F.Cu")
		(net "PCIE_TX_N2")
	)
	(arc
		(start 287.5026 -33.578546)
		(mid 287.232909 -33.632097)
		(end 287.004252 -33.784794)
		(width 0.136652)
		(layer "F.Cu")
		(net "PCIE_TX_N2")
	)
	(segment
		(start 333.052928 -224.133664)
		(end 333.052928 -213.722204)
		(width 0.136652)
		(layer "F.Cu")
		(net "PCIE_TX_N19")
	)
	(segment
		(start 333.30007 -225.54438)
		(end 333.30007 -224.828608)
		(width 0.136652)
		(layer "F.Cu")
		(net "PCIE_TX_N19")
	)
	(segment
		(start 333.30007 -224.828608)
		(end 333.300324 -224.828354)
		(width 0.136652)
		(layer "F.Cu")
		(net "PCIE_TX_N19")
	)
	(arc
		(start 333.052928 -213.722204)
		(mid 333.145212 -213.258261)
		(end 333.40802 -212.864954)
		(width 0.136652)
		(layer "F.Cu")
		(net "PCIE_TX_N19")
	)
	(arc
		(start 333.300324 -224.828354)
		(mid 333.256687 -224.560646)
		(end 333.130398 -224.320608)
		(width 0.136652)
		(layer "F.Cu")
		(net "PCIE_TX_N19")
	)
	(arc
		(start 333.130398 -224.320608)
		(mid 333.073088 -224.234837)
		(end 333.052928 -224.133664)
		(width 0.136652)
		(layer "F.Cu")
		(net "PCIE_TX_N19")
	)
	(segment
		(start 336.500216 -225.54438)
		(end 336.500216 -224.828354)
		(width 0.136652)
		(layer "F.Cu")
		(net "PCIE_TX_N18")
	)
	(segment
		(start 336.25282 -224.133664)
		(end 336.25282 -213.722712)
		(width 0.136652)
		(layer "F.Cu")
		(net "PCIE_TX_N18")
	)
	(arc
		(start 336.500216 -224.828354)
		(mid 336.456579 -224.560646)
		(end 336.33029 -224.320608)
		(width 0.136652)
		(layer "F.Cu")
		(net "PCIE_TX_N18")
	)
	(arc
		(start 336.25282 -213.722712)
		(mid 336.345162 -213.258477)
		(end 336.608166 -212.864954)
		(width 0.136652)
		(layer "F.Cu")
		(net "PCIE_TX_N18")
	)
	(arc
		(start 336.33029 -224.320608)
		(mid 336.27298 -224.234837)
		(end 336.25282 -224.133664)
		(width 0.136652)
		(layer "F.Cu")
		(net "PCIE_TX_N18")
	)
	(segment
		(start 339.452712 -224.133664)
		(end 339.452712 -213.722712)
		(width 0.136652)
		(layer "F.Cu")
		(net "PCIE_TX_N17")
	)
	(segment
		(start 339.700108 -225.54438)
		(end 339.700108 -224.828354)
		(width 0.136652)
		(layer "F.Cu")
		(net "PCIE_TX_N17")
	)
	(arc
		(start 339.452712 -213.722712)
		(mid 339.545054 -213.258477)
		(end 339.808058 -212.864954)
		(width 0.136652)
		(layer "F.Cu")
		(net "PCIE_TX_N17")
	)
	(arc
		(start 339.700108 -224.828354)
		(mid 339.656471 -224.560646)
		(end 339.530182 -224.320608)
		(width 0.136652)
		(layer "F.Cu")
		(net "PCIE_TX_N17")
	)
	(arc
		(start 339.530182 -224.320608)
		(mid 339.472872 -224.234837)
		(end 339.452712 -224.133664)
		(width 0.136652)
		(layer "F.Cu")
		(net "PCIE_TX_N17")
	)
	(segment
		(start 342.652604 -224.133664)
		(end 342.652604 -213.722712)
		(width 0.136652)
		(layer "F.Cu")
		(net "PCIE_TX_N16")
	)
	(segment
		(start 342.9 -225.54438)
		(end 342.9 -224.828354)
		(width 0.136652)
		(layer "F.Cu")
		(net "PCIE_TX_N16")
	)
	(arc
		(start 342.9 -224.828354)
		(mid 342.856363 -224.560646)
		(end 342.730074 -224.320608)
		(width 0.136652)
		(layer "F.Cu")
		(net "PCIE_TX_N16")
	)
	(arc
		(start 342.652604 -213.722712)
		(mid 342.744946 -213.258477)
		(end 343.00795 -212.864954)
		(width 0.136652)
		(layer "F.Cu")
		(net "PCIE_TX_N16")
	)
	(arc
		(start 342.730074 -224.320608)
		(mid 342.672764 -224.234837)
		(end 342.652604 -224.133664)
		(width 0.136652)
		(layer "F.Cu")
		(net "PCIE_TX_N16")
	)
	(segment
		(start 324.6501 -22.047454)
		(end 324.6501 -21.506688)
		(width 0.136652)
		(layer "F.Cu")
		(net "PCIE_TX_N15")
	)
	(segment
		(start 324.650354 -22.0472)
		(end 324.6501 -22.047454)
		(width 0.136652)
		(layer "F.Cu")
		(net "PCIE_TX_N15")
	)
	(segment
		(start 324.384416 -20.86483)
		(end 324.384416 -20.130008)
		(width 0.136652)
		(layer "F.Cu")
		(net "PCIE_TX_N15")
	)
	(segment
		(start 328.499978 -26.164286)
		(end 324.839076 -22.503384)
		(width 0.136652)
		(layer "F.Cu")
		(net "PCIE_TX_N15")
	)
	(segment
		(start 328.908664 -32.397954)
		(end 328.908664 -27.150822)
		(width 0.136652)
		(layer "F.Cu")
		(net "PCIE_TX_N15")
	)
	(arc
		(start 329.213718 -32.988758)
		(mid 328.989436 -32.730407)
		(end 328.908664 -32.397954)
		(width 0.136652)
		(layer "F.Cu")
		(net "PCIE_TX_N15")
	)
	(arc
		(start 324.839076 -22.503384)
		(mid 324.699364 -22.294056)
		(end 324.650354 -22.0472)
		(width 0.136652)
		(layer "F.Cu")
		(net "PCIE_TX_N15")
	)
	(arc
		(start 324.4469 -21.015706)
		(mid 324.400647 -20.946484)
		(end 324.384416 -20.86483)
		(width 0.136652)
		(layer "F.Cu")
		(net "PCIE_TX_N15")
	)
	(arc
		(start 324.6501 -21.506688)
		(mid 324.597342 -21.240982)
		(end 324.4469 -21.015706)
		(width 0.136652)
		(layer "F.Cu")
		(net "PCIE_TX_N15")
	)
	(arc
		(start 328.908664 -27.150822)
		(mid 328.802444 -26.616908)
		(end 328.499978 -26.164286)
		(width 0.136652)
		(layer "F.Cu")
		(net "PCIE_TX_N15")
	)
	(segment
		(start 324.1929 -27.446224)
		(end 324.1929 -26.975816)
		(width 0.136652)
		(layer "F.Cu")
		(net "PCIE_TX_N14")
	)
	(segment
		(start 324.384416 -24.664924)
		(end 324.384416 -23.930102)
		(width 0.136652)
		(layer "F.Cu")
		(net "PCIE_TX_N14")
	)
	(segment
		(start 326.504046 -32.470344)
		(end 326.504046 -30.541976)
		(width 0.136652)
		(layer "F.Cu")
		(net "PCIE_TX_N14")
	)
	(segment
		(start 326.091804 -29.546804)
		(end 324.335648 -27.790648)
		(width 0.136652)
		(layer "F.Cu")
		(net "PCIE_TX_N14")
	)
	(segment
		(start 324.6501 -26.042112)
		(end 324.6501 -25.306782)
		(width 0.136652)
		(layer "F.Cu")
		(net "PCIE_TX_N14")
	)
	(segment
		(start 324.319646 -26.669746)
		(end 324.440296 -26.549096)
		(width 0.136652)
		(layer "F.Cu")
		(net "PCIE_TX_N14")
	)
	(arc
		(start 324.454012 -26.535126)
		(mid 324.599403 -26.307439)
		(end 324.6501 -26.042112)
		(width 0.136652)
		(layer "F.Cu")
		(net "PCIE_TX_N14")
	)
	(arc
		(start 324.335648 -27.790648)
		(mid 324.230007 -27.632639)
		(end 324.1929 -27.446224)
		(width 0.136652)
		(layer "F.Cu")
		(net "PCIE_TX_N14")
	)
	(arc
		(start 326.504046 -30.541976)
		(mid 326.396913 -30.003382)
		(end 326.091804 -29.546804)
		(width 0.136652)
		(layer "F.Cu")
		(net "PCIE_TX_N14")
	)
	(arc
		(start 324.6501 -25.306782)
		(mid 324.597342 -25.041076)
		(end 324.4469 -24.8158)
		(width 0.136652)
		(layer "F.Cu")
		(net "PCIE_TX_N14")
	)
	(arc
		(start 324.440296 -26.549096)
		(mid 324.447202 -26.542158)
		(end 324.454012 -26.535126)
		(width 0.136652)
		(layer "F.Cu")
		(net "PCIE_TX_N14")
	)
	(arc
		(start 324.4469 -24.8158)
		(mid 324.400647 -24.746578)
		(end 324.384416 -24.664924)
		(width 0.136652)
		(layer "F.Cu")
		(net "PCIE_TX_N14")
	)
	(arc
		(start 326.807322 -33.01492)
		(mid 326.584983 -32.782007)
		(end 326.504046 -32.470344)
		(width 0.136652)
		(layer "F.Cu")
		(net "PCIE_TX_N14")
	)
	(arc
		(start 324.1929 -26.975816)
		(mid 324.225846 -26.810184)
		(end 324.319646 -26.669746)
		(width 0.136652)
		(layer "F.Cu")
		(net "PCIE_TX_N14")
	)
	(segment
		(start 322.400168 -27.430984)
		(end 322.400168 -25.306782)
		(width 0.136652)
		(layer "F.Cu")
		(net "PCIE_TX_N13")
	)
	(segment
		(start 322.134484 -24.664924)
		(end 322.134484 -23.930102)
		(width 0.136652)
		(layer "F.Cu")
		(net "PCIE_TX_N13")
	)
	(segment
		(start 324.1294 -32.4358)
		(end 324.1294 -30.113986)
		(width 0.136652)
		(layer "F.Cu")
		(net "PCIE_TX_N13")
	)
	(segment
		(start 323.687694 -29.047694)
		(end 322.633086 -27.993086)
		(width 0.136652)
		(layer "F.Cu")
		(net "PCIE_TX_N13")
	)
	(arc
		(start 324.1294 -30.113986)
		(mid 324.01461 -29.5369)
		(end 323.687694 -29.047694)
		(width 0.136652)
		(layer "F.Cu")
		(net "PCIE_TX_N13")
	)
	(arc
		(start 322.400168 -25.306782)
		(mid 322.34741 -25.041076)
		(end 322.196968 -24.8158)
		(width 0.136652)
		(layer "F.Cu")
		(net "PCIE_TX_N13")
	)
	(arc
		(start 322.633086 -27.993086)
		(mid 322.460713 -27.735206)
		(end 322.400168 -27.430984)
		(width 0.136652)
		(layer "F.Cu")
		(net "PCIE_TX_N13")
	)
	(arc
		(start 322.196968 -24.8158)
		(mid 322.150715 -24.746578)
		(end 322.134484 -24.664924)
		(width 0.136652)
		(layer "F.Cu")
		(net "PCIE_TX_N13")
	)
	(arc
		(start 324.45071 -33.038288)
		(mid 324.214718 -32.777216)
		(end 324.1294 -32.4358)
		(width 0.136652)
		(layer "F.Cu")
		(net "PCIE_TX_N13")
	)
	(segment
		(start 318.0334 -28.080462)
		(end 318.0334 -24.530304)
		(width 0.136652)
		(layer "F.Cu")
		(net "PCIE_TX_N12")
	)
	(segment
		(start 322.400168 -21.7932)
		(end 322.400168 -21.506688)
		(width 0.136652)
		(layer "F.Cu")
		(net "PCIE_TX_N12")
	)
	(segment
		(start 319.625218 -22.95525)
		(end 321.238118 -22.95525)
		(width 0.136652)
		(layer "F.Cu")
		(net "PCIE_TX_N12")
	)
	(segment
		(start 318.217804 -24.085296)
		(end 319.151762 -23.151338)
		(width 0.136652)
		(layer "F.Cu")
		(net "PCIE_TX_N12")
	)
	(segment
		(start 320.242184 -32.497776)
		(end 320.242184 -30.92577)
		(width 0.136652)
		(layer "F.Cu")
		(net "PCIE_TX_N12")
	)
	(segment
		(start 322.134484 -20.86483)
		(end 322.134484 -20.130008)
		(width 0.136652)
		(layer "F.Cu")
		(net "PCIE_TX_N12")
	)
	(segment
		(start 320.002662 -30.347666)
		(end 318.24422 -28.589224)
		(width 0.136652)
		(layer "F.Cu")
		(net "PCIE_TX_N12")
	)
	(arc
		(start 321.238118 -22.95525)
		(mid 322.059811 -22.614893)
		(end 322.400168 -21.7932)
		(width 0.136652)
		(layer "F.Cu")
		(net "PCIE_TX_N12")
	)
	(arc
		(start 322.196968 -21.015706)
		(mid 322.150715 -20.946484)
		(end 322.134484 -20.86483)
		(width 0.136652)
		(layer "F.Cu")
		(net "PCIE_TX_N12")
	)
	(arc
		(start 320.559176 -33.062926)
		(mid 320.326807 -32.821779)
		(end 320.242184 -32.497776)
		(width 0.136652)
		(layer "F.Cu")
		(net "PCIE_TX_N12")
	)
	(arc
		(start 318.0334 -24.530304)
		(mid 318.081326 -24.289453)
		(end 318.217804 -24.085296)
		(width 0.136652)
		(layer "F.Cu")
		(net "PCIE_TX_N12")
	)
	(arc
		(start 322.400168 -21.506688)
		(mid 322.34741 -21.240982)
		(end 322.196968 -21.015706)
		(width 0.136652)
		(layer "F.Cu")
		(net "PCIE_TX_N12")
	)
	(arc
		(start 318.24422 -28.589224)
		(mid 318.088199 -28.355816)
		(end 318.0334 -28.080462)
		(width 0.136652)
		(layer "F.Cu")
		(net "PCIE_TX_N12")
	)
	(arc
		(start 320.242184 -30.92577)
		(mid 320.179931 -30.612892)
		(end 320.002662 -30.347666)
		(width 0.136652)
		(layer "F.Cu")
		(net "PCIE_TX_N12")
	)
	(arc
		(start 319.151762 -23.151338)
		(mid 319.368985 -23.006194)
		(end 319.625218 -22.95525)
		(width 0.136652)
		(layer "F.Cu")
		(net "PCIE_TX_N12")
	)
	(segment
		(start 315.4172 -24.53259)
		(end 315.4172 -32.5628)
		(width 0.136652)
		(layer "F.Cu")
		(net "PCIE_TX_N11")
	)
	(segment
		(start 313.650122 -21.506688)
		(end 313.650122 -22.126956)
		(width 0.136652)
		(layer "F.Cu")
		(net "PCIE_TX_N11")
	)
	(segment
		(start 313.817 -22.5298)
		(end 315.132466 -23.845266)
		(width 0.136652)
		(layer "F.Cu")
		(net "PCIE_TX_N11")
	)
	(segment
		(start 313.384438 -20.130008)
		(end 313.384438 -20.86483)
		(width 0.136652)
		(layer "F.Cu")
		(net "PCIE_TX_N11")
	)
	(arc
		(start 313.650122 -22.126956)
		(mid 313.69349 -22.344979)
		(end 313.817 -22.5298)
		(width 0.136652)
		(layer "F.Cu")
		(net "PCIE_TX_N11")
	)
	(arc
		(start 313.446922 -21.015706)
		(mid 313.597356 -21.240985)
		(end 313.650122 -21.506688)
		(width 0.136652)
		(layer "F.Cu")
		(net "PCIE_TX_N11")
	)
	(arc
		(start 313.384438 -20.86483)
		(mid 313.400679 -20.946479)
		(end 313.446922 -21.015706)
		(width 0.136652)
		(layer "F.Cu")
		(net "PCIE_TX_N11")
	)
	(arc
		(start 315.4172 -32.5628)
		(mid 315.499004 -32.864474)
		(end 315.722 -33.0835)
		(width 0.136652)
		(layer "F.Cu")
		(net "PCIE_TX_N11")
	)
	(arc
		(start 315.132466 -23.845266)
		(mid 315.343174 -24.160613)
		(end 315.4172 -24.53259)
		(width 0.136652)
		(layer "F.Cu")
		(net "PCIE_TX_N11")
	)
	(segment
		(start 313.440318 -26.549096)
		(end 313.319668 -26.669746)
		(width 0.136652)
		(layer "F.Cu")
		(net "PCIE_TX_N10")
	)
	(segment
		(start 313.384438 -23.930102)
		(end 313.384438 -24.664924)
		(width 0.136652)
		(layer "F.Cu")
		(net "PCIE_TX_N10")
	)
	(segment
		(start 313.192922 -26.975816)
		(end 313.192922 -32.5882)
		(width 0.136652)
		(layer "F.Cu")
		(net "PCIE_TX_N10")
	)
	(segment
		(start 313.650122 -25.306782)
		(end 313.650122 -26.042112)
		(width 0.136652)
		(layer "F.Cu")
		(net "PCIE_TX_N10")
	)
	(arc
		(start 313.192922 -32.5882)
		(mid 313.279733 -32.895484)
		(end 313.514486 -33.111948)
		(width 0.136652)
		(layer "F.Cu")
		(net "PCIE_TX_N10")
	)
	(arc
		(start 313.454034 -26.535126)
		(mid 313.447223 -26.542158)
		(end 313.440318 -26.549096)
		(width 0.136652)
		(layer "F.Cu")
		(net "PCIE_TX_N10")
	)
	(arc
		(start 313.650122 -26.042112)
		(mid 313.599324 -26.307399)
		(end 313.454034 -26.535126)
		(width 0.136652)
		(layer "F.Cu")
		(net "PCIE_TX_N10")
	)
	(arc
		(start 313.276742 -26.719784)
		(mid 313.214393 -26.841111)
		(end 313.192922 -26.975816)
		(width 0.136652)
		(layer "F.Cu")
		(net "PCIE_TX_N10")
	)
	(arc
		(start 313.384438 -24.664924)
		(mid 313.400679 -24.746573)
		(end 313.446922 -24.8158)
		(width 0.136652)
		(layer "F.Cu")
		(net "PCIE_TX_N10")
	)
	(arc
		(start 313.446922 -24.8158)
		(mid 313.597356 -25.041079)
		(end 313.650122 -25.306782)
		(width 0.136652)
		(layer "F.Cu")
		(net "PCIE_TX_N10")
	)
	(arc
		(start 313.319668 -26.669746)
		(mid 313.297248 -26.693944)
		(end 313.276742 -26.719784)
		(width 0.136652)
		(layer "F.Cu")
		(net "PCIE_TX_N10")
	)
	(segment
		(start 277.976584 -24.891238)
		(end 277.857966 -24.604726)
		(width 0.136652)
		(layer "F.Cu")
		(net "PCIE_TX_N1")
	)
	(segment
		(start 289.13455 -24.2062)
		(end 289.13455 -24.333708)
		(width 0.136652)
		(layer "F.Cu")
		(net "PCIE_TX_N1")
	)
	(segment
		(start 289.355022 -25.273)
		(end 289.355022 -25.609296)
		(width 0.136652)
		(layer "F.Cu")
		(net "PCIE_TX_N1")
	)
	(segment
		(start 289.134296 -23.930102)
		(end 289.134296 -24.205946)
		(width 0.136652)
		(layer "F.Cu")
		(net "PCIE_TX_N1")
	)
	(segment
		(start 288.593784 -26.370788)
		(end 280.903172 -26.370788)
		(width 0.136652)
		(layer "F.Cu")
		(net "PCIE_TX_N1")
	)
	(segment
		(start 277.659592 -23.60803)
		(end 277.659592 -16.609568)
		(width 0.136652)
		(layer "F.Cu")
		(net "PCIE_TX_N1")
	)
	(segment
		(start 289.134296 -24.205946)
		(end 289.13455 -24.2062)
		(width 0.136652)
		(layer "F.Cu")
		(net "PCIE_TX_N1")
	)
	(segment
		(start 275.759672 -15.0876)
		(end 275.058124 -15.0876)
		(width 0.136652)
		(layer "F.Cu")
		(net "PCIE_TX_N1")
	)
	(segment
		(start 279.677876 -26.0985)
		(end 279.182576 -25.866598)
		(width 0.136652)
		(layer "F.Cu")
		(net "PCIE_TX_N1")
	)
	(segment
		(start 279.182576 -25.866598)
		(end 278.687276 -25.63495)
		(width 0.136652)
		(layer "F.Cu")
		(net "PCIE_TX_N1")
	)
	(arc
		(start 289.355022 -25.609296)
		(mid 289.297057 -25.900706)
		(end 289.13201 -26.147776)
		(width 0.136652)
		(layer "F.Cu")
		(net "PCIE_TX_N1")
	)
	(arc
		(start 278.687276 -25.63495)
		(mid 278.262275 -25.329648)
		(end 277.976584 -24.891238)
		(width 0.136652)
		(layer "F.Cu")
		(net "PCIE_TX_N1")
	)
	(arc
		(start 277.857966 -24.604726)
		(mid 277.709702 -24.116147)
		(end 277.659592 -23.60803)
		(width 0.136652)
		(layer "F.Cu")
		(net "PCIE_TX_N1")
	)
	(arc
		(start 275.058124 -15.0876)
		(mid 274.693035 -15.160221)
		(end 274.3835 -15.367)
		(width 0.136652)
		(layer "F.Cu")
		(net "PCIE_TX_N1")
	)
	(arc
		(start 280.903172 -26.370788)
		(mid 280.275572 -26.301926)
		(end 279.677876 -26.0985)
		(width 0.136652)
		(layer "F.Cu")
		(net "PCIE_TX_N1")
	)
	(arc
		(start 289.299904 -24.92883)
		(mid 289.341189 -25.098715)
		(end 289.355022 -25.273)
		(width 0.136652)
		(layer "F.Cu")
		(net "PCIE_TX_N1")
	)
	(arc
		(start 277.292054 -15.722346)
		(mid 276.588991 -15.252574)
		(end 275.759672 -15.0876)
		(width 0.136652)
		(layer "F.Cu")
		(net "PCIE_TX_N1")
	)
	(arc
		(start 289.13201 -26.147776)
		(mid 288.885071 -26.312805)
		(end 288.593784 -26.370788)
		(width 0.136652)
		(layer "F.Cu")
		(net "PCIE_TX_N1")
	)
	(arc
		(start 289.166554 -24.586438)
		(mid 289.198248 -24.686909)
		(end 289.240214 -24.783542)
		(width 0.136652)
		(layer "F.Cu")
		(net "PCIE_TX_N1")
	)
	(arc
		(start 277.659592 -16.609568)
		(mid 277.564079 -16.129392)
		(end 277.292054 -15.722346)
		(width 0.136652)
		(layer "F.Cu")
		(net "PCIE_TX_N1")
	)
	(arc
		(start 289.240214 -24.783542)
		(mid 289.27265 -24.855121)
		(end 289.299904 -24.92883)
		(width 0.136652)
		(layer "F.Cu")
		(net "PCIE_TX_N1")
	)
	(arc
		(start 289.13455 -24.333708)
		(mid 289.142574 -24.461082)
		(end 289.166554 -24.586438)
		(width 0.136652)
		(layer "F.Cu")
		(net "PCIE_TX_N1")
	)
	(segment
		(start 277.386542 -12.9921)
		(end 275.088604 -12.9921)
		(width 0.136652)
		(layer "F.Cu")
		(net "PCIE_TX_N0")
	)
	(segment
		(start 287.149032 -18.87982)
		(end 283.982414 -18.87982)
		(width 0.136652)
		(layer "F.Cu")
		(net "PCIE_TX_N0")
	)
	(segment
		(start 288.511742 -20.374864)
		(end 288.327846 -20.190968)
		(width 0.136652)
		(layer "F.Cu")
		(net "PCIE_TX_N0")
	)
	(segment
		(start 287.972754 -19.331432)
		(end 287.784032 -19.14271)
		(width 0.136652)
		(layer "F.Cu")
		(net "PCIE_TX_N0")
	)
	(segment
		(start 283.305504 -18.599404)
		(end 277.918164 -13.212064)
		(width 0.136652)
		(layer "F.Cu")
		(net "PCIE_TX_N0")
	)
	(segment
		(start 288.265616 -20.041362)
		(end 288.265616 -20.038568)
		(width 0.136652)
		(layer "F.Cu")
		(net "PCIE_TX_N0")
	)
	(arc
		(start 277.918164 -13.212064)
		(mid 277.674224 -13.049225)
		(end 277.386542 -12.9921)
		(width 0.136652)
		(layer "F.Cu")
		(net "PCIE_TX_N0")
	)
	(arc
		(start 288.327846 -20.190968)
		(mid 288.281792 -20.122372)
		(end 288.265616 -20.041362)
		(width 0.136652)
		(layer "F.Cu")
		(net "PCIE_TX_N0")
	)
	(arc
		(start 289.134296 -20.130008)
		(mid 288.903257 -20.456238)
		(end 288.511742 -20.374864)
		(width 0.136652)
		(layer "F.Cu")
		(net "PCIE_TX_N0")
	)
	(arc
		(start 287.784032 -19.14271)
		(mid 287.492676 -18.948125)
		(end 287.149032 -18.87982)
		(width 0.136652)
		(layer "F.Cu")
		(net "PCIE_TX_N0")
	)
	(arc
		(start 288.265616 -20.038568)
		(mid 288.189511 -19.655871)
		(end 287.972754 -19.331432)
		(width 0.136652)
		(layer "F.Cu")
		(net "PCIE_TX_N0")
	)
	(arc
		(start 283.982414 -18.87982)
		(mid 283.616061 -18.806948)
		(end 283.305504 -18.599404)
		(width 0.136652)
		(layer "F.Cu")
		(net "PCIE_TX_N0")
	)
	(arc
		(start 275.088604 -12.9921)
		(mid 274.706991 -12.916192)
		(end 274.3835 -12.7)
		(width 0.136652)
		(layer "F.Cu")
		(net "PCIE_TX_N0")
	)
	(segment
		(start 182.23992 -20.515834)
		(end 182.0545 -20.701)
		(width 0.136652)
		(layer "F.Cu")
		(net "PCIE_TX_CAP_P95")
	)
	(segment
		(start 182.722266 -20.4089)
		(end 182.498238 -20.4089)
		(width 0.136652)
		(layer "F.Cu")
		(net "PCIE_TX_CAP_P95")
	)
	(segment
		(start 229.599998 -30.999938)
		(end 229.100126 -30.500066)
		(width 0.136652)
		(layer "F.Cu")
		(net "PCIE_TX_CAP_P95")
	)
	(via
		(at 183.0832 -20.6629)
		(size 0.508)
		(drill 0.254)
		(layers "F.Cu" "B.Cu")
		(net "PCIE_TX_CAP_P95")
	)
	(via
		(at 229.100126 -30.500066)
		(size 0.4572)
		(drill 0.2032)
		(layers "F.Cu" "B.Cu")
		(net "PCIE_TX_CAP_P95")
	)
	(arc
		(start 182.498238 -20.4089)
		(mid 182.358448 -20.436688)
		(end 182.23992 -20.515834)
		(width 0.136652)
		(layer "F.Cu")
		(net "PCIE_TX_CAP_P95")
	)
	(arc
		(start 183.0832 -20.6629)
		(mid 182.942922 -20.478808)
		(end 182.722266 -20.4089)
		(width 0.136652)
		(layer "F.Cu")
		(net "PCIE_TX_CAP_P95")
	)
	(segment
		(start 192.823592 -22.064218)
		(end 194.366642 -21.73605)
		(width 0.1397)
		(layer "In5.Cu")
		(net "PCIE_TX_CAP_P95")
	)
	(segment
		(start 203.956158 -24.274018)
		(end 204.782166 -24.098504)
		(width 0.1397)
		(layer "In5.Cu")
		(net "PCIE_TX_CAP_P95")
	)
	(segment
		(start 228.868478 -29.9974)
		(end 228.896418 -29.9974)
		(width 0.1016)
		(layer "In5.Cu")
		(net "PCIE_TX_CAP_P95")
	)
	(segment
		(start 223.752918 -23.116794)
		(end 225.478086 -23.42134)
		(width 0.1397)
		(layer "In5.Cu")
		(net "PCIE_TX_CAP_P95")
	)
	(segment
		(start 194.366642 -21.73605)
		(end 194.935094 -21.73605)
		(width 0.1397)
		(layer "In5.Cu")
		(net "PCIE_TX_CAP_P95")
	)
	(segment
		(start 206.491078 -22.164294)
		(end 207.44688 -21.961094)
		(width 0.1397)
		(layer "In5.Cu")
		(net "PCIE_TX_CAP_P95")
	)
	(segment
		(start 200.3171 -22.88032)
		(end 201.62647 -23.730712)
		(width 0.1397)
		(layer "In5.Cu")
		(net "PCIE_TX_CAP_P95")
	)
	(segment
		(start 215.490552 -23.5458)
		(end 218.406726 -24.059134)
		(width 0.1397)
		(layer "In5.Cu")
		(net "PCIE_TX_CAP_P95")
	)
	(segment
		(start 207.44688 -21.961094)
		(end 208.03108 -22.0853)
		(width 0.1397)
		(layer "In5.Cu")
		(net "PCIE_TX_CAP_P95")
	)
	(segment
		(start 228.428804 -28.582112)
		(end 228.492304 -28.645612)
		(width 0.1016)
		(layer "In5.Cu")
		(net "PCIE_TX_CAP_P95")
	)
	(segment
		(start 208.382362 -22.31263)
		(end 208.650586 -22.724872)
		(width 0.1397)
		(layer "In5.Cu")
		(net "PCIE_TX_CAP_P95")
	)
	(segment
		(start 205.823566 -22.742144)
		(end 205.985618 -22.492462)
		(width 0.1397)
		(layer "In5.Cu")
		(net "PCIE_TX_CAP_P95")
	)
	(segment
		(start 205.985618 -22.492462)
		(end 206.491078 -22.164294)
		(width 0.1397)
		(layer "In5.Cu")
		(net "PCIE_TX_CAP_P95")
	)
	(segment
		(start 209.87639 -24.500586)
		(end 210.436968 -24.619712)
		(width 0.1397)
		(layer "In5.Cu")
		(net "PCIE_TX_CAP_P95")
	)
	(segment
		(start 225.478086 -23.42134)
		(end 228.003608 -25.946862)
		(width 0.1397)
		(layer "In5.Cu")
		(net "PCIE_TX_CAP_P95")
	)
	(segment
		(start 208.829656 -23.56866)
		(end 209.112866 -24.004778)
		(width 0.1397)
		(layer "In5.Cu")
		(net "PCIE_TX_CAP_P95")
	)
	(segment
		(start 201.62647 -23.730712)
		(end 201.662792 -23.786592)
		(width 0.1397)
		(layer "In5.Cu")
		(net "PCIE_TX_CAP_P95")
	)
	(segment
		(start 186.014106 -20.619212)
		(end 192.823592 -22.064218)
		(width 0.1397)
		(layer "In5.Cu")
		(net "PCIE_TX_CAP_P95")
	)
	(segment
		(start 228.428804 -28.556712)
		(end 228.428804 -28.582112)
		(width 0.1016)
		(layer "In5.Cu")
		(net "PCIE_TX_CAP_P95")
	)
	(segment
		(start 194.935094 -21.73605)
		(end 200.3171 -22.88032)
		(width 0.1397)
		(layer "In5.Cu")
		(net "PCIE_TX_CAP_P95")
	)
	(segment
		(start 228.428804 -26.815034)
		(end 228.428804 -28.556712)
		(width 0.1397)
		(layer "In5.Cu")
		(net "PCIE_TX_CAP_P95")
	)
	(segment
		(start 204.782166 -24.098504)
		(end 205.47965 -23.645622)
		(width 0.1397)
		(layer "In5.Cu")
		(net "PCIE_TX_CAP_P95")
	)
	(segment
		(start 208.03108 -22.0853)
		(end 208.382362 -22.31263)
		(width 0.1397)
		(layer "In5.Cu")
		(net "PCIE_TX_CAP_P95")
	)
	(segment
		(start 205.705202 -23.298404)
		(end 205.823566 -22.742144)
		(width 0.1397)
		(layer "In5.Cu")
		(net "PCIE_TX_CAP_P95")
	)
	(segment
		(start 209.112866 -24.004778)
		(end 209.87639 -24.500586)
		(width 0.1397)
		(layer "In5.Cu")
		(net "PCIE_TX_CAP_P95")
	)
	(segment
		(start 210.436968 -24.619712)
		(end 215.490552 -23.5458)
		(width 0.1397)
		(layer "In5.Cu")
		(net "PCIE_TX_CAP_P95")
	)
	(segment
		(start 201.662792 -23.786592)
		(end 203.956158 -24.274018)
		(width 0.1397)
		(layer "In5.Cu")
		(net "PCIE_TX_CAP_P95")
	)
	(segment
		(start 208.650586 -22.724872)
		(end 208.829656 -23.56866)
		(width 0.1397)
		(layer "In5.Cu")
		(net "PCIE_TX_CAP_P95")
	)
	(segment
		(start 228.492304 -28.645612)
		(end 228.492304 -29.620718)
		(width 0.1016)
		(layer "In5.Cu")
		(net "PCIE_TX_CAP_P95")
	)
	(segment
		(start 228.003608 -25.946862)
		(end 228.367336 -26.465784)
		(width 0.1397)
		(layer "In5.Cu")
		(net "PCIE_TX_CAP_P95")
	)
	(segment
		(start 183.410606 -20.430236)
		(end 185.12409 -20.430236)
		(width 0.1397)
		(layer "In5.Cu")
		(net "PCIE_TX_CAP_P95")
	)
	(segment
		(start 228.367336 -26.465784)
		(end 228.428804 -26.815034)
		(width 0.1397)
		(layer "In5.Cu")
		(net "PCIE_TX_CAP_P95")
	)
	(segment
		(start 186.01436 -20.619212)
		(end 186.014106 -20.619212)
		(width 0.1397)
		(layer "In5.Cu")
		(net "PCIE_TX_CAP_P95")
	)
	(segment
		(start 205.47965 -23.645622)
		(end 205.705202 -23.298404)
		(width 0.1397)
		(layer "In5.Cu")
		(net "PCIE_TX_CAP_P95")
	)
	(segment
		(start 218.406726 -24.059134)
		(end 223.752918 -23.116794)
		(width 0.1397)
		(layer "In5.Cu")
		(net "PCIE_TX_CAP_P95")
	)
	(segment
		(start 185.12409 -20.430236)
		(end 186.01436 -20.619212)
		(width 0.1397)
		(layer "In5.Cu")
		(net "PCIE_TX_CAP_P95")
	)
	(segment
		(start 229.100126 -30.157674)
		(end 229.100126 -30.500066)
		(width 0.1016)
		(layer "In5.Cu")
		(net "PCIE_TX_CAP_P95")
	)
	(arc
		(start 228.896418 -29.9974)
		(mid 229.026008 -30.042276)
		(end 229.100126 -30.157674)
		(width 0.1016)
		(layer "In5.Cu")
		(net "PCIE_TX_CAP_P95")
	)
	(arc
		(start 228.802438 -29.991558)
		(mid 228.83533 -29.995928)
		(end 228.868478 -29.9974)
		(width 0.1016)
		(layer "In5.Cu")
		(net "PCIE_TX_CAP_P95")
	)
	(arc
		(start 228.492304 -29.620718)
		(mid 228.580064 -29.862407)
		(end 228.802438 -29.991558)
		(width 0.1016)
		(layer "In5.Cu")
		(net "PCIE_TX_CAP_P95")
	)
	(arc
		(start 183.0832 -20.6629)
		(mid 183.095806 -20.599525)
		(end 183.131714 -20.545806)
		(width 0.1397)
		(layer "In5.Cu")
		(net "PCIE_TX_CAP_P95")
	)
	(arc
		(start 183.131714 -20.545806)
		(mid 183.259656 -20.460254)
		(end 183.410606 -20.430236)
		(width 0.1397)
		(layer "In5.Cu")
		(net "PCIE_TX_CAP_P95")
	)
	(segment
		(start 182.0545 -24.511)
		(end 182.127652 -24.438102)
		(width 0.136652)
		(layer "F.Cu")
		(net "PCIE_TX_CAP_P94")
	)
	(segment
		(start 182.331868 -24.301196)
		(end 182.396384 -24.274272)
		(width 0.136652)
		(layer "F.Cu")
		(net "PCIE_TX_CAP_P94")
	)
	(segment
		(start 228.6 -31.999936)
		(end 228.100128 -31.500064)
		(width 0.136652)
		(layer "F.Cu")
		(net "PCIE_TX_CAP_P94")
	)
	(segment
		(start 182.99176 -24.38146)
		(end 183.0832 -24.4729)
		(width 0.136652)
		(layer "F.Cu")
		(net "PCIE_TX_CAP_P94")
	)
	(segment
		(start 182.499254 -24.25319)
		(end 182.682134 -24.25319)
		(width 0.136652)
		(layer "F.Cu")
		(net "PCIE_TX_CAP_P94")
	)
	(via
		(at 183.0832 -24.4729)
		(size 0.508)
		(drill 0.254)
		(layers "F.Cu" "B.Cu")
		(net "PCIE_TX_CAP_P94")
	)
	(via
		(at 228.100128 -31.500064)
		(size 0.4572)
		(drill 0.2032)
		(layers "F.Cu" "B.Cu")
		(net "PCIE_TX_CAP_P94")
	)
	(arc
		(start 182.127652 -24.438102)
		(mid 182.22307 -24.35967)
		(end 182.331868 -24.301196)
		(width 0.136652)
		(layer "F.Cu")
		(net "PCIE_TX_CAP_P94")
	)
	(arc
		(start 182.682134 -24.25319)
		(mid 182.84971 -24.286523)
		(end 182.99176 -24.38146)
		(width 0.136652)
		(layer "F.Cu")
		(net "PCIE_TX_CAP_P94")
	)
	(arc
		(start 182.396384 -24.274272)
		(mid 182.446804 -24.258793)
		(end 182.499254 -24.25319)
		(width 0.136652)
		(layer "F.Cu")
		(net "PCIE_TX_CAP_P94")
	)
	(segment
		(start 215.419432 -24.471122)
		(end 218.665298 -25.043384)
		(width 0.1397)
		(layer "In5.Cu")
		(net "PCIE_TX_CAP_P94")
	)
	(segment
		(start 227.847652 -30.987492)
		(end 227.998782 -30.987492)
		(width 0.1016)
		(layer "In5.Cu")
		(net "PCIE_TX_CAP_P94")
	)
	(segment
		(start 188.430662 -23.085552)
		(end 188.430662 -23.085806)
		(width 0.1397)
		(layer "In5.Cu")
		(net "PCIE_TX_CAP_P94")
	)
	(segment
		(start 207.389222 -26.178764)
		(end 215.419432 -24.471122)
		(width 0.1397)
		(layer "In5.Cu")
		(net "PCIE_TX_CAP_P94")
	)
	(segment
		(start 227.435156 -28.693618)
		(end 227.498656 -28.757118)
		(width 0.1016)
		(layer "In5.Cu")
		(net "PCIE_TX_CAP_P94")
	)
	(segment
		(start 227.435156 -28.067)
		(end 227.435156 -28.668218)
		(width 0.1397)
		(layer "In5.Cu")
		(net "PCIE_TX_CAP_P94")
	)
	(segment
		(start 184.481216 -23.801324)
		(end 184.857644 -22.030944)
		(width 0.1397)
		(layer "In5.Cu")
		(net "PCIE_TX_CAP_P94")
	)
	(segment
		(start 228.100128 -31.088838)
		(end 228.100128 -31.500064)
		(width 0.1016)
		(layer "In5.Cu")
		(net "PCIE_TX_CAP_P94")
	)
	(segment
		(start 224.4471 -24.4221)
		(end 224.6503 -24.6253)
		(width 0.1397)
		(layer "In5.Cu")
		(net "PCIE_TX_CAP_P94")
	)
	(segment
		(start 183.515 -24.2316)
		(end 183.7436 -24.2316)
		(width 0.1397)
		(layer "In5.Cu")
		(net "PCIE_TX_CAP_P94")
	)
	(segment
		(start 194.05346 -23.344378)
		(end 207.389222 -26.178764)
		(width 0.1397)
		(layer "In5.Cu")
		(net "PCIE_TX_CAP_P94")
	)
	(segment
		(start 189.662054 -23.885652)
		(end 190.584582 -24.08174)
		(width 0.1397)
		(layer "In5.Cu")
		(net "PCIE_TX_CAP_P94")
	)
	(segment
		(start 187.789058 -22.099016)
		(end 188.430662 -23.085552)
		(width 0.1397)
		(layer "In5.Cu")
		(net "PCIE_TX_CAP_P94")
	)
	(segment
		(start 188.430662 -23.085806)
		(end 189.662054 -23.885652)
		(width 0.1397)
		(layer "In5.Cu")
		(net "PCIE_TX_CAP_P94")
	)
	(segment
		(start 183.0832 -24.4729)
		(end 183.189626 -24.36622)
		(width 0.1397)
		(layer "In5.Cu")
		(net "PCIE_TX_CAP_P94")
	)
	(segment
		(start 221.798642 -24.416512)
		(end 223.161352 -24.176482)
		(width 0.1397)
		(layer "In5.Cu")
		(net "PCIE_TX_CAP_P94")
	)
	(segment
		(start 223.161352 -24.176482)
		(end 224.423986 -24.39924)
		(width 0.1397)
		(layer "In5.Cu")
		(net "PCIE_TX_CAP_P94")
	)
	(segment
		(start 227.498656 -28.757118)
		(end 227.498656 -30.607254)
		(width 0.1016)
		(layer "In5.Cu")
		(net "PCIE_TX_CAP_P94")
	)
	(segment
		(start 224.6503 -24.6253)
		(end 225.319844 -25.581356)
		(width 0.1397)
		(layer "In5.Cu")
		(net "PCIE_TX_CAP_P94")
	)
	(segment
		(start 226.2759 -26.2509)
		(end 226.6315 -26.6065)
		(width 0.1397)
		(layer "In5.Cu")
		(net "PCIE_TX_CAP_P94")
	)
	(segment
		(start 227.361496 -27.648916)
		(end 227.435156 -28.067)
		(width 0.1397)
		(layer "In5.Cu")
		(net "PCIE_TX_CAP_P94")
	)
	(segment
		(start 225.319844 -25.581356)
		(end 226.2759 -26.2509)
		(width 0.1397)
		(layer "In5.Cu")
		(net "PCIE_TX_CAP_P94")
	)
	(segment
		(start 224.446338 -24.421592)
		(end 224.4471 -24.4221)
		(width 0.1397)
		(layer "In5.Cu")
		(net "PCIE_TX_CAP_P94")
	)
	(segment
		(start 184.857644 -22.030944)
		(end 185.497216 -21.615146)
		(width 0.1397)
		(layer "In5.Cu")
		(net "PCIE_TX_CAP_P94")
	)
	(segment
		(start 184.267348 -24.015192)
		(end 184.481216 -23.801324)
		(width 0.1397)
		(layer "In5.Cu")
		(net "PCIE_TX_CAP_P94")
	)
	(segment
		(start 185.497216 -21.615146)
		(end 187.789058 -22.099016)
		(width 0.1397)
		(layer "In5.Cu")
		(net "PCIE_TX_CAP_P94")
	)
	(segment
		(start 226.6315 -26.6065)
		(end 227.361496 -27.648916)
		(width 0.1397)
		(layer "In5.Cu")
		(net "PCIE_TX_CAP_P94")
	)
	(segment
		(start 224.423986 -24.39924)
		(end 224.446338 -24.421592)
		(width 0.1397)
		(layer "In5.Cu")
		(net "PCIE_TX_CAP_P94")
	)
	(segment
		(start 190.584582 -24.08174)
		(end 194.05346 -23.344378)
		(width 0.1397)
		(layer "In5.Cu")
		(net "PCIE_TX_CAP_P94")
	)
	(segment
		(start 227.610162 -30.87624)
		(end 227.632006 -30.898084)
		(width 0.1016)
		(layer "In5.Cu")
		(net "PCIE_TX_CAP_P94")
	)
	(segment
		(start 227.435156 -28.668218)
		(end 227.435156 -28.693618)
		(width 0.1016)
		(layer "In5.Cu")
		(net "PCIE_TX_CAP_P94")
	)
	(segment
		(start 218.665298 -25.043384)
		(end 221.798642 -24.416512)
		(width 0.1397)
		(layer "In5.Cu")
		(net "PCIE_TX_CAP_P94")
	)
	(arc
		(start 227.998782 -30.987492)
		(mid 228.070444 -31.017176)
		(end 228.100128 -31.088838)
		(width 0.1016)
		(layer "In5.Cu")
		(net "PCIE_TX_CAP_P94")
	)
	(arc
		(start 184.188608 -24.083518)
		(mid 184.229181 -24.050742)
		(end 184.267348 -24.015192)
		(width 0.1397)
		(layer "In5.Cu")
		(net "PCIE_TX_CAP_P94")
	)
	(arc
		(start 184.008776 -24.182832)
		(mid 184.102147 -24.139431)
		(end 184.188608 -24.083518)
		(width 0.1397)
		(layer "In5.Cu")
		(net "PCIE_TX_CAP_P94")
	)
	(arc
		(start 227.632006 -30.898084)
		(mid 227.730945 -30.964193)
		(end 227.847652 -30.987492)
		(width 0.1016)
		(layer "In5.Cu")
		(net "PCIE_TX_CAP_P94")
	)
	(arc
		(start 183.189626 -24.36622)
		(mid 183.338924 -24.266555)
		(end 183.515 -24.2316)
		(width 0.1397)
		(layer "In5.Cu")
		(net "PCIE_TX_CAP_P94")
	)
	(arc
		(start 227.498656 -30.607254)
		(mid 227.527687 -30.752823)
		(end 227.610162 -30.87624)
		(width 0.1016)
		(layer "In5.Cu")
		(net "PCIE_TX_CAP_P94")
	)
	(arc
		(start 183.7436 -24.2316)
		(mid 183.878419 -24.21935)
		(end 184.008776 -24.182832)
		(width 0.1397)
		(layer "In5.Cu")
		(net "PCIE_TX_CAP_P94")
	)
	(segment
		(start 227.600002 -30.999938)
		(end 227.10013 -30.500066)
		(width 0.136652)
		(layer "F.Cu")
		(net "PCIE_TX_CAP_P93")
	)
	(segment
		(start 182.95874 -26.63444)
		(end 183.0832 -26.7589)
		(width 0.136652)
		(layer "F.Cu")
		(net "PCIE_TX_CAP_P93")
	)
	(segment
		(start 182.4736 -26.5049)
		(end 182.646066 -26.5049)
		(width 0.136652)
		(layer "F.Cu")
		(net "PCIE_TX_CAP_P93")
	)
	(segment
		(start 182.0545 -26.797)
		(end 182.256938 -26.594816)
		(width 0.136652)
		(layer "F.Cu")
		(net "PCIE_TX_CAP_P93")
	)
	(via
		(at 227.10013 -30.500066)
		(size 0.4572)
		(drill 0.2032)
		(layers "F.Cu" "B.Cu")
		(net "PCIE_TX_CAP_P93")
	)
	(via
		(at 183.0832 -26.7589)
		(size 0.508)
		(drill 0.254)
		(layers "F.Cu" "B.Cu")
		(net "PCIE_TX_CAP_P93")
	)
	(arc
		(start 182.256938 -26.594816)
		(mid 182.356328 -26.528313)
		(end 182.4736 -26.5049)
		(width 0.136652)
		(layer "F.Cu")
		(net "PCIE_TX_CAP_P93")
	)
	(arc
		(start 182.646066 -26.5049)
		(mid 182.815294 -26.538562)
		(end 182.95874 -26.63444)
		(width 0.136652)
		(layer "F.Cu")
		(net "PCIE_TX_CAP_P93")
	)
	(segment
		(start 224.74682 -26.37282)
		(end 225.79838 -27.108912)
		(width 0.1397)
		(layer "In5.Cu")
		(net "PCIE_TX_CAP_P93")
	)
	(segment
		(start 226.614228 -29.90342)
		(end 226.614736 -29.903928)
		(width 0.1016)
		(layer "In5.Cu")
		(net "PCIE_TX_CAP_P93")
	)
	(segment
		(start 227.10013 -30.139894)
		(end 227.10013 -30.500066)
		(width 0.1016)
		(layer "In5.Cu")
		(net "PCIE_TX_CAP_P93")
	)
	(segment
		(start 215.117426 -25.397206)
		(end 218.497404 -26.073608)
		(width 0.1397)
		(layer "In5.Cu")
		(net "PCIE_TX_CAP_P93")
	)
	(segment
		(start 226.428554 -28.93187)
		(end 226.428554 -28.95727)
		(width 0.1016)
		(layer "In5.Cu")
		(net "PCIE_TX_CAP_P93")
	)
	(segment
		(start 227.064062 -30.061662)
		(end 227.070412 -30.068012)
		(width 0.1016)
		(layer "In5.Cu")
		(net "PCIE_TX_CAP_P93")
	)
	(segment
		(start 221.896178 -25.394412)
		(end 222.872808 -25.222454)
		(width 0.1397)
		(layer "In5.Cu")
		(net "PCIE_TX_CAP_P93")
	)
	(segment
		(start 218.497404 -26.073608)
		(end 221.896178 -25.394412)
		(width 0.1397)
		(layer "In5.Cu")
		(net "PCIE_TX_CAP_P93")
	)
	(segment
		(start 196.864224 -24.7396)
		(end 207.539844 -27.008582)
		(width 0.1397)
		(layer "In5.Cu")
		(net "PCIE_TX_CAP_P93")
	)
	(segment
		(start 207.539844 -27.008582)
		(end 215.117426 -25.397206)
		(width 0.1397)
		(layer "In5.Cu")
		(net "PCIE_TX_CAP_P93")
	)
	(segment
		(start 188.111638 -24.134572)
		(end 189.412626 -24.979884)
		(width 0.1397)
		(layer "In5.Cu")
		(net "PCIE_TX_CAP_P93")
	)
	(segment
		(start 183.383936 -26.5176)
		(end 184.2008 -26.5176)
		(width 0.1397)
		(layer "In5.Cu")
		(net "PCIE_TX_CAP_P93")
	)
	(segment
		(start 186.849766 -23.866348)
		(end 188.111638 -24.134572)
		(width 0.1397)
		(layer "In5.Cu")
		(net "PCIE_TX_CAP_P93")
	)
	(segment
		(start 226.428554 -28.95727)
		(end 226.492054 -29.02077)
		(width 0.1016)
		(layer "In5.Cu")
		(net "PCIE_TX_CAP_P93")
	)
	(segment
		(start 225.79838 -27.108912)
		(end 226.428554 -28.022042)
		(width 0.1397)
		(layer "In5.Cu")
		(net "PCIE_TX_CAP_P93")
	)
	(segment
		(start 189.412626 -24.979884)
		(end 192.573148 -25.651714)
		(width 0.1397)
		(layer "In5.Cu")
		(net "PCIE_TX_CAP_P93")
	)
	(segment
		(start 226.428554 -28.022042)
		(end 226.428554 -28.93187)
		(width 0.1397)
		(layer "In5.Cu")
		(net "PCIE_TX_CAP_P93")
	)
	(segment
		(start 222.872808 -25.222454)
		(end 223.751394 -25.377394)
		(width 0.1397)
		(layer "In5.Cu")
		(net "PCIE_TX_CAP_P93")
	)
	(segment
		(start 185.405522 -24.578818)
		(end 186.849766 -23.866348)
		(width 0.1397)
		(layer "In5.Cu")
		(net "PCIE_TX_CAP_P93")
	)
	(segment
		(start 192.573148 -25.651714)
		(end 196.864224 -24.7396)
		(width 0.1397)
		(layer "In5.Cu")
		(net "PCIE_TX_CAP_P93")
	)
	(segment
		(start 184.85485 -25.94229)
		(end 185.405522 -24.578818)
		(width 0.1397)
		(layer "In5.Cu")
		(net "PCIE_TX_CAP_P93")
	)
	(segment
		(start 223.751394 -25.377394)
		(end 224.74682 -26.37282)
		(width 0.1397)
		(layer "In5.Cu")
		(net "PCIE_TX_CAP_P93")
	)
	(segment
		(start 226.492054 -29.02077)
		(end 226.492054 -29.608272)
		(width 0.1016)
		(layer "In5.Cu")
		(net "PCIE_TX_CAP_P93")
	)
	(segment
		(start 226.908868 -30.025594)
		(end 226.97694 -30.025594)
		(width 0.1016)
		(layer "In5.Cu")
		(net "PCIE_TX_CAP_P93")
	)
	(segment
		(start 184.2008 -26.5176)
		(end 184.85485 -25.94229)
		(width 0.1397)
		(layer "In5.Cu")
		(net "PCIE_TX_CAP_P93")
	)
	(arc
		(start 226.614736 -29.903928)
		(mid 226.749714 -29.993961)
		(end 226.908868 -30.025594)
		(width 0.1016)
		(layer "In5.Cu")
		(net "PCIE_TX_CAP_P93")
	)
	(arc
		(start 227.070412 -30.068012)
		(mid 227.092395 -30.101006)
		(end 227.10013 -30.139894)
		(width 0.1016)
		(layer "In5.Cu")
		(net "PCIE_TX_CAP_P93")
	)
	(arc
		(start 226.492054 -29.608272)
		(mid 226.523738 -29.768028)
		(end 226.614228 -29.90342)
		(width 0.1016)
		(layer "In5.Cu")
		(net "PCIE_TX_CAP_P93")
	)
	(arc
		(start 226.97694 -30.025594)
		(mid 227.024083 -30.034971)
		(end 227.064062 -30.061662)
		(width 0.1016)
		(layer "In5.Cu")
		(net "PCIE_TX_CAP_P93")
	)
	(arc
		(start 183.0832 -26.7589)
		(mid 183.19116 -26.585406)
		(end 183.383936 -26.5176)
		(width 0.1397)
		(layer "In5.Cu")
		(net "PCIE_TX_CAP_P93")
	)
	(segment
		(start 185.81243 -25.569164)
		(end 185.358786 -25.569164)
		(width 0.136652)
		(layer "F.Cu")
		(net "PCIE_TX_CAP_P92")
	)
	(segment
		(start 226.600004 -31.999936)
		(end 226.100132 -31.500064)
		(width 0.136652)
		(layer "F.Cu")
		(net "PCIE_TX_CAP_P92")
	)
	(segment
		(start 183.210454 -22.1996)
		(end 182.7276 -22.1996)
		(width 0.136652)
		(layer "F.Cu")
		(net "PCIE_TX_CAP_P92")
	)
	(segment
		(start 184.39003 -23.175976)
		(end 183.557926 -22.343872)
		(width 0.136652)
		(layer "F.Cu")
		(net "PCIE_TX_CAP_P92")
	)
	(segment
		(start 184.566814 -24.809958)
		(end 184.566814 -23.602188)
		(width 0.136652)
		(layer "F.Cu")
		(net "PCIE_TX_CAP_P92")
	)
	(segment
		(start 184.957974 -25.403302)
		(end 184.709562 -25.15489)
		(width 0.136652)
		(layer "F.Cu")
		(net "PCIE_TX_CAP_P92")
	)
	(via
		(at 226.100132 -31.500064)
		(size 0.4572)
		(drill 0.2032)
		(layers "F.Cu" "B.Cu")
		(net "PCIE_TX_CAP_P92")
	)
	(via
		(at 186.055 -25.811734)
		(size 0.508)
		(drill 0.254)
		(layers "F.Cu" "B.Cu")
		(net "PCIE_TX_CAP_P92")
	)
	(arc
		(start 184.566814 -23.602188)
		(mid 184.520816 -23.371499)
		(end 184.39003 -23.175976)
		(width 0.136652)
		(layer "F.Cu")
		(net "PCIE_TX_CAP_P92")
	)
	(arc
		(start 184.709562 -25.15489)
		(mid 184.603902 -24.996619)
		(end 184.566814 -24.809958)
		(width 0.136652)
		(layer "F.Cu")
		(net "PCIE_TX_CAP_P92")
	)
	(arc
		(start 186.055 -25.811734)
		(mid 185.983953 -25.640211)
		(end 185.81243 -25.569164)
		(width 0.136652)
		(layer "F.Cu")
		(net "PCIE_TX_CAP_P92")
	)
	(arc
		(start 185.358786 -25.569164)
		(mid 185.141901 -25.526059)
		(end 184.957974 -25.403302)
		(width 0.136652)
		(layer "F.Cu")
		(net "PCIE_TX_CAP_P92")
	)
	(arc
		(start 182.7276 -22.1996)
		(mid 182.363208 -22.272225)
		(end 182.0545 -22.479)
		(width 0.136652)
		(layer "F.Cu")
		(net "PCIE_TX_CAP_P92")
	)
	(arc
		(start 183.557926 -22.343872)
		(mid 183.398535 -22.237184)
		(end 183.210454 -22.1996)
		(width 0.136652)
		(layer "F.Cu")
		(net "PCIE_TX_CAP_P92")
	)
	(segment
		(start 205.327504 -28.78074)
		(end 196.702426 -26.01849)
		(width 0.1397)
		(layer "In5.Cu")
		(net "PCIE_TX_CAP_P92")
	)
	(segment
		(start 189.775084 -26.752042)
		(end 187.658756 -25.552654)
		(width 0.1397)
		(layer "In5.Cu")
		(net "PCIE_TX_CAP_P92")
	)
	(segment
		(start 221.979236 -26.5176)
		(end 218.342972 -27.244802)
		(width 0.1397)
		(layer "In5.Cu")
		(net "PCIE_TX_CAP_P92")
	)
	(segment
		(start 223.400874 -26.5176)
		(end 221.979236 -26.5176)
		(width 0.1397)
		(layer "In5.Cu")
		(net "PCIE_TX_CAP_P92")
	)
	(segment
		(start 225.922078 -30.987492)
		(end 225.847656 -30.987492)
		(width 0.1016)
		(layer "In5.Cu")
		(net "PCIE_TX_CAP_P92")
	)
	(segment
		(start 192.05956 -27.162506)
		(end 189.775084 -26.752042)
		(width 0.1397)
		(layer "In5.Cu")
		(net "PCIE_TX_CAP_P92")
	)
	(segment
		(start 225.43516 -28.29941)
		(end 225.417888 -28.202636)
		(width 0.1397)
		(layer "In5.Cu")
		(net "PCIE_TX_CAP_P92")
	)
	(segment
		(start 225.49866 -30.6324)
		(end 225.49866 -29.2735)
		(width 0.1016)
		(layer "In5.Cu")
		(net "PCIE_TX_CAP_P92")
	)
	(segment
		(start 215.675718 -26.711402)
		(end 205.327504 -28.78074)
		(width 0.1397)
		(layer "In5.Cu")
		(net "PCIE_TX_CAP_P92")
	)
	(segment
		(start 194.380866 -26.590498)
		(end 194.380358 -26.590752)
		(width 0.1397)
		(layer "In5.Cu")
		(net "PCIE_TX_CAP_P92")
	)
	(segment
		(start 225.49866 -29.2735)
		(end 225.43516 -29.21)
		(width 0.1016)
		(layer "In5.Cu")
		(net "PCIE_TX_CAP_P92")
	)
	(segment
		(start 225.043746 -27.66822)
		(end 223.400874 -26.5176)
		(width 0.1397)
		(layer "In5.Cu")
		(net "PCIE_TX_CAP_P92")
	)
	(segment
		(start 187.658756 -25.552654)
		(end 186.450732 -25.552654)
		(width 0.1397)
		(layer "In5.Cu")
		(net "PCIE_TX_CAP_P92")
	)
	(segment
		(start 218.342972 -27.244802)
		(end 215.675718 -26.711402)
		(width 0.1397)
		(layer "In5.Cu")
		(net "PCIE_TX_CAP_P92")
	)
	(segment
		(start 225.43516 -29.1846)
		(end 225.43516 -28.29941)
		(width 0.1397)
		(layer "In5.Cu")
		(net "PCIE_TX_CAP_P92")
	)
	(segment
		(start 194.380358 -26.590752)
		(end 192.05956 -27.162506)
		(width 0.1397)
		(layer "In5.Cu")
		(net "PCIE_TX_CAP_P92")
	)
	(segment
		(start 225.43516 -29.21)
		(end 225.43516 -29.1846)
		(width 0.1016)
		(layer "In5.Cu")
		(net "PCIE_TX_CAP_P92")
	)
	(segment
		(start 226.100132 -31.500064)
		(end 226.100132 -31.204662)
		(width 0.1016)
		(layer "In5.Cu")
		(net "PCIE_TX_CAP_P92")
	)
	(segment
		(start 225.417888 -28.202636)
		(end 225.043746 -27.66822)
		(width 0.1397)
		(layer "In5.Cu")
		(net "PCIE_TX_CAP_P92")
	)
	(segment
		(start 196.702426 -26.01849)
		(end 194.380866 -26.590498)
		(width 0.1397)
		(layer "In5.Cu")
		(net "PCIE_TX_CAP_P92")
	)
	(arc
		(start 226.100132 -31.204662)
		(mid 226.04993 -31.064241)
		(end 225.922078 -30.987492)
		(width 0.1016)
		(layer "In5.Cu")
		(net "PCIE_TX_CAP_P92")
	)
	(arc
		(start 186.450732 -25.552654)
		(mid 186.214229 -25.623182)
		(end 186.055 -25.811734)
		(width 0.1397)
		(layer "In5.Cu")
		(net "PCIE_TX_CAP_P92")
	)
	(arc
		(start 225.847656 -30.987492)
		(mid 225.705826 -30.956199)
		(end 225.590354 -30.868112)
		(width 0.1016)
		(layer "In5.Cu")
		(net "PCIE_TX_CAP_P92")
	)
	(arc
		(start 225.590354 -30.868112)
		(mid 225.524398 -30.758086)
		(end 225.49866 -30.6324)
		(width 0.1016)
		(layer "In5.Cu")
		(net "PCIE_TX_CAP_P92")
	)
	(segment
		(start 225.600006 -30.999938)
		(end 225.100134 -30.500066)
		(width 0.136652)
		(layer "F.Cu")
		(net "PCIE_TX_CAP_P91")
	)
	(segment
		(start 182.0545 -29.845)
		(end 182.256938 -29.642816)
		(width 0.136652)
		(layer "F.Cu")
		(net "PCIE_TX_CAP_P91")
	)
	(segment
		(start 182.962804 -29.686504)
		(end 183.0832 -29.8069)
		(width 0.136652)
		(layer "F.Cu")
		(net "PCIE_TX_CAP_P91")
	)
	(segment
		(start 182.4736 -29.5529)
		(end 182.640224 -29.5529)
		(width 0.136652)
		(layer "F.Cu")
		(net "PCIE_TX_CAP_P91")
	)
	(via
		(at 183.0832 -29.8069)
		(size 0.508)
		(drill 0.254)
		(layers "F.Cu" "B.Cu")
		(net "PCIE_TX_CAP_P91")
	)
	(via
		(at 225.100134 -30.500066)
		(size 0.4572)
		(drill 0.2032)
		(layers "F.Cu" "B.Cu")
		(net "PCIE_TX_CAP_P91")
	)
	(arc
		(start 182.640224 -29.5529)
		(mid 182.814798 -29.587625)
		(end 182.962804 -29.686504)
		(width 0.136652)
		(layer "F.Cu")
		(net "PCIE_TX_CAP_P91")
	)
	(arc
		(start 182.256938 -29.642816)
		(mid 182.356328 -29.576313)
		(end 182.4736 -29.5529)
		(width 0.136652)
		(layer "F.Cu")
		(net "PCIE_TX_CAP_P91")
	)
	(segment
		(start 183.488076 -29.5656)
		(end 184.277762 -29.5656)
		(width 0.1397)
		(layer "In5.Cu")
		(net "PCIE_TX_CAP_P91")
	)
	(segment
		(start 215.664288 -27.773884)
		(end 217.000074 -28.041092)
		(width 0.1397)
		(layer "In5.Cu")
		(net "PCIE_TX_CAP_P91")
	)
	(segment
		(start 224.40519 -29.856176)
		(end 224.862644 -30.31363)
		(width 0.1397)
		(layer "In5.Cu")
		(net "PCIE_TX_CAP_P91")
	)
	(segment
		(start 187.399168 -29.9339)
		(end 191.645032 -29.185108)
		(width 0.1397)
		(layer "In5.Cu")
		(net "PCIE_TX_CAP_P91")
	)
	(segment
		(start 184.792874 -29.474668)
		(end 187.399168 -29.9339)
		(width 0.1397)
		(layer "In5.Cu")
		(net "PCIE_TX_CAP_P91")
	)
	(segment
		(start 218.4654 -28.334208)
		(end 222.087948 -27.6098)
		(width 0.1397)
		(layer "In5.Cu")
		(net "PCIE_TX_CAP_P91")
	)
	(segment
		(start 222.087948 -27.6098)
		(end 223.012508 -27.6098)
		(width 0.1397)
		(layer "In5.Cu")
		(net "PCIE_TX_CAP_P91")
	)
	(segment
		(start 194.10426 -27.84221)
		(end 194.460114 -27.744928)
		(width 0.1397)
		(layer "In5.Cu")
		(net "PCIE_TX_CAP_P91")
	)
	(segment
		(start 197.21195 -28.33624)
		(end 198.828152 -27.806396)
		(width 0.1397)
		(layer "In5.Cu")
		(net "PCIE_TX_CAP_P91")
	)
	(segment
		(start 223.602296 -27.854148)
		(end 224.09023 -28.342336)
		(width 0.1397)
		(layer "In5.Cu")
		(net "PCIE_TX_CAP_P91")
	)
	(segment
		(start 205.225904 -29.861764)
		(end 215.664288 -27.773884)
		(width 0.1397)
		(layer "In5.Cu")
		(net "PCIE_TX_CAP_P91")
	)
	(segment
		(start 224.30232 -28.8544)
		(end 224.30232 -29.53131)
		(width 0.1397)
		(layer "In5.Cu")
		(net "PCIE_TX_CAP_P91")
	)
	(segment
		(start 224.862644 -30.31363)
		(end 225.100134 -30.500066)
		(width 0.1397)
		(layer "In5.Cu")
		(net "PCIE_TX_CAP_P91")
	)
	(segment
		(start 191.645032 -29.185108)
		(end 194.10426 -27.84221)
		(width 0.1397)
		(layer "In5.Cu")
		(net "PCIE_TX_CAP_P91")
	)
	(segment
		(start 194.815714 -27.6479)
		(end 197.21195 -28.33624)
		(width 0.1397)
		(layer "In5.Cu")
		(net "PCIE_TX_CAP_P91")
	)
	(segment
		(start 194.460114 -27.744928)
		(end 194.815714 -27.6479)
		(width 0.1397)
		(layer "In5.Cu")
		(net "PCIE_TX_CAP_P91")
	)
	(segment
		(start 198.828152 -27.806396)
		(end 205.225904 -29.861764)
		(width 0.1397)
		(layer "In5.Cu")
		(net "PCIE_TX_CAP_P91")
	)
	(segment
		(start 184.277762 -29.5656)
		(end 184.792874 -29.474668)
		(width 0.1397)
		(layer "In5.Cu")
		(net "PCIE_TX_CAP_P91")
	)
	(segment
		(start 217.000074 -28.041092)
		(end 218.4654 -28.334208)
		(width 0.1397)
		(layer "In5.Cu")
		(net "PCIE_TX_CAP_P91")
	)
	(arc
		(start 224.27819 -28.668726)
		(mid 224.296286 -28.76078)
		(end 224.30232 -28.8544)
		(width 0.1397)
		(layer "In5.Cu")
		(net "PCIE_TX_CAP_P91")
	)
	(arc
		(start 223.012508 -27.6098)
		(mid 223.331718 -27.673295)
		(end 223.602296 -27.854148)
		(width 0.1397)
		(layer "In5.Cu")
		(net "PCIE_TX_CAP_P91")
	)
	(arc
		(start 224.30232 -29.53131)
		(mid 224.328663 -29.701685)
		(end 224.40519 -29.856176)
		(width 0.1397)
		(layer "In5.Cu")
		(net "PCIE_TX_CAP_P91")
	)
	(arc
		(start 224.09023 -28.342336)
		(mid 224.205771 -28.49311)
		(end 224.27819 -28.668726)
		(width 0.1397)
		(layer "In5.Cu")
		(net "PCIE_TX_CAP_P91")
	)
	(arc
		(start 183.0832 -29.8069)
		(mid 183.252402 -29.630474)
		(end 183.488076 -29.5656)
		(width 0.1397)
		(layer "In5.Cu")
		(net "PCIE_TX_CAP_P91")
	)
	(segment
		(start 224.600008 -31.999936)
		(end 224.1042 -31.504128)
		(width 0.136652)
		(layer "F.Cu")
		(net "PCIE_TX_CAP_P90")
	)
	(segment
		(start 161.49828 -34.43224)
		(end 161.49828 -34.60496)
		(width 0.136652)
		(layer "F.Cu")
		(net "PCIE_TX_CAP_P90")
	)
	(via
		(at 161.2773 -35.02152)
		(size 0.508)
		(drill 0.254)
		(layers "F.Cu" "B.Cu")
		(net "PCIE_TX_CAP_P90")
	)
	(via
		(at 224.1042 -31.504128)
		(size 0.4572)
		(drill 0.2032)
		(layers "F.Cu" "B.Cu")
		(net "PCIE_TX_CAP_P90")
	)
	(arc
		(start 161.163 -33.9725)
		(mid 161.405551 -34.147737)
		(end 161.49828 -34.43224)
		(width 0.136652)
		(layer "F.Cu")
		(net "PCIE_TX_CAP_P90")
	)
	(arc
		(start 161.49828 -34.60496)
		(mid 161.43962 -34.840739)
		(end 161.2773 -35.02152)
		(width 0.136652)
		(layer "F.Cu")
		(net "PCIE_TX_CAP_P90")
	)
	(segment
		(start 223.178878 -28.5877)
		(end 222.184976 -28.5877)
		(width 0.1397)
		(layer "In5.Cu")
		(net "PCIE_TX_CAP_P90")
	)
	(segment
		(start 187.474606 -30.95625)
		(end 186.172602 -30.726634)
		(width 0.1397)
		(layer "In5.Cu")
		(net "PCIE_TX_CAP_P90")
	)
	(segment
		(start 173.505368 -31.603442)
		(end 168.234868 -35.031172)
		(width 0.1397)
		(layer "In5.Cu")
		(net "PCIE_TX_CAP_P90")
	)
	(segment
		(start 200.42759 -29.917898)
		(end 198.7296 -30.3784)
		(width 0.1397)
		(layer "In5.Cu")
		(net "PCIE_TX_CAP_P90")
	)
	(segment
		(start 194.618864 -29.696918)
		(end 191.103504 -30.316678)
		(width 0.1397)
		(layer "In5.Cu")
		(net "PCIE_TX_CAP_P90")
	)
	(segment
		(start 223.432878 -28.9814)
		(end 223.432878 -28.8417)
		(width 0.1397)
		(layer "In5.Cu")
		(net "PCIE_TX_CAP_P90")
	)
	(segment
		(start 186.172602 -30.726634)
		(end 185.730642 -30.804358)
		(width 0.1397)
		(layer "In5.Cu")
		(net "PCIE_TX_CAP_P90")
	)
	(segment
		(start 198.7296 -30.3784)
		(end 195.833238 -29.899356)
		(width 0.1397)
		(layer "In5.Cu")
		(net "PCIE_TX_CAP_P90")
	)
	(segment
		(start 222.184976 -28.5877)
		(end 218.4654 -29.331666)
		(width 0.1397)
		(layer "In5.Cu")
		(net "PCIE_TX_CAP_P90")
	)
	(segment
		(start 161.5186 -35.527234)
		(end 161.5186 -35.387534)
		(width 0.1397)
		(layer "In5.Cu")
		(net "PCIE_TX_CAP_P90")
	)
	(segment
		(start 216.08415 -28.85567)
		(end 215.2904 -28.696666)
		(width 0.1397)
		(layer "In5.Cu")
		(net "PCIE_TX_CAP_P90")
	)
	(segment
		(start 185.730388 -30.804612)
		(end 183.166512 -31.256732)
		(width 0.1397)
		(layer "In5.Cu")
		(net "PCIE_TX_CAP_P90")
	)
	(segment
		(start 188.416692 -30.790388)
		(end 187.474606 -30.95625)
		(width 0.1397)
		(layer "In5.Cu")
		(net "PCIE_TX_CAP_P90")
	)
	(segment
		(start 183.166512 -31.256732)
		(end 179.319428 -30.578552)
		(width 0.1397)
		(layer "In5.Cu")
		(net "PCIE_TX_CAP_P90")
	)
	(segment
		(start 223.458786 -29.007308)
		(end 223.432878 -28.9814)
		(width 0.1016)
		(layer "In5.Cu")
		(net "PCIE_TX_CAP_P90")
	)
	(segment
		(start 203.786994 -30.997652)
		(end 200.42759 -29.917898)
		(width 0.1397)
		(layer "In5.Cu")
		(net "PCIE_TX_CAP_P90")
	)
	(segment
		(start 185.730642 -30.804358)
		(end 185.730388 -30.804612)
		(width 0.1397)
		(layer "In5.Cu")
		(net "PCIE_TX_CAP_P90")
	)
	(segment
		(start 161.430462 -35.174682)
		(end 161.2773 -35.02152)
		(width 0.1397)
		(layer "In5.Cu")
		(net "PCIE_TX_CAP_P90")
	)
	(segment
		(start 195.833238 -29.899356)
		(end 194.618864 -29.696918)
		(width 0.1397)
		(layer "In5.Cu")
		(net "PCIE_TX_CAP_P90")
	)
	(segment
		(start 162.869118 -36.308284)
		(end 162.29965 -36.308284)
		(width 0.1397)
		(layer "In5.Cu")
		(net "PCIE_TX_CAP_P90")
	)
	(segment
		(start 223.502728 -30.636464)
		(end 223.502728 -29.11348)
		(width 0.1016)
		(layer "In5.Cu")
		(net "PCIE_TX_CAP_P90")
	)
	(segment
		(start 218.4654 -29.331666)
		(end 216.08415 -28.85567)
		(width 0.1397)
		(layer "In5.Cu")
		(net "PCIE_TX_CAP_P90")
	)
	(segment
		(start 168.234868 -35.031172)
		(end 164.05987 -35.767518)
		(width 0.1397)
		(layer "In5.Cu")
		(net "PCIE_TX_CAP_P90")
	)
	(segment
		(start 215.2904 -28.696666)
		(end 203.786994 -30.997652)
		(width 0.1397)
		(layer "In5.Cu")
		(net "PCIE_TX_CAP_P90")
	)
	(segment
		(start 179.319428 -30.578552)
		(end 173.505368 -31.603442)
		(width 0.1397)
		(layer "In5.Cu")
		(net "PCIE_TX_CAP_P90")
	)
	(segment
		(start 223.432878 -28.8417)
		(end 223.178878 -28.5877)
		(width 0.1397)
		(layer "In5.Cu")
		(net "PCIE_TX_CAP_P90")
	)
	(segment
		(start 191.103504 -30.316678)
		(end 188.416692 -30.790388)
		(width 0.1397)
		(layer "In5.Cu")
		(net "PCIE_TX_CAP_P90")
	)
	(arc
		(start 223.778826 -30.983682)
		(mid 223.677502 -30.94303)
		(end 223.594422 -30.872176)
		(width 0.1016)
		(layer "In5.Cu")
		(net "PCIE_TX_CAP_P90")
	)
	(arc
		(start 223.986852 -31.084266)
		(mid 223.888698 -31.021855)
		(end 223.778826 -30.983682)
		(width 0.1016)
		(layer "In5.Cu")
		(net "PCIE_TX_CAP_P90")
	)
	(arc
		(start 162.29965 -36.308284)
		(mid 161.747364 -36.07952)
		(end 161.5186 -35.527234)
		(width 0.1397)
		(layer "In5.Cu")
		(net "PCIE_TX_CAP_P90")
	)
	(arc
		(start 223.594422 -30.872176)
		(mid 223.528466 -30.76215)
		(end 223.502728 -30.636464)
		(width 0.1016)
		(layer "In5.Cu")
		(net "PCIE_TX_CAP_P90")
	)
	(arc
		(start 164.05987 -35.767518)
		(mid 163.818809 -35.849322)
		(end 163.613592 -35.999928)
		(width 0.1397)
		(layer "In5.Cu")
		(net "PCIE_TX_CAP_P90")
	)
	(arc
		(start 223.502728 -29.11348)
		(mid 223.491301 -29.056034)
		(end 223.458786 -29.007308)
		(width 0.1016)
		(layer "In5.Cu")
		(net "PCIE_TX_CAP_P90")
	)
	(arc
		(start 224.1042 -31.504128)
		(mid 224.07431 -31.286152)
		(end 223.986852 -31.084266)
		(width 0.1016)
		(layer "In5.Cu")
		(net "PCIE_TX_CAP_P90")
	)
	(arc
		(start 161.5186 -35.387534)
		(mid 161.495689 -35.27235)
		(end 161.430462 -35.174682)
		(width 0.1397)
		(layer "In5.Cu")
		(net "PCIE_TX_CAP_P90")
	)
	(arc
		(start 163.613592 -35.999928)
		(mid 163.272024 -36.228156)
		(end 162.869118 -36.308284)
		(width 0.1397)
		(layer "In5.Cu")
		(net "PCIE_TX_CAP_P90")
	)
	(segment
		(start 310.575452 -34.892234)
		(end 310.425592 -35.04184)
		(width 0.136652)
		(layer "F.Cu")
		(net "PCIE_TX_CAP_P9")
	)
	(segment
		(start 310.374792 -34.000186)
		(end 310.584596 -34.209736)
		(width 0.136652)
		(layer "F.Cu")
		(net "PCIE_TX_CAP_P9")
	)
	(segment
		(start 256.599944 -34.99993)
		(end 257.099816 -34.500058)
		(width 0.136652)
		(layer "F.Cu")
		(net "PCIE_TX_CAP_P9")
	)
	(segment
		(start 310.692292 -34.470086)
		(end 310.692292 -34.609786)
		(width 0.136652)
		(layer "F.Cu")
		(net "PCIE_TX_CAP_P9")
	)
	(via
		(at 310.425592 -35.04184)
		(size 0.508)
		(drill 0.254)
		(layers "F.Cu" "B.Cu")
		(net "PCIE_TX_CAP_P9")
	)
	(via
		(at 257.099816 -34.500058)
		(size 0.4572)
		(drill 0.2032)
		(layers "F.Cu" "B.Cu")
		(net "PCIE_TX_CAP_P9")
	)
	(arc
		(start 310.584596 -34.209736)
		(mid 310.664327 -34.329201)
		(end 310.692292 -34.470086)
		(width 0.136652)
		(layer "F.Cu")
		(net "PCIE_TX_CAP_P9")
	)
	(arc
		(start 310.692292 -34.609786)
		(mid 310.661981 -34.762641)
		(end 310.575452 -34.892234)
		(width 0.136652)
		(layer "F.Cu")
		(net "PCIE_TX_CAP_P9")
	)
	(segment
		(start 307.13553 -41.459658)
		(end 306.805838 -41.661334)
		(width 0.1397)
		(layer "In5.Cu")
		(net "PCIE_TX_CAP_P9")
	)
	(segment
		(start 276.654006 -36.470844)
		(end 272.736818 -33.727898)
		(width 0.1397)
		(layer "In5.Cu")
		(net "PCIE_TX_CAP_P9")
	)
	(segment
		(start 296.012616 -43.82008)
		(end 291.90315 -42.998136)
		(width 0.1397)
		(layer "In5.Cu")
		(net "PCIE_TX_CAP_P9")
	)
	(segment
		(start 307.69052 -40.733218)
		(end 307.13553 -41.459658)
		(width 0.1397)
		(layer "In5.Cu")
		(net "PCIE_TX_CAP_P9")
	)
	(segment
		(start 291.248084 -43.1292)
		(end 282.245054 -41.328594)
		(width 0.1397)
		(layer "In5.Cu")
		(net "PCIE_TX_CAP_P9")
	)
	(segment
		(start 259.4864 -33.901888)
		(end 259.284216 -33.901888)
		(width 0.1016)
		(layer "In5.Cu")
		(net "PCIE_TX_CAP_P9")
	)
	(segment
		(start 310.6674 -36.009326)
		(end 310.667146 -36.00958)
		(width 0.1397)
		(layer "In5.Cu")
		(net "PCIE_TX_CAP_P9")
	)
	(segment
		(start 259.283962 -33.901634)
		(end 257.902202 -33.901634)
		(width 0.1016)
		(layer "In5.Cu")
		(net "PCIE_TX_CAP_P9")
	)
	(segment
		(start 261.99465 -33.901888)
		(end 259.4864 -33.901888)
		(width 0.1397)
		(layer "In5.Cu")
		(net "PCIE_TX_CAP_P9")
	)
	(segment
		(start 267.858494 -32.867854)
		(end 261.99465 -33.901888)
		(width 0.1397)
		(layer "In5.Cu")
		(net "PCIE_TX_CAP_P9")
	)
	(segment
		(start 306.805838 -41.661334)
		(end 296.012616 -43.82008)
		(width 0.1397)
		(layer "In5.Cu")
		(net "PCIE_TX_CAP_P9")
	)
	(segment
		(start 277.949152 -38.320472)
		(end 276.654006 -36.470844)
		(width 0.1397)
		(layer "In5.Cu")
		(net "PCIE_TX_CAP_P9")
	)
	(segment
		(start 310.585104 -36.474146)
		(end 309.438548 -38.11143)
		(width 0.1397)
		(layer "In5.Cu")
		(net "PCIE_TX_CAP_P9")
	)
	(segment
		(start 310.6674 -35.625532)
		(end 310.6674 -36.009326)
		(width 0.1397)
		(layer "In5.Cu")
		(net "PCIE_TX_CAP_P9")
	)
	(segment
		(start 282.245054 -41.328594)
		(end 277.949152 -38.320472)
		(width 0.1397)
		(layer "In5.Cu")
		(net "PCIE_TX_CAP_P9")
	)
	(segment
		(start 308.237636 -38.952424)
		(end 307.69052 -40.733218)
		(width 0.1397)
		(layer "In5.Cu")
		(net "PCIE_TX_CAP_P9")
	)
	(segment
		(start 309.438548 -38.11143)
		(end 308.237636 -38.952424)
		(width 0.1397)
		(layer "In5.Cu")
		(net "PCIE_TX_CAP_P9")
	)
	(segment
		(start 291.90315 -42.998136)
		(end 291.248084 -43.1292)
		(width 0.1397)
		(layer "In5.Cu")
		(net "PCIE_TX_CAP_P9")
	)
	(segment
		(start 257.553968 -34.045906)
		(end 257.099816 -34.500058)
		(width 0.1016)
		(layer "In5.Cu")
		(net "PCIE_TX_CAP_P9")
	)
	(segment
		(start 310.667146 -36.00958)
		(end 310.585104 -36.474146)
		(width 0.1397)
		(layer "In5.Cu")
		(net "PCIE_TX_CAP_P9")
	)
	(segment
		(start 259.284216 -33.901888)
		(end 259.283962 -33.901634)
		(width 0.1016)
		(layer "In5.Cu")
		(net "PCIE_TX_CAP_P9")
	)
	(segment
		(start 272.736818 -33.727898)
		(end 267.858494 -32.867854)
		(width 0.1397)
		(layer "In5.Cu")
		(net "PCIE_TX_CAP_P9")
	)
	(arc
		(start 310.425592 -35.04184)
		(mid 310.60453 -35.30964)
		(end 310.6674 -35.625532)
		(width 0.1397)
		(layer "In5.Cu")
		(net "PCIE_TX_CAP_P9")
	)
	(arc
		(start 257.902202 -33.901634)
		(mid 257.713728 -33.939124)
		(end 257.553968 -34.045906)
		(width 0.1016)
		(layer "In5.Cu")
		(net "PCIE_TX_CAP_P9")
	)
	(segment
		(start 223.60001 -30.999938)
		(end 223.100138 -30.500066)
		(width 0.136652)
		(layer "F.Cu")
		(net "PCIE_TX_CAP_P89")
	)
	(segment
		(start 158.875984 -34.43224)
		(end 158.875984 -34.60496)
		(width 0.136652)
		(layer "F.Cu")
		(net "PCIE_TX_CAP_P89")
	)
	(via
		(at 158.655004 -35.02152)
		(size 0.508)
		(drill 0.254)
		(layers "F.Cu" "B.Cu")
		(net "PCIE_TX_CAP_P89")
	)
	(via
		(at 223.100138 -30.500066)
		(size 0.4572)
		(drill 0.2032)
		(layers "F.Cu" "B.Cu")
		(net "PCIE_TX_CAP_P89")
	)
	(arc
		(start 158.875984 -34.60496)
		(mid 158.817324 -34.840739)
		(end 158.655004 -35.02152)
		(width 0.136652)
		(layer "F.Cu")
		(net "PCIE_TX_CAP_P89")
	)
	(arc
		(start 158.540704 -33.9725)
		(mid 158.783255 -34.147737)
		(end 158.875984 -34.43224)
		(width 0.136652)
		(layer "F.Cu")
		(net "PCIE_TX_CAP_P89")
	)
	(segment
		(start 160.211516 -37.2872)
		(end 166.520622 -37.2872)
		(width 0.1397)
		(layer "In5.Cu")
		(net "PCIE_TX_CAP_P89")
	)
	(segment
		(start 158.896304 -35.387534)
		(end 158.896304 -35.823144)
		(width 0.1397)
		(layer "In5.Cu")
		(net "PCIE_TX_CAP_P89")
	)
	(segment
		(start 173.42739 -32.823658)
		(end 179.992782 -31.666434)
		(width 0.1397)
		(layer "In5.Cu")
		(net "PCIE_TX_CAP_P89")
	)
	(segment
		(start 158.655004 -35.02152)
		(end 158.808166 -35.174682)
		(width 0.1397)
		(layer "In5.Cu")
		(net "PCIE_TX_CAP_P89")
	)
	(segment
		(start 187.108338 -31.942786)
		(end 187.108338 -31.942532)
		(width 0.1397)
		(layer "In5.Cu")
		(net "PCIE_TX_CAP_P89")
	)
	(segment
		(start 221.4626 -30.16504)
		(end 221.488 -30.16504)
		(width 0.1016)
		(layer "In5.Cu")
		(net "PCIE_TX_CAP_P89")
	)
	(segment
		(start 216.457022 -31.750762)
		(end 217.411554 -31.91891)
		(width 0.1397)
		(layer "In5.Cu")
		(net "PCIE_TX_CAP_P89")
	)
	(segment
		(start 167.501062 -36.973256)
		(end 173.42739 -32.823658)
		(width 0.1397)
		(layer "In5.Cu")
		(net "PCIE_TX_CAP_P89")
	)
	(segment
		(start 185.061098 -31.781242)
		(end 185.23077 -31.751524)
		(width 0.1397)
		(layer "In5.Cu")
		(net "PCIE_TX_CAP_P89")
	)
	(segment
		(start 159.172402 -36.490402)
		(end 159.798258 -37.116258)
		(width 0.1397)
		(layer "In5.Cu")
		(net "PCIE_TX_CAP_P89")
	)
	(segment
		(start 187.108338 -31.942532)
		(end 190.914528 -31.270448)
		(width 0.1397)
		(layer "In5.Cu")
		(net "PCIE_TX_CAP_P89")
	)
	(segment
		(start 219.434918 -31.562548)
		(end 219.910406 -31.2293)
		(width 0.1397)
		(layer "In5.Cu")
		(net "PCIE_TX_CAP_P89")
	)
	(segment
		(start 179.992782 -31.666434)
		(end 179.992782 -31.66618)
		(width 0.1397)
		(layer "In5.Cu")
		(net "PCIE_TX_CAP_P89")
	)
	(segment
		(start 166.563294 -37.280596)
		(end 167.463724 -36.991544)
		(width 0.1397)
		(layer "In5.Cu")
		(net "PCIE_TX_CAP_P89")
	)
	(segment
		(start 190.914528 -31.270448)
		(end 194.721226 -30.597856)
		(width 0.1397)
		(layer "In5.Cu")
		(net "PCIE_TX_CAP_P89")
	)
	(segment
		(start 187.050934 -31.952692)
		(end 187.108338 -31.942786)
		(width 0.1397)
		(layer "In5.Cu")
		(net "PCIE_TX_CAP_P89")
	)
	(segment
		(start 198.831708 -31.327852)
		(end 200.23074 -30.964124)
		(width 0.1397)
		(layer "In5.Cu")
		(net "PCIE_TX_CAP_P89")
	)
	(segment
		(start 179.992782 -31.66618)
		(end 182.855362 -32.170116)
		(width 0.1397)
		(layer "In5.Cu")
		(net "PCIE_TX_CAP_P89")
	)
	(segment
		(start 221.596458 -30.10154)
		(end 222.998538 -30.10154)
		(width 0.1016)
		(layer "In5.Cu")
		(net "PCIE_TX_CAP_P89")
	)
	(segment
		(start 221.488 -30.16504)
		(end 221.51975 -30.13329)
		(width 0.1016)
		(layer "In5.Cu")
		(net "PCIE_TX_CAP_P89")
	)
	(segment
		(start 182.855362 -32.170116)
		(end 184.89168 -31.811214)
		(width 0.1397)
		(layer "In5.Cu")
		(net "PCIE_TX_CAP_P89")
	)
	(segment
		(start 215.559132 -31.59252)
		(end 216.457022 -31.750762)
		(width 0.1397)
		(layer "In5.Cu")
		(net "PCIE_TX_CAP_P89")
	)
	(segment
		(start 167.501062 -36.973002)
		(end 167.501062 -36.973256)
		(width 0.1397)
		(layer "In5.Cu")
		(net "PCIE_TX_CAP_P89")
	)
	(segment
		(start 200.23074 -30.964124)
		(end 203.70165 -32.023558)
		(width 0.1397)
		(layer "In5.Cu")
		(net "PCIE_TX_CAP_P89")
	)
	(segment
		(start 195.421758 -30.7213)
		(end 196.122798 -30.844998)
		(width 0.1397)
		(layer "In5.Cu")
		(net "PCIE_TX_CAP_P89")
	)
	(segment
		(start 196.122798 -30.844998)
		(end 198.831708 -31.327852)
		(width 0.1397)
		(layer "In5.Cu")
		(net "PCIE_TX_CAP_P89")
	)
	(segment
		(start 218.178888 -31.784036)
		(end 218.889072 -31.658814)
		(width 0.1397)
		(layer "In5.Cu")
		(net "PCIE_TX_CAP_P89")
	)
	(segment
		(start 217.411554 -31.91891)
		(end 217.549984 -31.89478)
		(width 0.1397)
		(layer "In5.Cu")
		(net "PCIE_TX_CAP_P89")
	)
	(segment
		(start 185.570368 -31.691834)
		(end 187.050934 -31.952692)
		(width 0.1397)
		(layer "In5.Cu")
		(net "PCIE_TX_CAP_P89")
	)
	(segment
		(start 223.100138 -30.20314)
		(end 223.100138 -30.500066)
		(width 0.1016)
		(layer "In5.Cu")
		(net "PCIE_TX_CAP_P89")
	)
	(segment
		(start 185.23077 -31.751524)
		(end 185.570368 -31.691834)
		(width 0.1397)
		(layer "In5.Cu")
		(net "PCIE_TX_CAP_P89")
	)
	(segment
		(start 194.721226 -30.597856)
		(end 195.175378 -30.677866)
		(width 0.1397)
		(layer "In5.Cu")
		(net "PCIE_TX_CAP_P89")
	)
	(segment
		(start 203.70165 -32.023558)
		(end 210.853274 -30.762194)
		(width 0.1397)
		(layer "In5.Cu")
		(net "PCIE_TX_CAP_P89")
	)
	(segment
		(start 210.853274 -30.762194)
		(end 215.559132 -31.59252)
		(width 0.1397)
		(layer "In5.Cu")
		(net "PCIE_TX_CAP_P89")
	)
	(segment
		(start 217.549984 -31.89478)
		(end 218.178888 -31.784036)
		(width 0.1397)
		(layer "In5.Cu")
		(net "PCIE_TX_CAP_P89")
	)
	(segment
		(start 221.2086 -30.16504)
		(end 221.4626 -30.16504)
		(width 0.1397)
		(layer "In5.Cu")
		(net "PCIE_TX_CAP_P89")
	)
	(segment
		(start 184.89168 -31.811214)
		(end 185.061098 -31.781242)
		(width 0.1397)
		(layer "In5.Cu")
		(net "PCIE_TX_CAP_P89")
	)
	(segment
		(start 218.889072 -31.658814)
		(end 219.434918 -31.562548)
		(width 0.1397)
		(layer "In5.Cu")
		(net "PCIE_TX_CAP_P89")
	)
	(segment
		(start 195.175378 -30.677866)
		(end 195.421758 -30.7213)
		(width 0.1397)
		(layer "In5.Cu")
		(net "PCIE_TX_CAP_P89")
	)
	(segment
		(start 219.910406 -31.2293)
		(end 220.809312 -30.330394)
		(width 0.1397)
		(layer "In5.Cu")
		(net "PCIE_TX_CAP_P89")
	)
	(arc
		(start 159.798258 -37.116258)
		(mid 159.987877 -37.242865)
		(end 160.211516 -37.2872)
		(width 0.1397)
		(layer "In5.Cu")
		(net "PCIE_TX_CAP_P89")
	)
	(arc
		(start 158.808166 -35.174682)
		(mid 158.873419 -35.272339)
		(end 158.896304 -35.387534)
		(width 0.1397)
		(layer "In5.Cu")
		(net "PCIE_TX_CAP_P89")
	)
	(arc
		(start 167.463724 -36.991544)
		(mid 167.483091 -36.983678)
		(end 167.501062 -36.973002)
		(width 0.1397)
		(layer "In5.Cu")
		(net "PCIE_TX_CAP_P89")
	)
	(arc
		(start 158.896304 -35.823144)
		(mid 158.968015 -36.184219)
		(end 159.172402 -36.490402)
		(width 0.1397)
		(layer "In5.Cu")
		(net "PCIE_TX_CAP_P89")
	)
	(arc
		(start 166.520622 -37.2872)
		(mid 166.542216 -37.285561)
		(end 166.563294 -37.280596)
		(width 0.1397)
		(layer "In5.Cu")
		(net "PCIE_TX_CAP_P89")
	)
	(arc
		(start 221.51975 -30.13329)
		(mid 221.554944 -30.109774)
		(end 221.596458 -30.10154)
		(width 0.1016)
		(layer "In5.Cu")
		(net "PCIE_TX_CAP_P89")
	)
	(arc
		(start 220.912436 -30.249114)
		(mid 221.054678 -30.186507)
		(end 221.2086 -30.16504)
		(width 0.1397)
		(layer "In5.Cu")
		(net "PCIE_TX_CAP_P89")
	)
	(arc
		(start 222.998538 -30.10154)
		(mid 223.07038 -30.131298)
		(end 223.100138 -30.20314)
		(width 0.1016)
		(layer "In5.Cu")
		(net "PCIE_TX_CAP_P89")
	)
	(arc
		(start 220.809312 -30.330394)
		(mid 220.858499 -30.286741)
		(end 220.912436 -30.249114)
		(width 0.1397)
		(layer "In5.Cu")
		(net "PCIE_TX_CAP_P89")
	)
	(segment
		(start 163.4871 -35.117024)
		(end 163.4871 -34.4424)
		(width 0.136652)
		(layer "F.Cu")
		(net "PCIE_TX_CAP_P88")
	)
	(segment
		(start 162.487356 -36.369752)
		(end 163.30803 -35.549078)
		(width 0.136652)
		(layer "F.Cu")
		(net "PCIE_TX_CAP_P88")
	)
	(segment
		(start 222.600012 -31.999936)
		(end 222.10014 -31.500064)
		(width 0.136652)
		(layer "F.Cu")
		(net "PCIE_TX_CAP_P88")
	)
	(segment
		(start 163.36137 -34.13887)
		(end 163.195 -33.9725)
		(width 0.136652)
		(layer "F.Cu")
		(net "PCIE_TX_CAP_P88")
	)
	(via
		(at 222.10014 -31.500064)
		(size 0.4572)
		(drill 0.2032)
		(layers "F.Cu" "B.Cu")
		(net "PCIE_TX_CAP_P88")
	)
	(via
		(at 161.7853 -38.0111)
		(size 0.508)
		(drill 0.254)
		(layers "F.Cu" "B.Cu")
		(net "PCIE_TX_CAP_P88")
	)
	(arc
		(start 161.7853 -38.0111)
		(mid 161.99913 -37.719514)
		(end 162.07486 -37.36594)
		(width 0.136652)
		(layer "F.Cu")
		(net "PCIE_TX_CAP_P88")
	)
	(arc
		(start 163.4871 -34.4424)
		(mid 163.454425 -34.278129)
		(end 163.36137 -34.13887)
		(width 0.136652)
		(layer "F.Cu")
		(net "PCIE_TX_CAP_P88")
	)
	(arc
		(start 162.07486 -37.36594)
		(mid 162.182007 -36.826806)
		(end 162.487356 -36.369752)
		(width 0.136652)
		(layer "F.Cu")
		(net "PCIE_TX_CAP_P88")
	)
	(arc
		(start 163.30803 -35.549078)
		(mid 163.440511 -35.350851)
		(end 163.4871 -35.117024)
		(width 0.136652)
		(layer "F.Cu")
		(net "PCIE_TX_CAP_P88")
	)
	(segment
		(start 184.471056 -32.934656)
		(end 183.191404 -33.160462)
		(width 0.1397)
		(layer "In5.Cu")
		(net "PCIE_TX_CAP_P88")
	)
	(segment
		(start 203.938378 -33.188148)
		(end 199.25665 -32.362648)
		(width 0.1397)
		(layer "In5.Cu")
		(net "PCIE_TX_CAP_P88")
	)
	(segment
		(start 185.749946 -32.709358)
		(end 184.471056 -32.934656)
		(width 0.1397)
		(layer "In5.Cu")
		(net "PCIE_TX_CAP_P88")
	)
	(segment
		(start 183.135016 -33.170368)
		(end 183.134 -33.165288)
		(width 0.1397)
		(layer "In5.Cu")
		(net "PCIE_TX_CAP_P88")
	)
	(segment
		(start 180.0987 -32.635444)
		(end 173.966378 -33.716722)
		(width 0.1397)
		(layer "In5.Cu")
		(net "PCIE_TX_CAP_P88")
	)
	(segment
		(start 186.410854 -32.82569)
		(end 185.749946 -32.709358)
		(width 0.1397)
		(layer "In5.Cu")
		(net "PCIE_TX_CAP_P88")
	)
	(segment
		(start 219.632784 -32.919924)
		(end 218.826334 -33.06191)
		(width 0.1397)
		(layer "In5.Cu")
		(net "PCIE_TX_CAP_P88")
	)
	(segment
		(start 183.134 -33.165288)
		(end 183.105044 -33.165288)
		(width 0.1397)
		(layer "In5.Cu")
		(net "PCIE_TX_CAP_P88")
	)
	(segment
		(start 218.826334 -33.06191)
		(end 218.236038 -33.16605)
		(width 0.1397)
		(layer "In5.Cu")
		(net "PCIE_TX_CAP_P88")
	)
	(segment
		(start 162.549078 -39.515288)
		(end 162.20059 -39.233094)
		(width 0.1397)
		(layer "In5.Cu")
		(net "PCIE_TX_CAP_P88")
	)
	(segment
		(start 194.812412 -31.578804)
		(end 187.07735 -32.943292)
		(width 0.1397)
		(layer "In5.Cu")
		(net "PCIE_TX_CAP_P88")
	)
	(segment
		(start 217.43543 -33.02508)
		(end 216.691464 -32.894016)
		(width 0.1397)
		(layer "In5.Cu")
		(net "PCIE_TX_CAP_P88")
	)
	(segment
		(start 183.191404 -33.160462)
		(end 183.135016 -33.170368)
		(width 0.1397)
		(layer "In5.Cu")
		(net "PCIE_TX_CAP_P88")
	)
	(segment
		(start 220.850206 -31.905194)
		(end 220.289628 -32.466026)
		(width 0.1397)
		(layer "In5.Cu")
		(net "PCIE_TX_CAP_P88")
	)
	(segment
		(start 220.278198 -32.468058)
		(end 219.632784 -32.919924)
		(width 0.1397)
		(layer "In5.Cu")
		(net "PCIE_TX_CAP_P88")
	)
	(segment
		(start 216.691464 -32.894016)
		(end 215.409526 -32.667956)
		(width 0.1397)
		(layer "In5.Cu")
		(net "PCIE_TX_CAP_P88")
	)
	(segment
		(start 187.07735 -32.943292)
		(end 186.410854 -32.82569)
		(width 0.1397)
		(layer "In5.Cu")
		(net "PCIE_TX_CAP_P88")
	)
	(segment
		(start 207.600804 -32.54248)
		(end 203.938378 -33.188148)
		(width 0.1397)
		(layer "In5.Cu")
		(net "PCIE_TX_CAP_P88")
	)
	(segment
		(start 211.14893 -31.917132)
		(end 207.600804 -32.54248)
		(width 0.1397)
		(layer "In5.Cu")
		(net "PCIE_TX_CAP_P88")
	)
	(segment
		(start 218.236038 -33.16605)
		(end 217.43543 -33.02508)
		(width 0.1397)
		(layer "In5.Cu")
		(net "PCIE_TX_CAP_P88")
	)
	(segment
		(start 162.0266 -38.867588)
		(end 162.0266 -38.395148)
		(width 0.1397)
		(layer "In5.Cu")
		(net "PCIE_TX_CAP_P88")
	)
	(segment
		(start 173.966378 -33.716722)
		(end 166.218616 -39.141654)
		(width 0.1397)
		(layer "In5.Cu")
		(net "PCIE_TX_CAP_P88")
	)
	(segment
		(start 163.37026 -39.708836)
		(end 162.549078 -39.515288)
		(width 0.1397)
		(layer "In5.Cu")
		(net "PCIE_TX_CAP_P88")
	)
	(segment
		(start 183.105044 -33.165288)
		(end 180.0987 -32.635444)
		(width 0.1397)
		(layer "In5.Cu")
		(net "PCIE_TX_CAP_P88")
	)
	(segment
		(start 220.289628 -32.466026)
		(end 220.278198 -32.468058)
		(width 0.1397)
		(layer "In5.Cu")
		(net "PCIE_TX_CAP_P88")
	)
	(segment
		(start 215.409526 -32.667956)
		(end 213.279482 -32.292544)
		(width 0.1397)
		(layer "In5.Cu")
		(net "PCIE_TX_CAP_P88")
	)
	(segment
		(start 221.0308 -31.724854)
		(end 220.850206 -31.905194)
		(width 0.1397)
		(layer "In5.Cu")
		(net "PCIE_TX_CAP_P88")
	)
	(segment
		(start 166.218616 -39.141654)
		(end 163.37026 -39.708836)
		(width 0.1397)
		(layer "In5.Cu")
		(net "PCIE_TX_CAP_P88")
	)
	(segment
		(start 199.25665 -32.362648)
		(end 194.812412 -31.578804)
		(width 0.1397)
		(layer "In5.Cu")
		(net "PCIE_TX_CAP_P88")
	)
	(segment
		(start 213.279482 -32.292544)
		(end 211.14893 -31.917132)
		(width 0.1397)
		(layer "In5.Cu")
		(net "PCIE_TX_CAP_P88")
	)
	(arc
		(start 162.20059 -39.233094)
		(mid 162.072273 -39.070013)
		(end 162.0266 -38.867588)
		(width 0.1397)
		(layer "In5.Cu")
		(net "PCIE_TX_CAP_P88")
	)
	(arc
		(start 162.0266 -38.395148)
		(mid 161.961263 -38.168376)
		(end 161.7853 -38.0111)
		(width 0.1397)
		(layer "In5.Cu")
		(net "PCIE_TX_CAP_P88")
	)
	(arc
		(start 221.68485 -31.532576)
		(mid 221.351628 -31.607637)
		(end 221.0308 -31.724854)
		(width 0.1397)
		(layer "In5.Cu")
		(net "PCIE_TX_CAP_P88")
	)
	(arc
		(start 222.10014 -31.500064)
		(mid 221.891856 -31.508164)
		(end 221.68485 -31.532576)
		(width 0.1397)
		(layer "In5.Cu")
		(net "PCIE_TX_CAP_P88")
	)
	(segment
		(start 223.60001 -33.999932)
		(end 223.100138 -33.50006)
		(width 0.136652)
		(layer "F.Cu")
		(net "PCIE_TX_CAP_P87")
	)
	(segment
		(start 152.93848 -34.40684)
		(end 152.93848 -34.57956)
		(width 0.136652)
		(layer "F.Cu")
		(net "PCIE_TX_CAP_P87")
	)
	(via
		(at 152.7175 -34.99612)
		(size 0.508)
		(drill 0.254)
		(layers "F.Cu" "B.Cu")
		(net "PCIE_TX_CAP_P87")
	)
	(via
		(at 223.100138 -33.50006)
		(size 0.4572)
		(drill 0.2032)
		(layers "F.Cu" "B.Cu")
		(net "PCIE_TX_CAP_P87")
	)
	(arc
		(start 152.93848 -34.57956)
		(mid 152.87982 -34.815339)
		(end 152.7175 -34.99612)
		(width 0.136652)
		(layer "F.Cu")
		(net "PCIE_TX_CAP_P87")
	)
	(arc
		(start 152.6032 -33.9471)
		(mid 152.845751 -34.122337)
		(end 152.93848 -34.40684)
		(width 0.136652)
		(layer "F.Cu")
		(net "PCIE_TX_CAP_P87")
	)
	(segment
		(start 180.1495 -33.653476)
		(end 181.60365 -33.909762)
		(width 0.1397)
		(layer "In5.Cu")
		(net "PCIE_TX_CAP_P87")
	)
	(segment
		(start 174.512478 -34.647124)
		(end 180.1495 -33.653476)
		(width 0.1397)
		(layer "In5.Cu")
		(net "PCIE_TX_CAP_P87")
	)
	(segment
		(start 221.230698 -34.165794)
		(end 221.234 -34.165286)
		(width 0.1397)
		(layer "In5.Cu")
		(net "PCIE_TX_CAP_P87")
	)
	(segment
		(start 156.045662 -37.638228)
		(end 158.439104 -38.14699)
		(width 0.1397)
		(layer "In5.Cu")
		(net "PCIE_TX_CAP_P87")
	)
	(segment
		(start 222.804736 -33.8455)
		(end 222.809054 -33.838642)
		(width 0.1016)
		(layer "In5.Cu")
		(net "PCIE_TX_CAP_P87")
	)
	(segment
		(start 153.114756 -36.17214)
		(end 154.065478 -36.837366)
		(width 0.1397)
		(layer "In5.Cu")
		(net "PCIE_TX_CAP_P87")
	)
	(segment
		(start 152.7175 -34.99612)
		(end 152.850088 -35.128708)
		(width 0.1397)
		(layer "In5.Cu")
		(net "PCIE_TX_CAP_P87")
	)
	(segment
		(start 211.251546 -32.948118)
		(end 218.3003 -34.190432)
		(width 0.1397)
		(layer "In5.Cu")
		(net "PCIE_TX_CAP_P87")
	)
	(segment
		(start 152.9588 -35.39109)
		(end 152.9588 -35.555428)
		(width 0.1397)
		(layer "In5.Cu")
		(net "PCIE_TX_CAP_P87")
	)
	(segment
		(start 162.57905 -40.589962)
		(end 163.086034 -40.697658)
		(width 0.1397)
		(layer "In5.Cu")
		(net "PCIE_TX_CAP_P87")
	)
	(segment
		(start 166.770812 -40.067992)
		(end 174.512478 -34.647124)
		(width 0.1397)
		(layer "In5.Cu")
		(net "PCIE_TX_CAP_P87")
	)
	(segment
		(start 163.480242 -40.767)
		(end 166.770812 -40.067992)
		(width 0.1397)
		(layer "In5.Cu")
		(net "PCIE_TX_CAP_P87")
	)
	(segment
		(start 196.1896 -32.827214)
		(end 204.063854 -34.21507)
		(width 0.1397)
		(layer "In5.Cu")
		(net "PCIE_TX_CAP_P87")
	)
	(segment
		(start 221.5896 -34.165286)
		(end 221.6531 -34.101786)
		(width 0.1016)
		(layer "In5.Cu")
		(net "PCIE_TX_CAP_P87")
	)
	(segment
		(start 162.077654 -40.48379)
		(end 162.077654 -40.483536)
		(width 0.1397)
		(layer "In5.Cu")
		(net "PCIE_TX_CAP_P87")
	)
	(segment
		(start 204.063854 -34.21507)
		(end 211.251546 -32.948118)
		(width 0.1397)
		(layer "In5.Cu")
		(net "PCIE_TX_CAP_P87")
	)
	(segment
		(start 221.5642 -34.165286)
		(end 221.5896 -34.165286)
		(width 0.1016)
		(layer "In5.Cu")
		(net "PCIE_TX_CAP_P87")
	)
	(segment
		(start 162.017456 -40.470836)
		(end 162.077654 -40.48379)
		(width 0.1397)
		(layer "In5.Cu")
		(net "PCIE_TX_CAP_P87")
	)
	(segment
		(start 155.098496 -37.019484)
		(end 155.496768 -37.089588)
		(width 0.1397)
		(layer "In5.Cu")
		(net "PCIE_TX_CAP_P87")
	)
	(segment
		(start 221.234 -34.165286)
		(end 221.5642 -34.165286)
		(width 0.1397)
		(layer "In5.Cu")
		(net "PCIE_TX_CAP_P87")
	)
	(segment
		(start 181.60365 -33.909762)
		(end 183.1721 -34.186114)
		(width 0.1397)
		(layer "In5.Cu")
		(net "PCIE_TX_CAP_P87")
	)
	(segment
		(start 183.1721 -34.186114)
		(end 185.813954 -33.720532)
		(width 0.1397)
		(layer "In5.Cu")
		(net "PCIE_TX_CAP_P87")
	)
	(segment
		(start 188.468 -34.188654)
		(end 196.1896 -32.827214)
		(width 0.1397)
		(layer "In5.Cu")
		(net "PCIE_TX_CAP_P87")
	)
	(segment
		(start 152.9588 -35.555428)
		(end 153.114756 -36.17214)
		(width 0.1397)
		(layer "In5.Cu")
		(net "PCIE_TX_CAP_P87")
	)
	(segment
		(start 221.6531 -34.101786)
		(end 222.344234 -34.101786)
		(width 0.1016)
		(layer "In5.Cu")
		(net "PCIE_TX_CAP_P87")
	)
	(segment
		(start 219.837254 -33.919922)
		(end 221.230698 -34.165794)
		(width 0.1397)
		(layer "In5.Cu")
		(net "PCIE_TX_CAP_P87")
	)
	(segment
		(start 154.065478 -36.837366)
		(end 155.098496 -37.019484)
		(width 0.1397)
		(layer "In5.Cu")
		(net "PCIE_TX_CAP_P87")
	)
	(segment
		(start 162.077654 -40.483536)
		(end 162.57905 -40.589962)
		(width 0.1397)
		(layer "In5.Cu")
		(net "PCIE_TX_CAP_P87")
	)
	(segment
		(start 155.496768 -37.089588)
		(end 155.497022 -37.089588)
		(width 0.1397)
		(layer "In5.Cu")
		(net "PCIE_TX_CAP_P87")
	)
	(segment
		(start 158.439104 -38.14699)
		(end 162.017456 -40.470836)
		(width 0.1397)
		(layer "In5.Cu")
		(net "PCIE_TX_CAP_P87")
	)
	(segment
		(start 155.497022 -37.089588)
		(end 156.045662 -37.638228)
		(width 0.1397)
		(layer "In5.Cu")
		(net "PCIE_TX_CAP_P87")
	)
	(segment
		(start 163.086034 -40.697658)
		(end 163.480242 -40.767)
		(width 0.1397)
		(layer "In5.Cu")
		(net "PCIE_TX_CAP_P87")
	)
	(segment
		(start 185.813954 -33.720532)
		(end 188.468 -34.188654)
		(width 0.1397)
		(layer "In5.Cu")
		(net "PCIE_TX_CAP_P87")
	)
	(segment
		(start 218.3003 -34.190432)
		(end 219.837254 -33.919922)
		(width 0.1397)
		(layer "In5.Cu")
		(net "PCIE_TX_CAP_P87")
	)
	(arc
		(start 152.850088 -35.128708)
		(mid 152.930525 -35.24909)
		(end 152.9588 -35.39109)
		(width 0.1397)
		(layer "In5.Cu")
		(net "PCIE_TX_CAP_P87")
	)
	(arc
		(start 222.809054 -33.838642)
		(mid 222.812012 -33.833073)
		(end 222.814896 -33.827466)
		(width 0.1016)
		(layer "In5.Cu")
		(net "PCIE_TX_CAP_P87")
	)
	(arc
		(start 222.814896 -33.827466)
		(mid 222.937134 -33.646001)
		(end 223.100138 -33.50006)
		(width 0.1016)
		(layer "In5.Cu")
		(net "PCIE_TX_CAP_P87")
	)
	(arc
		(start 222.344234 -34.101786)
		(mid 222.607784 -34.0335)
		(end 222.804736 -33.8455)
		(width 0.1016)
		(layer "In5.Cu")
		(net "PCIE_TX_CAP_P87")
	)
	(segment
		(start 148.7551 -34.3916)
		(end 148.7551 -34.593784)
		(width 0.136652)
		(layer "F.Cu")
		(net "PCIE_TX_CAP_P86")
	)
	(segment
		(start 148.463 -33.9725)
		(end 148.665184 -34.174938)
		(width 0.136652)
		(layer "F.Cu")
		(net "PCIE_TX_CAP_P86")
	)
	(segment
		(start 224.600008 -34.99993)
		(end 224.100136 -34.500058)
		(width 0.136652)
		(layer "F.Cu")
		(net "PCIE_TX_CAP_P86")
	)
	(segment
		(start 148.646642 -34.855658)
		(end 148.5011 -35.0012)
		(width 0.136652)
		(layer "F.Cu")
		(net "PCIE_TX_CAP_P86")
	)
	(via
		(at 148.5011 -35.0012)
		(size 0.508)
		(drill 0.254)
		(layers "F.Cu" "B.Cu")
		(net "PCIE_TX_CAP_P86")
	)
	(via
		(at 224.100136 -34.500058)
		(size 0.4572)
		(drill 0.2032)
		(layers "F.Cu" "B.Cu")
		(net "PCIE_TX_CAP_P86")
	)
	(arc
		(start 148.7551 -34.593784)
		(mid 148.72691 -34.735504)
		(end 148.646642 -34.855658)
		(width 0.136652)
		(layer "F.Cu")
		(net "PCIE_TX_CAP_P86")
	)
	(arc
		(start 148.665184 -34.174938)
		(mid 148.731687 -34.274328)
		(end 148.7551 -34.3916)
		(width 0.136652)
		(layer "F.Cu")
		(net "PCIE_TX_CAP_P86")
	)
	(segment
		(start 148.7678 -35.4838)
		(end 148.7678 -35.723322)
		(width 0.1397)
		(layer "In5.Cu")
		(net "PCIE_TX_CAP_P86")
	)
	(segment
		(start 150.707344 -36.413694)
		(end 152.364186 -36.765738)
		(width 0.1397)
		(layer "In5.Cu")
		(net "PCIE_TX_CAP_P86")
	)
	(segment
		(start 149.544024 -36.536884)
		(end 149.801072 -36.536884)
		(width 0.1397)
		(layer "In5.Cu")
		(net "PCIE_TX_CAP_P86")
	)
	(segment
		(start 148.98243 -36.24199)
		(end 149.08911 -36.34867)
		(width 0.1397)
		(layer "In5.Cu")
		(net "PCIE_TX_CAP_P86")
	)
	(segment
		(start 218.5162 -35.215068)
		(end 219.019882 -35.126168)
		(width 0.1397)
		(layer "In5.Cu")
		(net "PCIE_TX_CAP_P86")
	)
	(segment
		(start 167.698928 -40.663114)
		(end 169.599356 -39.428928)
		(width 0.1397)
		(layer "In5.Cu")
		(net "PCIE_TX_CAP_P86")
	)
	(segment
		(start 183.2356 -35.206432)
		(end 185.8645 -34.742882)
		(width 0.1397)
		(layer "In5.Cu")
		(net "PCIE_TX_CAP_P86")
	)
	(segment
		(start 185.8645 -34.742882)
		(end 188.468 -35.201606)
		(width 0.1397)
		(layer "In5.Cu")
		(net "PCIE_TX_CAP_P86")
	)
	(segment
		(start 150.197566 -36.495228)
		(end 150.583138 -36.41344)
		(width 0.1397)
		(layer "In5.Cu")
		(net "PCIE_TX_CAP_P86")
	)
	(segment
		(start 161.213038 -41.092374)
		(end 162.938206 -41.458642)
		(width 0.1397)
		(layer "In5.Cu")
		(net "PCIE_TX_CAP_P86")
	)
	(segment
		(start 188.468 -35.201606)
		(end 191.50965 -34.665412)
		(width 0.1397)
		(layer "In5.Cu")
		(net "PCIE_TX_CAP_P86")
	)
	(segment
		(start 154.700224 -38.281356)
		(end 157.947614 -38.971728)
		(width 0.1397)
		(layer "In5.Cu")
		(net "PCIE_TX_CAP_P86")
	)
	(segment
		(start 157.947614 -38.971728)
		(end 161.213038 -41.092374)
		(width 0.1397)
		(layer "In5.Cu")
		(net "PCIE_TX_CAP_P86")
	)
	(segment
		(start 219.019882 -35.126168)
		(end 219.837 -34.982404)
		(width 0.1397)
		(layer "In5.Cu")
		(net "PCIE_TX_CAP_P86")
	)
	(segment
		(start 191.50965 -34.665412)
		(end 196.163692 -33.844992)
		(width 0.1397)
		(layer "In5.Cu")
		(net "PCIE_TX_CAP_P86")
	)
	(segment
		(start 169.599356 -39.428928)
		(end 175.147986 -35.543998)
		(width 0.1397)
		(layer "In5.Cu")
		(net "PCIE_TX_CAP_P86")
	)
	(segment
		(start 221.5896 -35.165284)
		(end 221.6531 -35.101784)
		(width 0.1016)
		(layer "In5.Cu")
		(net "PCIE_TX_CAP_P86")
	)
	(segment
		(start 211.2391 -33.932622)
		(end 218.5162 -35.215068)
		(width 0.1397)
		(layer "In5.Cu")
		(net "PCIE_TX_CAP_P86")
	)
	(segment
		(start 196.163692 -33.844992)
		(end 203.9493 -35.217354)
		(width 0.1397)
		(layer "In5.Cu")
		(net "PCIE_TX_CAP_P86")
	)
	(segment
		(start 221.5642 -35.165284)
		(end 221.5896 -35.165284)
		(width 0.1016)
		(layer "In5.Cu")
		(net "PCIE_TX_CAP_P86")
	)
	(segment
		(start 181.6354 -34.924238)
		(end 183.2356 -35.206432)
		(width 0.1397)
		(layer "In5.Cu")
		(net "PCIE_TX_CAP_P86")
	)
	(segment
		(start 163.493958 -41.556686)
		(end 167.698928 -40.663114)
		(width 0.1397)
		(layer "In5.Cu")
		(net "PCIE_TX_CAP_P86")
	)
	(segment
		(start 207.65135 -34.564828)
		(end 211.2391 -33.932622)
		(width 0.1397)
		(layer "In5.Cu")
		(net "PCIE_TX_CAP_P86")
	)
	(segment
		(start 162.938206 -41.458642)
		(end 163.493958 -41.556686)
		(width 0.1397)
		(layer "In5.Cu")
		(net "PCIE_TX_CAP_P86")
	)
	(segment
		(start 203.9493 -35.217354)
		(end 207.65135 -34.564828)
		(width 0.1397)
		(layer "In5.Cu")
		(net "PCIE_TX_CAP_P86")
	)
	(segment
		(start 221.6531 -35.101784)
		(end 223.422464 -35.101784)
		(width 0.1016)
		(layer "In5.Cu")
		(net "PCIE_TX_CAP_P86")
	)
	(segment
		(start 175.147986 -35.543998)
		(end 180.1495 -34.662364)
		(width 0.1397)
		(layer "In5.Cu")
		(net "PCIE_TX_CAP_P86")
	)
	(segment
		(start 220.874844 -35.165284)
		(end 221.5642 -35.165284)
		(width 0.1397)
		(layer "In5.Cu")
		(net "PCIE_TX_CAP_P86")
	)
	(segment
		(start 219.837 -34.982404)
		(end 220.874844 -35.165284)
		(width 0.1397)
		(layer "In5.Cu")
		(net "PCIE_TX_CAP_P86")
	)
	(segment
		(start 180.1495 -34.662364)
		(end 181.6354 -34.924238)
		(width 0.1397)
		(layer "In5.Cu")
		(net "PCIE_TX_CAP_P86")
	)
	(segment
		(start 152.364186 -36.765738)
		(end 154.700224 -38.281356)
		(width 0.1397)
		(layer "In5.Cu")
		(net "PCIE_TX_CAP_P86")
	)
	(segment
		(start 223.899222 -34.700972)
		(end 224.100136 -34.500058)
		(width 0.1016)
		(layer "In5.Cu")
		(net "PCIE_TX_CAP_P86")
	)
	(arc
		(start 149.801072 -36.536884)
		(mid 150.000407 -36.526412)
		(end 150.197566 -36.495228)
		(width 0.1397)
		(layer "In5.Cu")
		(net "PCIE_TX_CAP_P86")
	)
	(arc
		(start 148.7678 -35.723322)
		(mid 148.823536 -36.003997)
		(end 148.98243 -36.24199)
		(width 0.1397)
		(layer "In5.Cu")
		(net "PCIE_TX_CAP_P86")
	)
	(arc
		(start 223.670368 -35.016694)
		(mid 223.741114 -34.945472)
		(end 223.792034 -34.85896)
		(width 0.1016)
		(layer "In5.Cu")
		(net "PCIE_TX_CAP_P86")
	)
	(arc
		(start 149.08911 -36.34867)
		(mid 149.297841 -36.488047)
		(end 149.544024 -36.536884)
		(width 0.1397)
		(layer "In5.Cu")
		(net "PCIE_TX_CAP_P86")
	)
	(arc
		(start 223.792034 -34.85896)
		(mid 223.838136 -34.774882)
		(end 223.899222 -34.700972)
		(width 0.1016)
		(layer "In5.Cu")
		(net "PCIE_TX_CAP_P86")
	)
	(arc
		(start 150.583138 -36.41344)
		(mid 150.645254 -36.407076)
		(end 150.707344 -36.413694)
		(width 0.1397)
		(layer "In5.Cu")
		(net "PCIE_TX_CAP_P86")
	)
	(arc
		(start 223.422464 -35.101784)
		(mid 223.553547 -35.080006)
		(end 223.670368 -35.016694)
		(width 0.1016)
		(layer "In5.Cu")
		(net "PCIE_TX_CAP_P86")
	)
	(arc
		(start 148.5011 -35.0012)
		(mid 148.696693 -35.208103)
		(end 148.7678 -35.4838)
		(width 0.1397)
		(layer "In5.Cu")
		(net "PCIE_TX_CAP_P86")
	)
	(segment
		(start 145.8722 -33.96742)
		(end 146.074384 -34.169858)
		(width 0.136652)
		(layer "F.Cu")
		(net "PCIE_TX_CAP_P85")
	)
	(segment
		(start 146.055842 -34.850578)
		(end 145.9103 -34.99612)
		(width 0.136652)
		(layer "F.Cu")
		(net "PCIE_TX_CAP_P85")
	)
	(segment
		(start 223.60001 -35.999928)
		(end 223.100138 -35.500056)
		(width 0.136652)
		(layer "F.Cu")
		(net "PCIE_TX_CAP_P85")
	)
	(segment
		(start 146.1643 -34.38652)
		(end 146.1643 -34.588704)
		(width 0.136652)
		(layer "F.Cu")
		(net "PCIE_TX_CAP_P85")
	)
	(via
		(at 145.9103 -34.99612)
		(size 0.508)
		(drill 0.254)
		(layers "F.Cu" "B.Cu")
		(net "PCIE_TX_CAP_P85")
	)
	(via
		(at 223.100138 -35.500056)
		(size 0.4572)
		(drill 0.2032)
		(layers "F.Cu" "B.Cu")
		(net "PCIE_TX_CAP_P85")
	)
	(arc
		(start 146.1643 -34.588704)
		(mid 146.13611 -34.730424)
		(end 146.055842 -34.850578)
		(width 0.136652)
		(layer "F.Cu")
		(net "PCIE_TX_CAP_P85")
	)
	(arc
		(start 146.074384 -34.169858)
		(mid 146.140887 -34.269248)
		(end 146.1643 -34.38652)
		(width 0.136652)
		(layer "F.Cu")
		(net "PCIE_TX_CAP_P85")
	)
	(segment
		(start 146.453098 -36.26358)
		(end 146.698716 -36.508944)
		(width 0.1397)
		(layer "In5.Cu")
		(net "PCIE_TX_CAP_P85")
	)
	(segment
		(start 183.28767 -36.129976)
		(end 185.8899 -35.671252)
		(width 0.1397)
		(layer "In5.Cu")
		(net "PCIE_TX_CAP_P85")
	)
	(segment
		(start 153.961084 -38.973252)
		(end 157.850332 -39.832534)
		(width 0.1397)
		(layer "In5.Cu")
		(net "PCIE_TX_CAP_P85")
	)
	(segment
		(start 221.285562 -36.165282)
		(end 221.310962 -36.165282)
		(width 0.1016)
		(layer "In5.Cu")
		(net "PCIE_TX_CAP_P85")
	)
	(segment
		(start 200.962514 -35.632644)
		(end 204.013308 -36.170362)
		(width 0.1397)
		(layer "In5.Cu")
		(net "PCIE_TX_CAP_P85")
	)
	(segment
		(start 152.059894 -37.52088)
		(end 153.961084 -38.973252)
		(width 0.1397)
		(layer "In5.Cu")
		(net "PCIE_TX_CAP_P85")
	)
	(segment
		(start 157.850332 -39.832534)
		(end 160.91154 -41.820592)
		(width 0.1397)
		(layer "In5.Cu")
		(net "PCIE_TX_CAP_P85")
	)
	(segment
		(start 180.391816 -35.619436)
		(end 183.28767 -36.129976)
		(width 0.1397)
		(layer "In5.Cu")
		(net "PCIE_TX_CAP_P85")
	)
	(segment
		(start 145.9103 -34.99612)
		(end 146.045428 -35.131248)
		(width 0.1397)
		(layer "In5.Cu")
		(net "PCIE_TX_CAP_P85")
	)
	(segment
		(start 191.440054 -35.691318)
		(end 196.03466 -36.50107)
		(width 0.1397)
		(layer "In5.Cu")
		(net "PCIE_TX_CAP_P85")
	)
	(segment
		(start 168.931844 -41.193466)
		(end 175.714914 -36.44392)
		(width 0.1397)
		(layer "In5.Cu")
		(net "PCIE_TX_CAP_P85")
	)
	(segment
		(start 211.5566 -34.840418)
		(end 219.071444 -36.165282)
		(width 0.1397)
		(layer "In5.Cu")
		(net "PCIE_TX_CAP_P85")
	)
	(segment
		(start 151.074374 -37.311584)
		(end 152.059894 -37.52088)
		(width 0.1397)
		(layer "In5.Cu")
		(net "PCIE_TX_CAP_P85")
	)
	(segment
		(start 221.310962 -36.165282)
		(end 221.374462 -36.101782)
		(width 0.1016)
		(layer "In5.Cu")
		(net "PCIE_TX_CAP_P85")
	)
	(segment
		(start 149.606762 -37.62375)
		(end 151.074374 -37.311584)
		(width 0.1397)
		(layer "In5.Cu")
		(net "PCIE_TX_CAP_P85")
	)
	(segment
		(start 162.790378 -42.219626)
		(end 163.507674 -42.346118)
		(width 0.1397)
		(layer "In5.Cu")
		(net "PCIE_TX_CAP_P85")
	)
	(segment
		(start 148.769324 -37.445696)
		(end 149.606762 -37.62375)
		(width 0.1397)
		(layer "In5.Cu")
		(net "PCIE_TX_CAP_P85")
	)
	(segment
		(start 175.714914 -36.44392)
		(end 180.391816 -35.619436)
		(width 0.1397)
		(layer "In5.Cu")
		(net "PCIE_TX_CAP_P85")
	)
	(segment
		(start 147.835874 -37.247322)
		(end 148.769324 -37.445696)
		(width 0.1397)
		(layer "In5.Cu")
		(net "PCIE_TX_CAP_P85")
	)
	(segment
		(start 146.1516 -35.387534)
		(end 146.1516 -35.535362)
		(width 0.1397)
		(layer "In5.Cu")
		(net "PCIE_TX_CAP_P85")
	)
	(segment
		(start 188.722508 -36.170362)
		(end 191.440054 -35.691318)
		(width 0.1397)
		(layer "In5.Cu")
		(net "PCIE_TX_CAP_P85")
	)
	(segment
		(start 221.374462 -36.101782)
		(end 222.41637 -36.101782)
		(width 0.1016)
		(layer "In5.Cu")
		(net "PCIE_TX_CAP_P85")
	)
	(segment
		(start 204.013308 -36.170362)
		(end 211.5566 -34.840418)
		(width 0.1397)
		(layer "In5.Cu")
		(net "PCIE_TX_CAP_P85")
	)
	(segment
		(start 160.91154 -41.820592)
		(end 162.790378 -42.219626)
		(width 0.1397)
		(layer "In5.Cu")
		(net "PCIE_TX_CAP_P85")
	)
	(segment
		(start 185.8899 -35.671252)
		(end 188.722508 -36.170362)
		(width 0.1397)
		(layer "In5.Cu")
		(net "PCIE_TX_CAP_P85")
	)
	(segment
		(start 219.071444 -36.165282)
		(end 221.285562 -36.165282)
		(width 0.1397)
		(layer "In5.Cu")
		(net "PCIE_TX_CAP_P85")
	)
	(segment
		(start 163.507674 -42.346118)
		(end 168.931844 -41.193466)
		(width 0.1397)
		(layer "In5.Cu")
		(net "PCIE_TX_CAP_P85")
	)
	(segment
		(start 196.03466 -36.50107)
		(end 200.962514 -35.632644)
		(width 0.1397)
		(layer "In5.Cu")
		(net "PCIE_TX_CAP_P85")
	)
	(segment
		(start 146.698716 -36.508944)
		(end 147.835874 -37.247322)
		(width 0.1397)
		(layer "In5.Cu")
		(net "PCIE_TX_CAP_P85")
	)
	(arc
		(start 222.66529 -36.034726)
		(mid 222.817204 -35.925553)
		(end 222.945452 -35.789362)
		(width 0.1016)
		(layer "In5.Cu")
		(net "PCIE_TX_CAP_P85")
	)
	(arc
		(start 222.41637 -36.101782)
		(mid 222.545275 -36.084755)
		(end 222.66529 -36.034726)
		(width 0.1016)
		(layer "In5.Cu")
		(net "PCIE_TX_CAP_P85")
	)
	(arc
		(start 146.045428 -35.131248)
		(mid 146.123996 -35.248833)
		(end 146.1516 -35.387534)
		(width 0.1397)
		(layer "In5.Cu")
		(net "PCIE_TX_CAP_P85")
	)
	(arc
		(start 222.945452 -35.789362)
		(mid 223.035048 -35.651261)
		(end 223.100138 -35.500056)
		(width 0.1016)
		(layer "In5.Cu")
		(net "PCIE_TX_CAP_P85")
	)
	(arc
		(start 146.1516 -35.535362)
		(mid 146.229952 -35.929446)
		(end 146.453098 -36.26358)
		(width 0.1397)
		(layer "In5.Cu")
		(net "PCIE_TX_CAP_P85")
	)
	(segment
		(start 150.9141 -34.737548)
		(end 150.9141 -35.628072)
		(width 0.136652)
		(layer "F.Cu")
		(net "PCIE_TX_CAP_P84")
	)
	(segment
		(start 224.600008 -36.999926)
		(end 224.100136 -36.500054)
		(width 0.136652)
		(layer "F.Cu")
		(net "PCIE_TX_CAP_P84")
	)
	(segment
		(start 151.1554 -36.210748)
		(end 151.1554 -37.592)
		(width 0.136652)
		(layer "F.Cu")
		(net "PCIE_TX_CAP_P84")
	)
	(via
		(at 224.100136 -36.500054)
		(size 0.4572)
		(drill 0.2032)
		(layers "F.Cu" "B.Cu")
		(net "PCIE_TX_CAP_P84")
	)
	(via
		(at 150.9141 -38.0873)
		(size 0.508)
		(drill 0.254)
		(layers "F.Cu" "B.Cu")
		(net "PCIE_TX_CAP_P84")
	)
	(arc
		(start 151.1554 -37.592)
		(mid 151.09186 -37.867469)
		(end 150.9141 -38.0873)
		(width 0.136652)
		(layer "F.Cu")
		(net "PCIE_TX_CAP_P84")
	)
	(arc
		(start 151.123904 -36.135056)
		(mid 151.147191 -36.169769)
		(end 151.1554 -36.210748)
		(width 0.136652)
		(layer "F.Cu")
		(net "PCIE_TX_CAP_P84")
	)
	(arc
		(start 150.622 -33.9725)
		(mid 150.838611 -34.328086)
		(end 150.9141 -34.737548)
		(width 0.136652)
		(layer "F.Cu")
		(net "PCIE_TX_CAP_P84")
	)
	(arc
		(start 150.9141 -35.628072)
		(mid 150.968564 -35.902443)
		(end 151.123904 -36.135056)
		(width 0.136652)
		(layer "F.Cu")
		(net "PCIE_TX_CAP_P84")
	)
	(segment
		(start 191.748156 -37.0205)
		(end 192.691258 -36.853876)
		(width 0.1397)
		(layer "In5.Cu")
		(net "PCIE_TX_CAP_P84")
	)
	(segment
		(start 152.081484 -40.20312)
		(end 155.983432 -41.033954)
		(width 0.1397)
		(layer "In5.Cu")
		(net "PCIE_TX_CAP_P84")
	)
	(segment
		(start 221.5388 -37.16528)
		(end 221.6023 -37.10178)
		(width 0.1016)
		(layer "In5.Cu")
		(net "PCIE_TX_CAP_P84")
	)
	(segment
		(start 157.18282 -41.884854)
		(end 163.579302 -43.246802)
		(width 0.1397)
		(layer "In5.Cu")
		(net "PCIE_TX_CAP_P84")
	)
	(segment
		(start 204.120496 -37.061648)
		(end 211.297774 -35.79622)
		(width 0.1397)
		(layer "In5.Cu")
		(net "PCIE_TX_CAP_P84")
	)
	(segment
		(start 151.321262 -39.670482)
		(end 152.081484 -40.20312)
		(width 0.1397)
		(layer "In5.Cu")
		(net "PCIE_TX_CAP_P84")
	)
	(segment
		(start 189.98946 -37.394134)
		(end 191.748156 -37.020246)
		(width 0.1397)
		(layer "In5.Cu")
		(net "PCIE_TX_CAP_P84")
	)
	(segment
		(start 163.579302 -43.246802)
		(end 169.092372 -42.0751)
		(width 0.1397)
		(layer "In5.Cu")
		(net "PCIE_TX_CAP_P84")
	)
	(segment
		(start 201.26198 -36.557966)
		(end 204.120496 -37.061648)
		(width 0.1397)
		(layer "In5.Cu")
		(net "PCIE_TX_CAP_P84")
	)
	(segment
		(start 211.297774 -35.79622)
		(end 219.064078 -37.16528)
		(width 0.1397)
		(layer "In5.Cu")
		(net "PCIE_TX_CAP_P84")
	)
	(segment
		(start 191.748156 -37.020246)
		(end 191.748156 -37.0205)
		(width 0.1397)
		(layer "In5.Cu")
		(net "PCIE_TX_CAP_P84")
	)
	(segment
		(start 221.6023 -37.10178)
		(end 223.442276 -37.10178)
		(width 0.1016)
		(layer "In5.Cu")
		(net "PCIE_TX_CAP_P84")
	)
	(segment
		(start 151.1554 -38.500304)
		(end 151.1554 -39.257224)
		(width 0.1397)
		(layer "In5.Cu")
		(net "PCIE_TX_CAP_P84")
	)
	(segment
		(start 221.5134 -37.16528)
		(end 221.5388 -37.16528)
		(width 0.1016)
		(layer "In5.Cu")
		(net "PCIE_TX_CAP_P84")
	)
	(segment
		(start 185.802778 -36.504118)
		(end 189.98946 -37.394134)
		(width 0.1397)
		(layer "In5.Cu")
		(net "PCIE_TX_CAP_P84")
	)
	(segment
		(start 173.713648 -39.073836)
		(end 185.802778 -36.504118)
		(width 0.1397)
		(layer "In5.Cu")
		(net "PCIE_TX_CAP_P84")
	)
	(segment
		(start 169.092372 -42.0751)
		(end 173.713648 -39.073836)
		(width 0.1397)
		(layer "In5.Cu")
		(net "PCIE_TX_CAP_P84")
	)
	(segment
		(start 151.1554 -39.257224)
		(end 151.321262 -39.670482)
		(width 0.1397)
		(layer "In5.Cu")
		(net "PCIE_TX_CAP_P84")
	)
	(segment
		(start 223.753426 -36.973002)
		(end 223.784414 -36.942268)
		(width 0.1016)
		(layer "In5.Cu")
		(net "PCIE_TX_CAP_P84")
	)
	(segment
		(start 196.138292 -37.46119)
		(end 201.26198 -36.557966)
		(width 0.1397)
		(layer "In5.Cu")
		(net "PCIE_TX_CAP_P84")
	)
	(segment
		(start 219.064078 -37.16528)
		(end 221.5134 -37.16528)
		(width 0.1397)
		(layer "In5.Cu")
		(net "PCIE_TX_CAP_P84")
	)
	(segment
		(start 192.691258 -36.853876)
		(end 196.138292 -37.46119)
		(width 0.1397)
		(layer "In5.Cu")
		(net "PCIE_TX_CAP_P84")
	)
	(segment
		(start 155.983432 -41.033954)
		(end 157.18282 -41.884854)
		(width 0.1397)
		(layer "In5.Cu")
		(net "PCIE_TX_CAP_P84")
	)
	(arc
		(start 223.784414 -36.942268)
		(mid 223.960601 -36.734244)
		(end 224.100136 -36.500054)
		(width 0.1016)
		(layer "In5.Cu")
		(net "PCIE_TX_CAP_P84")
	)
	(arc
		(start 223.442276 -37.10178)
		(mid 223.610683 -37.068375)
		(end 223.753426 -36.973002)
		(width 0.1016)
		(layer "In5.Cu")
		(net "PCIE_TX_CAP_P84")
	)
	(arc
		(start 150.9141 -38.0873)
		(mid 151.09061 -38.261156)
		(end 151.1554 -38.500304)
		(width 0.1397)
		(layer "In5.Cu")
		(net "PCIE_TX_CAP_P84")
	)
	(segment
		(start 137.8204 -34.336228)
		(end 137.8204 -34.739326)
		(width 0.136652)
		(layer "F.Cu")
		(net "PCIE_TX_CAP_P83")
	)
	(segment
		(start 137.5283 -33.98774)
		(end 137.780268 -34.239454)
		(width 0.136652)
		(layer "F.Cu")
		(net "PCIE_TX_CAP_P83")
	)
	(segment
		(start 223.60001 -37.999924)
		(end 223.100138 -37.500052)
		(width 0.136652)
		(layer "F.Cu")
		(net "PCIE_TX_CAP_P83")
	)
	(via
		(at 223.100138 -37.500052)
		(size 0.4572)
		(drill 0.2032)
		(layers "F.Cu" "B.Cu")
		(net "PCIE_TX_CAP_P83")
	)
	(via
		(at 137.5664 -34.993326)
		(size 0.508)
		(drill 0.254)
		(layers "F.Cu" "B.Cu")
		(net "PCIE_TX_CAP_P83")
	)
	(arc
		(start 137.8204 -34.739326)
		(mid 137.746005 -34.918931)
		(end 137.5664 -34.993326)
		(width 0.136652)
		(layer "F.Cu")
		(net "PCIE_TX_CAP_P83")
	)
	(arc
		(start 137.780268 -34.239454)
		(mid 137.809989 -34.28384)
		(end 137.8204 -34.336228)
		(width 0.136652)
		(layer "F.Cu")
		(net "PCIE_TX_CAP_P83")
	)
	(segment
		(start 171.79417 -41.749218)
		(end 193.263266 -37.958776)
		(width 0.1397)
		(layer "In5.Cu")
		(net "PCIE_TX_CAP_P83")
	)
	(segment
		(start 211.553298 -36.844732)
		(end 219.187014 -38.1889)
		(width 0.1397)
		(layer "In5.Cu")
		(net "PCIE_TX_CAP_P83")
	)
	(segment
		(start 139.275566 -36.113212)
		(end 139.74445 -36.417758)
		(width 0.1397)
		(layer "In5.Cu")
		(net "PCIE_TX_CAP_P83")
	)
	(segment
		(start 221.400624 -38.1889)
		(end 221.413324 -38.1762)
		(width 0.1016)
		(layer "In5.Cu")
		(net "PCIE_TX_CAP_P83")
	)
	(segment
		(start 139.74445 -36.417758)
		(end 139.753594 -36.417758)
		(width 0.1397)
		(layer "In5.Cu")
		(net "PCIE_TX_CAP_P83")
	)
	(segment
		(start 204.001624 -38.168072)
		(end 211.553298 -36.844732)
		(width 0.1397)
		(layer "In5.Cu")
		(net "PCIE_TX_CAP_P83")
	)
	(segment
		(start 201.332338 -37.698172)
		(end 204.001624 -38.168072)
		(width 0.1397)
		(layer "In5.Cu")
		(net "PCIE_TX_CAP_P83")
	)
	(segment
		(start 156.781754 -42.799508)
		(end 163.70681 -44.274232)
		(width 0.1397)
		(layer "In5.Cu")
		(net "PCIE_TX_CAP_P83")
	)
	(segment
		(start 138.30427 -35.99434)
		(end 138.874246 -35.99434)
		(width 0.1397)
		(layer "In5.Cu")
		(net "PCIE_TX_CAP_P83")
	)
	(segment
		(start 137.8077 -35.200336)
		(end 137.8077 -35.49777)
		(width 0.1397)
		(layer "In5.Cu")
		(net "PCIE_TX_CAP_P83")
	)
	(segment
		(start 147.332192 -40.19169)
		(end 147.334224 -40.192198)
		(width 0.1397)
		(layer "In5.Cu")
		(net "PCIE_TX_CAP_P83")
	)
	(segment
		(start 137.5664 -34.993326)
		(end 137.60069 -34.993326)
		(width 0.1397)
		(layer "In5.Cu")
		(net "PCIE_TX_CAP_P83")
	)
	(segment
		(start 222.828104 -37.47516)
		(end 223.075246 -37.47516)
		(width 0.1016)
		(layer "In5.Cu")
		(net "PCIE_TX_CAP_P83")
	)
	(segment
		(start 169.940986 -42.952416)
		(end 171.79417 -41.749218)
		(width 0.1397)
		(layer "In5.Cu")
		(net "PCIE_TX_CAP_P83")
	)
	(segment
		(start 196.557392 -38.53942)
		(end 201.332338 -37.698172)
		(width 0.1397)
		(layer "In5.Cu")
		(net "PCIE_TX_CAP_P83")
	)
	(segment
		(start 221.413324 -38.1762)
		(end 221.413324 -38.153848)
		(width 0.1016)
		(layer "In5.Cu")
		(net "PCIE_TX_CAP_P83")
	)
	(segment
		(start 221.413324 -38.153848)
		(end 221.441772 -38.1254)
		(width 0.1016)
		(layer "In5.Cu")
		(net "PCIE_TX_CAP_P83")
	)
	(segment
		(start 140.051028 -36.5252)
		(end 143.139414 -37.182044)
		(width 0.1397)
		(layer "In5.Cu")
		(net "PCIE_TX_CAP_P83")
	)
	(segment
		(start 193.263266 -37.958776)
		(end 196.557392 -38.53942)
		(width 0.1397)
		(layer "In5.Cu")
		(net "PCIE_TX_CAP_P83")
	)
	(segment
		(start 223.075246 -37.47516)
		(end 223.100138 -37.500052)
		(width 0.1016)
		(layer "In5.Cu")
		(net "PCIE_TX_CAP_P83")
	)
	(segment
		(start 163.70681 -44.274232)
		(end 169.940986 -42.952416)
		(width 0.1397)
		(layer "In5.Cu")
		(net "PCIE_TX_CAP_P83")
	)
	(segment
		(start 155.58262 -41.948862)
		(end 156.781754 -42.799508)
		(width 0.1397)
		(layer "In5.Cu")
		(net "PCIE_TX_CAP_P83")
	)
	(segment
		(start 222.701612 -37.611812)
		(end 222.701612 -37.601652)
		(width 0.1016)
		(layer "In5.Cu")
		(net "PCIE_TX_CAP_P83")
	)
	(segment
		(start 221.441772 -38.1254)
		(end 222.188024 -38.1254)
		(width 0.1016)
		(layer "In5.Cu")
		(net "PCIE_TX_CAP_P83")
	)
	(segment
		(start 147.334224 -40.192198)
		(end 155.58262 -41.948862)
		(width 0.1397)
		(layer "In5.Cu")
		(net "PCIE_TX_CAP_P83")
	)
	(segment
		(start 221.387924 -38.1889)
		(end 221.400624 -38.1889)
		(width 0.1016)
		(layer "In5.Cu")
		(net "PCIE_TX_CAP_P83")
	)
	(segment
		(start 219.187014 -38.1889)
		(end 221.387924 -38.1889)
		(width 0.1397)
		(layer "In5.Cu")
		(net "PCIE_TX_CAP_P83")
	)
	(segment
		(start 143.139414 -37.182044)
		(end 147.332192 -40.19169)
		(width 0.1397)
		(layer "In5.Cu")
		(net "PCIE_TX_CAP_P83")
	)
	(arc
		(start 139.753594 -36.417758)
		(mid 139.898609 -36.481727)
		(end 140.051028 -36.5252)
		(width 0.1397)
		(layer "In5.Cu")
		(net "PCIE_TX_CAP_P83")
	)
	(arc
		(start 222.188024 -38.1254)
		(mid 222.551186 -37.974974)
		(end 222.701612 -37.611812)
		(width 0.1016)
		(layer "In5.Cu")
		(net "PCIE_TX_CAP_P83")
	)
	(arc
		(start 222.701612 -37.601652)
		(mid 222.738661 -37.512209)
		(end 222.828104 -37.47516)
		(width 0.1016)
		(layer "In5.Cu")
		(net "PCIE_TX_CAP_P83")
	)
	(arc
		(start 137.8077 -35.49777)
		(mid 137.953142 -35.848898)
		(end 138.30427 -35.99434)
		(width 0.1397)
		(layer "In5.Cu")
		(net "PCIE_TX_CAP_P83")
	)
	(arc
		(start 138.874246 -35.99434)
		(mid 139.083505 -36.024731)
		(end 139.275566 -36.113212)
		(width 0.1397)
		(layer "In5.Cu")
		(net "PCIE_TX_CAP_P83")
	)
	(arc
		(start 137.60069 -34.993326)
		(mid 137.747068 -35.053958)
		(end 137.8077 -35.200336)
		(width 0.1397)
		(layer "In5.Cu")
		(net "PCIE_TX_CAP_P83")
	)
	(segment
		(start 134.106158 -35.358578)
		(end 134.106158 -35.485832)
		(width 0.136652)
		(layer "F.Cu")
		(net "PCIE_TX_CAP_P82")
	)
	(segment
		(start 224.600008 -38.999922)
		(end 224.100136 -38.50005)
		(width 0.136652)
		(layer "F.Cu")
		(net "PCIE_TX_CAP_P82")
	)
	(segment
		(start 133.656832 -34.764472)
		(end 134.003796 -35.111436)
		(width 0.136652)
		(layer "F.Cu")
		(net "PCIE_TX_CAP_P82")
	)
	(via
		(at 133.852158 -35.739832)
		(size 0.508)
		(drill 0.254)
		(layers "F.Cu" "B.Cu")
		(net "PCIE_TX_CAP_P82")
	)
	(via
		(at 224.100136 -38.50005)
		(size 0.4572)
		(drill 0.2032)
		(layers "F.Cu" "B.Cu")
		(net "PCIE_TX_CAP_P82")
	)
	(arc
		(start 133.5024 -34.3916)
		(mid 133.542539 -34.593391)
		(end 133.656832 -34.764472)
		(width 0.136652)
		(layer "F.Cu")
		(net "PCIE_TX_CAP_P82")
	)
	(arc
		(start 134.003796 -35.111436)
		(mid 134.079561 -35.224826)
		(end 134.106158 -35.358578)
		(width 0.136652)
		(layer "F.Cu")
		(net "PCIE_TX_CAP_P82")
	)
	(arc
		(start 133.2103 -33.98774)
		(mid 133.421742 -34.14238)
		(end 133.5024 -34.3916)
		(width 0.136652)
		(layer "F.Cu")
		(net "PCIE_TX_CAP_P82")
	)
	(arc
		(start 134.106158 -35.485832)
		(mid 134.031763 -35.665437)
		(end 133.852158 -35.739832)
		(width 0.136652)
		(layer "F.Cu")
		(net "PCIE_TX_CAP_P82")
	)
	(segment
		(start 204.1144 -39.188644)
		(end 211.721192 -37.847016)
		(width 0.1397)
		(layer "In5.Cu")
		(net "PCIE_TX_CAP_P82")
	)
	(segment
		(start 221.615 -39.165276)
		(end 221.6785 -39.101776)
		(width 0.1016)
		(layer "In5.Cu")
		(net "PCIE_TX_CAP_P82")
	)
	(segment
		(start 224.076006 -38.47592)
		(end 224.100136 -38.50005)
		(width 0.1016)
		(layer "In5.Cu")
		(net "PCIE_TX_CAP_P82")
	)
	(segment
		(start 172.617892 -42.391076)
		(end 192.785746 -38.83025)
		(width 0.1397)
		(layer "In5.Cu")
		(net "PCIE_TX_CAP_P82")
	)
	(segment
		(start 139.098528 -37.142166)
		(end 141.45133 -37.641784)
		(width 0.1397)
		(layer "In5.Cu")
		(net "PCIE_TX_CAP_P82")
	)
	(segment
		(start 223.82734 -38.47592)
		(end 224.076006 -38.47592)
		(width 0.1016)
		(layer "In5.Cu")
		(net "PCIE_TX_CAP_P82")
	)
	(segment
		(start 196.647054 -39.51097)
		(end 201.295254 -38.691566)
		(width 0.1397)
		(layer "In5.Cu")
		(net "PCIE_TX_CAP_P82")
	)
	(segment
		(start 141.45133 -37.641784)
		(end 147.93595 -41.853104)
		(width 0.1397)
		(layer "In5.Cu")
		(net "PCIE_TX_CAP_P82")
	)
	(segment
		(start 192.785746 -38.83025)
		(end 196.647054 -39.51097)
		(width 0.1397)
		(layer "In5.Cu")
		(net "PCIE_TX_CAP_P82")
	)
	(segment
		(start 211.721192 -37.847016)
		(end 219.195904 -39.165276)
		(width 0.1397)
		(layer "In5.Cu")
		(net "PCIE_TX_CAP_P82")
	)
	(segment
		(start 163.816538 -45.231558)
		(end 170.397424 -43.83278)
		(width 0.1397)
		(layer "In5.Cu")
		(net "PCIE_TX_CAP_P82")
	)
	(segment
		(start 223.70161 -38.70325)
		(end 223.70161 -38.60165)
		(width 0.1016)
		(layer "In5.Cu")
		(net "PCIE_TX_CAP_P82")
	)
	(segment
		(start 134.641082 -36.7919)
		(end 138.409426 -36.7919)
		(width 0.1397)
		(layer "In5.Cu")
		(net "PCIE_TX_CAP_P82")
	)
	(segment
		(start 170.397424 -43.83278)
		(end 172.617892 -42.391076)
		(width 0.1397)
		(layer "In5.Cu")
		(net "PCIE_TX_CAP_P82")
	)
	(segment
		(start 221.6785 -39.101776)
		(end 223.303084 -39.101776)
		(width 0.1016)
		(layer "In5.Cu")
		(net "PCIE_TX_CAP_P82")
	)
	(segment
		(start 201.295254 -38.691566)
		(end 204.1144 -39.188644)
		(width 0.1397)
		(layer "In5.Cu")
		(net "PCIE_TX_CAP_P82")
	)
	(segment
		(start 219.195904 -39.165276)
		(end 221.5896 -39.165276)
		(width 0.1397)
		(layer "In5.Cu")
		(net "PCIE_TX_CAP_P82")
	)
	(segment
		(start 221.5896 -39.165276)
		(end 221.615 -39.165276)
		(width 0.1016)
		(layer "In5.Cu")
		(net "PCIE_TX_CAP_P82")
	)
	(segment
		(start 133.852158 -35.739832)
		(end 133.886448 -35.739832)
		(width 0.1397)
		(layer "In5.Cu")
		(net "PCIE_TX_CAP_P82")
	)
	(segment
		(start 134.093458 -35.946842)
		(end 134.093458 -36.244276)
		(width 0.1397)
		(layer "In5.Cu")
		(net "PCIE_TX_CAP_P82")
	)
	(segment
		(start 147.93595 -41.853104)
		(end 163.816538 -45.231558)
		(width 0.1397)
		(layer "In5.Cu")
		(net "PCIE_TX_CAP_P82")
	)
	(arc
		(start 133.886448 -35.739832)
		(mid 134.032826 -35.800464)
		(end 134.093458 -35.946842)
		(width 0.1397)
		(layer "In5.Cu")
		(net "PCIE_TX_CAP_P82")
	)
	(arc
		(start 223.303084 -39.101776)
		(mid 223.584884 -38.98505)
		(end 223.70161 -38.70325)
		(width 0.1016)
		(layer "In5.Cu")
		(net "PCIE_TX_CAP_P82")
	)
	(arc
		(start 223.70161 -38.60165)
		(mid 223.738435 -38.512745)
		(end 223.82734 -38.47592)
		(width 0.1016)
		(layer "In5.Cu")
		(net "PCIE_TX_CAP_P82")
	)
	(arc
		(start 138.59637 -36.869624)
		(mid 138.827678 -37.042327)
		(end 139.098528 -37.142166)
		(width 0.1397)
		(layer "In5.Cu")
		(net "PCIE_TX_CAP_P82")
	)
	(arc
		(start 138.409426 -36.7919)
		(mid 138.510642 -36.812145)
		(end 138.59637 -36.869624)
		(width 0.1397)
		(layer "In5.Cu")
		(net "PCIE_TX_CAP_P82")
	)
	(arc
		(start 134.093458 -36.244276)
		(mid 134.253853 -36.631505)
		(end 134.641082 -36.7919)
		(width 0.1397)
		(layer "In5.Cu")
		(net "PCIE_TX_CAP_P82")
	)
	(segment
		(start 223.60001 -39.99992)
		(end 223.100138 -39.500048)
		(width 0.136652)
		(layer "F.Cu")
		(net "PCIE_TX_CAP_P81")
	)
	(segment
		(start 131.23037 -34.166556)
		(end 131.0513 -33.98774)
		(width 0.136652)
		(layer "F.Cu")
		(net "PCIE_TX_CAP_P81")
	)
	(segment
		(start 131.3434 -35.019234)
		(end 131.3434 -34.43986)
		(width 0.136652)
		(layer "F.Cu")
		(net "PCIE_TX_CAP_P81")
	)
	(via
		(at 223.100138 -39.500048)
		(size 0.4572)
		(drill 0.2032)
		(layers "F.Cu" "B.Cu")
		(net "PCIE_TX_CAP_P81")
	)
	(via
		(at 131.0894 -35.273234)
		(size 0.508)
		(drill 0.254)
		(layers "F.Cu" "B.Cu")
		(net "PCIE_TX_CAP_P81")
	)
	(arc
		(start 131.3434 -34.43986)
		(mid 131.314075 -34.291963)
		(end 131.23037 -34.166556)
		(width 0.136652)
		(layer "F.Cu")
		(net "PCIE_TX_CAP_P81")
	)
	(arc
		(start 131.0894 -35.273234)
		(mid 131.269005 -35.198839)
		(end 131.3434 -35.019234)
		(width 0.136652)
		(layer "F.Cu")
		(net "PCIE_TX_CAP_P81")
	)
	(segment
		(start 221.310962 -40.165274)
		(end 221.374462 -40.101774)
		(width 0.1016)
		(layer "In5.Cu")
		(net "PCIE_TX_CAP_P81")
	)
	(segment
		(start 140.142976 -38.18128)
		(end 147.066 -42.676572)
		(width 0.1397)
		(layer "In5.Cu")
		(net "PCIE_TX_CAP_P81")
	)
	(segment
		(start 173.482 -43.038522)
		(end 192.218818 -39.730426)
		(width 0.1397)
		(layer "In5.Cu")
		(net "PCIE_TX_CAP_P81")
	)
	(segment
		(start 211.8868 -38.827202)
		(end 219.477844 -40.165274)
		(width 0.1397)
		(layer "In5.Cu")
		(net "PCIE_TX_CAP_P81")
	)
	(segment
		(start 196.349366 -40.458644)
		(end 201.048874 -39.630096)
		(width 0.1397)
		(layer "In5.Cu")
		(net "PCIE_TX_CAP_P81")
	)
	(segment
		(start 131.3307 -35.480244)
		(end 131.3307 -35.924998)
		(width 0.1397)
		(layer "In5.Cu")
		(net "PCIE_TX_CAP_P81")
	)
	(segment
		(start 137.608564 -37.6428)
		(end 137.608818 -37.643054)
		(width 0.1397)
		(layer "In5.Cu")
		(net "PCIE_TX_CAP_P81")
	)
	(segment
		(start 221.374462 -40.101774)
		(end 222.42399 -40.101774)
		(width 0.1016)
		(layer "In5.Cu")
		(net "PCIE_TX_CAP_P81")
	)
	(segment
		(start 192.218818 -39.730426)
		(end 196.349366 -40.458644)
		(width 0.1397)
		(layer "In5.Cu")
		(net "PCIE_TX_CAP_P81")
	)
	(segment
		(start 201.048874 -39.630096)
		(end 204.1906 -40.18407)
		(width 0.1397)
		(layer "In5.Cu")
		(net "PCIE_TX_CAP_P81")
	)
	(segment
		(start 147.066 -42.676572)
		(end 163.45408 -46.159928)
		(width 0.1397)
		(layer "In5.Cu")
		(net "PCIE_TX_CAP_P81")
	)
	(segment
		(start 221.285562 -40.165274)
		(end 221.310962 -40.165274)
		(width 0.1016)
		(layer "In5.Cu")
		(net "PCIE_TX_CAP_P81")
	)
	(segment
		(start 219.477844 -40.165274)
		(end 221.285562 -40.165274)
		(width 0.1397)
		(layer "In5.Cu")
		(net "PCIE_TX_CAP_P81")
	)
	(segment
		(start 131.0894 -35.273234)
		(end 131.12369 -35.273234)
		(width 0.1397)
		(layer "In5.Cu")
		(net "PCIE_TX_CAP_P81")
	)
	(segment
		(start 204.1906 -40.18407)
		(end 211.8868 -38.827202)
		(width 0.1397)
		(layer "In5.Cu")
		(net "PCIE_TX_CAP_P81")
	)
	(segment
		(start 163.45408 -46.159928)
		(end 171.21505 -44.510706)
		(width 0.1397)
		(layer "In5.Cu")
		(net "PCIE_TX_CAP_P81")
	)
	(segment
		(start 133.258306 -37.6428)
		(end 137.608564 -37.6428)
		(width 0.1397)
		(layer "In5.Cu")
		(net "PCIE_TX_CAP_P81")
	)
	(segment
		(start 137.608818 -37.643054)
		(end 140.142976 -38.18128)
		(width 0.1397)
		(layer "In5.Cu")
		(net "PCIE_TX_CAP_P81")
	)
	(segment
		(start 171.21505 -44.510706)
		(end 173.482 -43.038522)
		(width 0.1397)
		(layer "In5.Cu")
		(net "PCIE_TX_CAP_P81")
	)
	(segment
		(start 131.524502 -36.393882)
		(end 132.431028 -37.300154)
		(width 0.1397)
		(layer "In5.Cu")
		(net "PCIE_TX_CAP_P81")
	)
	(arc
		(start 131.3307 -35.924998)
		(mid 131.380978 -36.178704)
		(end 131.524502 -36.393882)
		(width 0.1397)
		(layer "In5.Cu")
		(net "PCIE_TX_CAP_P81")
	)
	(arc
		(start 132.431028 -37.300154)
		(mid 132.810586 -37.553767)
		(end 133.258306 -37.6428)
		(width 0.1397)
		(layer "In5.Cu")
		(net "PCIE_TX_CAP_P81")
	)
	(arc
		(start 222.72625 -40.023288)
		(mid 222.97199 -39.803671)
		(end 223.100138 -39.500048)
		(width 0.1016)
		(layer "In5.Cu")
		(net "PCIE_TX_CAP_P81")
	)
	(arc
		(start 131.12369 -35.273234)
		(mid 131.270068 -35.333866)
		(end 131.3307 -35.480244)
		(width 0.1397)
		(layer "In5.Cu")
		(net "PCIE_TX_CAP_P81")
	)
	(arc
		(start 222.42399 -40.101774)
		(mid 222.58014 -40.081863)
		(end 222.72625 -40.023288)
		(width 0.1016)
		(layer "In5.Cu")
		(net "PCIE_TX_CAP_P81")
	)
	(segment
		(start 135.6614 -34.476436)
		(end 135.6614 -35.48761)
		(width 0.136652)
		(layer "F.Cu")
		(net "PCIE_TX_CAP_P80")
	)
	(segment
		(start 135.936736 -36.152328)
		(end 136.308592 -36.524184)
		(width 0.136652)
		(layer "F.Cu")
		(net "PCIE_TX_CAP_P80")
	)
	(segment
		(start 224.600008 -40.999918)
		(end 224.100136 -40.500046)
		(width 0.136652)
		(layer "F.Cu")
		(net "PCIE_TX_CAP_P80")
	)
	(segment
		(start 138.197844 -37.008562)
		(end 138.666474 -37.477192)
		(width 0.136652)
		(layer "F.Cu")
		(net "PCIE_TX_CAP_P80")
	)
	(segment
		(start 136.894062 -36.7665)
		(end 137.613898 -36.7665)
		(width 0.136652)
		(layer "F.Cu")
		(net "PCIE_TX_CAP_P80")
	)
	(segment
		(start 138.786362 -37.766244)
		(end 138.786362 -38.33876)
		(width 0.136652)
		(layer "F.Cu")
		(net "PCIE_TX_CAP_P80")
	)
	(segment
		(start 135.3693 -33.98774)
		(end 135.522462 -34.140648)
		(width 0.136652)
		(layer "F.Cu")
		(net "PCIE_TX_CAP_P80")
	)
	(via
		(at 138.557 -38.6588)
		(size 0.508)
		(drill 0.254)
		(layers "F.Cu" "B.Cu")
		(net "PCIE_TX_CAP_P80")
	)
	(via
		(at 224.100136 -40.500046)
		(size 0.4572)
		(drill 0.2032)
		(layers "F.Cu" "B.Cu")
		(net "PCIE_TX_CAP_P80")
	)
	(arc
		(start 136.308592 -36.524184)
		(mid 136.577237 -36.703531)
		(end 136.894062 -36.7665)
		(width 0.136652)
		(layer "F.Cu")
		(net "PCIE_TX_CAP_P80")
	)
	(arc
		(start 137.613898 -36.7665)
		(mid 137.92993 -36.829474)
		(end 138.197844 -37.008562)
		(width 0.136652)
		(layer "F.Cu")
		(net "PCIE_TX_CAP_P80")
	)
	(arc
		(start 135.6614 -35.48761)
		(mid 135.732972 -35.847339)
		(end 135.936736 -36.152328)
		(width 0.136652)
		(layer "F.Cu")
		(net "PCIE_TX_CAP_P80")
	)
	(arc
		(start 138.786362 -38.33876)
		(mid 138.72311 -38.535652)
		(end 138.557 -38.6588)
		(width 0.136652)
		(layer "F.Cu")
		(net "PCIE_TX_CAP_P80")
	)
	(arc
		(start 135.522462 -34.140648)
		(mid 135.625319 -34.294724)
		(end 135.6614 -34.476436)
		(width 0.136652)
		(layer "F.Cu")
		(net "PCIE_TX_CAP_P80")
	)
	(arc
		(start 138.666474 -37.477192)
		(mid 138.75517 -37.609795)
		(end 138.786362 -37.766244)
		(width 0.136652)
		(layer "F.Cu")
		(net "PCIE_TX_CAP_P80")
	)
	(segment
		(start 191.93764 -40.631364)
		(end 196.385942 -41.415462)
		(width 0.1397)
		(layer "In5.Cu")
		(net "PCIE_TX_CAP_P80")
	)
	(segment
		(start 141.91234 -40.913558)
		(end 141.912594 -40.913304)
		(width 0.1397)
		(layer "In5.Cu")
		(net "PCIE_TX_CAP_P80")
	)
	(segment
		(start 163.627054 -47.048674)
		(end 171.536868 -45.366686)
		(width 0.1397)
		(layer "In5.Cu")
		(net "PCIE_TX_CAP_P80")
	)
	(segment
		(start 221.615 -41.165272)
		(end 221.6785 -41.101772)
		(width 0.1016)
		(layer "In5.Cu")
		(net "PCIE_TX_CAP_P80")
	)
	(segment
		(start 139.391644 -40.255444)
		(end 141.911832 -40.913304)
		(width 0.1397)
		(layer "In5.Cu")
		(net "PCIE_TX_CAP_P80")
	)
	(segment
		(start 173.881288 -43.812206)
		(end 191.93764 -40.631364)
		(width 0.1397)
		(layer "In5.Cu")
		(net "PCIE_TX_CAP_P80")
	)
	(segment
		(start 141.912594 -40.913304)
		(end 145.394172 -43.172634)
		(width 0.1397)
		(layer "In5.Cu")
		(net "PCIE_TX_CAP_P80")
	)
	(segment
		(start 196.385942 -41.415462)
		(end 200.914254 -40.617394)
		(width 0.1397)
		(layer "In5.Cu")
		(net "PCIE_TX_CAP_P80")
	)
	(segment
		(start 204.070966 -41.173908)
		(end 211.517484 -39.860728)
		(width 0.1397)
		(layer "In5.Cu")
		(net "PCIE_TX_CAP_P80")
	)
	(segment
		(start 218.917266 -41.165272)
		(end 221.5896 -41.165272)
		(width 0.1397)
		(layer "In5.Cu")
		(net "PCIE_TX_CAP_P80")
	)
	(segment
		(start 171.536868 -45.366686)
		(end 171.57319 -45.310806)
		(width 0.1397)
		(layer "In5.Cu")
		(net "PCIE_TX_CAP_P80")
	)
	(segment
		(start 221.5896 -41.165272)
		(end 221.615 -41.165272)
		(width 0.1016)
		(layer "In5.Cu")
		(net "PCIE_TX_CAP_P80")
	)
	(segment
		(start 171.57319 -45.310806)
		(end 173.881288 -43.812206)
		(width 0.1397)
		(layer "In5.Cu")
		(net "PCIE_TX_CAP_P80")
	)
	(segment
		(start 141.911832 -40.913304)
		(end 141.911832 -40.91305)
		(width 0.1397)
		(layer "In5.Cu")
		(net "PCIE_TX_CAP_P80")
	)
	(segment
		(start 138.811 -38.9128)
		(end 138.811 -39.34079)
		(width 0.1397)
		(layer "In5.Cu")
		(net "PCIE_TX_CAP_P80")
	)
	(segment
		(start 141.911832 -40.91305)
		(end 141.91234 -40.913558)
		(width 0.1397)
		(layer "In5.Cu")
		(net "PCIE_TX_CAP_P80")
	)
	(segment
		(start 221.6785 -41.101772)
		(end 223.303084 -41.101772)
		(width 0.1016)
		(layer "In5.Cu")
		(net "PCIE_TX_CAP_P80")
	)
	(segment
		(start 200.914254 -40.617394)
		(end 204.070966 -41.173908)
		(width 0.1397)
		(layer "In5.Cu")
		(net "PCIE_TX_CAP_P80")
	)
	(segment
		(start 224.0153 -40.500046)
		(end 224.100136 -40.500046)
		(width 0.1016)
		(layer "In5.Cu")
		(net "PCIE_TX_CAP_P80")
	)
	(segment
		(start 211.517484 -39.860728)
		(end 218.917266 -41.165272)
		(width 0.1397)
		(layer "In5.Cu")
		(net "PCIE_TX_CAP_P80")
	)
	(segment
		(start 145.394172 -43.172634)
		(end 163.627054 -47.048674)
		(width 0.1397)
		(layer "In5.Cu")
		(net "PCIE_TX_CAP_P80")
	)
	(segment
		(start 139.046966 -39.91102)
		(end 139.391644 -40.255444)
		(width 0.1397)
		(layer "In5.Cu")
		(net "PCIE_TX_CAP_P80")
	)
	(arc
		(start 138.811 -39.34079)
		(mid 138.872285 -39.649362)
		(end 139.046966 -39.91102)
		(width 0.1397)
		(layer "In5.Cu")
		(net "PCIE_TX_CAP_P80")
	)
	(arc
		(start 223.696022 -40.769794)
		(mid 223.80632 -40.576525)
		(end 224.0153 -40.500046)
		(width 0.1016)
		(layer "In5.Cu")
		(net "PCIE_TX_CAP_P80")
	)
	(arc
		(start 138.557 -38.6588)
		(mid 138.736605 -38.733195)
		(end 138.811 -38.9128)
		(width 0.1397)
		(layer "In5.Cu")
		(net "PCIE_TX_CAP_P80")
	)
	(arc
		(start 223.303084 -41.101772)
		(mid 223.560283 -41.007666)
		(end 223.696022 -40.769794)
		(width 0.1016)
		(layer "In5.Cu")
		(net "PCIE_TX_CAP_P80")
	)
	(segment
		(start 306.219606 -34.4424)
		(end 306.219606 -35.891216)
		(width 0.136652)
		(layer "F.Cu")
		(net "PCIE_TX_CAP_P8")
	)
	(segment
		(start 306.016914 -36.093908)
		(end 306.016914 -39.55542)
		(width 0.136652)
		(layer "F.Cu")
		(net "PCIE_TX_CAP_P8")
	)
	(segment
		(start 306.219606 -35.891216)
		(end 306.016914 -36.093908)
		(width 0.136652)
		(layer "F.Cu")
		(net "PCIE_TX_CAP_P8")
	)
	(segment
		(start 257.599942 -33.999932)
		(end 258.099814 -33.50006)
		(width 0.136652)
		(layer "F.Cu")
		(net "PCIE_TX_CAP_P8")
	)
	(segment
		(start 305.930046 -33.95472)
		(end 306.079398 -34.104326)
		(width 0.136652)
		(layer "F.Cu")
		(net "PCIE_TX_CAP_P8")
	)
	(segment
		(start 306.016914 -39.55542)
		(end 305.762914 -39.80942)
		(width 0.136652)
		(layer "F.Cu")
		(net "PCIE_TX_CAP_P8")
	)
	(via
		(at 305.762914 -39.80942)
		(size 0.508)
		(drill 0.254)
		(layers "F.Cu" "B.Cu")
		(net "PCIE_TX_CAP_P8")
	)
	(via
		(at 258.099814 -33.50006)
		(size 0.4572)
		(drill 0.2032)
		(layers "F.Cu" "B.Cu")
		(net "PCIE_TX_CAP_P8")
	)
	(arc
		(start 306.079398 -34.104326)
		(mid 306.183122 -34.259421)
		(end 306.219606 -34.4424)
		(width 0.136652)
		(layer "F.Cu")
		(net "PCIE_TX_CAP_P8")
	)
	(segment
		(start 258.458462 -33.35147)
		(end 258.817364 -32.992568)
		(width 0.1016)
		(layer "In5.Cu")
		(net "PCIE_TX_CAP_P8")
	)
	(segment
		(start 260.297422 -32.938212)
		(end 260.322822 -32.938212)
		(width 0.1016)
		(layer "In5.Cu")
		(net "PCIE_TX_CAP_P8")
	)
	(segment
		(start 259.03682 -32.901636)
		(end 259.642864 -32.901636)
		(width 0.1016)
		(layer "In5.Cu")
		(net "PCIE_TX_CAP_P8")
	)
	(segment
		(start 306.004214 -40.05072)
		(end 305.762914 -39.80942)
		(width 0.1397)
		(layer "In5.Cu")
		(net "PCIE_TX_CAP_P8")
	)
	(segment
		(start 278.817324 -37.597842)
		(end 282.612592 -40.25519)
		(width 0.1397)
		(layer "In5.Cu")
		(net "PCIE_TX_CAP_P8")
	)
	(segment
		(start 267.708634 -31.854394)
		(end 273.617182 -32.896302)
		(width 0.1397)
		(layer "In5.Cu")
		(net "PCIE_TX_CAP_P8")
	)
	(segment
		(start 261.56158 -32.938212)
		(end 267.708634 -31.854394)
		(width 0.1397)
		(layer "In5.Cu")
		(net "PCIE_TX_CAP_P8")
	)
	(segment
		(start 260.233922 -33.001712)
		(end 260.297422 -32.938212)
		(width 0.1016)
		(layer "In5.Cu")
		(net "PCIE_TX_CAP_P8")
	)
	(segment
		(start 292.398704 -41.792144)
		(end 296.59326 -42.753026)
		(width 0.1397)
		(layer "In5.Cu")
		(net "PCIE_TX_CAP_P8")
	)
	(segment
		(start 306.004214 -40.395652)
		(end 306.004214 -40.05072)
		(width 0.1397)
		(layer "In5.Cu")
		(net "PCIE_TX_CAP_P8")
	)
	(segment
		(start 296.59326 -42.753026)
		(end 300.690788 -41.993566)
		(width 0.1397)
		(layer "In5.Cu")
		(net "PCIE_TX_CAP_P8")
	)
	(segment
		(start 282.612592 -40.25519)
		(end 291.281866 -41.989248)
		(width 0.1397)
		(layer "In5.Cu")
		(net "PCIE_TX_CAP_P8")
	)
	(segment
		(start 260.322822 -32.938212)
		(end 261.56158 -32.938212)
		(width 0.1397)
		(layer "In5.Cu")
		(net "PCIE_TX_CAP_P8")
	)
	(segment
		(start 305.535838 -40.864028)
		(end 306.004214 -40.395652)
		(width 0.1397)
		(layer "In5.Cu")
		(net "PCIE_TX_CAP_P8")
	)
	(segment
		(start 277.36038 -35.517074)
		(end 278.817324 -37.597842)
		(width 0.1397)
		(layer "In5.Cu")
		(net "PCIE_TX_CAP_P8")
	)
	(segment
		(start 291.281866 -41.989248)
		(end 292.398704 -41.792144)
		(width 0.1397)
		(layer "In5.Cu")
		(net "PCIE_TX_CAP_P8")
	)
	(segment
		(start 259.74294 -33.001712)
		(end 260.233922 -33.001712)
		(width 0.1016)
		(layer "In5.Cu")
		(net "PCIE_TX_CAP_P8")
	)
	(segment
		(start 259.642864 -32.901636)
		(end 259.74294 -33.001712)
		(width 0.1016)
		(layer "In5.Cu")
		(net "PCIE_TX_CAP_P8")
	)
	(segment
		(start 300.690788 -41.993566)
		(end 304.787046 -41.23436)
		(width 0.1397)
		(layer "In5.Cu")
		(net "PCIE_TX_CAP_P8")
	)
	(segment
		(start 273.617182 -32.896302)
		(end 277.36038 -35.517074)
		(width 0.1397)
		(layer "In5.Cu")
		(net "PCIE_TX_CAP_P8")
	)
	(segment
		(start 304.787046 -41.23436)
		(end 305.535838 -40.864028)
		(width 0.1397)
		(layer "In5.Cu")
		(net "PCIE_TX_CAP_P8")
	)
	(arc
		(start 258.099814 -33.50006)
		(mid 258.293926 -33.461449)
		(end 258.458462 -33.35147)
		(width 0.1016)
		(layer "In5.Cu")
		(net "PCIE_TX_CAP_P8")
	)
	(arc
		(start 258.817364 -32.992568)
		(mid 258.918051 -32.925291)
		(end 259.03682 -32.901636)
		(width 0.1016)
		(layer "In5.Cu")
		(net "PCIE_TX_CAP_P8")
	)
	(segment
		(start 18.692622 -118.138956)
		(end 18.655284 -118.534434)
		(width 0.136652)
		(layer "F.Cu")
		(net "PCIE_TX_CAP_P76")
	)
	(segment
		(start 23.671022 -111.810292)
		(end 23.600918 -111.798354)
		(width 0.136652)
		(layer "F.Cu")
		(net "PCIE_TX_CAP_P76")
	)
	(segment
		(start 202.639422 -46.94809)
		(end 206.451708 -46.13783)
		(width 0.136652)
		(layer "F.Cu")
		(net "PCIE_TX_CAP_P76")
	)
	(segment
		(start 23.672292 -111.810292)
		(end 23.671022 -111.810292)
		(width 0.136652)
		(layer "F.Cu")
		(net "PCIE_TX_CAP_P76")
	)
	(segment
		(start 21.033486 -112.98936)
		(end 19.363182 -115.560856)
		(width 0.136652)
		(layer "F.Cu")
		(net "PCIE_TX_CAP_P76")
	)
	(segment
		(start 217.592148 -47.507398)
		(end 218.06662 -47.40656)
		(width 0.136652)
		(layer "F.Cu")
		(net "PCIE_TX_CAP_P76")
	)
	(segment
		(start 218.06662 -47.40656)
		(end 218.713812 -47.269146)
		(width 0.136652)
		(layer "F.Cu")
		(net "PCIE_TX_CAP_P76")
	)
	(segment
		(start 21.71446 -124.050806)
		(end 22.00148 -124.050806)
		(width 0.136652)
		(layer "F.Cu")
		(net "PCIE_TX_CAP_P76")
	)
	(segment
		(start 22.412198 -112.027716)
		(end 22.282404 -112.105186)
		(width 0.136652)
		(layer "F.Cu")
		(net "PCIE_TX_CAP_P76")
	)
	(segment
		(start 218.76385 -47.247302)
		(end 221.332806 -45.448728)
		(width 0.136652)
		(layer "F.Cu")
		(net "PCIE_TX_CAP_P76")
	)
	(segment
		(start 200.547224 -48.542702)
		(end 200.813416 -48.132746)
		(width 0.136652)
		(layer "F.Cu")
		(net "PCIE_TX_CAP_P76")
	)
	(segment
		(start 200.813416 -48.132746)
		(end 202.639422 -46.94809)
		(width 0.136652)
		(layer "F.Cu")
		(net "PCIE_TX_CAP_P76")
	)
	(segment
		(start 215.243156 -48.006762)
		(end 217.592148 -47.507398)
		(width 0.136652)
		(layer "F.Cu")
		(net "PCIE_TX_CAP_P76")
	)
	(segment
		(start 200.4695 -48.90897)
		(end 200.547224 -48.542702)
		(width 0.136652)
		(layer "F.Cu")
		(net "PCIE_TX_CAP_P76")
	)
	(segment
		(start 206.451708 -46.13783)
		(end 215.243156 -48.006762)
		(width 0.136652)
		(layer "F.Cu")
		(net "PCIE_TX_CAP_P76")
	)
	(segment
		(start 18.655284 -118.758716)
		(end 19.267678 -121.59615)
		(width 0.136652)
		(layer "F.Cu")
		(net "PCIE_TX_CAP_P76")
	)
	(segment
		(start 19.496786 -122.016266)
		(end 21.40204 -123.92152)
		(width 0.136652)
		(layer "F.Cu")
		(net "PCIE_TX_CAP_P76")
	)
	(segment
		(start 23.304246 -111.802418)
		(end 22.668484 -111.929418)
		(width 0.136652)
		(layer "F.Cu")
		(net "PCIE_TX_CAP_P76")
	)
	(segment
		(start 22.230842 -112.137952)
		(end 21.069808 -112.951768)
		(width 0.136652)
		(layer "F.Cu")
		(net "PCIE_TX_CAP_P76")
	)
	(segment
		(start 200.4695 -49.26203)
		(end 200.4695 -48.90897)
		(width 0.136652)
		(layer "F.Cu")
		(net "PCIE_TX_CAP_P76")
	)
	(segment
		(start 18.655284 -118.534434)
		(end 18.655284 -118.758716)
		(width 0.136652)
		(layer "F.Cu")
		(net "PCIE_TX_CAP_P76")
	)
	(segment
		(start 22.00148 -124.050806)
		(end 22.28469 -124.334016)
		(width 0.136652)
		(layer "F.Cu")
		(net "PCIE_TX_CAP_P76")
	)
	(segment
		(start 19.111214 -116.169694)
		(end 18.692622 -118.138956)
		(width 0.136652)
		(layer "F.Cu")
		(net "PCIE_TX_CAP_P76")
	)
	(segment
		(start 221.411292 -45.42409)
		(end 223.209866 -45.42409)
		(width 0.136652)
		(layer "F.Cu")
		(net "PCIE_TX_CAP_P76")
	)
	(via
		(at 200.0504 -49.734216)
		(size 0.508)
		(drill 0.254)
		(layers "F.Cu" "B.Cu")
		(net "PCIE_TX_CAP_P76")
	)
	(via
		(at 24.473154 -111.4044)
		(size 0.508)
		(drill 0.254)
		(layers "F.Cu" "B.Cu")
		(net "PCIE_TX_CAP_P76")
	)
	(arc
		(start 218.713812 -47.269146)
		(mid 218.739942 -47.260764)
		(end 218.76385 -47.247302)
		(width 0.136652)
		(layer "F.Cu")
		(net "PCIE_TX_CAP_P76")
	)
	(arc
		(start 223.209866 -45.42409)
		(mid 223.962206 -45.57374)
		(end 224.600008 -45.999908)
		(width 0.136652)
		(layer "F.Cu")
		(net "PCIE_TX_CAP_P76")
	)
	(arc
		(start 21.40204 -123.92152)
		(mid 21.545395 -124.017213)
		(end 21.71446 -124.050806)
		(width 0.136652)
		(layer "F.Cu")
		(net "PCIE_TX_CAP_P76")
	)
	(arc
		(start 22.282404 -112.105186)
		(mid 22.256318 -112.121089)
		(end 22.230842 -112.137952)
		(width 0.136652)
		(layer "F.Cu")
		(net "PCIE_TX_CAP_P76")
	)
	(arc
		(start 200.0504 -49.734216)
		(mid 200.3495 -49.577649)
		(end 200.4695 -49.26203)
		(width 0.136652)
		(layer "F.Cu")
		(net "PCIE_TX_CAP_P76")
	)
	(arc
		(start 22.668484 -111.929418)
		(mid 22.536158 -111.967663)
		(end 22.412198 -112.027716)
		(width 0.136652)
		(layer "F.Cu")
		(net "PCIE_TX_CAP_P76")
	)
	(arc
		(start 23.600918 -111.798354)
		(mid 23.452395 -111.78673)
		(end 23.304246 -111.802418)
		(width 0.136652)
		(layer "F.Cu")
		(net "PCIE_TX_CAP_P76")
	)
	(arc
		(start 19.363182 -115.560856)
		(mid 19.209219 -115.853695)
		(end 19.111214 -116.169694)
		(width 0.136652)
		(layer "F.Cu")
		(net "PCIE_TX_CAP_P76")
	)
	(arc
		(start 19.267678 -121.59615)
		(mid 19.35196 -121.822715)
		(end 19.496786 -122.016266)
		(width 0.136652)
		(layer "F.Cu")
		(net "PCIE_TX_CAP_P76")
	)
	(arc
		(start 21.069808 -112.951768)
		(mid 21.049823 -112.968804)
		(end 21.033486 -112.98936)
		(width 0.136652)
		(layer "F.Cu")
		(net "PCIE_TX_CAP_P76")
	)
	(arc
		(start 221.332806 -45.448728)
		(mid 221.370153 -45.430374)
		(end 221.411292 -45.42409)
		(width 0.136652)
		(layer "F.Cu")
		(net "PCIE_TX_CAP_P76")
	)
	(arc
		(start 24.473154 -111.4044)
		(mid 24.118685 -111.698032)
		(end 23.672292 -111.810292)
		(width 0.136652)
		(layer "F.Cu")
		(net "PCIE_TX_CAP_P76")
	)
	(segment
		(start 44.2976 -101.48189)
		(end 50.89271 -100.080064)
		(width 0.1397)
		(layer "In2.Cu")
		(net "PCIE_TX_CAP_P76")
	)
	(segment
		(start 87.625936 -103.407464)
		(end 117.48262 -108.672376)
		(width 0.1397)
		(layer "In2.Cu")
		(net "PCIE_TX_CAP_P76")
	)
	(segment
		(start 127.296926 -108.9279)
		(end 134.303516 -107.438698)
		(width 0.1397)
		(layer "In2.Cu")
		(net "PCIE_TX_CAP_P76")
	)
	(segment
		(start 200.4568 -50.600102)
		(end 200.4568 -50.2412)
		(width 0.1397)
		(layer "In2.Cu")
		(net "PCIE_TX_CAP_P76")
	)
	(segment
		(start 193.5988 -56.674766)
		(end 194.586098 -55.265066)
		(width 0.1397)
		(layer "In2.Cu")
		(net "PCIE_TX_CAP_P76")
	)
	(segment
		(start 121.78792 -107.75696)
		(end 127.296926 -108.9279)
		(width 0.1397)
		(layer "In2.Cu")
		(net "PCIE_TX_CAP_P76")
	)
	(segment
		(start 195.66001 -53.791104)
		(end 200.393046 -50.71745)
		(width 0.1397)
		(layer "In2.Cu")
		(net "PCIE_TX_CAP_P76")
	)
	(segment
		(start 36.912296 -103.171752)
		(end 39.097458 -102.70744)
		(width 0.1397)
		(layer "In2.Cu")
		(net "PCIE_TX_CAP_P76")
	)
	(segment
		(start 141.8463 -102.540308)
		(end 148.528786 -101.362002)
		(width 0.1397)
		(layer "In2.Cu")
		(net "PCIE_TX_CAP_P76")
	)
	(segment
		(start 40.740076 -101.897434)
		(end 42.481246 -102.267766)
		(width 0.1397)
		(layer "In2.Cu")
		(net "PCIE_TX_CAP_P76")
	)
	(segment
		(start 28.323794 -109.86135)
		(end 32.577532 -103.785924)
		(width 0.1397)
		(layer "In2.Cu")
		(net "PCIE_TX_CAP_P76")
	)
	(segment
		(start 171.724828 -102.76967)
		(end 175.025304 -100.458778)
		(width 0.1397)
		(layer "In2.Cu")
		(net "PCIE_TX_CAP_P76")
	)
	(segment
		(start 164.118544 -104.110536)
		(end 171.724828 -102.76967)
		(width 0.1397)
		(layer "In2.Cu")
		(net "PCIE_TX_CAP_P76")
	)
	(segment
		(start 83.488784 -104.287066)
		(end 87.625936 -103.407464)
		(width 0.1397)
		(layer "In2.Cu")
		(net "PCIE_TX_CAP_P76")
	)
	(segment
		(start 192.900046 -60.643008)
		(end 193.5988 -56.674766)
		(width 0.1397)
		(layer "In2.Cu")
		(net "PCIE_TX_CAP_P76")
	)
	(segment
		(start 117.48262 -108.672376)
		(end 121.78792 -107.75696)
		(width 0.1397)
		(layer "In2.Cu")
		(net "PCIE_TX_CAP_P76")
	)
	(segment
		(start 28.122372 -110.062772)
		(end 28.323794 -109.86135)
		(width 0.1397)
		(layer "In2.Cu")
		(net "PCIE_TX_CAP_P76")
	)
	(segment
		(start 32.668972 -103.698548)
		(end 33.923986 -102.883462)
		(width 0.1397)
		(layer "In2.Cu")
		(net "PCIE_TX_CAP_P76")
	)
	(segment
		(start 192.173098 -75.94346)
		(end 193.884804 -66.233548)
		(width 0.1397)
		(layer "In2.Cu")
		(net "PCIE_TX_CAP_P76")
	)
	(segment
		(start 63.248286 -103.770176)
		(end 69.756782 -102.386892)
		(width 0.1397)
		(layer "In2.Cu")
		(net "PCIE_TX_CAP_P76")
	)
	(segment
		(start 24.924766 -111.7981)
		(end 25.420828 -111.7981)
		(width 0.1397)
		(layer "In2.Cu")
		(net "PCIE_TX_CAP_P76")
	)
	(segment
		(start 42.481246 -102.267766)
		(end 43.382184 -102.07625)
		(width 0.1397)
		(layer "In2.Cu")
		(net "PCIE_TX_CAP_P76")
	)
	(segment
		(start 39.097458 -102.70744)
		(end 40.15232 -102.022402)
		(width 0.1397)
		(layer "In2.Cu")
		(net "PCIE_TX_CAP_P76")
	)
	(segment
		(start 69.756782 -102.386892)
		(end 75.852274 -103.682546)
		(width 0.1397)
		(layer "In2.Cu")
		(net "PCIE_TX_CAP_P76")
	)
	(segment
		(start 43.382184 -102.07625)
		(end 44.2976 -101.48189)
		(width 0.1397)
		(layer "In2.Cu")
		(net "PCIE_TX_CAP_P76")
	)
	(segment
		(start 32.577532 -103.785924)
		(end 32.668972 -103.698548)
		(width 0.1397)
		(layer "In2.Cu")
		(net "PCIE_TX_CAP_P76")
	)
	(segment
		(start 75.852274 -103.682546)
		(end 78.24851 -103.173276)
		(width 0.1397)
		(layer "In2.Cu")
		(net "PCIE_TX_CAP_P76")
	)
	(segment
		(start 134.303516 -107.438698)
		(end 141.8463 -102.540308)
		(width 0.1397)
		(layer "In2.Cu")
		(net "PCIE_TX_CAP_P76")
	)
	(segment
		(start 24.473154 -111.4044)
		(end 24.82596 -111.757206)
		(width 0.1397)
		(layer "In2.Cu")
		(net "PCIE_TX_CAP_P76")
	)
	(segment
		(start 50.89271 -100.080064)
		(end 57.021476 -101.127052)
		(width 0.1397)
		(layer "In2.Cu")
		(net "PCIE_TX_CAP_P76")
	)
	(segment
		(start 175.025304 -100.458778)
		(end 192.173098 -75.94346)
		(width 0.1397)
		(layer "In2.Cu")
		(net "PCIE_TX_CAP_P76")
	)
	(segment
		(start 148.528786 -101.362002)
		(end 164.118544 -104.110536)
		(width 0.1397)
		(layer "In2.Cu")
		(net "PCIE_TX_CAP_P76")
	)
	(segment
		(start 57.021476 -101.127052)
		(end 59.972702 -103.192834)
		(width 0.1397)
		(layer "In2.Cu")
		(net "PCIE_TX_CAP_P76")
	)
	(segment
		(start 34.739326 -102.70998)
		(end 36.912296 -103.171752)
		(width 0.1397)
		(layer "In2.Cu")
		(net "PCIE_TX_CAP_P76")
	)
	(segment
		(start 40.15232 -102.022402)
		(end 40.740076 -101.897434)
		(width 0.1397)
		(layer "In2.Cu")
		(net "PCIE_TX_CAP_P76")
	)
	(segment
		(start 33.923986 -102.883462)
		(end 34.739326 -102.70998)
		(width 0.1397)
		(layer "In2.Cu")
		(net "PCIE_TX_CAP_P76")
	)
	(segment
		(start 25.82291 -111.655098)
		(end 28.122372 -110.062772)
		(width 0.1397)
		(layer "In2.Cu")
		(net "PCIE_TX_CAP_P76")
	)
	(segment
		(start 194.586098 -55.265066)
		(end 195.530978 -53.915818)
		(width 0.1397)
		(layer "In2.Cu")
		(net "PCIE_TX_CAP_P76")
	)
	(segment
		(start 193.884804 -66.233548)
		(end 192.900046 -60.643008)
		(width 0.1397)
		(layer "In2.Cu")
		(net "PCIE_TX_CAP_P76")
	)
	(segment
		(start 78.24851 -103.173276)
		(end 83.488784 -104.287066)
		(width 0.1397)
		(layer "In2.Cu")
		(net "PCIE_TX_CAP_P76")
	)
	(segment
		(start 59.972702 -103.192834)
		(end 63.248286 -103.770176)
		(width 0.1397)
		(layer "In2.Cu")
		(net "PCIE_TX_CAP_P76")
	)
	(arc
		(start 195.530978 -53.915818)
		(mid 195.589484 -53.847242)
		(end 195.66001 -53.791104)
		(width 0.1397)
		(layer "In2.Cu")
		(net "PCIE_TX_CAP_P76")
	)
	(arc
		(start 25.751536 -111.70539)
		(mid 25.788078 -111.681457)
		(end 25.82291 -111.655098)
		(width 0.1397)
		(layer "In2.Cu")
		(net "PCIE_TX_CAP_P76")
	)
	(arc
		(start 200.4568 -50.2412)
		(mid 200.333769 -49.923469)
		(end 200.0504 -49.734216)
		(width 0.1397)
		(layer "In2.Cu")
		(net "PCIE_TX_CAP_P76")
	)
	(arc
		(start 200.393046 -50.71745)
		(mid 200.439807 -50.666867)
		(end 200.4568 -50.600102)
		(width 0.1397)
		(layer "In2.Cu")
		(net "PCIE_TX_CAP_P76")
	)
	(arc
		(start 25.420828 -111.7981)
		(mid 25.592546 -111.774448)
		(end 25.751536 -111.70539)
		(width 0.1397)
		(layer "In2.Cu")
		(net "PCIE_TX_CAP_P76")
	)
	(arc
		(start 24.82596 -111.757206)
		(mid 24.871293 -111.787496)
		(end 24.924766 -111.7981)
		(width 0.1397)
		(layer "In2.Cu")
		(net "PCIE_TX_CAP_P76")
	)
	(segment
		(start 48.74133 -211.5312)
		(end 48.74133 -211.2772)
		(width 0.136652)
		(layer "F.Cu")
		(net "PCIE_TX_CAP_P75")
	)
	(segment
		(start 48.647096 -211.050124)
		(end 48.49368 -210.896454)
		(width 0.136652)
		(layer "F.Cu")
		(net "PCIE_TX_CAP_P75")
	)
	(segment
		(start 48.39208 -211.975954)
		(end 48.673766 -211.694268)
		(width 0.136652)
		(layer "F.Cu")
		(net "PCIE_TX_CAP_P75")
	)
	(segment
		(start 223.60001 -46.999906)
		(end 223.100138 -46.500034)
		(width 0.136652)
		(layer "F.Cu")
		(net "PCIE_TX_CAP_P75")
	)
	(via
		(at 223.100138 -46.500034)
		(size 0.4572)
		(drill 0.2032)
		(layers "F.Cu" "B.Cu")
		(net "PCIE_TX_CAP_P75")
	)
	(via
		(at 48.49368 -210.896454)
		(size 0.508)
		(drill 0.254)
		(layers "F.Cu" "B.Cu")
		(net "PCIE_TX_CAP_P75")
	)
	(arc
		(start 48.673766 -211.694268)
		(mid 48.723757 -211.619452)
		(end 48.74133 -211.5312)
		(width 0.136652)
		(layer "F.Cu")
		(net "PCIE_TX_CAP_P75")
	)
	(arc
		(start 48.74133 -211.2772)
		(mid 48.716789 -211.154294)
		(end 48.647096 -211.050124)
		(width 0.136652)
		(layer "F.Cu")
		(net "PCIE_TX_CAP_P75")
	)
	(segment
		(start 221.480634 -45.671232)
		(end 221.344998 -45.671232)
		(width 0.1016)
		(layer "In5.Cu")
		(net "PCIE_TX_CAP_P75")
	)
	(segment
		(start 196.433694 -67.83324)
		(end 195.581016 -69.050916)
		(width 0.1397)
		(layer "In5.Cu")
		(net "PCIE_TX_CAP_P75")
	)
	(segment
		(start 222.612966 -46.012608)
		(end 222.612712 -46.012608)
		(width 0.1016)
		(layer "In5.Cu")
		(net "PCIE_TX_CAP_P75")
	)
	(segment
		(start 202.793854 -65.857882)
		(end 198.063866 -66.691764)
		(width 0.1397)
		(layer "In5.Cu")
		(net "PCIE_TX_CAP_P75")
	)
	(segment
		(start 204.867764 -64.405764)
		(end 202.793854 -65.857882)
		(width 0.1397)
		(layer "In5.Cu")
		(net "PCIE_TX_CAP_P75")
	)
	(segment
		(start 217.016076 -47.781464)
		(end 215.05164 -48.12792)
		(width 0.1397)
		(layer "In5.Cu")
		(net "PCIE_TX_CAP_P75")
	)
	(segment
		(start 220.914214 -45.671232)
		(end 220.807788 -45.68952)
		(width 0.1397)
		(layer "In5.Cu")
		(net "PCIE_TX_CAP_P75")
	)
	(segment
		(start 71.62546 -198.442326)
		(end 56.329326 -201.139552)
		(width 0.1397)
		(layer "In5.Cu")
		(net "PCIE_TX_CAP_P75")
	)
	(segment
		(start 205.318106 -63.762636)
		(end 204.867764 -64.405764)
		(width 0.1397)
		(layer "In5.Cu")
		(net "PCIE_TX_CAP_P75")
	)
	(segment
		(start 222.362522 -45.837094)
		(end 221.493588 -45.684186)
		(width 0.1016)
		(layer "In5.Cu")
		(net "PCIE_TX_CAP_P75")
	)
	(segment
		(start 74.722228 -196.273928)
		(end 71.62546 -198.442326)
		(width 0.1397)
		(layer "In5.Cu")
		(net "PCIE_TX_CAP_P75")
	)
	(segment
		(start 221.493588 -45.684186)
		(end 221.480634 -45.671232)
		(width 0.1016)
		(layer "In5.Cu")
		(net "PCIE_TX_CAP_P75")
	)
	(segment
		(start 219.11564 -46.87443)
		(end 218.040966 -47.064168)
		(width 0.1397)
		(layer "In5.Cu")
		(net "PCIE_TX_CAP_P75")
	)
	(segment
		(start 215.05164 -48.127666)
		(end 215.050878 -48.12792)
		(width 0.1397)
		(layer "In5.Cu")
		(net "PCIE_TX_CAP_P75")
	)
	(segment
		(start 84.450936 -194.558666)
		(end 74.722228 -196.273928)
		(width 0.1397)
		(layer "In5.Cu")
		(net "PCIE_TX_CAP_P75")
	)
	(segment
		(start 221.344998 -45.671232)
		(end 220.914214 -45.671232)
		(width 0.1397)
		(layer "In5.Cu")
		(net "PCIE_TX_CAP_P75")
	)
	(segment
		(start 196.536818 -79.121508)
		(end 194.297046 -91.822016)
		(width 0.1397)
		(layer "In5.Cu")
		(net "PCIE_TX_CAP_P75")
	)
	(segment
		(start 215.050878 -48.12792)
		(end 211.096352 -50.815748)
		(width 0.1397)
		(layer "In5.Cu")
		(net "PCIE_TX_CAP_P75")
	)
	(segment
		(start 48.73498 -210.106768)
		(end 48.73498 -210.439)
		(width 0.1397)
		(layer "In5.Cu")
		(net "PCIE_TX_CAP_P75")
	)
	(segment
		(start 220.807788 -45.68952)
		(end 219.11564 -46.87443)
		(width 0.1397)
		(layer "In5.Cu")
		(net "PCIE_TX_CAP_P75")
	)
	(segment
		(start 48.26 -208.264506)
		(end 48.26 -208.960212)
		(width 0.1397)
		(layer "In5.Cu")
		(net "PCIE_TX_CAP_P75")
	)
	(segment
		(start 48.582072 -210.807808)
		(end 48.49368 -210.896454)
		(width 0.1397)
		(layer "In5.Cu")
		(net "PCIE_TX_CAP_P75")
	)
	(segment
		(start 48.404018 -207.44688)
		(end 48.26 -208.264506)
		(width 0.1397)
		(layer "In5.Cu")
		(net "PCIE_TX_CAP_P75")
	)
	(segment
		(start 194.297046 -91.822016)
		(end 158.824168 -142.482824)
		(width 0.1397)
		(layer "In5.Cu")
		(net "PCIE_TX_CAP_P75")
	)
	(segment
		(start 215.05164 -48.12792)
		(end 215.05164 -48.127666)
		(width 0.1397)
		(layer "In5.Cu")
		(net "PCIE_TX_CAP_P75")
	)
	(segment
		(start 158.824168 -142.482824)
		(end 84.450936 -194.558666)
		(width 0.1397)
		(layer "In5.Cu")
		(net "PCIE_TX_CAP_P75")
	)
	(segment
		(start 222.950532 -46.426374)
		(end 222.711264 -46.115478)
		(width 0.1016)
		(layer "In5.Cu")
		(net "PCIE_TX_CAP_P75")
	)
	(segment
		(start 49.445164 -205.959964)
		(end 48.404018 -207.44688)
		(width 0.1397)
		(layer "In5.Cu")
		(net "PCIE_TX_CAP_P75")
	)
	(segment
		(start 56.329326 -201.139552)
		(end 49.445164 -205.959964)
		(width 0.1397)
		(layer "In5.Cu")
		(net "PCIE_TX_CAP_P75")
	)
	(segment
		(start 218.040966 -47.064168)
		(end 217.016076 -47.781464)
		(width 0.1397)
		(layer "In5.Cu")
		(net "PCIE_TX_CAP_P75")
	)
	(segment
		(start 222.676212 -46.0756)
		(end 222.612966 -46.012608)
		(width 0.1016)
		(layer "In5.Cu")
		(net "PCIE_TX_CAP_P75")
	)
	(segment
		(start 198.063866 -66.691764)
		(end 196.433694 -67.83324)
		(width 0.1397)
		(layer "In5.Cu")
		(net "PCIE_TX_CAP_P75")
	)
	(segment
		(start 195.17106 -71.376032)
		(end 196.536818 -79.121508)
		(width 0.1397)
		(layer "In5.Cu")
		(net "PCIE_TX_CAP_P75")
	)
	(segment
		(start 195.581016 -69.050916)
		(end 195.17106 -71.376032)
		(width 0.1397)
		(layer "In5.Cu")
		(net "PCIE_TX_CAP_P75")
	)
	(segment
		(start 211.096352 -50.815748)
		(end 206.426562 -57.485026)
		(width 0.1397)
		(layer "In5.Cu")
		(net "PCIE_TX_CAP_P75")
	)
	(segment
		(start 222.612712 -46.012608)
		(end 222.362522 -45.837094)
		(width 0.1016)
		(layer "In5.Cu")
		(net "PCIE_TX_CAP_P75")
	)
	(segment
		(start 206.426562 -57.485026)
		(end 205.318106 -63.762636)
		(width 0.1397)
		(layer "In5.Cu")
		(net "PCIE_TX_CAP_P75")
	)
	(arc
		(start 222.711264 -46.115478)
		(mid 222.694387 -46.094969)
		(end 222.676212 -46.0756)
		(width 0.1016)
		(layer "In5.Cu")
		(net "PCIE_TX_CAP_P75")
	)
	(arc
		(start 48.59401 -209.76717)
		(mid 48.698255 -209.92295)
		(end 48.73498 -210.106768)
		(width 0.1397)
		(layer "In5.Cu")
		(net "PCIE_TX_CAP_P75")
	)
	(arc
		(start 223.100138 -46.500034)
		(mid 223.016763 -46.480618)
		(end 222.950532 -46.426374)
		(width 0.1016)
		(layer "In5.Cu")
		(net "PCIE_TX_CAP_P75")
	)
	(arc
		(start 48.73498 -210.439)
		(mid 48.695237 -210.638624)
		(end 48.582072 -210.807808)
		(width 0.1397)
		(layer "In5.Cu")
		(net "PCIE_TX_CAP_P75")
	)
	(arc
		(start 48.26 -208.960212)
		(mid 48.346768 -209.396895)
		(end 48.59401 -209.76717)
		(width 0.1397)
		(layer "In5.Cu")
		(net "PCIE_TX_CAP_P75")
	)
	(segment
		(start 51.591972 -211.975954)
		(end 51.873658 -211.694268)
		(width 0.136652)
		(layer "F.Cu")
		(net "PCIE_TX_CAP_P74")
	)
	(segment
		(start 51.829208 -211.03209)
		(end 51.693572 -210.896454)
		(width 0.136652)
		(layer "F.Cu")
		(net "PCIE_TX_CAP_P74")
	)
	(segment
		(start 51.941222 -211.5312)
		(end 51.941222 -211.3026)
		(width 0.136652)
		(layer "F.Cu")
		(net "PCIE_TX_CAP_P74")
	)
	(segment
		(start 224.600008 -47.999904)
		(end 224.100136 -48.499776)
		(width 0.136652)
		(layer "F.Cu")
		(net "PCIE_TX_CAP_P74")
	)
	(via
		(at 224.100136 -48.499776)
		(size 0.4572)
		(drill 0.2032)
		(layers "F.Cu" "B.Cu")
		(net "PCIE_TX_CAP_P74")
	)
	(via
		(at 51.693572 -210.896454)
		(size 0.508)
		(drill 0.254)
		(layers "F.Cu" "B.Cu")
		(net "PCIE_TX_CAP_P74")
	)
	(arc
		(start 51.941222 -211.3026)
		(mid 51.912104 -211.156214)
		(end 51.829208 -211.03209)
		(width 0.136652)
		(layer "F.Cu")
		(net "PCIE_TX_CAP_P74")
	)
	(arc
		(start 51.873658 -211.694268)
		(mid 51.923649 -211.619452)
		(end 51.941222 -211.5312)
		(width 0.136652)
		(layer "F.Cu")
		(net "PCIE_TX_CAP_P74")
	)
	(segment
		(start 215.123014 -49.01946)
		(end 217.613484 -48.580548)
		(width 0.1397)
		(layer "In5.Cu")
		(net "PCIE_TX_CAP_P74")
	)
	(segment
		(start 55.016654 -205.305914)
		(end 55.634128 -204.873606)
		(width 0.1397)
		(layer "In5.Cu")
		(net "PCIE_TX_CAP_P74")
	)
	(segment
		(start 222.638874 -47.704756)
		(end 222.690182 -47.778162)
		(width 0.1016)
		(layer "In5.Cu")
		(net "PCIE_TX_CAP_P74")
	)
	(segment
		(start 222.476314 -47.676308)
		(end 222.613982 -47.700438)
		(width 0.1397)
		(layer "In5.Cu")
		(net "PCIE_TX_CAP_P74")
	)
	(segment
		(start 205.044548 -69.7865)
		(end 207.160114 -57.78881)
		(width 0.1397)
		(layer "In5.Cu")
		(net "PCIE_TX_CAP_P74")
	)
	(segment
		(start 223.919542 -48.424338)
		(end 223.921828 -48.426624)
		(width 0.1016)
		(layer "In5.Cu")
		(net "PCIE_TX_CAP_P74")
	)
	(segment
		(start 224.098104 -48.499776)
		(end 224.100136 -48.499776)
		(width 0.1016)
		(layer "In5.Cu")
		(net "PCIE_TX_CAP_P74")
	)
	(segment
		(start 51.934872 -210.22945)
		(end 51.934872 -209.707226)
		(width 0.1397)
		(layer "In5.Cu")
		(net "PCIE_TX_CAP_P74")
	)
	(segment
		(start 223.798384 -48.232568)
		(end 223.810322 -48.26127)
		(width 0.1016)
		(layer "In5.Cu")
		(net "PCIE_TX_CAP_P74")
	)
	(segment
		(start 223.61271 -48.012096)
		(end 223.641666 -48.041052)
		(width 0.1016)
		(layer "In5.Cu")
		(net "PCIE_TX_CAP_P74")
	)
	(segment
		(start 205.82128 -74.191368)
		(end 205.044548 -69.7865)
		(width 0.1397)
		(layer "In5.Cu")
		(net "PCIE_TX_CAP_P74")
	)
	(segment
		(start 217.613484 -48.580548)
		(end 217.950542 -48.344582)
		(width 0.1397)
		(layer "In5.Cu")
		(net "PCIE_TX_CAP_P74")
	)
	(segment
		(start 211.547202 -51.523392)
		(end 215.123014 -49.01946)
		(width 0.1397)
		(layer "In5.Cu")
		(net "PCIE_TX_CAP_P74")
	)
	(segment
		(start 223.724978 -48.12157)
		(end 223.736408 -48.133)
		(width 0.1016)
		(layer "In5.Cu")
		(net "PCIE_TX_CAP_P74")
	)
	(segment
		(start 222.613982 -47.700438)
		(end 222.638874 -47.704756)
		(width 0.1016)
		(layer "In5.Cu")
		(net "PCIE_TX_CAP_P74")
	)
	(segment
		(start 60.0456 -201.784458)
		(end 82.926428 -197.749922)
		(width 0.1397)
		(layer "In5.Cu")
		(net "PCIE_TX_CAP_P74")
	)
	(segment
		(start 221.071694 -47.794164)
		(end 222.43288 -47.668688)
		(width 0.1397)
		(layer "In5.Cu")
		(net "PCIE_TX_CAP_P74")
	)
	(segment
		(start 51.934872 -209.707226)
		(end 55.016654 -205.305914)
		(width 0.1397)
		(layer "In5.Cu")
		(net "PCIE_TX_CAP_P74")
	)
	(segment
		(start 217.950542 -48.344582)
		(end 221.071694 -47.794164)
		(width 0.1397)
		(layer "In5.Cu")
		(net "PCIE_TX_CAP_P74")
	)
	(segment
		(start 223.756728 -48.157892)
		(end 223.766634 -48.172624)
		(width 0.1016)
		(layer "In5.Cu")
		(net "PCIE_TX_CAP_P74")
	)
	(segment
		(start 207.160114 -57.78881)
		(end 211.547202 -51.523392)
		(width 0.1397)
		(layer "In5.Cu")
		(net "PCIE_TX_CAP_P74")
	)
	(segment
		(start 82.926428 -197.749922)
		(end 160.507934 -143.426688)
		(width 0.1397)
		(layer "In5.Cu")
		(net "PCIE_TX_CAP_P74")
	)
	(segment
		(start 223.641666 -48.041052)
		(end 223.724978 -48.12157)
		(width 0.1016)
		(layer "In5.Cu")
		(net "PCIE_TX_CAP_P74")
	)
	(segment
		(start 55.633874 -204.873352)
		(end 58.274204 -203.024486)
		(width 0.1397)
		(layer "In5.Cu")
		(net "PCIE_TX_CAP_P74")
	)
	(segment
		(start 55.634128 -204.873606)
		(end 55.633874 -204.873352)
		(width 0.1397)
		(layer "In5.Cu")
		(net "PCIE_TX_CAP_P74")
	)
	(segment
		(start 160.507934 -143.426688)
		(end 160.732978 -143.201644)
		(width 0.1397)
		(layer "In5.Cu")
		(net "PCIE_TX_CAP_P74")
	)
	(segment
		(start 58.274204 -203.024486)
		(end 60.0456 -201.784458)
		(width 0.1397)
		(layer "In5.Cu")
		(net "PCIE_TX_CAP_P74")
	)
	(segment
		(start 160.732978 -143.201644)
		(end 204.733144 -80.36306)
		(width 0.1397)
		(layer "In5.Cu")
		(net "PCIE_TX_CAP_P74")
	)
	(segment
		(start 222.690182 -47.778162)
		(end 222.690944 -47.778416)
		(width 0.1016)
		(layer "In5.Cu")
		(net "PCIE_TX_CAP_P74")
	)
	(segment
		(start 204.733144 -80.36306)
		(end 205.82128 -74.191368)
		(width 0.1397)
		(layer "In5.Cu")
		(net "PCIE_TX_CAP_P74")
	)
	(segment
		(start 222.690944 -47.778416)
		(end 222.708978 -47.781464)
		(width 0.1016)
		(layer "In5.Cu")
		(net "PCIE_TX_CAP_P74")
	)
	(segment
		(start 222.708978 -47.781464)
		(end 223.346518 -47.893986)
		(width 0.1016)
		(layer "In5.Cu")
		(net "PCIE_TX_CAP_P74")
	)
	(segment
		(start 222.43288 -47.668688)
		(end 222.476314 -47.676308)
		(width 0.1397)
		(layer "In5.Cu")
		(net "PCIE_TX_CAP_P74")
	)
	(arc
		(start 223.346518 -47.893986)
		(mid 223.490529 -47.928432)
		(end 223.61271 -48.012096)
		(width 0.1016)
		(layer "In5.Cu")
		(net "PCIE_TX_CAP_P74")
	)
	(arc
		(start 223.810322 -48.26127)
		(mid 223.85686 -48.348209)
		(end 223.919542 -48.424338)
		(width 0.1016)
		(layer "In5.Cu")
		(net "PCIE_TX_CAP_P74")
	)
	(arc
		(start 51.693572 -210.896454)
		(mid 51.87271 -210.584109)
		(end 51.934872 -210.22945)
		(width 0.1397)
		(layer "In5.Cu")
		(net "PCIE_TX_CAP_P74")
	)
	(arc
		(start 223.736408 -48.133)
		(mid 223.747181 -48.144945)
		(end 223.756728 -48.157892)
		(width 0.1016)
		(layer "In5.Cu")
		(net "PCIE_TX_CAP_P74")
	)
	(arc
		(start 223.766634 -48.172624)
		(mid 223.783963 -48.201825)
		(end 223.798384 -48.232568)
		(width 0.1016)
		(layer "In5.Cu")
		(net "PCIE_TX_CAP_P74")
	)
	(arc
		(start 223.921828 -48.426624)
		(mid 224.002676 -48.480771)
		(end 224.098104 -48.499776)
		(width 0.1016)
		(layer "In5.Cu")
		(net "PCIE_TX_CAP_P74")
	)
	(segment
		(start 223.60001 -48.999902)
		(end 223.100138 -49.499774)
		(width 0.136652)
		(layer "F.Cu")
		(net "PCIE_TX_CAP_P73")
	)
	(segment
		(start 55.141368 -211.5312)
		(end 55.141368 -211.282788)
		(width 0.136652)
		(layer "F.Cu")
		(net "PCIE_TX_CAP_P73")
	)
	(segment
		(start 55.043324 -211.04606)
		(end 54.893718 -210.896454)
		(width 0.136652)
		(layer "F.Cu")
		(net "PCIE_TX_CAP_P73")
	)
	(segment
		(start 54.792118 -211.975954)
		(end 55.073804 -211.694268)
		(width 0.136652)
		(layer "F.Cu")
		(net "PCIE_TX_CAP_P73")
	)
	(via
		(at 223.100138 -49.499774)
		(size 0.4572)
		(drill 0.2032)
		(layers "F.Cu" "B.Cu")
		(net "PCIE_TX_CAP_P73")
	)
	(via
		(at 54.893718 -210.896454)
		(size 0.508)
		(drill 0.254)
		(layers "F.Cu" "B.Cu")
		(net "PCIE_TX_CAP_P73")
	)
	(arc
		(start 55.073804 -211.694268)
		(mid 55.123795 -211.619452)
		(end 55.141368 -211.5312)
		(width 0.136652)
		(layer "F.Cu")
		(net "PCIE_TX_CAP_P73")
	)
	(arc
		(start 55.141368 -211.282788)
		(mid 55.115885 -211.154676)
		(end 55.043324 -211.04606)
		(width 0.136652)
		(layer "F.Cu")
		(net "PCIE_TX_CAP_P73")
	)
	(segment
		(start 221.75216 -48.72482)
		(end 221.821248 -48.80102)
		(width 0.1016)
		(layer "In5.Cu")
		(net "PCIE_TX_CAP_P73")
	)
	(segment
		(start 206.674466 -74.295)
		(end 205.913228 -69.977)
		(width 0.1397)
		(layer "In5.Cu")
		(net "PCIE_TX_CAP_P73")
	)
	(segment
		(start 208.004918 -58.113422)
		(end 212.133688 -52.21605)
		(width 0.1397)
		(layer "In5.Cu")
		(net "PCIE_TX_CAP_P73")
	)
	(segment
		(start 205.913228 -69.977)
		(end 208.004918 -58.113422)
		(width 0.1397)
		(layer "In5.Cu")
		(net "PCIE_TX_CAP_P73")
	)
	(segment
		(start 212.133688 -52.21605)
		(end 215.690958 -49.725326)
		(width 0.1397)
		(layer "In5.Cu")
		(net "PCIE_TX_CAP_P73")
	)
	(segment
		(start 215.690958 -49.725326)
		(end 215.690958 -49.725072)
		(width 0.1397)
		(layer "In5.Cu")
		(net "PCIE_TX_CAP_P73")
	)
	(segment
		(start 61.530484 -202.523344)
		(end 82.822542 -198.76897)
		(width 0.1397)
		(layer "In5.Cu")
		(net "PCIE_TX_CAP_P73")
	)
	(segment
		(start 55.135018 -208.296002)
		(end 56.912764 -205.756764)
		(width 0.1397)
		(layer "In5.Cu")
		(net "PCIE_TX_CAP_P73")
	)
	(segment
		(start 223.100138 -49.499266)
		(end 223.100138 -49.499774)
		(width 0.1016)
		(layer "In5.Cu")
		(net "PCIE_TX_CAP_P73")
	)
	(segment
		(start 221.557088 -48.690276)
		(end 221.75216 -48.72482)
		(width 0.1397)
		(layer "In5.Cu")
		(net "PCIE_TX_CAP_P73")
	)
	(segment
		(start 161.203132 -143.886174)
		(end 205.578202 -80.511904)
		(width 0.1397)
		(layer "In5.Cu")
		(net "PCIE_TX_CAP_P73")
	)
	(segment
		(start 222.676212 -49.07534)
		(end 223.100138 -49.499266)
		(width 0.1016)
		(layer "In5.Cu")
		(net "PCIE_TX_CAP_P73")
	)
	(segment
		(start 82.822542 -198.76897)
		(end 161.203132 -143.886174)
		(width 0.1397)
		(layer "In5.Cu")
		(net "PCIE_TX_CAP_P73")
	)
	(segment
		(start 56.912764 -205.756764)
		(end 61.530484 -202.523344)
		(width 0.1397)
		(layer "In5.Cu")
		(net "PCIE_TX_CAP_P73")
	)
	(segment
		(start 205.578202 -80.511904)
		(end 206.674466 -74.295)
		(width 0.1397)
		(layer "In5.Cu")
		(net "PCIE_TX_CAP_P73")
	)
	(segment
		(start 215.690958 -49.725072)
		(end 221.557088 -48.690276)
		(width 0.1397)
		(layer "In5.Cu")
		(net "PCIE_TX_CAP_P73")
	)
	(segment
		(start 55.135018 -210.22945)
		(end 55.135018 -208.296002)
		(width 0.1397)
		(layer "In5.Cu")
		(net "PCIE_TX_CAP_P73")
	)
	(segment
		(start 221.821248 -48.80102)
		(end 222.34652 -48.893984)
		(width 0.1016)
		(layer "In5.Cu")
		(net "PCIE_TX_CAP_P73")
	)
	(segment
		(start 222.612966 -49.012348)
		(end 222.676212 -49.07534)
		(width 0.1016)
		(layer "In5.Cu")
		(net "PCIE_TX_CAP_P73")
	)
	(segment
		(start 222.612712 -49.012094)
		(end 222.612966 -49.012348)
		(width 0.1016)
		(layer "In5.Cu")
		(net "PCIE_TX_CAP_P73")
	)
	(arc
		(start 222.34652 -48.893984)
		(mid 222.490531 -48.92843)
		(end 222.612712 -49.012094)
		(width 0.1016)
		(layer "In5.Cu")
		(net "PCIE_TX_CAP_P73")
	)
	(arc
		(start 54.893718 -210.896454)
		(mid 55.072856 -210.584109)
		(end 55.135018 -210.22945)
		(width 0.1397)
		(layer "In5.Cu")
		(net "PCIE_TX_CAP_P73")
	)
	(segment
		(start 58.34126 -211.5312)
		(end 58.34126 -211.281518)
		(width 0.136652)
		(layer "F.Cu")
		(net "PCIE_TX_CAP_P72")
	)
	(segment
		(start 57.99201 -211.975954)
		(end 58.273696 -211.694268)
		(width 0.136652)
		(layer "F.Cu")
		(net "PCIE_TX_CAP_P72")
	)
	(segment
		(start 224.600008 -49.9999)
		(end 224.100136 -50.499772)
		(width 0.136652)
		(layer "F.Cu")
		(net "PCIE_TX_CAP_P72")
	)
	(segment
		(start 58.243978 -211.047076)
		(end 58.09361 -210.896454)
		(width 0.136652)
		(layer "F.Cu")
		(net "PCIE_TX_CAP_P72")
	)
	(via
		(at 224.100136 -50.499772)
		(size 0.4572)
		(drill 0.2032)
		(layers "F.Cu" "B.Cu")
		(net "PCIE_TX_CAP_P72")
	)
	(via
		(at 58.09361 -210.896454)
		(size 0.508)
		(drill 0.254)
		(layers "F.Cu" "B.Cu")
		(net "PCIE_TX_CAP_P72")
	)
	(arc
		(start 58.273696 -211.694268)
		(mid 58.323687 -211.619452)
		(end 58.34126 -211.5312)
		(width 0.136652)
		(layer "F.Cu")
		(net "PCIE_TX_CAP_P72")
	)
	(arc
		(start 58.34126 -211.281518)
		(mid 58.315926 -211.154626)
		(end 58.243978 -211.047076)
		(width 0.136652)
		(layer "F.Cu")
		(net "PCIE_TX_CAP_P72")
	)
	(segment
		(start 221.491556 -50.467768)
		(end 218.438476 -50.467768)
		(width 0.1397)
		(layer "In5.Cu")
		(net "PCIE_TX_CAP_P72")
	)
	(segment
		(start 212.894672 -53.922422)
		(end 208.464912 -79.04353)
		(width 0.1397)
		(layer "In5.Cu")
		(net "PCIE_TX_CAP_P72")
	)
	(segment
		(start 84.88426 -199.22236)
		(end 64.21501 -202.866752)
		(width 0.1397)
		(layer "In5.Cu")
		(net "PCIE_TX_CAP_P72")
	)
	(segment
		(start 60.087764 -205.756764)
		(end 58.33491 -208.260442)
		(width 0.1397)
		(layer "In5.Cu")
		(net "PCIE_TX_CAP_P72")
	)
	(segment
		(start 223.325436 -49.893474)
		(end 222.664528 -49.893474)
		(width 0.1016)
		(layer "In5.Cu")
		(net "PCIE_TX_CAP_P72")
	)
	(segment
		(start 216.246202 -50.854102)
		(end 213.886288 -52.506372)
		(width 0.1397)
		(layer "In5.Cu")
		(net "PCIE_TX_CAP_P72")
	)
	(segment
		(start 217.364564 -50.656998)
		(end 216.246202 -50.854102)
		(width 0.1397)
		(layer "In5.Cu")
		(net "PCIE_TX_CAP_P72")
	)
	(segment
		(start 208.464912 -79.04353)
		(end 162.243008 -145.055336)
		(width 0.1397)
		(layer "In5.Cu")
		(net "PCIE_TX_CAP_P72")
	)
	(segment
		(start 223.95053 -50.426112)
		(end 223.711262 -50.115216)
		(width 0.1016)
		(layer "In5.Cu")
		(net "PCIE_TX_CAP_P72")
	)
	(segment
		(start 58.33491 -208.260442)
		(end 58.33491 -210.22945)
		(width 0.1397)
		(layer "In5.Cu")
		(net "PCIE_TX_CAP_P72")
	)
	(segment
		(start 162.243008 -145.055336)
		(end 84.88426 -199.22236)
		(width 0.1397)
		(layer "In5.Cu")
		(net "PCIE_TX_CAP_P72")
	)
	(segment
		(start 64.21501 -202.866752)
		(end 60.087764 -205.756764)
		(width 0.1397)
		(layer "In5.Cu")
		(net "PCIE_TX_CAP_P72")
	)
	(segment
		(start 221.883986 -50.075338)
		(end 221.491556 -50.467768)
		(width 0.1397)
		(layer "In5.Cu")
		(net "PCIE_TX_CAP_P72")
	)
	(segment
		(start 223.67621 -50.075338)
		(end 223.612964 -50.012346)
		(width 0.1016)
		(layer "In5.Cu")
		(net "PCIE_TX_CAP_P72")
	)
	(segment
		(start 218.438476 -50.467768)
		(end 217.364564 -50.656998)
		(width 0.1397)
		(layer "In5.Cu")
		(net "PCIE_TX_CAP_P72")
	)
	(segment
		(start 213.886288 -52.506372)
		(end 212.894672 -53.922422)
		(width 0.1397)
		(layer "In5.Cu")
		(net "PCIE_TX_CAP_P72")
	)
	(segment
		(start 223.612964 -50.012346)
		(end 223.61271 -50.012092)
		(width 0.1016)
		(layer "In5.Cu")
		(net "PCIE_TX_CAP_P72")
	)
	(arc
		(start 223.711262 -50.115216)
		(mid 223.694385 -50.094707)
		(end 223.67621 -50.075338)
		(width 0.1016)
		(layer "In5.Cu")
		(net "PCIE_TX_CAP_P72")
	)
	(arc
		(start 58.33491 -210.22945)
		(mid 58.272726 -210.584101)
		(end 58.09361 -210.896454)
		(width 0.1397)
		(layer "In5.Cu")
		(net "PCIE_TX_CAP_P72")
	)
	(arc
		(start 222.233236 -49.984406)
		(mid 222.062278 -50.04396)
		(end 221.883986 -50.075338)
		(width 0.1016)
		(layer "In5.Cu")
		(net "PCIE_TX_CAP_P72")
	)
	(arc
		(start 223.61271 -50.012092)
		(mid 223.480837 -49.924292)
		(end 223.325436 -49.893474)
		(width 0.1016)
		(layer "In5.Cu")
		(net "PCIE_TX_CAP_P72")
	)
	(arc
		(start 224.100136 -50.499772)
		(mid 224.016761 -50.480356)
		(end 223.95053 -50.426112)
		(width 0.1016)
		(layer "In5.Cu")
		(net "PCIE_TX_CAP_P72")
	)
	(arc
		(start 222.664528 -49.893474)
		(mid 222.444141 -49.916453)
		(end 222.233236 -49.984406)
		(width 0.1016)
		(layer "In5.Cu")
		(net "PCIE_TX_CAP_P72")
	)
	(segment
		(start 223.60001 -51.999896)
		(end 223.100138 -52.499768)
		(width 0.136652)
		(layer "F.Cu")
		(net "PCIE_TX_CAP_P71")
	)
	(segment
		(start 63.941198 -211.5312)
		(end 63.941198 -211.325206)
		(width 0.136652)
		(layer "F.Cu")
		(net "PCIE_TX_CAP_P71")
	)
	(segment
		(start 63.813182 -211.016088)
		(end 63.693548 -210.896454)
		(width 0.136652)
		(layer "F.Cu")
		(net "PCIE_TX_CAP_P71")
	)
	(segment
		(start 63.591948 -211.975954)
		(end 63.873634 -211.694268)
		(width 0.136652)
		(layer "F.Cu")
		(net "PCIE_TX_CAP_P71")
	)
	(via
		(at 223.100138 -52.499768)
		(size 0.4572)
		(drill 0.2032)
		(layers "F.Cu" "B.Cu")
		(net "PCIE_TX_CAP_P71")
	)
	(via
		(at 63.693548 -210.896454)
		(size 0.508)
		(drill 0.254)
		(layers "F.Cu" "B.Cu")
		(net "PCIE_TX_CAP_P71")
	)
	(arc
		(start 63.941198 -211.325206)
		(mid 63.907923 -211.157922)
		(end 63.813182 -211.016088)
		(width 0.136652)
		(layer "F.Cu")
		(net "PCIE_TX_CAP_P71")
	)
	(arc
		(start 63.873634 -211.694268)
		(mid 63.923625 -211.619452)
		(end 63.941198 -211.5312)
		(width 0.136652)
		(layer "F.Cu")
		(net "PCIE_TX_CAP_P71")
	)
	(segment
		(start 209.279998 -80.056228)
		(end 163.592764 -145.304764)
		(width 0.1397)
		(layer "In5.Cu")
		(net "PCIE_TX_CAP_P71")
	)
	(segment
		(start 67.950588 -203.61783)
		(end 65.802764 -205.121764)
		(width 0.1397)
		(layer "In5.Cu")
		(net "PCIE_TX_CAP_P71")
	)
	(segment
		(start 222.676212 -52.075334)
		(end 222.612966 -52.012342)
		(width 0.1016)
		(layer "In5.Cu")
		(net "PCIE_TX_CAP_P71")
	)
	(segment
		(start 222.325438 -51.89347)
		(end 221.888812 -51.89347)
		(width 0.1016)
		(layer "In5.Cu")
		(net "PCIE_TX_CAP_P71")
	)
	(segment
		(start 63.934848 -207.78978)
		(end 63.934848 -210.22945)
		(width 0.1397)
		(layer "In5.Cu")
		(net "PCIE_TX_CAP_P71")
	)
	(segment
		(start 222.856298 -52.30368)
		(end 222.850964 -52.297076)
		(width 0.1016)
		(layer "In5.Cu")
		(net "PCIE_TX_CAP_P71")
	)
	(segment
		(start 77.470762 -201.93889)
		(end 76.284582 -202.148186)
		(width 0.1397)
		(layer "In5.Cu")
		(net "PCIE_TX_CAP_P71")
	)
	(segment
		(start 65.802764 -205.121764)
		(end 63.934848 -207.78978)
		(width 0.1397)
		(layer "In5.Cu")
		(net "PCIE_TX_CAP_P71")
	)
	(segment
		(start 222.849694 -52.295298)
		(end 222.82277 -52.260246)
		(width 0.1016)
		(layer "In5.Cu")
		(net "PCIE_TX_CAP_P71")
	)
	(segment
		(start 215.161622 -53.022246)
		(end 213.671658 -55.150258)
		(width 0.1397)
		(layer "In5.Cu")
		(net "PCIE_TX_CAP_P71")
	)
	(segment
		(start 76.284582 -202.148186)
		(end 67.950588 -203.61783)
		(width 0.1397)
		(layer "In5.Cu")
		(net "PCIE_TX_CAP_P71")
	)
	(segment
		(start 221.6404 -51.7906)
		(end 218.741244 -51.7906)
		(width 0.1397)
		(layer "In5.Cu")
		(net "PCIE_TX_CAP_P71")
	)
	(segment
		(start 217.546682 -52.001166)
		(end 216.307924 -52.219606)
		(width 0.1397)
		(layer "In5.Cu")
		(net "PCIE_TX_CAP_P71")
	)
	(segment
		(start 222.900748 -52.361592)
		(end 222.894906 -52.353972)
		(width 0.1016)
		(layer "In5.Cu")
		(net "PCIE_TX_CAP_P71")
	)
	(segment
		(start 222.850964 -52.297076)
		(end 222.849694 -52.295298)
		(width 0.1016)
		(layer "In5.Cu")
		(net "PCIE_TX_CAP_P71")
	)
	(segment
		(start 222.82277 -52.260246)
		(end 222.786956 -52.213764)
		(width 0.1016)
		(layer "In5.Cu")
		(net "PCIE_TX_CAP_P71")
	)
	(segment
		(start 163.592764 -145.304764)
		(end 84.47405 -200.704196)
		(width 0.1397)
		(layer "In5.Cu")
		(net "PCIE_TX_CAP_P71")
	)
	(segment
		(start 222.786956 -52.213764)
		(end 222.711264 -52.115212)
		(width 0.1016)
		(layer "In5.Cu")
		(net "PCIE_TX_CAP_P71")
	)
	(segment
		(start 222.612966 -52.012342)
		(end 222.612712 -52.012088)
		(width 0.1016)
		(layer "In5.Cu")
		(net "PCIE_TX_CAP_P71")
	)
	(segment
		(start 222.894906 -52.353972)
		(end 222.856298 -52.30368)
		(width 0.1016)
		(layer "In5.Cu")
		(net "PCIE_TX_CAP_P71")
	)
	(segment
		(start 213.671658 -55.150258)
		(end 209.279998 -80.056228)
		(width 0.1397)
		(layer "In5.Cu")
		(net "PCIE_TX_CAP_P71")
	)
	(segment
		(start 84.47405 -200.704196)
		(end 77.470762 -201.93889)
		(width 0.1397)
		(layer "In5.Cu")
		(net "PCIE_TX_CAP_P71")
	)
	(segment
		(start 216.307924 -52.219606)
		(end 215.161622 -53.022246)
		(width 0.1397)
		(layer "In5.Cu")
		(net "PCIE_TX_CAP_P71")
	)
	(segment
		(start 218.741244 -51.7906)
		(end 217.546682 -52.001166)
		(width 0.1397)
		(layer "In5.Cu")
		(net "PCIE_TX_CAP_P71")
	)
	(segment
		(start 222.950532 -52.426108)
		(end 222.900748 -52.361592)
		(width 0.1016)
		(layer "In5.Cu")
		(net "PCIE_TX_CAP_P71")
	)
	(arc
		(start 222.711264 -52.115212)
		(mid 222.694387 -52.094703)
		(end 222.676212 -52.075334)
		(width 0.1016)
		(layer "In5.Cu")
		(net "PCIE_TX_CAP_P71")
	)
	(arc
		(start 223.100138 -52.499768)
		(mid 223.016763 -52.480352)
		(end 222.950532 -52.426108)
		(width 0.1016)
		(layer "In5.Cu")
		(net "PCIE_TX_CAP_P71")
	)
	(arc
		(start 221.888812 -51.89347)
		(mid 221.754382 -51.86673)
		(end 221.6404 -51.7906)
		(width 0.1016)
		(layer "In5.Cu")
		(net "PCIE_TX_CAP_P71")
	)
	(arc
		(start 63.934848 -210.22945)
		(mid 63.872664 -210.584101)
		(end 63.693548 -210.896454)
		(width 0.1397)
		(layer "In5.Cu")
		(net "PCIE_TX_CAP_P71")
	)
	(arc
		(start 222.612712 -52.012088)
		(mid 222.480839 -51.924288)
		(end 222.325438 -51.89347)
		(width 0.1016)
		(layer "In5.Cu")
		(net "PCIE_TX_CAP_P71")
	)
	(segment
		(start 66.792094 -211.975954)
		(end 67.07378 -211.694268)
		(width 0.136652)
		(layer "F.Cu")
		(net "PCIE_TX_CAP_P70")
	)
	(segment
		(start 67.031616 -211.034376)
		(end 66.893694 -210.896454)
		(width 0.136652)
		(layer "F.Cu")
		(net "PCIE_TX_CAP_P70")
	)
	(segment
		(start 224.600008 -52.999894)
		(end 224.100136 -53.499766)
		(width 0.136652)
		(layer "F.Cu")
		(net "PCIE_TX_CAP_P70")
	)
	(segment
		(start 67.141344 -211.5312)
		(end 67.141344 -211.299298)
		(width 0.136652)
		(layer "F.Cu")
		(net "PCIE_TX_CAP_P70")
	)
	(via
		(at 224.100136 -53.499766)
		(size 0.4572)
		(drill 0.2032)
		(layers "F.Cu" "B.Cu")
		(net "PCIE_TX_CAP_P70")
	)
	(via
		(at 66.893694 -210.896454)
		(size 0.508)
		(drill 0.254)
		(layers "F.Cu" "B.Cu")
		(net "PCIE_TX_CAP_P70")
	)
	(arc
		(start 67.141344 -211.299298)
		(mid 67.112825 -211.155926)
		(end 67.031616 -211.034376)
		(width 0.136652)
		(layer "F.Cu")
		(net "PCIE_TX_CAP_P70")
	)
	(arc
		(start 67.07378 -211.694268)
		(mid 67.123771 -211.619452)
		(end 67.141344 -211.5312)
		(width 0.136652)
		(layer "F.Cu")
		(net "PCIE_TX_CAP_P70")
	)
	(segment
		(start 223.67621 -53.075332)
		(end 223.612964 -53.01234)
		(width 0.1016)
		(layer "In5.Cu")
		(net "PCIE_TX_CAP_P70")
	)
	(segment
		(start 215.828118 -54.33695)
		(end 214.189564 -56.677052)
		(width 0.1397)
		(layer "In5.Cu")
		(net "PCIE_TX_CAP_P70")
	)
	(segment
		(start 223.856296 -53.303678)
		(end 223.849692 -53.295296)
		(width 0.1016)
		(layer "In5.Cu")
		(net "PCIE_TX_CAP_P70")
	)
	(segment
		(start 223.95053 -53.426106)
		(end 223.900746 -53.36159)
		(width 0.1016)
		(layer "In5.Cu")
		(net "PCIE_TX_CAP_P70")
	)
	(segment
		(start 223.828356 -53.26761)
		(end 223.786954 -53.213762)
		(width 0.1016)
		(layer "In5.Cu")
		(net "PCIE_TX_CAP_P70")
	)
	(segment
		(start 68.729606 -205.6765)
		(end 67.134994 -207.954118)
		(width 0.1397)
		(layer "In5.Cu")
		(net "PCIE_TX_CAP_P70")
	)
	(segment
		(start 223.900746 -53.36159)
		(end 223.894904 -53.35397)
		(width 0.1016)
		(layer "In5.Cu")
		(net "PCIE_TX_CAP_P70")
	)
	(segment
		(start 223.325436 -52.893468)
		(end 221.951804 -52.893468)
		(width 0.1016)
		(layer "In5.Cu")
		(net "PCIE_TX_CAP_P70")
	)
	(segment
		(start 164.129466 -146.309588)
		(end 84.96046 -201.744326)
		(width 0.1397)
		(layer "In5.Cu")
		(net "PCIE_TX_CAP_P70")
	)
	(segment
		(start 223.786954 -53.213762)
		(end 223.766634 -53.187346)
		(width 0.1016)
		(layer "In5.Cu")
		(net "PCIE_TX_CAP_P70")
	)
	(segment
		(start 67.134994 -207.954118)
		(end 67.134994 -210.22945)
		(width 0.1397)
		(layer "In5.Cu")
		(net "PCIE_TX_CAP_P70")
	)
	(segment
		(start 223.766634 -53.187346)
		(end 223.711262 -53.11521)
		(width 0.1016)
		(layer "In5.Cu")
		(net "PCIE_TX_CAP_P70")
	)
	(segment
		(start 223.894904 -53.35397)
		(end 223.856296 -53.303678)
		(width 0.1016)
		(layer "In5.Cu")
		(net "PCIE_TX_CAP_P70")
	)
	(segment
		(start 219.071444 -52.8066)
		(end 217.657934 -53.05552)
		(width 0.1397)
		(layer "In5.Cu")
		(net "PCIE_TX_CAP_P70")
	)
	(segment
		(start 214.189564 -56.677052)
		(end 209.91322 -80.92948)
		(width 0.1397)
		(layer "In5.Cu")
		(net "PCIE_TX_CAP_P70")
	)
	(segment
		(start 223.612964 -53.01234)
		(end 223.61271 -53.012086)
		(width 0.1016)
		(layer "In5.Cu")
		(net "PCIE_TX_CAP_P70")
	)
	(segment
		(start 70.772782 -204.245972)
		(end 68.729606 -205.6765)
		(width 0.1397)
		(layer "In5.Cu")
		(net "PCIE_TX_CAP_P70")
	)
	(segment
		(start 217.657934 -53.05552)
		(end 215.828118 -54.33695)
		(width 0.1397)
		(layer "In5.Cu")
		(net "PCIE_TX_CAP_P70")
	)
	(segment
		(start 83.48599 -202.004168)
		(end 75.073256 -203.487528)
		(width 0.1397)
		(layer "In5.Cu")
		(net "PCIE_TX_CAP_P70")
	)
	(segment
		(start 221.742 -52.8066)
		(end 219.071444 -52.8066)
		(width 0.1397)
		(layer "In5.Cu")
		(net "PCIE_TX_CAP_P70")
	)
	(segment
		(start 223.849692 -53.295296)
		(end 223.828356 -53.26761)
		(width 0.1016)
		(layer "In5.Cu")
		(net "PCIE_TX_CAP_P70")
	)
	(segment
		(start 75.073256 -203.487528)
		(end 70.772782 -204.245972)
		(width 0.1397)
		(layer "In5.Cu")
		(net "PCIE_TX_CAP_P70")
	)
	(segment
		(start 84.96046 -201.744326)
		(end 83.48599 -202.004168)
		(width 0.1397)
		(layer "In5.Cu")
		(net "PCIE_TX_CAP_P70")
	)
	(segment
		(start 209.91322 -80.92948)
		(end 164.129466 -146.309588)
		(width 0.1397)
		(layer "In5.Cu")
		(net "PCIE_TX_CAP_P70")
	)
	(arc
		(start 223.711262 -53.11521)
		(mid 223.694385 -53.094701)
		(end 223.67621 -53.075332)
		(width 0.1016)
		(layer "In5.Cu")
		(net "PCIE_TX_CAP_P70")
	)
	(arc
		(start 224.100136 -53.499766)
		(mid 224.016761 -53.48035)
		(end 223.95053 -53.426106)
		(width 0.1016)
		(layer "In5.Cu")
		(net "PCIE_TX_CAP_P70")
	)
	(arc
		(start 67.134994 -210.22945)
		(mid 67.07281 -210.584101)
		(end 66.893694 -210.896454)
		(width 0.1397)
		(layer "In5.Cu")
		(net "PCIE_TX_CAP_P70")
	)
	(arc
		(start 221.951804 -52.893468)
		(mid 221.838273 -52.870885)
		(end 221.742 -52.8066)
		(width 0.1016)
		(layer "In5.Cu")
		(net "PCIE_TX_CAP_P70")
	)
	(arc
		(start 223.61271 -53.012086)
		(mid 223.480837 -52.924286)
		(end 223.325436 -52.893468)
		(width 0.1016)
		(layer "In5.Cu")
		(net "PCIE_TX_CAP_P70")
	)
	(segment
		(start 304.1015 -34.739072)
		(end 304.1015 -35.8521)
		(width 0.136652)
		(layer "F.Cu")
		(net "PCIE_TX_CAP_P7")
	)
	(segment
		(start 258.59994 -31.999936)
		(end 258.59994 -31.812738)
		(width 0.136652)
		(layer "F.Cu")
		(net "PCIE_TX_CAP_P7")
	)
	(segment
		(start 303.98466 -36.134548)
		(end 303.8348 -36.284154)
		(width 0.136652)
		(layer "F.Cu")
		(net "PCIE_TX_CAP_P7")
	)
	(segment
		(start 258.59994 -31.812738)
		(end 259.912612 -30.500066)
		(width 0.136652)
		(layer "F.Cu")
		(net "PCIE_TX_CAP_P7")
	)
	(via
		(at 303.8348 -36.284154)
		(size 0.508)
		(drill 0.254)
		(layers "F.Cu" "B.Cu")
		(net "PCIE_TX_CAP_P7")
	)
	(via
		(at 259.912612 -30.500066)
		(size 0.4572)
		(drill 0.2032)
		(layers "F.Cu" "B.Cu")
		(net "PCIE_TX_CAP_P7")
	)
	(arc
		(start 304.1015 -35.8521)
		(mid 304.071189 -36.004955)
		(end 303.98466 -36.134548)
		(width 0.136652)
		(layer "F.Cu")
		(net "PCIE_TX_CAP_P7")
	)
	(arc
		(start 303.784 -33.9725)
		(mid 304.019003 -34.324206)
		(end 304.1015 -34.739072)
		(width 0.136652)
		(layer "F.Cu")
		(net "PCIE_TX_CAP_P7")
	)
	(segment
		(start 301.514256 -40.721788)
		(end 297.07586 -41.538652)
		(width 0.1397)
		(layer "In5.Cu")
		(net "PCIE_TX_CAP_P7")
	)
	(segment
		(start 297.07586 -41.538652)
		(end 292.130226 -40.66667)
		(width 0.1397)
		(layer "In5.Cu")
		(net "PCIE_TX_CAP_P7")
	)
	(segment
		(start 259.671312 -30.741366)
		(end 259.912612 -30.500066)
		(width 0.1397)
		(layer "In5.Cu")
		(net "PCIE_TX_CAP_P7")
	)
	(segment
		(start 283.19603 -39.254176)
		(end 279.929844 -36.966906)
		(width 0.1397)
		(layer "In5.Cu")
		(net "PCIE_TX_CAP_P7")
	)
	(segment
		(start 303.894236 -38.057582)
		(end 303.125378 -39.593012)
		(width 0.1397)
		(layer "In5.Cu")
		(net "PCIE_TX_CAP_P7")
	)
	(segment
		(start 303.125378 -39.593012)
		(end 301.514256 -40.721788)
		(width 0.1397)
		(layer "In5.Cu")
		(net "PCIE_TX_CAP_P7")
	)
	(segment
		(start 262.038592 -31.068264)
		(end 259.744464 -31.068264)
		(width 0.1397)
		(layer "In5.Cu")
		(net "PCIE_TX_CAP_P7")
	)
	(segment
		(start 259.744464 -31.068264)
		(end 259.671312 -30.995112)
		(width 0.1397)
		(layer "In5.Cu")
		(net "PCIE_TX_CAP_P7")
	)
	(segment
		(start 304.0761 -37.062156)
		(end 304.0761 -37.377624)
		(width 0.1397)
		(layer "In5.Cu")
		(net "PCIE_TX_CAP_P7")
	)
	(segment
		(start 291.226748 -40.825928)
		(end 283.19603 -39.254176)
		(width 0.1397)
		(layer "In5.Cu")
		(net "PCIE_TX_CAP_P7")
	)
	(segment
		(start 292.130226 -40.66667)
		(end 291.226748 -40.825928)
		(width 0.1397)
		(layer "In5.Cu")
		(net "PCIE_TX_CAP_P7")
	)
	(segment
		(start 268.09192 -30.000702)
		(end 262.038592 -31.068264)
		(width 0.1397)
		(layer "In5.Cu")
		(net "PCIE_TX_CAP_P7")
	)
	(segment
		(start 279.929844 -36.966906)
		(end 277.743666 -33.844992)
		(width 0.1397)
		(layer "In5.Cu")
		(net "PCIE_TX_CAP_P7")
	)
	(segment
		(start 304.0761 -37.377624)
		(end 303.894236 -38.057582)
		(width 0.1397)
		(layer "In5.Cu")
		(net "PCIE_TX_CAP_P7")
	)
	(segment
		(start 259.671312 -30.995112)
		(end 259.671312 -30.741366)
		(width 0.1397)
		(layer "In5.Cu")
		(net "PCIE_TX_CAP_P7")
	)
	(segment
		(start 273.654774 -30.98165)
		(end 268.09192 -30.000702)
		(width 0.1397)
		(layer "In5.Cu")
		(net "PCIE_TX_CAP_P7")
	)
	(segment
		(start 277.743666 -33.844992)
		(end 273.654774 -30.98165)
		(width 0.1397)
		(layer "In5.Cu")
		(net "PCIE_TX_CAP_P7")
	)
	(arc
		(start 303.8348 -36.284154)
		(mid 304.014386 -36.654875)
		(end 304.0761 -37.062156)
		(width 0.1397)
		(layer "In5.Cu")
		(net "PCIE_TX_CAP_P7")
	)
	(segment
		(start 70.23227 -211.035392)
		(end 70.093586 -210.896454)
		(width 0.136652)
		(layer "F.Cu")
		(net "PCIE_TX_CAP_P69")
	)
	(segment
		(start 69.991986 -211.975954)
		(end 70.273672 -211.694268)
		(width 0.136652)
		(layer "F.Cu")
		(net "PCIE_TX_CAP_P69")
	)
	(segment
		(start 223.60001 -53.999892)
		(end 223.100138 -54.499764)
		(width 0.136652)
		(layer "F.Cu")
		(net "PCIE_TX_CAP_P69")
	)
	(segment
		(start 70.341236 -211.5312)
		(end 70.341236 -211.298028)
		(width 0.136652)
		(layer "F.Cu")
		(net "PCIE_TX_CAP_P69")
	)
	(via
		(at 223.100138 -54.499764)
		(size 0.4572)
		(drill 0.2032)
		(layers "F.Cu" "B.Cu")
		(net "PCIE_TX_CAP_P69")
	)
	(via
		(at 70.093586 -210.896454)
		(size 0.508)
		(drill 0.254)
		(layers "F.Cu" "B.Cu")
		(net "PCIE_TX_CAP_P69")
	)
	(arc
		(start 70.341236 -211.298028)
		(mid 70.312867 -211.155876)
		(end 70.23227 -211.035392)
		(width 0.136652)
		(layer "F.Cu")
		(net "PCIE_TX_CAP_P69")
	)
	(arc
		(start 70.273672 -211.694268)
		(mid 70.323663 -211.619452)
		(end 70.341236 -211.5312)
		(width 0.136652)
		(layer "F.Cu")
		(net "PCIE_TX_CAP_P69")
	)
	(segment
		(start 70.334886 -208.081372)
		(end 70.334886 -210.1088)
		(width 0.1397)
		(layer "In5.Cu")
		(net "PCIE_TX_CAP_P69")
	)
	(segment
		(start 71.517764 -206.391764)
		(end 70.334886 -208.081372)
		(width 0.1397)
		(layer "In5.Cu")
		(net "PCIE_TX_CAP_P69")
	)
	(segment
		(start 221.7928 -53.8226)
		(end 219.452444 -53.8226)
		(width 0.1397)
		(layer "In5.Cu")
		(net "PCIE_TX_CAP_P69")
	)
	(segment
		(start 78.998318 -203.938378)
		(end 73.68286 -204.875892)
		(width 0.1397)
		(layer "In5.Cu")
		(net "PCIE_TX_CAP_P69")
	)
	(segment
		(start 222.894906 -54.353968)
		(end 222.856298 -54.303676)
		(width 0.1016)
		(layer "In5.Cu")
		(net "PCIE_TX_CAP_P69")
	)
	(segment
		(start 218.24188 -54.03596)
		(end 216.608406 -55.179722)
		(width 0.1397)
		(layer "In5.Cu")
		(net "PCIE_TX_CAP_P69")
	)
	(segment
		(start 222.856298 -54.303676)
		(end 222.849694 -54.295294)
		(width 0.1016)
		(layer "In5.Cu")
		(net "PCIE_TX_CAP_P69")
	)
	(segment
		(start 221.82201 -53.85181)
		(end 221.7928 -53.8226)
		(width 0.1016)
		(layer "In5.Cu")
		(net "PCIE_TX_CAP_P69")
	)
	(segment
		(start 73.68286 -204.875892)
		(end 71.517764 -206.391764)
		(width 0.1397)
		(layer "In5.Cu")
		(net "PCIE_TX_CAP_P69")
	)
	(segment
		(start 222.676212 -54.07533)
		(end 222.612966 -54.012338)
		(width 0.1016)
		(layer "In5.Cu")
		(net "PCIE_TX_CAP_P69")
	)
	(segment
		(start 164.958776 -146.871944)
		(end 84.96046 -202.887326)
		(width 0.1397)
		(layer "In5.Cu")
		(net "PCIE_TX_CAP_P69")
	)
	(segment
		(start 222.849694 -54.295294)
		(end 222.786956 -54.21376)
		(width 0.1016)
		(layer "In5.Cu")
		(net "PCIE_TX_CAP_P69")
	)
	(segment
		(start 222.612966 -54.012338)
		(end 222.612712 -54.012084)
		(width 0.1016)
		(layer "In5.Cu")
		(net "PCIE_TX_CAP_P69")
	)
	(segment
		(start 84.96046 -202.887326)
		(end 78.998318 -203.938378)
		(width 0.1397)
		(layer "In5.Cu")
		(net "PCIE_TX_CAP_P69")
	)
	(segment
		(start 215.407494 -56.89473)
		(end 211.182204 -80.859376)
		(width 0.1397)
		(layer "In5.Cu")
		(net "PCIE_TX_CAP_P69")
	)
	(segment
		(start 216.608406 -55.179722)
		(end 215.407494 -56.89473)
		(width 0.1397)
		(layer "In5.Cu")
		(net "PCIE_TX_CAP_P69")
	)
	(segment
		(start 222.325438 -53.893466)
		(end 221.922594 -53.893466)
		(width 0.1016)
		(layer "In5.Cu")
		(net "PCIE_TX_CAP_P69")
	)
	(segment
		(start 222.950532 -54.426104)
		(end 222.900748 -54.361588)
		(width 0.1016)
		(layer "In5.Cu")
		(net "PCIE_TX_CAP_P69")
	)
	(segment
		(start 219.452444 -53.8226)
		(end 218.24188 -54.03596)
		(width 0.1397)
		(layer "In5.Cu")
		(net "PCIE_TX_CAP_P69")
	)
	(segment
		(start 222.786956 -54.21376)
		(end 222.711264 -54.115208)
		(width 0.1016)
		(layer "In5.Cu")
		(net "PCIE_TX_CAP_P69")
	)
	(segment
		(start 211.182204 -80.859376)
		(end 164.958776 -146.871944)
		(width 0.1397)
		(layer "In5.Cu")
		(net "PCIE_TX_CAP_P69")
	)
	(segment
		(start 222.900748 -54.361588)
		(end 222.894906 -54.353968)
		(width 0.1016)
		(layer "In5.Cu")
		(net "PCIE_TX_CAP_P69")
	)
	(arc
		(start 70.334886 -210.1088)
		(mid 70.273207 -210.520692)
		(end 70.093586 -210.896454)
		(width 0.1397)
		(layer "In5.Cu")
		(net "PCIE_TX_CAP_P69")
	)
	(arc
		(start 223.100138 -54.499764)
		(mid 223.016763 -54.480348)
		(end 222.950532 -54.426104)
		(width 0.1016)
		(layer "In5.Cu")
		(net "PCIE_TX_CAP_P69")
	)
	(arc
		(start 222.711264 -54.115208)
		(mid 222.694387 -54.094699)
		(end 222.676212 -54.07533)
		(width 0.1016)
		(layer "In5.Cu")
		(net "PCIE_TX_CAP_P69")
	)
	(arc
		(start 221.922594 -53.893466)
		(mid 221.868161 -53.882639)
		(end 221.82201 -53.85181)
		(width 0.1016)
		(layer "In5.Cu")
		(net "PCIE_TX_CAP_P69")
	)
	(arc
		(start 222.612712 -54.012084)
		(mid 222.480839 -53.924284)
		(end 222.325438 -53.893466)
		(width 0.1016)
		(layer "In5.Cu")
		(net "PCIE_TX_CAP_P69")
	)
	(segment
		(start 79.864966 -211.067904)
		(end 79.693516 -210.896454)
		(width 0.136652)
		(layer "F.Cu")
		(net "PCIE_TX_CAP_P68")
	)
	(segment
		(start 79.941166 -211.5312)
		(end 79.941166 -211.2518)
		(width 0.136652)
		(layer "F.Cu")
		(net "PCIE_TX_CAP_P68")
	)
	(segment
		(start 79.591916 -211.975954)
		(end 79.873602 -211.694268)
		(width 0.136652)
		(layer "F.Cu")
		(net "PCIE_TX_CAP_P68")
	)
	(segment
		(start 224.600008 -54.99989)
		(end 224.100136 -55.499762)
		(width 0.136652)
		(layer "F.Cu")
		(net "PCIE_TX_CAP_P68")
	)
	(via
		(at 224.100136 -55.499762)
		(size 0.4572)
		(drill 0.2032)
		(layers "F.Cu" "B.Cu")
		(net "PCIE_TX_CAP_P68")
	)
	(via
		(at 79.693516 -210.896454)
		(size 0.508)
		(drill 0.254)
		(layers "F.Cu" "B.Cu")
		(net "PCIE_TX_CAP_P68")
	)
	(arc
		(start 79.873602 -211.694268)
		(mid 79.923593 -211.619452)
		(end 79.941166 -211.5312)
		(width 0.136652)
		(layer "F.Cu")
		(net "PCIE_TX_CAP_P68")
	)
	(arc
		(start 79.941166 -211.2518)
		(mid 79.921367 -211.152266)
		(end 79.864966 -211.067904)
		(width 0.136652)
		(layer "F.Cu")
		(net "PCIE_TX_CAP_P68")
	)
	(segment
		(start 84.833206 -204.89418)
		(end 80.99171 -207.589882)
		(width 0.1397)
		(layer "In5.Cu")
		(net "PCIE_TX_CAP_P68")
	)
	(segment
		(start 223.900746 -55.361586)
		(end 223.894904 -55.353966)
		(width 0.1016)
		(layer "In5.Cu")
		(net "PCIE_TX_CAP_P68")
	)
	(segment
		(start 223.95053 -55.426102)
		(end 223.900746 -55.361586)
		(width 0.1016)
		(layer "In5.Cu")
		(net "PCIE_TX_CAP_P68")
	)
	(segment
		(start 79.934816 -209.098896)
		(end 79.934816 -210.22945)
		(width 0.1397)
		(layer "In5.Cu")
		(net "PCIE_TX_CAP_P68")
	)
	(segment
		(start 223.612964 -55.012336)
		(end 223.61271 -55.012082)
		(width 0.1016)
		(layer "In5.Cu")
		(net "PCIE_TX_CAP_P68")
	)
	(segment
		(start 218.863418 -54.97576)
		(end 217.688922 -55.798212)
		(width 0.1397)
		(layer "In5.Cu")
		(net "PCIE_TX_CAP_P68")
	)
	(segment
		(start 164.64407 -149.009608)
		(end 84.833206 -204.89418)
		(width 0.1397)
		(layer "In5.Cu")
		(net "PCIE_TX_CAP_P68")
	)
	(segment
		(start 223.786954 -55.213758)
		(end 223.711262 -55.115206)
		(width 0.1016)
		(layer "In5.Cu")
		(net "PCIE_TX_CAP_P68")
	)
	(segment
		(start 165.129464 -148.669756)
		(end 164.64407 -149.009608)
		(width 0.1397)
		(layer "In5.Cu")
		(net "PCIE_TX_CAP_P68")
	)
	(segment
		(start 80.99171 -207.589882)
		(end 79.934816 -209.098896)
		(width 0.1397)
		(layer "In5.Cu")
		(net "PCIE_TX_CAP_P68")
	)
	(segment
		(start 212.405214 -81.152492)
		(end 165.129464 -148.669756)
		(width 0.1397)
		(layer "In5.Cu")
		(net "PCIE_TX_CAP_P68")
	)
	(segment
		(start 223.325436 -54.893464)
		(end 221.899734 -54.893464)
		(width 0.1016)
		(layer "In5.Cu")
		(net "PCIE_TX_CAP_P68")
	)
	(segment
		(start 221.7674 -54.8386)
		(end 219.642182 -54.8386)
		(width 0.1397)
		(layer "In5.Cu")
		(net "PCIE_TX_CAP_P68")
	)
	(segment
		(start 223.894904 -55.353966)
		(end 223.856296 -55.303674)
		(width 0.1016)
		(layer "In5.Cu")
		(net "PCIE_TX_CAP_P68")
	)
	(segment
		(start 223.67621 -55.075328)
		(end 223.612964 -55.012336)
		(width 0.1016)
		(layer "In5.Cu")
		(net "PCIE_TX_CAP_P68")
	)
	(segment
		(start 219.642182 -54.8386)
		(end 218.863418 -54.97576)
		(width 0.1397)
		(layer "In5.Cu")
		(net "PCIE_TX_CAP_P68")
	)
	(segment
		(start 217.688922 -55.798212)
		(end 216.60231 -57.349898)
		(width 0.1397)
		(layer "In5.Cu")
		(net "PCIE_TX_CAP_P68")
	)
	(segment
		(start 216.60231 -57.349898)
		(end 212.405214 -81.152492)
		(width 0.1397)
		(layer "In5.Cu")
		(net "PCIE_TX_CAP_P68")
	)
	(segment
		(start 223.849692 -55.295292)
		(end 223.786954 -55.213758)
		(width 0.1016)
		(layer "In5.Cu")
		(net "PCIE_TX_CAP_P68")
	)
	(segment
		(start 223.856296 -55.303674)
		(end 223.849692 -55.295292)
		(width 0.1016)
		(layer "In5.Cu")
		(net "PCIE_TX_CAP_P68")
	)
	(arc
		(start 223.711262 -55.115206)
		(mid 223.694385 -55.094697)
		(end 223.67621 -55.075328)
		(width 0.1016)
		(layer "In5.Cu")
		(net "PCIE_TX_CAP_P68")
	)
	(arc
		(start 224.100136 -55.499762)
		(mid 224.016761 -55.480346)
		(end 223.95053 -55.426102)
		(width 0.1016)
		(layer "In5.Cu")
		(net "PCIE_TX_CAP_P68")
	)
	(arc
		(start 223.61271 -55.012082)
		(mid 223.480837 -54.924282)
		(end 223.325436 -54.893464)
		(width 0.1016)
		(layer "In5.Cu")
		(net "PCIE_TX_CAP_P68")
	)
	(arc
		(start 79.934816 -210.22945)
		(mid 79.872632 -210.584101)
		(end 79.693516 -210.896454)
		(width 0.1397)
		(layer "In5.Cu")
		(net "PCIE_TX_CAP_P68")
	)
	(arc
		(start 221.899734 -54.893464)
		(mid 221.828096 -54.879214)
		(end 221.7674 -54.8386)
		(width 0.1016)
		(layer "In5.Cu")
		(net "PCIE_TX_CAP_P68")
	)
	(segment
		(start 83.141312 -211.5312)
		(end 83.141312 -211.3026)
		(width 0.136652)
		(layer "F.Cu")
		(net "PCIE_TX_CAP_P67")
	)
	(segment
		(start 82.792062 -211.975954)
		(end 83.073748 -211.694268)
		(width 0.136652)
		(layer "F.Cu")
		(net "PCIE_TX_CAP_P67")
	)
	(segment
		(start 83.029298 -211.03209)
		(end 82.893662 -210.896454)
		(width 0.136652)
		(layer "F.Cu")
		(net "PCIE_TX_CAP_P67")
	)
	(segment
		(start 223.60001 -55.999888)
		(end 223.100138 -56.49976)
		(width 0.136652)
		(layer "F.Cu")
		(net "PCIE_TX_CAP_P67")
	)
	(via
		(at 223.100138 -56.49976)
		(size 0.4572)
		(drill 0.2032)
		(layers "F.Cu" "B.Cu")
		(net "PCIE_TX_CAP_P67")
	)
	(via
		(at 82.893662 -210.896454)
		(size 0.508)
		(drill 0.254)
		(layers "F.Cu" "B.Cu")
		(net "PCIE_TX_CAP_P67")
	)
	(arc
		(start 83.073748 -211.694268)
		(mid 83.123739 -211.619452)
		(end 83.141312 -211.5312)
		(width 0.136652)
		(layer "F.Cu")
		(net "PCIE_TX_CAP_P67")
	)
	(arc
		(start 83.141312 -211.3026)
		(mid 83.112194 -211.156214)
		(end 83.029298 -211.03209)
		(width 0.136652)
		(layer "F.Cu")
		(net "PCIE_TX_CAP_P67")
	)
	(segment
		(start 223.099122 -56.500522)
		(end 223.099376 -56.500522)
		(width 0.1016)
		(layer "In5.Cu")
		(net "PCIE_TX_CAP_P67")
	)
	(segment
		(start 221.844362 -55.893462)
		(end 222.325438 -55.893462)
		(width 0.1016)
		(layer "In5.Cu")
		(net "PCIE_TX_CAP_P67")
	)
	(segment
		(start 213.372446 -81.47685)
		(end 217.51417 -57.9882)
		(width 0.1397)
		(layer "In5.Cu")
		(net "PCIE_TX_CAP_P67")
	)
	(segment
		(start 221.7674 -55.8292)
		(end 221.7801 -55.8292)
		(width 0.1016)
		(layer "In5.Cu")
		(net "PCIE_TX_CAP_P67")
	)
	(segment
		(start 221.7801 -55.8292)
		(end 221.844362 -55.893462)
		(width 0.1016)
		(layer "In5.Cu")
		(net "PCIE_TX_CAP_P67")
	)
	(segment
		(start 223.099376 -56.500522)
		(end 223.100138 -56.49976)
		(width 0.1016)
		(layer "In5.Cu")
		(net "PCIE_TX_CAP_P67")
	)
	(segment
		(start 165.83152 -149.372574)
		(end 213.372446 -81.47685)
		(width 0.1397)
		(layer "In5.Cu")
		(net "PCIE_TX_CAP_P67")
	)
	(segment
		(start 222.609664 -56.011064)
		(end 223.099122 -56.500522)
		(width 0.1016)
		(layer "In5.Cu")
		(net "PCIE_TX_CAP_P67")
	)
	(segment
		(start 85.487764 -205.629764)
		(end 165.83152 -149.372574)
		(width 0.1397)
		(layer "In5.Cu")
		(net "PCIE_TX_CAP_P67")
	)
	(segment
		(start 217.51417 -57.9882)
		(end 218.419172 -56.695848)
		(width 0.1397)
		(layer "In5.Cu")
		(net "PCIE_TX_CAP_P67")
	)
	(segment
		(start 83.134962 -210.22945)
		(end 83.134962 -208.98993)
		(width 0.1397)
		(layer "In5.Cu")
		(net "PCIE_TX_CAP_P67")
	)
	(segment
		(start 219.530422 -55.917846)
		(end 220.034866 -55.8292)
		(width 0.1397)
		(layer "In5.Cu")
		(net "PCIE_TX_CAP_P67")
	)
	(segment
		(start 218.419172 -56.695848)
		(end 219.530422 -55.917846)
		(width 0.1397)
		(layer "In5.Cu")
		(net "PCIE_TX_CAP_P67")
	)
	(segment
		(start 220.034866 -55.8292)
		(end 221.7674 -55.8292)
		(width 0.1397)
		(layer "In5.Cu")
		(net "PCIE_TX_CAP_P67")
	)
	(segment
		(start 83.134962 -208.98993)
		(end 85.487764 -205.629764)
		(width 0.1397)
		(layer "In5.Cu")
		(net "PCIE_TX_CAP_P67")
	)
	(arc
		(start 222.325438 -55.893462)
		(mid 222.479265 -55.923966)
		(end 222.609664 -56.011064)
		(width 0.1016)
		(layer "In5.Cu")
		(net "PCIE_TX_CAP_P67")
	)
	(arc
		(start 82.893662 -210.896454)
		(mid 83.0728 -210.584109)
		(end 83.134962 -210.22945)
		(width 0.1397)
		(layer "In5.Cu")
		(net "PCIE_TX_CAP_P67")
	)
	(segment
		(start 86.22919 -211.03209)
		(end 86.093554 -210.896454)
		(width 0.136652)
		(layer "F.Cu")
		(net "PCIE_TX_CAP_P66")
	)
	(segment
		(start 224.600008 -56.999886)
		(end 224.100136 -57.499758)
		(width 0.136652)
		(layer "F.Cu")
		(net "PCIE_TX_CAP_P66")
	)
	(segment
		(start 85.991954 -211.975954)
		(end 86.27364 -211.694268)
		(width 0.136652)
		(layer "F.Cu")
		(net "PCIE_TX_CAP_P66")
	)
	(segment
		(start 86.341204 -211.5312)
		(end 86.341204 -211.3026)
		(width 0.136652)
		(layer "F.Cu")
		(net "PCIE_TX_CAP_P66")
	)
	(via
		(at 224.100136 -57.499758)
		(size 0.4572)
		(drill 0.2032)
		(layers "F.Cu" "B.Cu")
		(net "PCIE_TX_CAP_P66")
	)
	(via
		(at 86.093554 -210.896454)
		(size 0.508)
		(drill 0.254)
		(layers "F.Cu" "B.Cu")
		(net "PCIE_TX_CAP_P66")
	)
	(arc
		(start 86.27364 -211.694268)
		(mid 86.323631 -211.619452)
		(end 86.341204 -211.5312)
		(width 0.136652)
		(layer "F.Cu")
		(net "PCIE_TX_CAP_P66")
	)
	(arc
		(start 86.341204 -211.3026)
		(mid 86.312086 -211.156214)
		(end 86.22919 -211.03209)
		(width 0.136652)
		(layer "F.Cu")
		(net "PCIE_TX_CAP_P66")
	)
	(segment
		(start 223.856296 -57.30367)
		(end 223.894904 -57.353962)
		(width 0.1016)
		(layer "In5.Cu")
		(net "PCIE_TX_CAP_P66")
	)
	(segment
		(start 220.14053 -56.920892)
		(end 220.714824 -56.8198)
		(width 0.1397)
		(layer "In5.Cu")
		(net "PCIE_TX_CAP_P66")
	)
	(segment
		(start 88.305132 -205.197964)
		(end 166.767764 -150.257764)
		(width 0.1397)
		(layer "In5.Cu")
		(net "PCIE_TX_CAP_P66")
	)
	(segment
		(start 217.952066 -61.38672)
		(end 218.467686 -58.465212)
		(width 0.1397)
		(layer "In5.Cu")
		(net "PCIE_TX_CAP_P66")
	)
	(segment
		(start 220.714824 -56.8198)
		(end 221.8182 -56.8198)
		(width 0.1397)
		(layer "In5.Cu")
		(net "PCIE_TX_CAP_P66")
	)
	(segment
		(start 223.61271 -57.012078)
		(end 223.612964 -57.012332)
		(width 0.1016)
		(layer "In5.Cu")
		(net "PCIE_TX_CAP_P66")
	)
	(segment
		(start 216.948512 -67.079368)
		(end 217.394028 -64.551814)
		(width 0.1397)
		(layer "In5.Cu")
		(net "PCIE_TX_CAP_P66")
	)
	(segment
		(start 214.235284 -82.467196)
		(end 215.50503 -75.265788)
		(width 0.1397)
		(layer "In5.Cu")
		(net "PCIE_TX_CAP_P66")
	)
	(segment
		(start 215.50503 -75.265788)
		(end 216.948512 -67.079368)
		(width 0.1397)
		(layer "In5.Cu")
		(net "PCIE_TX_CAP_P66")
	)
	(segment
		(start 223.849692 -57.295288)
		(end 223.856296 -57.30367)
		(width 0.1016)
		(layer "In5.Cu")
		(net "PCIE_TX_CAP_P66")
	)
	(segment
		(start 218.980258 -57.733438)
		(end 220.14053 -56.920892)
		(width 0.1397)
		(layer "In5.Cu")
		(net "PCIE_TX_CAP_P66")
	)
	(segment
		(start 221.996 -56.89346)
		(end 223.325436 -56.89346)
		(width 0.1016)
		(layer "In5.Cu")
		(net "PCIE_TX_CAP_P66")
	)
	(segment
		(start 166.767764 -150.257764)
		(end 214.235284 -82.467196)
		(width 0.1397)
		(layer "In5.Cu")
		(net "PCIE_TX_CAP_P66")
	)
	(segment
		(start 217.582242 -63.483236)
		(end 217.952066 -61.38672)
		(width 0.1397)
		(layer "In5.Cu")
		(net "PCIE_TX_CAP_P66")
	)
	(segment
		(start 223.612964 -57.012332)
		(end 223.67621 -57.075324)
		(width 0.1016)
		(layer "In5.Cu")
		(net "PCIE_TX_CAP_P66")
	)
	(segment
		(start 86.334854 -210.22945)
		(end 86.334854 -208.01203)
		(width 0.1397)
		(layer "In5.Cu")
		(net "PCIE_TX_CAP_P66")
	)
	(segment
		(start 223.786954 -57.213754)
		(end 223.849692 -57.295288)
		(width 0.1016)
		(layer "In5.Cu")
		(net "PCIE_TX_CAP_P66")
	)
	(segment
		(start 217.394028 -64.551814)
		(end 217.582242 -63.483236)
		(width 0.1397)
		(layer "In5.Cu")
		(net "PCIE_TX_CAP_P66")
	)
	(segment
		(start 223.900746 -57.361582)
		(end 223.95053 -57.426098)
		(width 0.1016)
		(layer "In5.Cu")
		(net "PCIE_TX_CAP_P66")
	)
	(segment
		(start 218.467686 -58.465212)
		(end 218.980258 -57.733438)
		(width 0.1397)
		(layer "In5.Cu")
		(net "PCIE_TX_CAP_P66")
	)
	(segment
		(start 223.711262 -57.115202)
		(end 223.786954 -57.213754)
		(width 0.1016)
		(layer "In5.Cu")
		(net "PCIE_TX_CAP_P66")
	)
	(segment
		(start 223.894904 -57.353962)
		(end 223.900746 -57.361582)
		(width 0.1016)
		(layer "In5.Cu")
		(net "PCIE_TX_CAP_P66")
	)
	(segment
		(start 86.334854 -208.01203)
		(end 88.305132 -205.197964)
		(width 0.1397)
		(layer "In5.Cu")
		(net "PCIE_TX_CAP_P66")
	)
	(arc
		(start 86.093554 -210.896454)
		(mid 86.272692 -210.584109)
		(end 86.334854 -210.22945)
		(width 0.1397)
		(layer "In5.Cu")
		(net "PCIE_TX_CAP_P66")
	)
	(arc
		(start 223.67621 -57.075324)
		(mid 223.694387 -57.094691)
		(end 223.711262 -57.115202)
		(width 0.1016)
		(layer "In5.Cu")
		(net "PCIE_TX_CAP_P66")
	)
	(arc
		(start 223.325436 -56.89346)
		(mid 223.480835 -56.924282)
		(end 223.61271 -57.012078)
		(width 0.1016)
		(layer "In5.Cu")
		(net "PCIE_TX_CAP_P66")
	)
	(arc
		(start 223.95053 -57.426098)
		(mid 224.016755 -57.480355)
		(end 224.100136 -57.499758)
		(width 0.1016)
		(layer "In5.Cu")
		(net "PCIE_TX_CAP_P66")
	)
	(arc
		(start 221.8182 -56.8198)
		(mid 221.899775 -56.874307)
		(end 221.996 -56.89346)
		(width 0.1016)
		(layer "In5.Cu")
		(net "PCIE_TX_CAP_P66")
	)
	(segment
		(start 223.60001 -57.999884)
		(end 223.100138 -58.499756)
		(width 0.136652)
		(layer "F.Cu")
		(net "PCIE_TX_CAP_P65")
	)
	(segment
		(start 89.54135 -211.5312)
		(end 89.54135 -211.33435)
		(width 0.136652)
		(layer "F.Cu")
		(net "PCIE_TX_CAP_P65")
	)
	(segment
		(start 89.40673 -211.009738)
		(end 89.2937 -210.896454)
		(width 0.136652)
		(layer "F.Cu")
		(net "PCIE_TX_CAP_P65")
	)
	(segment
		(start 89.1921 -211.975954)
		(end 89.473786 -211.694268)
		(width 0.136652)
		(layer "F.Cu")
		(net "PCIE_TX_CAP_P65")
	)
	(via
		(at 223.100138 -58.499756)
		(size 0.4572)
		(drill 0.2032)
		(layers "F.Cu" "B.Cu")
		(net "PCIE_TX_CAP_P65")
	)
	(via
		(at 89.2937 -210.896454)
		(size 0.508)
		(drill 0.254)
		(layers "F.Cu" "B.Cu")
		(net "PCIE_TX_CAP_P65")
	)
	(arc
		(start 89.54135 -211.33435)
		(mid 89.50631 -211.158663)
		(end 89.40673 -211.009738)
		(width 0.136652)
		(layer "F.Cu")
		(net "PCIE_TX_CAP_P65")
	)
	(arc
		(start 89.473786 -211.694268)
		(mid 89.523777 -211.619452)
		(end 89.54135 -211.5312)
		(width 0.136652)
		(layer "F.Cu")
		(net "PCIE_TX_CAP_P65")
	)
	(segment
		(start 222.856298 -58.303668)
		(end 222.894906 -58.35396)
		(width 0.1016)
		(layer "In5.Cu")
		(net "PCIE_TX_CAP_P65")
	)
	(segment
		(start 167.402764 -151.146764)
		(end 215.640158 -82.25663)
		(width 0.1397)
		(layer "In5.Cu")
		(net "PCIE_TX_CAP_P65")
	)
	(segment
		(start 222.849694 -58.295286)
		(end 222.856298 -58.303668)
		(width 0.1016)
		(layer "In5.Cu")
		(net "PCIE_TX_CAP_P65")
	)
	(segment
		(start 222.612966 -58.01233)
		(end 222.676212 -58.075322)
		(width 0.1016)
		(layer "In5.Cu")
		(net "PCIE_TX_CAP_P65")
	)
	(segment
		(start 215.640158 -82.25663)
		(end 216.691718 -76.291948)
		(width 0.1397)
		(layer "In5.Cu")
		(net "PCIE_TX_CAP_P65")
	)
	(segment
		(start 91.74734 -204.121258)
		(end 167.402764 -151.146764)
		(width 0.1397)
		(layer "In5.Cu")
		(net "PCIE_TX_CAP_P65")
	)
	(segment
		(start 218.98483 -63.28791)
		(end 219.734892 -59.03468)
		(width 0.1397)
		(layer "In5.Cu")
		(net "PCIE_TX_CAP_P65")
	)
	(segment
		(start 218.122754 -68.176648)
		(end 218.98483 -63.28791)
		(width 0.1397)
		(layer "In5.Cu")
		(net "PCIE_TX_CAP_P65")
	)
	(segment
		(start 222.711264 -58.1152)
		(end 222.786956 -58.213752)
		(width 0.1016)
		(layer "In5.Cu")
		(net "PCIE_TX_CAP_P65")
	)
	(segment
		(start 221.804992 -57.893458)
		(end 222.325438 -57.893458)
		(width 0.1016)
		(layer "In5.Cu")
		(net "PCIE_TX_CAP_P65")
	)
	(segment
		(start 222.612712 -58.012076)
		(end 222.612966 -58.01233)
		(width 0.1016)
		(layer "In5.Cu")
		(net "PCIE_TX_CAP_P65")
	)
	(segment
		(start 89.535 -210.22945)
		(end 89.535 -207.280764)
		(width 0.1397)
		(layer "In5.Cu")
		(net "PCIE_TX_CAP_P65")
	)
	(segment
		(start 89.535 -207.280764)
		(end 91.74734 -204.121258)
		(width 0.1397)
		(layer "In5.Cu")
		(net "PCIE_TX_CAP_P65")
	)
	(segment
		(start 222.786956 -58.213752)
		(end 222.823278 -58.26125)
		(width 0.1016)
		(layer "In5.Cu")
		(net "PCIE_TX_CAP_P65")
	)
	(segment
		(start 219.734892 -59.03468)
		(end 220.270578 -58.27014)
		(width 0.1397)
		(layer "In5.Cu")
		(net "PCIE_TX_CAP_P65")
	)
	(segment
		(start 222.900748 -58.36158)
		(end 222.950532 -58.426096)
		(width 0.1016)
		(layer "In5.Cu")
		(net "PCIE_TX_CAP_P65")
	)
	(segment
		(start 216.691718 -76.291948)
		(end 218.122754 -68.176648)
		(width 0.1397)
		(layer "In5.Cu")
		(net "PCIE_TX_CAP_P65")
	)
	(segment
		(start 220.772482 -57.918604)
		(end 221.243144 -57.8358)
		(width 0.1397)
		(layer "In5.Cu")
		(net "PCIE_TX_CAP_P65")
	)
	(segment
		(start 222.894906 -58.35396)
		(end 222.900748 -58.36158)
		(width 0.1016)
		(layer "In5.Cu")
		(net "PCIE_TX_CAP_P65")
	)
	(segment
		(start 220.270578 -58.27014)
		(end 220.772482 -57.918604)
		(width 0.1397)
		(layer "In5.Cu")
		(net "PCIE_TX_CAP_P65")
	)
	(segment
		(start 222.823278 -58.26125)
		(end 222.849694 -58.295286)
		(width 0.1016)
		(layer "In5.Cu")
		(net "PCIE_TX_CAP_P65")
	)
	(segment
		(start 221.243144 -57.8358)
		(end 221.6658 -57.8358)
		(width 0.1397)
		(layer "In5.Cu")
		(net "PCIE_TX_CAP_P65")
	)
	(arc
		(start 222.325438 -57.893458)
		(mid 222.480837 -57.92428)
		(end 222.612712 -58.012076)
		(width 0.1016)
		(layer "In5.Cu")
		(net "PCIE_TX_CAP_P65")
	)
	(arc
		(start 89.2937 -210.896454)
		(mid 89.472838 -210.584109)
		(end 89.535 -210.22945)
		(width 0.1397)
		(layer "In5.Cu")
		(net "PCIE_TX_CAP_P65")
	)
	(arc
		(start 222.676212 -58.075322)
		(mid 222.694389 -58.094689)
		(end 222.711264 -58.1152)
		(width 0.1016)
		(layer "In5.Cu")
		(net "PCIE_TX_CAP_P65")
	)
	(arc
		(start 221.6658 -57.8358)
		(mid 221.729662 -57.878471)
		(end 221.804992 -57.893458)
		(width 0.1016)
		(layer "In5.Cu")
		(net "PCIE_TX_CAP_P65")
	)
	(arc
		(start 222.950532 -58.426096)
		(mid 223.016757 -58.480353)
		(end 223.100138 -58.499756)
		(width 0.1016)
		(layer "In5.Cu")
		(net "PCIE_TX_CAP_P65")
	)
	(segment
		(start 224.600008 -58.999882)
		(end 224.100136 -59.499754)
		(width 0.136652)
		(layer "F.Cu")
		(net "PCIE_TX_CAP_P64")
	)
	(segment
		(start 92.625164 -211.027772)
		(end 92.493592 -210.896454)
		(width 0.136652)
		(layer "F.Cu")
		(net "PCIE_TX_CAP_P64")
	)
	(segment
		(start 92.741242 -211.5312)
		(end 92.741242 -211.308442)
		(width 0.136652)
		(layer "F.Cu")
		(net "PCIE_TX_CAP_P64")
	)
	(segment
		(start 92.391992 -211.975954)
		(end 92.673678 -211.694268)
		(width 0.136652)
		(layer "F.Cu")
		(net "PCIE_TX_CAP_P64")
	)
	(via
		(at 92.493592 -210.896454)
		(size 0.508)
		(drill 0.254)
		(layers "F.Cu" "B.Cu")
		(net "PCIE_TX_CAP_P64")
	)
	(via
		(at 224.100136 -59.499754)
		(size 0.4572)
		(drill 0.2032)
		(layers "F.Cu" "B.Cu")
		(net "PCIE_TX_CAP_P64")
	)
	(arc
		(start 92.673678 -211.694268)
		(mid 92.723669 -211.619452)
		(end 92.741242 -211.5312)
		(width 0.136652)
		(layer "F.Cu")
		(net "PCIE_TX_CAP_P64")
	)
	(arc
		(start 92.741242 -211.308442)
		(mid 92.711124 -211.156559)
		(end 92.625164 -211.027772)
		(width 0.136652)
		(layer "F.Cu")
		(net "PCIE_TX_CAP_P64")
	)
	(segment
		(start 221.140782 -59.82843)
		(end 221.489524 -59.33059)
		(width 0.1397)
		(layer "In5.Cu")
		(net "PCIE_TX_CAP_P64")
	)
	(segment
		(start 99.323398 -203.703174)
		(end 169.411904 -154.627326)
		(width 0.1397)
		(layer "In5.Cu")
		(net "PCIE_TX_CAP_P64")
	)
	(segment
		(start 222.377 -58.893456)
		(end 223.409764 -58.893456)
		(width 0.1016)
		(layer "In5.Cu")
		(net "PCIE_TX_CAP_P64")
	)
	(segment
		(start 92.734892 -210.1088)
		(end 92.734892 -207.334866)
		(width 0.1397)
		(layer "In5.Cu")
		(net "PCIE_TX_CAP_P64")
	)
	(segment
		(start 220.7387 -62.107826)
		(end 221.140782 -59.82843)
		(width 0.1397)
		(layer "In5.Cu")
		(net "PCIE_TX_CAP_P64")
	)
	(segment
		(start 95.733108 -204.336142)
		(end 99.323398 -203.703174)
		(width 0.1397)
		(layer "In5.Cu")
		(net "PCIE_TX_CAP_P64")
	)
	(segment
		(start 223.835722 -59.333384)
		(end 223.838262 -59.338464)
		(width 0.1016)
		(layer "In5.Cu")
		(net "PCIE_TX_CAP_P64")
	)
	(segment
		(start 169.411904 -154.627326)
		(end 216.209626 -87.793322)
		(width 0.1397)
		(layer "In5.Cu")
		(net "PCIE_TX_CAP_P64")
	)
	(segment
		(start 93.583506 -206.486252)
		(end 95.733108 -204.336142)
		(width 0.1397)
		(layer "In5.Cu")
		(net "PCIE_TX_CAP_P64")
	)
	(segment
		(start 223.711262 -59.115198)
		(end 223.711516 -59.114944)
		(width 0.1016)
		(layer "In5.Cu")
		(net "PCIE_TX_CAP_P64")
	)
	(segment
		(start 92.734892 -207.334866)
		(end 93.583506 -206.486252)
		(width 0.1397)
		(layer "In5.Cu")
		(net "PCIE_TX_CAP_P64")
	)
	(segment
		(start 216.209626 -87.793322)
		(end 219.271088 -70.431406)
		(width 0.1397)
		(layer "In5.Cu")
		(net "PCIE_TX_CAP_P64")
	)
	(segment
		(start 223.55429 -58.953146)
		(end 223.67621 -59.07532)
		(width 0.1016)
		(layer "In5.Cu")
		(net "PCIE_TX_CAP_P64")
	)
	(segment
		(start 223.780858 -59.224418)
		(end 223.835722 -59.333384)
		(width 0.1016)
		(layer "In5.Cu")
		(net "PCIE_TX_CAP_P64")
	)
	(segment
		(start 219.271088 -70.431406)
		(end 220.7387 -62.107826)
		(width 0.1397)
		(layer "In5.Cu")
		(net "PCIE_TX_CAP_P64")
	)
	(arc
		(start 221.489524 -59.33059)
		(mid 221.882347 -59.008648)
		(end 222.377 -58.893456)
		(width 0.1016)
		(layer "In5.Cu")
		(net "PCIE_TX_CAP_P64")
	)
	(arc
		(start 223.711516 -59.114944)
		(mid 223.748866 -59.167984)
		(end 223.780858 -59.224418)
		(width 0.1016)
		(layer "In5.Cu")
		(net "PCIE_TX_CAP_P64")
	)
	(arc
		(start 223.838262 -59.338464)
		(mid 223.848297 -59.356748)
		(end 223.859598 -59.374278)
		(width 0.1016)
		(layer "In5.Cu")
		(net "PCIE_TX_CAP_P64")
	)
	(arc
		(start 223.67621 -59.07532)
		(mid 223.694387 -59.094687)
		(end 223.711262 -59.115198)
		(width 0.1016)
		(layer "In5.Cu")
		(net "PCIE_TX_CAP_P64")
	)
	(arc
		(start 92.493592 -210.896454)
		(mid 92.673219 -210.520694)
		(end 92.734892 -210.1088)
		(width 0.1397)
		(layer "In5.Cu")
		(net "PCIE_TX_CAP_P64")
	)
	(arc
		(start 223.409764 -58.893456)
		(mid 223.487968 -58.908918)
		(end 223.55429 -58.953146)
		(width 0.1016)
		(layer "In5.Cu")
		(net "PCIE_TX_CAP_P64")
	)
	(arc
		(start 223.859598 -59.374278)
		(mid 223.964469 -59.466554)
		(end 224.100136 -59.499754)
		(width 0.1016)
		(layer "In5.Cu")
		(net "PCIE_TX_CAP_P64")
	)
	(segment
		(start 98.341434 -211.5312)
		(end 98.341434 -211.2772)
		(width 0.136652)
		(layer "F.Cu")
		(net "PCIE_TX_CAP_P63")
	)
	(segment
		(start 97.992184 -211.975954)
		(end 98.27387 -211.694268)
		(width 0.136652)
		(layer "F.Cu")
		(net "PCIE_TX_CAP_P63")
	)
	(segment
		(start 98.2472 -211.050124)
		(end 98.093784 -210.896454)
		(width 0.136652)
		(layer "F.Cu")
		(net "PCIE_TX_CAP_P63")
	)
	(segment
		(start 223.60001 -64.99987)
		(end 223.100138 -65.499742)
		(width 0.136652)
		(layer "F.Cu")
		(net "PCIE_TX_CAP_P63")
	)
	(via
		(at 223.100138 -65.499742)
		(size 0.4572)
		(drill 0.2032)
		(layers "F.Cu" "B.Cu")
		(net "PCIE_TX_CAP_P63")
	)
	(via
		(at 98.093784 -210.896454)
		(size 0.508)
		(drill 0.254)
		(layers "F.Cu" "B.Cu")
		(net "PCIE_TX_CAP_P63")
	)
	(arc
		(start 98.341434 -211.2772)
		(mid 98.316893 -211.154294)
		(end 98.2472 -211.050124)
		(width 0.136652)
		(layer "F.Cu")
		(net "PCIE_TX_CAP_P63")
	)
	(arc
		(start 98.27387 -211.694268)
		(mid 98.323861 -211.619452)
		(end 98.341434 -211.5312)
		(width 0.136652)
		(layer "F.Cu")
		(net "PCIE_TX_CAP_P63")
	)
	(segment
		(start 222.089472 -65.919604)
		(end 222.089472 -65.919858)
		(width 0.1397)
		(layer "In5.Cu")
		(net "PCIE_TX_CAP_P63")
	)
	(segment
		(start 98.335084 -210.22945)
		(end 98.335084 -207.705452)
		(width 0.1397)
		(layer "In5.Cu")
		(net "PCIE_TX_CAP_P63")
	)
	(segment
		(start 220.99778 -66.761868)
		(end 221.606872 -66.152776)
		(width 0.1397)
		(layer "In5.Cu")
		(net "PCIE_TX_CAP_P63")
	)
	(segment
		(start 99.972876 -205.366366)
		(end 170.040808 -156.304996)
		(width 0.1397)
		(layer "In5.Cu")
		(net "PCIE_TX_CAP_P63")
	)
	(segment
		(start 98.335084 -207.705452)
		(end 99.972876 -205.366366)
		(width 0.1397)
		(layer "In5.Cu")
		(net "PCIE_TX_CAP_P63")
	)
	(segment
		(start 216.962736 -89.293446)
		(end 220.843094 -67.29222)
		(width 0.1397)
		(layer "In5.Cu")
		(net "PCIE_TX_CAP_P63")
	)
	(segment
		(start 222.387414 -65.796414)
		(end 222.389954 -65.793874)
		(width 0.1397)
		(layer "In5.Cu")
		(net "PCIE_TX_CAP_P63")
	)
	(segment
		(start 221.839028 -65.98285)
		(end 221.859602 -65.972436)
		(width 0.1397)
		(layer "In5.Cu")
		(net "PCIE_TX_CAP_P63")
	)
	(segment
		(start 170.040808 -156.304996)
		(end 216.962736 -89.293446)
		(width 0.1397)
		(layer "In5.Cu")
		(net "PCIE_TX_CAP_P63")
	)
	(segment
		(start 220.8911 -67.019424)
		(end 220.90507 -66.939922)
		(width 0.1397)
		(layer "In5.Cu")
		(net "PCIE_TX_CAP_P63")
	)
	(segment
		(start 220.843094 -67.29222)
		(end 220.8911 -67.019424)
		(width 0.1397)
		(layer "In5.Cu")
		(net "PCIE_TX_CAP_P63")
	)
	(arc
		(start 222.389954 -65.793874)
		(mid 222.715789 -65.576158)
		(end 223.100138 -65.499742)
		(width 0.1397)
		(layer "In5.Cu")
		(net "PCIE_TX_CAP_P63")
	)
	(arc
		(start 222.074994 -65.919858)
		(mid 222.082234 -65.919788)
		(end 222.089472 -65.919604)
		(width 0.1397)
		(layer "In5.Cu")
		(net "PCIE_TX_CAP_P63")
	)
	(arc
		(start 221.606872 -66.152776)
		(mid 221.640395 -66.120815)
		(end 221.675452 -66.090546)
		(width 0.1397)
		(layer "In5.Cu")
		(net "PCIE_TX_CAP_P63")
	)
	(arc
		(start 98.093784 -210.896454)
		(mid 98.272922 -210.584109)
		(end 98.335084 -210.22945)
		(width 0.1397)
		(layer "In5.Cu")
		(net "PCIE_TX_CAP_P63")
	)
	(arc
		(start 221.859602 -65.972436)
		(mid 221.964131 -65.933162)
		(end 222.074994 -65.919858)
		(width 0.1397)
		(layer "In5.Cu")
		(net "PCIE_TX_CAP_P63")
	)
	(arc
		(start 220.90507 -66.939922)
		(mid 220.937706 -66.843749)
		(end 220.99778 -66.761868)
		(width 0.1397)
		(layer "In5.Cu")
		(net "PCIE_TX_CAP_P63")
	)
	(arc
		(start 222.089472 -65.919858)
		(mid 222.250729 -65.887782)
		(end 222.387414 -65.796414)
		(width 0.1397)
		(layer "In5.Cu")
		(net "PCIE_TX_CAP_P63")
	)
	(arc
		(start 221.675452 -66.090546)
		(mid 221.754437 -66.032441)
		(end 221.839028 -65.98285)
		(width 0.1397)
		(layer "In5.Cu")
		(net "PCIE_TX_CAP_P63")
	)
	(segment
		(start 224.600008 -63.999872)
		(end 224.100136 -64.499744)
		(width 0.136652)
		(layer "F.Cu")
		(net "PCIE_TX_CAP_P62")
	)
	(segment
		(start 101.435154 -211.037932)
		(end 101.293676 -210.896454)
		(width 0.136652)
		(layer "F.Cu")
		(net "PCIE_TX_CAP_P62")
	)
	(segment
		(start 101.541326 -211.5312)
		(end 101.541326 -211.294218)
		(width 0.136652)
		(layer "F.Cu")
		(net "PCIE_TX_CAP_P62")
	)
	(segment
		(start 101.192076 -211.975954)
		(end 101.473762 -211.694268)
		(width 0.136652)
		(layer "F.Cu")
		(net "PCIE_TX_CAP_P62")
	)
	(via
		(at 101.293676 -210.896454)
		(size 0.508)
		(drill 0.254)
		(layers "F.Cu" "B.Cu")
		(net "PCIE_TX_CAP_P62")
	)
	(via
		(at 224.100136 -64.499744)
		(size 0.4572)
		(drill 0.2032)
		(layers "F.Cu" "B.Cu")
		(net "PCIE_TX_CAP_P62")
	)
	(arc
		(start 101.541326 -211.294218)
		(mid 101.513736 -211.155511)
		(end 101.435154 -211.037932)
		(width 0.136652)
		(layer "F.Cu")
		(net "PCIE_TX_CAP_P62")
	)
	(arc
		(start 101.473762 -211.694268)
		(mid 101.523753 -211.619452)
		(end 101.541326 -211.5312)
		(width 0.136652)
		(layer "F.Cu")
		(net "PCIE_TX_CAP_P62")
	)
	(segment
		(start 105.46334 -203.301346)
		(end 170.714162 -157.611572)
		(width 0.1397)
		(layer "In5.Cu")
		(net "PCIE_TX_CAP_P62")
	)
	(segment
		(start 218.124532 -89.902538)
		(end 221.841822 -68.819776)
		(width 0.1397)
		(layer "In5.Cu")
		(net "PCIE_TX_CAP_P62")
	)
	(segment
		(start 221.841822 -68.819776)
		(end 222.710502 -67.579748)
		(width 0.1397)
		(layer "In5.Cu")
		(net "PCIE_TX_CAP_P62")
	)
	(segment
		(start 101.534976 -210.22945)
		(end 101.534976 -208.911952)
		(width 0.1397)
		(layer "In5.Cu")
		(net "PCIE_TX_CAP_P62")
	)
	(segment
		(start 223.578166 -64.91478)
		(end 223.73082 -64.761872)
		(width 0.1016)
		(layer "In5.Cu")
		(net "PCIE_TX_CAP_P62")
	)
	(segment
		(start 222.710502 -67.579748)
		(end 222.78086 -67.579748)
		(width 0.1016)
		(layer "In5.Cu")
		(net "PCIE_TX_CAP_P62")
	)
	(segment
		(start 222.78086 -67.579748)
		(end 223.493838 -66.86677)
		(width 0.1016)
		(layer "In5.Cu")
		(net "PCIE_TX_CAP_P62")
	)
	(segment
		(start 223.73082 -64.761872)
		(end 223.918018 -64.575182)
		(width 0.1016)
		(layer "In5.Cu")
		(net "PCIE_TX_CAP_P62")
	)
	(segment
		(start 170.714162 -157.611572)
		(end 218.124532 -89.902538)
		(width 0.1397)
		(layer "In5.Cu")
		(net "PCIE_TX_CAP_P62")
	)
	(segment
		(start 101.534976 -208.911952)
		(end 105.46334 -203.301346)
		(width 0.1397)
		(layer "In5.Cu")
		(net "PCIE_TX_CAP_P62")
	)
	(segment
		(start 223.493838 -66.86677)
		(end 223.493838 -65.118742)
		(width 0.1016)
		(layer "In5.Cu")
		(net "PCIE_TX_CAP_P62")
	)
	(arc
		(start 223.493838 -65.118742)
		(mid 223.5157 -65.008364)
		(end 223.578166 -64.91478)
		(width 0.1016)
		(layer "In5.Cu")
		(net "PCIE_TX_CAP_P62")
	)
	(arc
		(start 101.293676 -210.896454)
		(mid 101.472814 -210.584109)
		(end 101.534976 -210.22945)
		(width 0.1397)
		(layer "In5.Cu")
		(net "PCIE_TX_CAP_P62")
	)
	(arc
		(start 223.918018 -64.575182)
		(mid 224.001574 -64.519351)
		(end 224.100136 -64.499744)
		(width 0.1016)
		(layer "In5.Cu")
		(net "PCIE_TX_CAP_P62")
	)
	(segment
		(start 104.392222 -211.975954)
		(end 104.673908 -211.694268)
		(width 0.136652)
		(layer "F.Cu")
		(net "PCIE_TX_CAP_P61")
	)
	(segment
		(start 104.741472 -211.5312)
		(end 104.741472 -211.293456)
		(width 0.136652)
		(layer "F.Cu")
		(net "PCIE_TX_CAP_P61")
	)
	(segment
		(start 225.600006 -64.99987)
		(end 225.100134 -65.499742)
		(width 0.136652)
		(layer "F.Cu")
		(net "PCIE_TX_CAP_P61")
	)
	(segment
		(start 104.635808 -211.03844)
		(end 104.493822 -210.896454)
		(width 0.136652)
		(layer "F.Cu")
		(net "PCIE_TX_CAP_P61")
	)
	(via
		(at 104.493822 -210.896454)
		(size 0.508)
		(drill 0.254)
		(layers "F.Cu" "B.Cu")
		(net "PCIE_TX_CAP_P61")
	)
	(via
		(at 225.100134 -65.499742)
		(size 0.4572)
		(drill 0.2032)
		(layers "F.Cu" "B.Cu")
		(net "PCIE_TX_CAP_P61")
	)
	(arc
		(start 104.673908 -211.694268)
		(mid 104.723899 -211.619452)
		(end 104.741472 -211.5312)
		(width 0.136652)
		(layer "F.Cu")
		(net "PCIE_TX_CAP_P61")
	)
	(arc
		(start 104.741472 -211.293456)
		(mid 104.714017 -211.15543)
		(end 104.635808 -211.03844)
		(width 0.136652)
		(layer "F.Cu")
		(net "PCIE_TX_CAP_P61")
	)
	(segment
		(start 224.4344 -66.9798)
		(end 224.4344 -68.825618)
		(width 0.1397)
		(layer "In5.Cu")
		(net "PCIE_TX_CAP_P61")
	)
	(segment
		(start 224.918016 -65.57518)
		(end 224.578164 -65.914778)
		(width 0.1016)
		(layer "In5.Cu")
		(net "PCIE_TX_CAP_P61")
	)
	(segment
		(start 104.735122 -209.046572)
		(end 104.735122 -210.22945)
		(width 0.1397)
		(layer "In5.Cu")
		(net "PCIE_TX_CAP_P61")
	)
	(segment
		(start 104.95534 -207.797146)
		(end 104.735122 -209.046572)
		(width 0.1397)
		(layer "In5.Cu")
		(net "PCIE_TX_CAP_P61")
	)
	(segment
		(start 224.493836 -66.920364)
		(end 224.4344 -66.9798)
		(width 0.1016)
		(layer "In5.Cu")
		(net "PCIE_TX_CAP_P61")
	)
	(segment
		(start 171.896786 -158.371286)
		(end 108.462826 -202.787758)
		(width 0.1397)
		(layer "In5.Cu")
		(net "PCIE_TX_CAP_P61")
	)
	(segment
		(start 108.462826 -202.787758)
		(end 104.95534 -207.797146)
		(width 0.1397)
		(layer "In5.Cu")
		(net "PCIE_TX_CAP_P61")
	)
	(segment
		(start 221.015052 -88.223344)
		(end 171.896786 -158.371286)
		(width 0.1397)
		(layer "In5.Cu")
		(net "PCIE_TX_CAP_P61")
	)
	(segment
		(start 224.4344 -68.825618)
		(end 221.015052 -88.223344)
		(width 0.1397)
		(layer "In5.Cu")
		(net "PCIE_TX_CAP_P61")
	)
	(segment
		(start 224.493836 -66.11874)
		(end 224.493836 -66.920364)
		(width 0.1016)
		(layer "In5.Cu")
		(net "PCIE_TX_CAP_P61")
	)
	(arc
		(start 104.735122 -210.22945)
		(mid 104.672938 -210.584101)
		(end 104.493822 -210.896454)
		(width 0.1397)
		(layer "In5.Cu")
		(net "PCIE_TX_CAP_P61")
	)
	(arc
		(start 224.578164 -65.914778)
		(mid 224.51572 -66.008372)
		(end 224.493836 -66.11874)
		(width 0.1016)
		(layer "In5.Cu")
		(net "PCIE_TX_CAP_P61")
	)
	(arc
		(start 225.100134 -65.499742)
		(mid 225.001572 -65.519347)
		(end 224.918016 -65.57518)
		(width 0.1016)
		(layer "In5.Cu")
		(net "PCIE_TX_CAP_P61")
	)
	(segment
		(start 107.592114 -211.975954)
		(end 107.8738 -211.694268)
		(width 0.136652)
		(layer "F.Cu")
		(net "PCIE_TX_CAP_P60")
	)
	(segment
		(start 226.600004 -63.999872)
		(end 226.100132 -64.499744)
		(width 0.136652)
		(layer "F.Cu")
		(net "PCIE_TX_CAP_P60")
	)
	(segment
		(start 107.814618 -211.017358)
		(end 107.693714 -210.896454)
		(width 0.136652)
		(layer "F.Cu")
		(net "PCIE_TX_CAP_P60")
	)
	(segment
		(start 107.941364 -211.5312)
		(end 107.941364 -211.323428)
		(width 0.136652)
		(layer "F.Cu")
		(net "PCIE_TX_CAP_P60")
	)
	(via
		(at 226.100132 -64.499744)
		(size 0.4572)
		(drill 0.2032)
		(layers "F.Cu" "B.Cu")
		(net "PCIE_TX_CAP_P60")
	)
	(via
		(at 107.693714 -210.896454)
		(size 0.508)
		(drill 0.254)
		(layers "F.Cu" "B.Cu")
		(net "PCIE_TX_CAP_P60")
	)
	(arc
		(start 107.941364 -211.323428)
		(mid 107.908418 -211.157796)
		(end 107.814618 -211.017358)
		(width 0.136652)
		(layer "F.Cu")
		(net "PCIE_TX_CAP_P60")
	)
	(arc
		(start 107.8738 -211.694268)
		(mid 107.923791 -211.619452)
		(end 107.941364 -211.5312)
		(width 0.136652)
		(layer "F.Cu")
		(net "PCIE_TX_CAP_P60")
	)
	(segment
		(start 107.935014 -209.301842)
		(end 108.567474 -205.714854)
		(width 0.1397)
		(layer "In5.Cu")
		(net "PCIE_TX_CAP_P60")
	)
	(segment
		(start 225.493834 -66.99885)
		(end 225.493834 -65.118742)
		(width 0.1016)
		(layer "In5.Cu")
		(net "PCIE_TX_CAP_P60")
	)
	(segment
		(start 108.567474 -205.714854)
		(end 109.84103 -203.896214)
		(width 0.1397)
		(layer "In5.Cu")
		(net "PCIE_TX_CAP_P60")
	)
	(segment
		(start 225.462084 -68.784724)
		(end 225.462084 -67.0306)
		(width 0.1397)
		(layer "In5.Cu")
		(net "PCIE_TX_CAP_P60")
	)
	(segment
		(start 226.186238 -72.405494)
		(end 225.462084 -68.784724)
		(width 0.1397)
		(layer "In5.Cu")
		(net "PCIE_TX_CAP_P60")
	)
	(segment
		(start 225.759264 -64.733678)
		(end 225.918014 -64.575182)
		(width 0.1016)
		(layer "In5.Cu")
		(net "PCIE_TX_CAP_P60")
	)
	(segment
		(start 109.84103 -203.896214)
		(end 172.362876 -160.119568)
		(width 0.1397)
		(layer "In5.Cu")
		(net "PCIE_TX_CAP_P60")
	)
	(segment
		(start 223.149414 -87.588852)
		(end 226.186238 -72.405494)
		(width 0.1397)
		(layer "In5.Cu")
		(net "PCIE_TX_CAP_P60")
	)
	(segment
		(start 172.362876 -160.119568)
		(end 223.149414 -87.588852)
		(width 0.1397)
		(layer "In5.Cu")
		(net "PCIE_TX_CAP_P60")
	)
	(segment
		(start 107.935014 -210.22945)
		(end 107.935014 -209.301842)
		(width 0.1397)
		(layer "In5.Cu")
		(net "PCIE_TX_CAP_P60")
	)
	(segment
		(start 225.578162 -64.91478)
		(end 225.759264 -64.733678)
		(width 0.1016)
		(layer "In5.Cu")
		(net "PCIE_TX_CAP_P60")
	)
	(segment
		(start 225.462084 -67.0306)
		(end 225.493834 -66.99885)
		(width 0.1016)
		(layer "In5.Cu")
		(net "PCIE_TX_CAP_P60")
	)
	(arc
		(start 107.693714 -210.896454)
		(mid 107.872852 -210.584109)
		(end 107.935014 -210.22945)
		(width 0.1397)
		(layer "In5.Cu")
		(net "PCIE_TX_CAP_P60")
	)
	(arc
		(start 225.493834 -65.118742)
		(mid 225.515696 -65.008364)
		(end 225.578162 -64.91478)
		(width 0.1016)
		(layer "In5.Cu")
		(net "PCIE_TX_CAP_P60")
	)
	(arc
		(start 225.918014 -64.575182)
		(mid 226.00157 -64.519351)
		(end 226.100132 -64.499744)
		(width 0.1016)
		(layer "In5.Cu")
		(net "PCIE_TX_CAP_P60")
	)
	(segment
		(start 301.60849 -33.984692)
		(end 301.818294 -34.194242)
		(width 0.136652)
		(layer "F.Cu")
		(net "PCIE_TX_CAP_P6")
	)
	(segment
		(start 301.80915 -34.87674)
		(end 301.65929 -35.026346)
		(width 0.136652)
		(layer "F.Cu")
		(net "PCIE_TX_CAP_P6")
	)
	(segment
		(start 301.92599 -34.454592)
		(end 301.92599 -34.594292)
		(width 0.136652)
		(layer "F.Cu")
		(net "PCIE_TX_CAP_P6")
	)
	(segment
		(start 257.599942 -30.999938)
		(end 258.099814 -30.500066)
		(width 0.136652)
		(layer "F.Cu")
		(net "PCIE_TX_CAP_P6")
	)
	(via
		(at 301.65929 -35.026346)
		(size 0.508)
		(drill 0.254)
		(layers "F.Cu" "B.Cu")
		(net "PCIE_TX_CAP_P6")
	)
	(via
		(at 258.099814 -30.500066)
		(size 0.4572)
		(drill 0.2032)
		(layers "F.Cu" "B.Cu")
		(net "PCIE_TX_CAP_P6")
	)
	(arc
		(start 301.92599 -34.594292)
		(mid 301.895679 -34.747147)
		(end 301.80915 -34.87674)
		(width 0.136652)
		(layer "F.Cu")
		(net "PCIE_TX_CAP_P6")
	)
	(arc
		(start 301.818294 -34.194242)
		(mid 301.898025 -34.313707)
		(end 301.92599 -34.454592)
		(width 0.136652)
		(layer "F.Cu")
		(net "PCIE_TX_CAP_P6")
	)
	(segment
		(start 258.099814 -30.456886)
		(end 258.099814 -30.500066)
		(width 0.1016)
		(layer "In5.Cu")
		(net "PCIE_TX_CAP_P6")
	)
	(segment
		(start 302.616616 -37.947092)
		(end 302.541432 -38.373812)
		(width 0.1397)
		(layer "In5.Cu")
		(net "PCIE_TX_CAP_P6")
	)
	(segment
		(start 257.50139 -29.0068)
		(end 257.50139 -29.632402)
		(width 0.1016)
		(layer "In5.Cu")
		(net "PCIE_TX_CAP_P6")
	)
	(segment
		(start 302.378364 -38.606476)
		(end 300.688756 -39.789862)
		(width 0.1397)
		(layer "In5.Cu")
		(net "PCIE_TX_CAP_P6")
	)
	(segment
		(start 284.160976 -38.341554)
		(end 280.45537 -35.746944)
		(width 0.1397)
		(layer "In5.Cu")
		(net "PCIE_TX_CAP_P6")
	)
	(segment
		(start 301.999396 -36.803838)
		(end 302.555148 -37.597842)
		(width 0.1397)
		(layer "In5.Cu")
		(net "PCIE_TX_CAP_P6")
	)
	(segment
		(start 274.117054 -29.913072)
		(end 265.665204 -28.4226)
		(width 0.1397)
		(layer "In5.Cu")
		(net "PCIE_TX_CAP_P6")
	)
	(segment
		(start 300.688756 -39.789862)
		(end 296.53611 -40.522398)
		(width 0.1397)
		(layer "In5.Cu")
		(net "PCIE_TX_CAP_P6")
	)
	(segment
		(start 258.7752 -28.4226)
		(end 258.08559 -28.4226)
		(width 0.1016)
		(layer "In5.Cu")
		(net "PCIE_TX_CAP_P6")
	)
	(segment
		(start 301.879 -35.556698)
		(end 301.879 -36.114736)
		(width 0.1397)
		(layer "In5.Cu")
		(net "PCIE_TX_CAP_P6")
	)
	(segment
		(start 265.665204 -28.4226)
		(end 258.7752 -28.4226)
		(width 0.1397)
		(layer "In5.Cu")
		(net "PCIE_TX_CAP_P6")
	)
	(segment
		(start 280.45537 -35.746944)
		(end 278.537924 -33.00857)
		(width 0.1397)
		(layer "In5.Cu")
		(net "PCIE_TX_CAP_P6")
	)
	(segment
		(start 302.555148 -37.597842)
		(end 302.616616 -37.947092)
		(width 0.1397)
		(layer "In5.Cu")
		(net "PCIE_TX_CAP_P6")
	)
	(segment
		(start 301.879 -36.114736)
		(end 301.999396 -36.803838)
		(width 0.1397)
		(layer "In5.Cu")
		(net "PCIE_TX_CAP_P6")
	)
	(segment
		(start 278.537924 -33.00857)
		(end 274.117054 -29.913072)
		(width 0.1397)
		(layer "In5.Cu")
		(net "PCIE_TX_CAP_P6")
	)
	(segment
		(start 296.53611 -40.522398)
		(end 284.160976 -38.341554)
		(width 0.1397)
		(layer "In5.Cu")
		(net "PCIE_TX_CAP_P6")
	)
	(segment
		(start 302.541432 -38.373812)
		(end 302.378364 -38.606476)
		(width 0.1397)
		(layer "In5.Cu")
		(net "PCIE_TX_CAP_P6")
	)
	(arc
		(start 301.65929 -35.026346)
		(mid 301.821876 -35.269674)
		(end 301.879 -35.556698)
		(width 0.1397)
		(layer "In5.Cu")
		(net "PCIE_TX_CAP_P6")
	)
	(arc
		(start 257.806952 -30.052518)
		(mid 258.018858 -30.207267)
		(end 258.099814 -30.456886)
		(width 0.1016)
		(layer "In5.Cu")
		(net "PCIE_TX_CAP_P6")
	)
	(arc
		(start 257.50139 -29.632402)
		(mid 257.581805 -29.886434)
		(end 257.793744 -30.047946)
		(width 0.1016)
		(layer "In5.Cu")
		(net "PCIE_TX_CAP_P6")
	)
	(arc
		(start 258.08559 -28.4226)
		(mid 257.672498 -28.593708)
		(end 257.50139 -29.0068)
		(width 0.1016)
		(layer "In5.Cu")
		(net "PCIE_TX_CAP_P6")
	)
	(arc
		(start 257.793744 -30.047946)
		(mid 257.80033 -30.050283)
		(end 257.806952 -30.052518)
		(width 0.1016)
		(layer "In5.Cu")
		(net "PCIE_TX_CAP_P6")
	)
	(segment
		(start 138.392154 -211.975954)
		(end 138.67384 -211.694268)
		(width 0.136652)
		(layer "F.Cu")
		(net "PCIE_TX_CAP_P59")
	)
	(segment
		(start 138.741404 -211.5312)
		(end 138.741404 -211.3534)
		(width 0.136652)
		(layer "F.Cu")
		(net "PCIE_TX_CAP_P59")
	)
	(segment
		(start 138.593322 -210.996276)
		(end 138.493754 -210.896454)
		(width 0.136652)
		(layer "F.Cu")
		(net "PCIE_TX_CAP_P59")
	)
	(segment
		(start 227.600002 -64.99987)
		(end 227.10013 -65.499742)
		(width 0.136652)
		(layer "F.Cu")
		(net "PCIE_TX_CAP_P59")
	)
	(via
		(at 227.10013 -65.499742)
		(size 0.4572)
		(drill 0.2032)
		(layers "F.Cu" "B.Cu")
		(net "PCIE_TX_CAP_P59")
	)
	(via
		(at 138.493754 -210.896454)
		(size 0.508)
		(drill 0.254)
		(layers "F.Cu" "B.Cu")
		(net "PCIE_TX_CAP_P59")
	)
	(arc
		(start 138.67384 -211.694268)
		(mid 138.723831 -211.619452)
		(end 138.741404 -211.5312)
		(width 0.136652)
		(layer "F.Cu")
		(net "PCIE_TX_CAP_P59")
	)
	(arc
		(start 138.741404 -211.3534)
		(mid 138.702865 -211.16012)
		(end 138.593322 -210.996276)
		(width 0.136652)
		(layer "F.Cu")
		(net "PCIE_TX_CAP_P59")
	)
	(segment
		(start 138.7348 -210.314032)
		(end 138.73607 -210.369912)
		(width 0.1397)
		(layer "In5.Cu")
		(net "PCIE_TX_CAP_P59")
	)
	(segment
		(start 227.264722 -72.805798)
		(end 224.501456 -88.475566)
		(width 0.1397)
		(layer "In5.Cu")
		(net "PCIE_TX_CAP_P59")
	)
	(segment
		(start 226.441 -66.9798)
		(end 226.441 -68.687188)
		(width 0.1397)
		(layer "In5.Cu")
		(net "PCIE_TX_CAP_P59")
	)
	(segment
		(start 138.735054 -197.449948)
		(end 138.735054 -210.313778)
		(width 0.1397)
		(layer "In5.Cu")
		(net "PCIE_TX_CAP_P59")
	)
	(segment
		(start 145.812764 -187.341764)
		(end 138.735054 -197.449948)
		(width 0.1397)
		(layer "In5.Cu")
		(net "PCIE_TX_CAP_P59")
	)
	(segment
		(start 226.441 -68.687188)
		(end 227.264722 -72.805798)
		(width 0.1397)
		(layer "In5.Cu")
		(net "PCIE_TX_CAP_P59")
	)
	(segment
		(start 226.493832 -66.926968)
		(end 226.441 -66.9798)
		(width 0.1016)
		(layer "In5.Cu")
		(net "PCIE_TX_CAP_P59")
	)
	(segment
		(start 226.918012 -65.57518)
		(end 226.57816 -65.914778)
		(width 0.1016)
		(layer "In5.Cu")
		(net "PCIE_TX_CAP_P59")
	)
	(segment
		(start 138.735054 -210.313778)
		(end 138.7348 -210.314032)
		(width 0.1397)
		(layer "In5.Cu")
		(net "PCIE_TX_CAP_P59")
	)
	(segment
		(start 164.375846 -174.343568)
		(end 145.812764 -187.341764)
		(width 0.1397)
		(layer "In5.Cu")
		(net "PCIE_TX_CAP_P59")
	)
	(segment
		(start 226.493832 -66.11874)
		(end 226.493832 -66.926968)
		(width 0.1016)
		(layer "In5.Cu")
		(net "PCIE_TX_CAP_P59")
	)
	(segment
		(start 138.545824 -210.844384)
		(end 138.493754 -210.896454)
		(width 0.1397)
		(layer "In5.Cu")
		(net "PCIE_TX_CAP_P59")
	)
	(segment
		(start 224.501456 -88.475566)
		(end 164.375846 -174.343568)
		(width 0.1397)
		(layer "In5.Cu")
		(net "PCIE_TX_CAP_P59")
	)
	(arc
		(start 226.57816 -65.914778)
		(mid 226.515716 -66.008372)
		(end 226.493832 -66.11874)
		(width 0.1016)
		(layer "In5.Cu")
		(net "PCIE_TX_CAP_P59")
	)
	(arc
		(start 227.10013 -65.499742)
		(mid 227.001568 -65.519347)
		(end 226.918012 -65.57518)
		(width 0.1016)
		(layer "In5.Cu")
		(net "PCIE_TX_CAP_P59")
	)
	(arc
		(start 138.73607 -210.369912)
		(mid 138.689527 -210.626625)
		(end 138.545824 -210.844384)
		(width 0.1397)
		(layer "In5.Cu")
		(net "PCIE_TX_CAP_P59")
	)
	(segment
		(start 228.6 -63.999872)
		(end 228.100128 -64.499744)
		(width 0.136652)
		(layer "F.Cu")
		(net "PCIE_TX_CAP_P58")
	)
	(segment
		(start 141.86535 -211.067904)
		(end 141.6939 -210.896454)
		(width 0.136652)
		(layer "F.Cu")
		(net "PCIE_TX_CAP_P58")
	)
	(segment
		(start 141.592046 -211.975954)
		(end 141.5923 -211.975954)
		(width 0.136652)
		(layer "F.Cu")
		(net "PCIE_TX_CAP_P58")
	)
	(segment
		(start 141.5923 -211.975954)
		(end 141.873986 -211.694268)
		(width 0.136652)
		(layer "F.Cu")
		(net "PCIE_TX_CAP_P58")
	)
	(segment
		(start 141.94155 -211.5312)
		(end 141.94155 -211.2518)
		(width 0.136652)
		(layer "F.Cu")
		(net "PCIE_TX_CAP_P58")
	)
	(via
		(at 228.100128 -64.499744)
		(size 0.4572)
		(drill 0.2032)
		(layers "F.Cu" "B.Cu")
		(net "PCIE_TX_CAP_P58")
	)
	(via
		(at 141.6939 -210.896454)
		(size 0.508)
		(drill 0.254)
		(layers "F.Cu" "B.Cu")
		(net "PCIE_TX_CAP_P58")
	)
	(arc
		(start 141.873986 -211.694268)
		(mid 141.923977 -211.619452)
		(end 141.94155 -211.5312)
		(width 0.136652)
		(layer "F.Cu")
		(net "PCIE_TX_CAP_P58")
	)
	(arc
		(start 141.94155 -211.2518)
		(mid 141.921751 -211.152266)
		(end 141.86535 -211.067904)
		(width 0.136652)
		(layer "F.Cu")
		(net "PCIE_TX_CAP_P58")
	)
	(segment
		(start 141.9352 -195.83654)
		(end 147.082764 -188.484764)
		(width 0.1397)
		(layer "In5.Cu")
		(net "PCIE_TX_CAP_P58")
	)
	(segment
		(start 164.717984 -176.1363)
		(end 225.2218 -89.727786)
		(width 0.1397)
		(layer "In5.Cu")
		(net "PCIE_TX_CAP_P58")
	)
	(segment
		(start 227.4316 -66.9544)
		(end 227.49383 -66.89217)
		(width 0.1016)
		(layer "In5.Cu")
		(net "PCIE_TX_CAP_P58")
	)
	(segment
		(start 227.49383 -66.89217)
		(end 227.49383 -65.118742)
		(width 0.1016)
		(layer "In5.Cu")
		(net "PCIE_TX_CAP_P58")
	)
	(segment
		(start 227.4316 -68.58889)
		(end 227.4316 -66.9544)
		(width 0.1397)
		(layer "In5.Cu")
		(net "PCIE_TX_CAP_P58")
	)
	(segment
		(start 141.6939 -210.896454)
		(end 141.728444 -210.86191)
		(width 0.1397)
		(layer "In5.Cu")
		(net "PCIE_TX_CAP_P58")
	)
	(segment
		(start 141.9352 -210.3628)
		(end 141.9352 -195.83654)
		(width 0.1397)
		(layer "In5.Cu")
		(net "PCIE_TX_CAP_P58")
	)
	(segment
		(start 225.2218 -89.727786)
		(end 228.198172 -72.84974)
		(width 0.1397)
		(layer "In5.Cu")
		(net "PCIE_TX_CAP_P58")
	)
	(segment
		(start 228.198172 -72.84974)
		(end 228.198172 -72.42175)
		(width 0.1397)
		(layer "In5.Cu")
		(net "PCIE_TX_CAP_P58")
	)
	(segment
		(start 228.198172 -72.42175)
		(end 227.4316 -68.58889)
		(width 0.1397)
		(layer "In5.Cu")
		(net "PCIE_TX_CAP_P58")
	)
	(segment
		(start 147.082764 -188.484764)
		(end 164.717984 -176.1363)
		(width 0.1397)
		(layer "In5.Cu")
		(net "PCIE_TX_CAP_P58")
	)
	(segment
		(start 227.578158 -64.91478)
		(end 227.91801 -64.575182)
		(width 0.1016)
		(layer "In5.Cu")
		(net "PCIE_TX_CAP_P58")
	)
	(arc
		(start 227.91801 -64.575182)
		(mid 228.001566 -64.519351)
		(end 228.100128 -64.499744)
		(width 0.1016)
		(layer "In5.Cu")
		(net "PCIE_TX_CAP_P58")
	)
	(arc
		(start 227.49383 -65.118742)
		(mid 227.515692 -65.008364)
		(end 227.578158 -64.91478)
		(width 0.1016)
		(layer "In5.Cu")
		(net "PCIE_TX_CAP_P58")
	)
	(arc
		(start 141.728444 -210.86191)
		(mid 141.881453 -210.632916)
		(end 141.9352 -210.3628)
		(width 0.1397)
		(layer "In5.Cu")
		(net "PCIE_TX_CAP_P58")
	)
	(segment
		(start 145.141442 -211.5312)
		(end 145.141442 -211.308442)
		(width 0.136652)
		(layer "F.Cu")
		(net "PCIE_TX_CAP_P57")
	)
	(segment
		(start 144.792192 -211.975954)
		(end 145.073878 -211.694268)
		(width 0.136652)
		(layer "F.Cu")
		(net "PCIE_TX_CAP_P57")
	)
	(segment
		(start 229.599998 -64.99987)
		(end 229.100126 -65.499742)
		(width 0.136652)
		(layer "F.Cu")
		(net "PCIE_TX_CAP_P57")
	)
	(segment
		(start 145.025364 -211.027772)
		(end 144.893792 -210.896454)
		(width 0.136652)
		(layer "F.Cu")
		(net "PCIE_TX_CAP_P57")
	)
	(via
		(at 229.100126 -65.499742)
		(size 0.4572)
		(drill 0.2032)
		(layers "F.Cu" "B.Cu")
		(net "PCIE_TX_CAP_P57")
	)
	(via
		(at 144.893792 -210.896454)
		(size 0.508)
		(drill 0.254)
		(layers "F.Cu" "B.Cu")
		(net "PCIE_TX_CAP_P57")
	)
	(arc
		(start 145.073878 -211.694268)
		(mid 145.123869 -211.619452)
		(end 145.141442 -211.5312)
		(width 0.136652)
		(layer "F.Cu")
		(net "PCIE_TX_CAP_P57")
	)
	(arc
		(start 145.141442 -211.308442)
		(mid 145.111324 -211.156559)
		(end 145.025364 -211.027772)
		(width 0.136652)
		(layer "F.Cu")
		(net "PCIE_TX_CAP_P57")
	)
	(segment
		(start 144.893792 -210.896454)
		(end 144.94637 -210.843876)
		(width 0.1397)
		(layer "In5.Cu")
		(net "PCIE_TX_CAP_P57")
	)
	(segment
		(start 145.135092 -210.3882)
		(end 145.135092 -194.477132)
		(width 0.1397)
		(layer "In5.Cu")
		(net "PCIE_TX_CAP_P57")
	)
	(segment
		(start 148.352764 -189.881764)
		(end 165.265608 -178.039268)
		(width 0.1397)
		(layer "In5.Cu")
		(net "PCIE_TX_CAP_P57")
	)
	(segment
		(start 228.493828 -66.882772)
		(end 228.493828 -66.11874)
		(width 0.1016)
		(layer "In5.Cu")
		(net "PCIE_TX_CAP_P57")
	)
	(segment
		(start 228.4222 -68.490084)
		(end 228.4222 -66.9544)
		(width 0.1397)
		(layer "In5.Cu")
		(net "PCIE_TX_CAP_P57")
	)
	(segment
		(start 145.135092 -194.477132)
		(end 148.352764 -189.881764)
		(width 0.1397)
		(layer "In5.Cu")
		(net "PCIE_TX_CAP_P57")
	)
	(segment
		(start 225.832416 -91.540838)
		(end 229.206044 -72.409304)
		(width 0.1397)
		(layer "In5.Cu")
		(net "PCIE_TX_CAP_P57")
	)
	(segment
		(start 165.265608 -178.039268)
		(end 225.832416 -91.540838)
		(width 0.1397)
		(layer "In5.Cu")
		(net "PCIE_TX_CAP_P57")
	)
	(segment
		(start 228.4222 -66.9544)
		(end 228.493828 -66.882772)
		(width 0.1016)
		(layer "In5.Cu")
		(net "PCIE_TX_CAP_P57")
	)
	(segment
		(start 228.578156 -65.914778)
		(end 228.918008 -65.57518)
		(width 0.1016)
		(layer "In5.Cu")
		(net "PCIE_TX_CAP_P57")
	)
	(segment
		(start 229.206044 -72.409304)
		(end 228.4222 -68.490084)
		(width 0.1397)
		(layer "In5.Cu")
		(net "PCIE_TX_CAP_P57")
	)
	(arc
		(start 228.493828 -66.11874)
		(mid 228.51569 -66.008362)
		(end 228.578156 -65.914778)
		(width 0.1016)
		(layer "In5.Cu")
		(net "PCIE_TX_CAP_P57")
	)
	(arc
		(start 228.918008 -65.57518)
		(mid 229.001564 -65.519349)
		(end 229.100126 -65.499742)
		(width 0.1016)
		(layer "In5.Cu")
		(net "PCIE_TX_CAP_P57")
	)
	(arc
		(start 144.94637 -210.843876)
		(mid 145.086063 -210.63481)
		(end 145.135092 -210.3882)
		(width 0.1397)
		(layer "In5.Cu")
		(net "PCIE_TX_CAP_P57")
	)
	(segment
		(start 148.243544 -211.04606)
		(end 148.093684 -210.896454)
		(width 0.136652)
		(layer "F.Cu")
		(net "PCIE_TX_CAP_P56")
	)
	(segment
		(start 148.341334 -211.5312)
		(end 148.341334 -211.282534)
		(width 0.136652)
		(layer "F.Cu")
		(net "PCIE_TX_CAP_P56")
	)
	(segment
		(start 147.992084 -211.975954)
		(end 148.27377 -211.694268)
		(width 0.136652)
		(layer "F.Cu")
		(net "PCIE_TX_CAP_P56")
	)
	(segment
		(start 230.599996 -63.999872)
		(end 230.100124 -64.499744)
		(width 0.136652)
		(layer "F.Cu")
		(net "PCIE_TX_CAP_P56")
	)
	(via
		(at 230.100124 -64.499744)
		(size 0.4572)
		(drill 0.2032)
		(layers "F.Cu" "B.Cu")
		(net "PCIE_TX_CAP_P56")
	)
	(via
		(at 148.093684 -210.896454)
		(size 0.508)
		(drill 0.254)
		(layers "F.Cu" "B.Cu")
		(net "PCIE_TX_CAP_P56")
	)
	(arc
		(start 148.341334 -211.282534)
		(mid 148.315973 -211.154563)
		(end 148.243544 -211.04606)
		(width 0.136652)
		(layer "F.Cu")
		(net "PCIE_TX_CAP_P56")
	)
	(arc
		(start 148.27377 -211.694268)
		(mid 148.323761 -211.619452)
		(end 148.341334 -211.5312)
		(width 0.136652)
		(layer "F.Cu")
		(net "PCIE_TX_CAP_P56")
	)
	(segment
		(start 165.392608 -180.109876)
		(end 226.886008 -92.28836)
		(width 0.1397)
		(layer "In5.Cu")
		(net "PCIE_TX_CAP_P56")
	)
	(segment
		(start 226.886008 -92.28836)
		(end 230.321612 -72.805798)
		(width 0.1397)
		(layer "In5.Cu")
		(net "PCIE_TX_CAP_P56")
	)
	(segment
		(start 230.321612 -72.805798)
		(end 229.4382 -68.388992)
		(width 0.1397)
		(layer "In5.Cu")
		(net "PCIE_TX_CAP_P56")
	)
	(segment
		(start 148.336 -210.312762)
		(end 148.336 -193.914776)
		(width 0.1397)
		(layer "In5.Cu")
		(net "PCIE_TX_CAP_P56")
	)
	(segment
		(start 229.4382 -66.9798)
		(end 229.493826 -66.924174)
		(width 0.1016)
		(layer "In5.Cu")
		(net "PCIE_TX_CAP_P56")
	)
	(segment
		(start 148.334984 -210.313778)
		(end 148.336 -210.312762)
		(width 0.1397)
		(layer "In5.Cu")
		(net "PCIE_TX_CAP_P56")
	)
	(segment
		(start 150.892764 -190.262764)
		(end 165.392608 -180.109876)
		(width 0.1397)
		(layer "In5.Cu")
		(net "PCIE_TX_CAP_P56")
	)
	(segment
		(start 229.493826 -66.924174)
		(end 229.493826 -65.118742)
		(width 0.1016)
		(layer "In5.Cu")
		(net "PCIE_TX_CAP_P56")
	)
	(segment
		(start 148.336 -193.914776)
		(end 150.892764 -190.262764)
		(width 0.1397)
		(layer "In5.Cu")
		(net "PCIE_TX_CAP_P56")
	)
	(segment
		(start 229.578154 -64.91478)
		(end 229.918006 -64.575182)
		(width 0.1016)
		(layer "In5.Cu")
		(net "PCIE_TX_CAP_P56")
	)
	(segment
		(start 229.4382 -68.388992)
		(end 229.4382 -66.9798)
		(width 0.1397)
		(layer "In5.Cu")
		(net "PCIE_TX_CAP_P56")
	)
	(arc
		(start 148.093684 -210.896454)
		(mid 148.272311 -210.62912)
		(end 148.334984 -210.313778)
		(width 0.1397)
		(layer "In5.Cu")
		(net "PCIE_TX_CAP_P56")
	)
	(arc
		(start 229.493826 -65.118742)
		(mid 229.515688 -65.008364)
		(end 229.578154 -64.91478)
		(width 0.1016)
		(layer "In5.Cu")
		(net "PCIE_TX_CAP_P56")
	)
	(arc
		(start 229.918006 -64.575182)
		(mid 230.001562 -64.519351)
		(end 230.100124 -64.499744)
		(width 0.1016)
		(layer "In5.Cu")
		(net "PCIE_TX_CAP_P56")
	)
	(segment
		(start 232.599992 -64.99987)
		(end 232.10012 -65.499742)
		(width 0.136652)
		(layer "F.Cu")
		(net "PCIE_TX_CAP_P55")
	)
	(segment
		(start 151.19223 -211.975954)
		(end 151.473916 -211.694268)
		(width 0.136652)
		(layer "F.Cu")
		(net "PCIE_TX_CAP_P55")
	)
	(segment
		(start 151.447246 -211.050124)
		(end 151.29383 -210.896454)
		(width 0.136652)
		(layer "F.Cu")
		(net "PCIE_TX_CAP_P55")
	)
	(segment
		(start 151.54148 -211.5312)
		(end 151.54148 -211.2772)
		(width 0.136652)
		(layer "F.Cu")
		(net "PCIE_TX_CAP_P55")
	)
	(via
		(at 151.29383 -210.896454)
		(size 0.508)
		(drill 0.254)
		(layers "F.Cu" "B.Cu")
		(net "PCIE_TX_CAP_P55")
	)
	(via
		(at 232.10012 -65.499742)
		(size 0.4572)
		(drill 0.2032)
		(layers "F.Cu" "B.Cu")
		(net "PCIE_TX_CAP_P55")
	)
	(arc
		(start 151.54148 -211.2772)
		(mid 151.516939 -211.154294)
		(end 151.447246 -211.050124)
		(width 0.136652)
		(layer "F.Cu")
		(net "PCIE_TX_CAP_P55")
	)
	(arc
		(start 151.473916 -211.694268)
		(mid 151.523907 -211.619452)
		(end 151.54148 -211.5312)
		(width 0.136652)
		(layer "F.Cu")
		(net "PCIE_TX_CAP_P55")
	)
	(segment
		(start 158.477966 -195.64604)
		(end 158.450026 -195.68668)
		(width 0.1397)
		(layer "In5.Cu")
		(net "PCIE_TX_CAP_P55")
	)
	(segment
		(start 231.493822 -66.905378)
		(end 231.4194 -66.9798)
		(width 0.1016)
		(layer "In5.Cu")
		(net "PCIE_TX_CAP_P55")
	)
	(segment
		(start 232.0544 -80.533494)
		(end 231.4194 -83.708494)
		(width 0.1397)
		(layer "In5.Cu")
		(net "PCIE_TX_CAP_P55")
	)
	(segment
		(start 232.0544 -74.183494)
		(end 231.4194 -77.358494)
		(width 0.1397)
		(layer "In5.Cu")
		(net "PCIE_TX_CAP_P55")
	)
	(segment
		(start 232.0544 -99.583494)
		(end 158.477966 -195.64604)
		(width 0.1397)
		(layer "In5.Cu")
		(net "PCIE_TX_CAP_P55")
	)
	(segment
		(start 231.4194 -77.358494)
		(end 232.0544 -80.533494)
		(width 0.1397)
		(layer "In5.Cu")
		(net "PCIE_TX_CAP_P55")
	)
	(segment
		(start 231.4194 -90.058494)
		(end 232.0544 -93.233494)
		(width 0.1397)
		(layer "In5.Cu")
		(net "PCIE_TX_CAP_P55")
	)
	(segment
		(start 231.493822 -66.11874)
		(end 231.493822 -66.905378)
		(width 0.1016)
		(layer "In5.Cu")
		(net "PCIE_TX_CAP_P55")
	)
	(segment
		(start 231.4194 -66.9798)
		(end 231.4194 -71.008494)
		(width 0.1397)
		(layer "In5.Cu")
		(net "PCIE_TX_CAP_P55")
	)
	(segment
		(start 151.53513 -205.562708)
		(end 151.53513 -210.313778)
		(width 0.1397)
		(layer "In5.Cu")
		(net "PCIE_TX_CAP_P55")
	)
	(segment
		(start 231.918002 -65.57518)
		(end 231.57815 -65.914778)
		(width 0.1016)
		(layer "In5.Cu")
		(net "PCIE_TX_CAP_P55")
	)
	(segment
		(start 231.4194 -96.408494)
		(end 232.0544 -99.583494)
		(width 0.1397)
		(layer "In5.Cu")
		(net "PCIE_TX_CAP_P55")
	)
	(segment
		(start 232.0544 -93.233494)
		(end 231.4194 -96.408494)
		(width 0.1397)
		(layer "In5.Cu")
		(net "PCIE_TX_CAP_P55")
	)
	(segment
		(start 232.0544 -86.883494)
		(end 231.4194 -90.058494)
		(width 0.1397)
		(layer "In5.Cu")
		(net "PCIE_TX_CAP_P55")
	)
	(segment
		(start 158.450026 -195.68668)
		(end 157.758638 -196.674232)
		(width 0.1397)
		(layer "In5.Cu")
		(net "PCIE_TX_CAP_P55")
	)
	(segment
		(start 231.4194 -71.008494)
		(end 232.0544 -74.183494)
		(width 0.1397)
		(layer "In5.Cu")
		(net "PCIE_TX_CAP_P55")
	)
	(segment
		(start 231.4194 -83.708494)
		(end 232.0544 -86.883494)
		(width 0.1397)
		(layer "In5.Cu")
		(net "PCIE_TX_CAP_P55")
	)
	(segment
		(start 157.758638 -196.674232)
		(end 151.53513 -205.562708)
		(width 0.1397)
		(layer "In5.Cu")
		(net "PCIE_TX_CAP_P55")
	)
	(arc
		(start 231.57815 -65.914778)
		(mid 231.515706 -66.008372)
		(end 231.493822 -66.11874)
		(width 0.1016)
		(layer "In5.Cu")
		(net "PCIE_TX_CAP_P55")
	)
	(arc
		(start 151.53513 -210.313778)
		(mid 151.472409 -210.6291)
		(end 151.29383 -210.896454)
		(width 0.1397)
		(layer "In5.Cu")
		(net "PCIE_TX_CAP_P55")
	)
	(arc
		(start 232.10012 -65.499742)
		(mid 232.001558 -65.519347)
		(end 231.918002 -65.57518)
		(width 0.1016)
		(layer "In5.Cu")
		(net "PCIE_TX_CAP_P55")
	)
	(segment
		(start 154.741372 -211.5312)
		(end 154.741372 -211.2772)
		(width 0.136652)
		(layer "F.Cu")
		(net "PCIE_TX_CAP_P54")
	)
	(segment
		(start 154.392122 -211.975954)
		(end 154.673808 -211.694268)
		(width 0.136652)
		(layer "F.Cu")
		(net "PCIE_TX_CAP_P54")
	)
	(segment
		(start 154.647138 -211.050124)
		(end 154.493722 -210.896454)
		(width 0.136652)
		(layer "F.Cu")
		(net "PCIE_TX_CAP_P54")
	)
	(segment
		(start 233.59999 -63.999872)
		(end 233.100118 -64.499744)
		(width 0.136652)
		(layer "F.Cu")
		(net "PCIE_TX_CAP_P54")
	)
	(via
		(at 154.493722 -210.896454)
		(size 0.508)
		(drill 0.254)
		(layers "F.Cu" "B.Cu")
		(net "PCIE_TX_CAP_P54")
	)
	(via
		(at 233.100118 -64.499744)
		(size 0.4572)
		(drill 0.2032)
		(layers "F.Cu" "B.Cu")
		(net "PCIE_TX_CAP_P54")
	)
	(arc
		(start 154.673808 -211.694268)
		(mid 154.723799 -211.619452)
		(end 154.741372 -211.5312)
		(width 0.136652)
		(layer "F.Cu")
		(net "PCIE_TX_CAP_P54")
	)
	(arc
		(start 154.741372 -211.2772)
		(mid 154.716831 -211.154294)
		(end 154.647138 -211.050124)
		(width 0.136652)
		(layer "F.Cu")
		(net "PCIE_TX_CAP_P54")
	)
	(segment
		(start 233.09072 -86.883494)
		(end 232.45572 -83.708494)
		(width 0.1397)
		(layer "In5.Cu")
		(net "PCIE_TX_CAP_P54")
	)
	(segment
		(start 154.735022 -204.603604)
		(end 167.480488 -191.858138)
		(width 0.1397)
		(layer "In5.Cu")
		(net "PCIE_TX_CAP_P54")
	)
	(segment
		(start 154.735022 -210.313778)
		(end 154.735022 -204.603604)
		(width 0.1397)
		(layer "In5.Cu")
		(net "PCIE_TX_CAP_P54")
	)
	(segment
		(start 232.578148 -64.91478)
		(end 232.918 -64.575182)
		(width 0.1016)
		(layer "In5.Cu")
		(net "PCIE_TX_CAP_P54")
	)
	(segment
		(start 232.49382 -66.94678)
		(end 232.49382 -65.118742)
		(width 0.1016)
		(layer "In5.Cu")
		(net "PCIE_TX_CAP_P54")
	)
	(segment
		(start 167.480488 -191.858138)
		(end 172.424852 -188.395864)
		(width 0.1397)
		(layer "In5.Cu")
		(net "PCIE_TX_CAP_P54")
	)
	(segment
		(start 232.45572 -83.708494)
		(end 233.09072 -80.533494)
		(width 0.1397)
		(layer "In5.Cu")
		(net "PCIE_TX_CAP_P54")
	)
	(segment
		(start 233.09072 -99.583494)
		(end 232.45572 -96.408494)
		(width 0.1397)
		(layer "In5.Cu")
		(net "PCIE_TX_CAP_P54")
	)
	(segment
		(start 232.45572 -90.058494)
		(end 233.09072 -86.883494)
		(width 0.1397)
		(layer "In5.Cu")
		(net "PCIE_TX_CAP_P54")
	)
	(segment
		(start 172.424852 -188.395864)
		(end 232.482136 -102.625652)
		(width 0.1397)
		(layer "In5.Cu")
		(net "PCIE_TX_CAP_P54")
	)
	(segment
		(start 232.45572 -96.408494)
		(end 233.09072 -93.233494)
		(width 0.1397)
		(layer "In5.Cu")
		(net "PCIE_TX_CAP_P54")
	)
	(segment
		(start 232.45572 -77.358494)
		(end 233.09072 -74.183494)
		(width 0.1397)
		(layer "In5.Cu")
		(net "PCIE_TX_CAP_P54")
	)
	(segment
		(start 233.09072 -93.233494)
		(end 232.45572 -90.058494)
		(width 0.1397)
		(layer "In5.Cu")
		(net "PCIE_TX_CAP_P54")
	)
	(segment
		(start 232.4354 -70.907402)
		(end 232.4354 -67.0052)
		(width 0.1397)
		(layer "In5.Cu")
		(net "PCIE_TX_CAP_P54")
	)
	(segment
		(start 233.09072 -74.183494)
		(end 232.4354 -70.907402)
		(width 0.1397)
		(layer "In5.Cu")
		(net "PCIE_TX_CAP_P54")
	)
	(segment
		(start 232.482136 -102.625652)
		(end 233.09072 -99.583494)
		(width 0.1397)
		(layer "In5.Cu")
		(net "PCIE_TX_CAP_P54")
	)
	(segment
		(start 232.4354 -67.0052)
		(end 232.49382 -66.94678)
		(width 0.1016)
		(layer "In5.Cu")
		(net "PCIE_TX_CAP_P54")
	)
	(segment
		(start 233.09072 -80.533494)
		(end 232.45572 -77.358494)
		(width 0.1397)
		(layer "In5.Cu")
		(net "PCIE_TX_CAP_P54")
	)
	(arc
		(start 232.918 -64.575182)
		(mid 233.001556 -64.519351)
		(end 233.100118 -64.499744)
		(width 0.1016)
		(layer "In5.Cu")
		(net "PCIE_TX_CAP_P54")
	)
	(arc
		(start 154.493722 -210.896454)
		(mid 154.672349 -210.62912)
		(end 154.735022 -210.313778)
		(width 0.1397)
		(layer "In5.Cu")
		(net "PCIE_TX_CAP_P54")
	)
	(arc
		(start 232.49382 -65.118742)
		(mid 232.515682 -65.008364)
		(end 232.578148 -64.91478)
		(width 0.1016)
		(layer "In5.Cu")
		(net "PCIE_TX_CAP_P54")
	)
	(segment
		(start 157.592268 -211.975954)
		(end 157.873954 -211.694268)
		(width 0.136652)
		(layer "F.Cu")
		(net "PCIE_TX_CAP_P53")
	)
	(segment
		(start 157.865318 -211.067904)
		(end 157.693868 -210.896454)
		(width 0.136652)
		(layer "F.Cu")
		(net "PCIE_TX_CAP_P53")
	)
	(segment
		(start 234.599988 -64.99987)
		(end 234.100116 -65.499742)
		(width 0.136652)
		(layer "F.Cu")
		(net "PCIE_TX_CAP_P53")
	)
	(segment
		(start 157.941518 -211.5312)
		(end 157.941518 -211.2518)
		(width 0.136652)
		(layer "F.Cu")
		(net "PCIE_TX_CAP_P53")
	)
	(via
		(at 157.693868 -210.896454)
		(size 0.508)
		(drill 0.254)
		(layers "F.Cu" "B.Cu")
		(net "PCIE_TX_CAP_P53")
	)
	(via
		(at 234.100116 -65.499742)
		(size 0.4572)
		(drill 0.2032)
		(layers "F.Cu" "B.Cu")
		(net "PCIE_TX_CAP_P53")
	)
	(arc
		(start 157.941518 -211.2518)
		(mid 157.921719 -211.152266)
		(end 157.865318 -211.067904)
		(width 0.136652)
		(layer "F.Cu")
		(net "PCIE_TX_CAP_P53")
	)
	(arc
		(start 157.873954 -211.694268)
		(mid 157.923945 -211.619452)
		(end 157.941518 -211.5312)
		(width 0.136652)
		(layer "F.Cu")
		(net "PCIE_TX_CAP_P53")
	)
	(segment
		(start 166.767764 -198.898764)
		(end 161.413698 -202.647804)
		(width 0.1397)
		(layer "In5.Cu")
		(net "PCIE_TX_CAP_P53")
	)
	(segment
		(start 233.493818 -66.911982)
		(end 233.426 -66.9798)
		(width 0.1016)
		(layer "In5.Cu")
		(net "PCIE_TX_CAP_P53")
	)
	(segment
		(start 161.413698 -202.647804)
		(end 157.935168 -207.61579)
		(width 0.1397)
		(layer "In5.Cu")
		(net "PCIE_TX_CAP_P53")
	)
	(segment
		(start 233.21772 -103.998014)
		(end 166.767764 -198.898764)
		(width 0.1397)
		(layer "In5.Cu")
		(net "PCIE_TX_CAP_P53")
	)
	(segment
		(start 157.935168 -207.61579)
		(end 157.935168 -210.313778)
		(width 0.1397)
		(layer "In5.Cu")
		(net "PCIE_TX_CAP_P53")
	)
	(segment
		(start 234.100878 -99.583494)
		(end 233.21772 -103.998014)
		(width 0.1397)
		(layer "In5.Cu")
		(net "PCIE_TX_CAP_P53")
	)
	(segment
		(start 233.465878 -83.708494)
		(end 234.100878 -86.883494)
		(width 0.1397)
		(layer "In5.Cu")
		(net "PCIE_TX_CAP_P53")
	)
	(segment
		(start 234.100878 -93.233494)
		(end 233.465878 -96.408494)
		(width 0.1397)
		(layer "In5.Cu")
		(net "PCIE_TX_CAP_P53")
	)
	(segment
		(start 233.426 -66.9798)
		(end 233.426 -70.80885)
		(width 0.1397)
		(layer "In5.Cu")
		(net "PCIE_TX_CAP_P53")
	)
	(segment
		(start 233.465878 -77.358494)
		(end 234.100878 -80.533494)
		(width 0.1397)
		(layer "In5.Cu")
		(net "PCIE_TX_CAP_P53")
	)
	(segment
		(start 234.100878 -74.183494)
		(end 233.465878 -77.358494)
		(width 0.1397)
		(layer "In5.Cu")
		(net "PCIE_TX_CAP_P53")
	)
	(segment
		(start 233.465878 -90.058494)
		(end 234.100878 -93.233494)
		(width 0.1397)
		(layer "In5.Cu")
		(net "PCIE_TX_CAP_P53")
	)
	(segment
		(start 233.426 -70.80885)
		(end 234.100878 -74.183494)
		(width 0.1397)
		(layer "In5.Cu")
		(net "PCIE_TX_CAP_P53")
	)
	(segment
		(start 233.493818 -66.11874)
		(end 233.493818 -66.911982)
		(width 0.1016)
		(layer "In5.Cu")
		(net "PCIE_TX_CAP_P53")
	)
	(segment
		(start 233.917998 -65.57518)
		(end 233.578146 -65.914778)
		(width 0.1016)
		(layer "In5.Cu")
		(net "PCIE_TX_CAP_P53")
	)
	(segment
		(start 233.465878 -96.408494)
		(end 234.100878 -99.583494)
		(width 0.1397)
		(layer "In5.Cu")
		(net "PCIE_TX_CAP_P53")
	)
	(segment
		(start 234.100878 -80.533494)
		(end 233.465878 -83.708494)
		(width 0.1397)
		(layer "In5.Cu")
		(net "PCIE_TX_CAP_P53")
	)
	(segment
		(start 234.100878 -86.883494)
		(end 233.465878 -90.058494)
		(width 0.1397)
		(layer "In5.Cu")
		(net "PCIE_TX_CAP_P53")
	)
	(arc
		(start 157.935168 -210.313778)
		(mid 157.872447 -210.6291)
		(end 157.693868 -210.896454)
		(width 0.1397)
		(layer "In5.Cu")
		(net "PCIE_TX_CAP_P53")
	)
	(arc
		(start 234.100116 -65.499742)
		(mid 234.001554 -65.519347)
		(end 233.917998 -65.57518)
		(width 0.1016)
		(layer "In5.Cu")
		(net "PCIE_TX_CAP_P53")
	)
	(arc
		(start 233.578146 -65.914778)
		(mid 233.515702 -66.008372)
		(end 233.493818 -66.11874)
		(width 0.1016)
		(layer "In5.Cu")
		(net "PCIE_TX_CAP_P53")
	)
	(segment
		(start 160.79216 -211.975954)
		(end 161.073846 -211.694268)
		(width 0.136652)
		(layer "F.Cu")
		(net "PCIE_TX_CAP_P52")
	)
	(segment
		(start 235.599986 -63.999872)
		(end 235.100114 -64.499744)
		(width 0.136652)
		(layer "F.Cu")
		(net "PCIE_TX_CAP_P52")
	)
	(segment
		(start 161.047176 -211.050124)
		(end 160.89376 -210.896454)
		(width 0.136652)
		(layer "F.Cu")
		(net "PCIE_TX_CAP_P52")
	)
	(segment
		(start 161.14141 -211.5312)
		(end 161.14141 -211.2772)
		(width 0.136652)
		(layer "F.Cu")
		(net "PCIE_TX_CAP_P52")
	)
	(via
		(at 235.100114 -64.499744)
		(size 0.4572)
		(drill 0.2032)
		(layers "F.Cu" "B.Cu")
		(net "PCIE_TX_CAP_P52")
	)
	(via
		(at 160.89376 -210.896454)
		(size 0.508)
		(drill 0.254)
		(layers "F.Cu" "B.Cu")
		(net "PCIE_TX_CAP_P52")
	)
	(arc
		(start 161.073846 -211.694268)
		(mid 161.123837 -211.619452)
		(end 161.14141 -211.5312)
		(width 0.136652)
		(layer "F.Cu")
		(net "PCIE_TX_CAP_P52")
	)
	(arc
		(start 161.14141 -211.2772)
		(mid 161.116869 -211.154294)
		(end 161.047176 -211.050124)
		(width 0.136652)
		(layer "F.Cu")
		(net "PCIE_TX_CAP_P52")
	)
	(segment
		(start 234.47629 -77.358494)
		(end 235.11129 -80.533494)
		(width 0.1397)
		(layer "In5.Cu")
		(net "PCIE_TX_CAP_P52")
	)
	(segment
		(start 234.493816 -65.118742)
		(end 234.493816 -66.902584)
		(width 0.1016)
		(layer "In5.Cu")
		(net "PCIE_TX_CAP_P52")
	)
	(segment
		(start 234.47629 -90.058494)
		(end 235.11129 -93.233494)
		(width 0.1397)
		(layer "In5.Cu")
		(net "PCIE_TX_CAP_P52")
	)
	(segment
		(start 235.11129 -74.183494)
		(end 234.47629 -77.358494)
		(width 0.1397)
		(layer "In5.Cu")
		(net "PCIE_TX_CAP_P52")
	)
	(segment
		(start 161.13506 -208.309718)
		(end 161.13506 -210.313778)
		(width 0.1397)
		(layer "In5.Cu")
		(net "PCIE_TX_CAP_P52")
	)
	(segment
		(start 234.4166 -66.9798)
		(end 234.4166 -70.710298)
		(width 0.1397)
		(layer "In5.Cu")
		(net "PCIE_TX_CAP_P52")
	)
	(segment
		(start 234.4166 -70.710298)
		(end 235.11129 -74.183494)
		(width 0.1397)
		(layer "In5.Cu")
		(net "PCIE_TX_CAP_P52")
	)
	(segment
		(start 233.311954 -108.647738)
		(end 168.418764 -201.324718)
		(width 0.1397)
		(layer "In5.Cu")
		(net "PCIE_TX_CAP_P52")
	)
	(segment
		(start 167.422068 -202.02271)
		(end 161.13506 -208.309718)
		(width 0.1397)
		(layer "In5.Cu")
		(net "PCIE_TX_CAP_P52")
	)
	(segment
		(start 235.11129 -80.533494)
		(end 234.47629 -83.708494)
		(width 0.1397)
		(layer "In5.Cu")
		(net "PCIE_TX_CAP_P52")
	)
	(segment
		(start 235.11129 -86.883494)
		(end 234.47629 -90.058494)
		(width 0.1397)
		(layer "In5.Cu")
		(net "PCIE_TX_CAP_P52")
	)
	(segment
		(start 234.47629 -83.708494)
		(end 235.11129 -86.883494)
		(width 0.1397)
		(layer "In5.Cu")
		(net "PCIE_TX_CAP_P52")
	)
	(segment
		(start 168.418764 -201.324718)
		(end 167.422068 -202.02271)
		(width 0.1397)
		(layer "In5.Cu")
		(net "PCIE_TX_CAP_P52")
	)
	(segment
		(start 234.47629 -96.408494)
		(end 235.11129 -99.583748)
		(width 0.1397)
		(layer "In5.Cu")
		(net "PCIE_TX_CAP_P52")
	)
	(segment
		(start 234.917996 -64.575182)
		(end 234.578144 -64.91478)
		(width 0.1016)
		(layer "In5.Cu")
		(net "PCIE_TX_CAP_P52")
	)
	(segment
		(start 235.11129 -93.233494)
		(end 234.47629 -96.408494)
		(width 0.1397)
		(layer "In5.Cu")
		(net "PCIE_TX_CAP_P52")
	)
	(segment
		(start 234.493816 -66.902584)
		(end 234.4166 -66.9798)
		(width 0.1016)
		(layer "In5.Cu")
		(net "PCIE_TX_CAP_P52")
	)
	(segment
		(start 234.211622 -104.11587)
		(end 233.311954 -108.647738)
		(width 0.1397)
		(layer "In5.Cu")
		(net "PCIE_TX_CAP_P52")
	)
	(segment
		(start 235.11129 -99.583748)
		(end 234.211622 -104.11587)
		(width 0.1397)
		(layer "In5.Cu")
		(net "PCIE_TX_CAP_P52")
	)
	(arc
		(start 161.13506 -210.313778)
		(mid 161.072339 -210.6291)
		(end 160.89376 -210.896454)
		(width 0.1397)
		(layer "In5.Cu")
		(net "PCIE_TX_CAP_P52")
	)
	(arc
		(start 234.578144 -64.91478)
		(mid 234.5157 -65.008374)
		(end 234.493816 -65.118742)
		(width 0.1016)
		(layer "In5.Cu")
		(net "PCIE_TX_CAP_P52")
	)
	(arc
		(start 235.100114 -64.499744)
		(mid 235.001552 -64.519349)
		(end 234.917996 -64.575182)
		(width 0.1016)
		(layer "In5.Cu")
		(net "PCIE_TX_CAP_P52")
	)
	(segment
		(start 166.392098 -211.975954)
		(end 166.673784 -211.694268)
		(width 0.136652)
		(layer "F.Cu")
		(net "PCIE_TX_CAP_P51")
	)
	(segment
		(start 236.599984 -64.99987)
		(end 236.100112 -65.499742)
		(width 0.136652)
		(layer "F.Cu")
		(net "PCIE_TX_CAP_P51")
	)
	(segment
		(start 166.638224 -211.04098)
		(end 166.493698 -210.896454)
		(width 0.136652)
		(layer "F.Cu")
		(net "PCIE_TX_CAP_P51")
	)
	(segment
		(start 166.741348 -211.5312)
		(end 166.741348 -211.2899)
		(width 0.136652)
		(layer "F.Cu")
		(net "PCIE_TX_CAP_P51")
	)
	(via
		(at 166.493698 -210.896454)
		(size 0.508)
		(drill 0.254)
		(layers "F.Cu" "B.Cu")
		(net "PCIE_TX_CAP_P51")
	)
	(via
		(at 236.100112 -65.499742)
		(size 0.4572)
		(drill 0.2032)
		(layers "F.Cu" "B.Cu")
		(net "PCIE_TX_CAP_P51")
	)
	(arc
		(start 166.741348 -211.2899)
		(mid 166.71455 -211.155179)
		(end 166.638224 -211.04098)
		(width 0.136652)
		(layer "F.Cu")
		(net "PCIE_TX_CAP_P51")
	)
	(arc
		(start 166.673784 -211.694268)
		(mid 166.723775 -211.619452)
		(end 166.741348 -211.5312)
		(width 0.136652)
		(layer "F.Cu")
		(net "PCIE_TX_CAP_P51")
	)
	(segment
		(start 166.734998 -209.332576)
		(end 235.109258 -111.683546)
		(width 0.1397)
		(layer "In5.Cu")
		(net "PCIE_TX_CAP_P51")
	)
	(segment
		(start 236.121956 -99.582478)
		(end 236.117892 -99.561396)
		(width 0.1397)
		(layer "In5.Cu")
		(net "PCIE_TX_CAP_P51")
	)
	(segment
		(start 236.12094 -99.58832)
		(end 236.121956 -99.582478)
		(width 0.1397)
		(layer "In5.Cu")
		(net "PCIE_TX_CAP_P51")
	)
	(segment
		(start 236.121956 -93.232732)
		(end 235.486702 -90.059002)
		(width 0.1397)
		(layer "In5.Cu")
		(net "PCIE_TX_CAP_P51")
	)
	(segment
		(start 236.121956 -80.532732)
		(end 235.486702 -77.359002)
		(width 0.1397)
		(layer "In5.Cu")
		(net "PCIE_TX_CAP_P51")
	)
	(segment
		(start 236.12094 -74.186796)
		(end 235.4072 -70.611492)
		(width 0.1397)
		(layer "In5.Cu")
		(net "PCIE_TX_CAP_P51")
	)
	(segment
		(start 236.121956 -93.232986)
		(end 236.121956 -93.232732)
		(width 0.1397)
		(layer "In5.Cu")
		(net "PCIE_TX_CAP_P51")
	)
	(segment
		(start 235.4072 -66.9798)
		(end 235.493814 -66.893186)
		(width 0.1016)
		(layer "In5.Cu")
		(net "PCIE_TX_CAP_P51")
	)
	(segment
		(start 235.486702 -96.409002)
		(end 236.121956 -93.232986)
		(width 0.1397)
		(layer "In5.Cu")
		(net "PCIE_TX_CAP_P51")
	)
	(segment
		(start 235.578142 -65.914778)
		(end 235.917994 -65.57518)
		(width 0.1016)
		(layer "In5.Cu")
		(net "PCIE_TX_CAP_P51")
	)
	(segment
		(start 236.121956 -86.882732)
		(end 235.486702 -83.709002)
		(width 0.1397)
		(layer "In5.Cu")
		(net "PCIE_TX_CAP_P51")
	)
	(segment
		(start 235.486702 -83.709002)
		(end 236.121956 -80.532732)
		(width 0.1397)
		(layer "In5.Cu")
		(net "PCIE_TX_CAP_P51")
	)
	(segment
		(start 235.4072 -70.611492)
		(end 235.4072 -66.9798)
		(width 0.1397)
		(layer "In5.Cu")
		(net "PCIE_TX_CAP_P51")
	)
	(segment
		(start 235.109258 -111.683546)
		(end 236.122464 -105.937812)
		(width 0.1397)
		(layer "In5.Cu")
		(net "PCIE_TX_CAP_P51")
	)
	(segment
		(start 235.495592 -102.802944)
		(end 235.483908 -102.73919)
		(width 0.1397)
		(layer "In5.Cu")
		(net "PCIE_TX_CAP_P51")
	)
	(segment
		(start 235.483908 -102.73919)
		(end 235.495592 -102.67315)
		(width 0.1397)
		(layer "In5.Cu")
		(net "PCIE_TX_CAP_P51")
	)
	(segment
		(start 235.495592 -102.67315)
		(end 235.82122 -101.065584)
		(width 0.1397)
		(layer "In5.Cu")
		(net "PCIE_TX_CAP_P51")
	)
	(segment
		(start 235.486702 -90.059002)
		(end 236.121956 -86.882732)
		(width 0.1397)
		(layer "In5.Cu")
		(net "PCIE_TX_CAP_P51")
	)
	(segment
		(start 235.486702 -77.359002)
		(end 236.12094 -74.186796)
		(width 0.1397)
		(layer "In5.Cu")
		(net "PCIE_TX_CAP_P51")
	)
	(segment
		(start 235.82122 -101.065584)
		(end 236.12094 -99.58832)
		(width 0.1397)
		(layer "In5.Cu")
		(net "PCIE_TX_CAP_P51")
	)
	(segment
		(start 166.734998 -210.313778)
		(end 166.734998 -209.332576)
		(width 0.1397)
		(layer "In5.Cu")
		(net "PCIE_TX_CAP_P51")
	)
	(segment
		(start 236.122464 -105.937812)
		(end 235.495592 -102.802944)
		(width 0.1397)
		(layer "In5.Cu")
		(net "PCIE_TX_CAP_P51")
	)
	(segment
		(start 236.117892 -99.561396)
		(end 235.486702 -96.409002)
		(width 0.1397)
		(layer "In5.Cu")
		(net "PCIE_TX_CAP_P51")
	)
	(segment
		(start 235.493814 -66.893186)
		(end 235.493814 -66.11874)
		(width 0.1016)
		(layer "In5.Cu")
		(net "PCIE_TX_CAP_P51")
	)
	(arc
		(start 166.493698 -210.896454)
		(mid 166.672325 -210.62912)
		(end 166.734998 -210.313778)
		(width 0.1397)
		(layer "In5.Cu")
		(net "PCIE_TX_CAP_P51")
	)
	(arc
		(start 235.493814 -66.11874)
		(mid 235.515676 -66.008362)
		(end 235.578142 -65.914778)
		(width 0.1016)
		(layer "In5.Cu")
		(net "PCIE_TX_CAP_P51")
	)
	(arc
		(start 235.917994 -65.57518)
		(mid 236.00155 -65.519349)
		(end 236.100112 -65.499742)
		(width 0.1016)
		(layer "In5.Cu")
		(net "PCIE_TX_CAP_P51")
	)
	(segment
		(start 237.599982 -63.999872)
		(end 237.10011 -64.499744)
		(width 0.136652)
		(layer "F.Cu")
		(net "PCIE_TX_CAP_P50")
	)
	(segment
		(start 169.839132 -211.041742)
		(end 169.69359 -210.896454)
		(width 0.136652)
		(layer "F.Cu")
		(net "PCIE_TX_CAP_P50")
	)
	(segment
		(start 169.59199 -211.975954)
		(end 169.873676 -211.694268)
		(width 0.136652)
		(layer "F.Cu")
		(net "PCIE_TX_CAP_P50")
	)
	(segment
		(start 169.94124 -211.5312)
		(end 169.94124 -211.28863)
		(width 0.136652)
		(layer "F.Cu")
		(net "PCIE_TX_CAP_P50")
	)
	(via
		(at 237.10011 -64.499744)
		(size 0.4572)
		(drill 0.2032)
		(layers "F.Cu" "B.Cu")
		(net "PCIE_TX_CAP_P50")
	)
	(via
		(at 169.69359 -210.896454)
		(size 0.508)
		(drill 0.254)
		(layers "F.Cu" "B.Cu")
		(net "PCIE_TX_CAP_P50")
	)
	(arc
		(start 169.94124 -211.28863)
		(mid 169.914757 -211.155021)
		(end 169.839132 -211.041742)
		(width 0.136652)
		(layer "F.Cu")
		(net "PCIE_TX_CAP_P50")
	)
	(arc
		(start 169.873676 -211.694268)
		(mid 169.923667 -211.619452)
		(end 169.94124 -211.5312)
		(width 0.136652)
		(layer "F.Cu")
		(net "PCIE_TX_CAP_P50")
	)
	(segment
		(start 237.157768 -93.233494)
		(end 236.522768 -96.408494)
		(width 0.1397)
		(layer "In5.Cu")
		(net "PCIE_TX_CAP_P50")
	)
	(segment
		(start 237.157768 -86.883494)
		(end 236.522768 -90.058494)
		(width 0.1397)
		(layer "In5.Cu")
		(net "PCIE_TX_CAP_P50")
	)
	(segment
		(start 236.522768 -96.408494)
		(end 237.157768 -99.583494)
		(width 0.1397)
		(layer "In5.Cu")
		(net "PCIE_TX_CAP_P50")
	)
	(segment
		(start 237.157768 -105.933494)
		(end 235.548678 -113.977928)
		(width 0.1397)
		(layer "In5.Cu")
		(net "PCIE_TX_CAP_P50")
	)
	(segment
		(start 236.522768 -77.358494)
		(end 237.157768 -80.533494)
		(width 0.1397)
		(layer "In5.Cu")
		(net "PCIE_TX_CAP_P50")
	)
	(segment
		(start 169.93489 -207.685386)
		(end 169.93489 -210.4644)
		(width 0.1397)
		(layer "In5.Cu")
		(net "PCIE_TX_CAP_P50")
	)
	(segment
		(start 236.917992 -64.575182)
		(end 236.57814 -64.91478)
		(width 0.1016)
		(layer "In5.Cu")
		(net "PCIE_TX_CAP_P50")
	)
	(segment
		(start 237.157768 -99.583494)
		(end 236.522768 -102.758494)
		(width 0.1397)
		(layer "In5.Cu")
		(net "PCIE_TX_CAP_P50")
	)
	(segment
		(start 236.4232 -67.0052)
		(end 236.4232 -70.5104)
		(width 0.1397)
		(layer "In5.Cu")
		(net "PCIE_TX_CAP_P50")
	)
	(segment
		(start 236.493812 -65.118742)
		(end 236.493812 -66.934588)
		(width 0.1016)
		(layer "In5.Cu")
		(net "PCIE_TX_CAP_P50")
	)
	(segment
		(start 237.157768 -80.533494)
		(end 236.522768 -83.708494)
		(width 0.1397)
		(layer "In5.Cu")
		(net "PCIE_TX_CAP_P50")
	)
	(segment
		(start 236.4232 -70.5104)
		(end 237.157768 -74.183494)
		(width 0.1397)
		(layer "In5.Cu")
		(net "PCIE_TX_CAP_P50")
	)
	(segment
		(start 236.493812 -66.934588)
		(end 236.4232 -67.0052)
		(width 0.1016)
		(layer "In5.Cu")
		(net "PCIE_TX_CAP_P50")
	)
	(segment
		(start 235.548678 -113.977928)
		(end 169.93489 -207.685386)
		(width 0.1397)
		(layer "In5.Cu")
		(net "PCIE_TX_CAP_P50")
	)
	(segment
		(start 237.157768 -74.183494)
		(end 236.522768 -77.358494)
		(width 0.1397)
		(layer "In5.Cu")
		(net "PCIE_TX_CAP_P50")
	)
	(segment
		(start 236.522768 -83.708494)
		(end 237.157768 -86.883494)
		(width 0.1397)
		(layer "In5.Cu")
		(net "PCIE_TX_CAP_P50")
	)
	(segment
		(start 236.522768 -90.058494)
		(end 237.157768 -93.233494)
		(width 0.1397)
		(layer "In5.Cu")
		(net "PCIE_TX_CAP_P50")
	)
	(segment
		(start 169.800016 -210.790028)
		(end 169.69359 -210.896454)
		(width 0.1397)
		(layer "In5.Cu")
		(net "PCIE_TX_CAP_P50")
	)
	(segment
		(start 236.522768 -102.758494)
		(end 237.157768 -105.933494)
		(width 0.1397)
		(layer "In5.Cu")
		(net "PCIE_TX_CAP_P50")
	)
	(arc
		(start 169.93489 -210.4644)
		(mid 169.932326 -210.512672)
		(end 169.92473 -210.560412)
		(width 0.1397)
		(layer "In5.Cu")
		(net "PCIE_TX_CAP_P50")
	)
	(arc
		(start 236.57814 -64.91478)
		(mid 236.515696 -65.008374)
		(end 236.493812 -65.118742)
		(width 0.1016)
		(layer "In5.Cu")
		(net "PCIE_TX_CAP_P50")
	)
	(arc
		(start 237.10011 -64.499744)
		(mid 237.001548 -64.519349)
		(end 236.917992 -64.575182)
		(width 0.1016)
		(layer "In5.Cu")
		(net "PCIE_TX_CAP_P50")
	)
	(arc
		(start 169.92473 -210.560412)
		(mid 169.878983 -210.684238)
		(end 169.800016 -210.790028)
		(width 0.1397)
		(layer "In5.Cu")
		(net "PCIE_TX_CAP_P50")
	)
	(segment
		(start 299.697394 -34.77133)
		(end 299.697394 -35.757358)
		(width 0.136652)
		(layer "F.Cu")
		(net "PCIE_TX_CAP_P5")
	)
	(segment
		(start 299.580554 -36.039806)
		(end 299.430694 -36.189412)
		(width 0.136652)
		(layer "F.Cu")
		(net "PCIE_TX_CAP_P5")
	)
	(segment
		(start 256.599944 -31.999936)
		(end 257.099816 -31.500064)
		(width 0.136652)
		(layer "F.Cu")
		(net "PCIE_TX_CAP_P5")
	)
	(via
		(at 257.099816 -31.500064)
		(size 0.4572)
		(drill 0.2032)
		(layers "F.Cu" "B.Cu")
		(net "PCIE_TX_CAP_P5")
	)
	(via
		(at 299.430694 -36.189412)
		(size 0.508)
		(drill 0.254)
		(layers "F.Cu" "B.Cu")
		(net "PCIE_TX_CAP_P5")
	)
	(arc
		(start 299.379894 -34.004758)
		(mid 299.614897 -34.356464)
		(end 299.697394 -34.77133)
		(width 0.136652)
		(layer "F.Cu")
		(net "PCIE_TX_CAP_P5")
	)
	(arc
		(start 299.697394 -35.757358)
		(mid 299.667083 -35.910213)
		(end 299.580554 -36.039806)
		(width 0.136652)
		(layer "F.Cu")
		(net "PCIE_TX_CAP_P5")
	)
	(segment
		(start 257.856736 -26.058368)
		(end 257.066542 -26.61158)
		(width 0.1397)
		(layer "In5.Cu")
		(net "PCIE_TX_CAP_P5")
	)
	(segment
		(start 260.7564 -25.547066)
		(end 257.856736 -26.058368)
		(width 0.1397)
		(layer "In5.Cu")
		(net "PCIE_TX_CAP_P5")
	)
	(segment
		(start 256.6162 -27.590242)
		(end 256.6162 -28.32862)
		(width 0.1397)
		(layer "In5.Cu")
		(net "PCIE_TX_CAP_P5")
	)
	(segment
		(start 277.271734 -27.667966)
		(end 275.61794 -26.509726)
		(width 0.1397)
		(layer "In5.Cu")
		(net "PCIE_TX_CAP_P5")
	)
	(segment
		(start 291.739066 -37.40785)
		(end 287.819338 -38.098984)
		(width 0.1397)
		(layer "In5.Cu")
		(net "PCIE_TX_CAP_P5")
	)
	(segment
		(start 278.622252 -29.596588)
		(end 277.271734 -27.667966)
		(width 0.1397)
		(layer "In5.Cu")
		(net "PCIE_TX_CAP_P5")
	)
	(segment
		(start 256.691638 -31.091632)
		(end 257.099816 -31.500064)
		(width 0.1016)
		(layer "In5.Cu")
		(net "PCIE_TX_CAP_P5")
	)
	(segment
		(start 281.194764 -35.202876)
		(end 279.077674 -32.17926)
		(width 0.1397)
		(layer "In5.Cu")
		(net "PCIE_TX_CAP_P5")
	)
	(segment
		(start 295.795192 -36.692586)
		(end 291.739066 -37.40785)
		(width 0.1397)
		(layer "In5.Cu")
		(net "PCIE_TX_CAP_P5")
	)
	(segment
		(start 299.435012 -37.065966)
		(end 298.190158 -37.445188)
		(width 0.1397)
		(layer "In5.Cu")
		(net "PCIE_TX_CAP_P5")
	)
	(segment
		(start 299.6819 -36.819078)
		(end 299.435012 -37.065966)
		(width 0.1397)
		(layer "In5.Cu")
		(net "PCIE_TX_CAP_P5")
	)
	(segment
		(start 256.6797 -28.41752)
		(end 256.6797 -29.205174)
		(width 0.1016)
		(layer "In5.Cu")
		(net "PCIE_TX_CAP_P5")
	)
	(segment
		(start 256.6797 -29.205174)
		(end 256.501392 -29.383482)
		(width 0.1016)
		(layer "In5.Cu")
		(net "PCIE_TX_CAP_P5")
	)
	(segment
		(start 256.6162 -28.35402)
		(end 256.6797 -28.41752)
		(width 0.1016)
		(layer "In5.Cu")
		(net "PCIE_TX_CAP_P5")
	)
	(segment
		(start 279.077674 -32.17926)
		(end 278.622252 -29.596588)
		(width 0.1397)
		(layer "In5.Cu")
		(net "PCIE_TX_CAP_P5")
	)
	(segment
		(start 287.819338 -38.098984)
		(end 284.494224 -37.513006)
		(width 0.1397)
		(layer "In5.Cu")
		(net "PCIE_TX_CAP_P5")
	)
	(segment
		(start 298.190158 -37.445188)
		(end 295.795192 -36.692586)
		(width 0.1397)
		(layer "In5.Cu")
		(net "PCIE_TX_CAP_P5")
	)
	(segment
		(start 257.066542 -26.61158)
		(end 256.695194 -27.141424)
		(width 0.1397)
		(layer "In5.Cu")
		(net "PCIE_TX_CAP_P5")
	)
	(segment
		(start 256.695194 -27.141424)
		(end 256.6162 -27.590242)
		(width 0.1397)
		(layer "In5.Cu")
		(net "PCIE_TX_CAP_P5")
	)
	(segment
		(start 284.494224 -37.513006)
		(end 281.194764 -35.202876)
		(width 0.1397)
		(layer "In5.Cu")
		(net "PCIE_TX_CAP_P5")
	)
	(segment
		(start 269.372334 -25.408382)
		(end 264.671556 -26.237438)
		(width 0.1397)
		(layer "In5.Cu")
		(net "PCIE_TX_CAP_P5")
	)
	(segment
		(start 275.61794 -26.509726)
		(end 269.372334 -25.408382)
		(width 0.1397)
		(layer "In5.Cu")
		(net "PCIE_TX_CAP_P5")
	)
	(segment
		(start 256.6162 -28.32862)
		(end 256.6162 -28.35402)
		(width 0.1016)
		(layer "In5.Cu")
		(net "PCIE_TX_CAP_P5")
	)
	(segment
		(start 299.6819 -36.6522)
		(end 299.6819 -36.819078)
		(width 0.1397)
		(layer "In5.Cu")
		(net "PCIE_TX_CAP_P5")
	)
	(segment
		(start 264.671556 -26.237438)
		(end 260.7564 -25.547066)
		(width 0.1397)
		(layer "In5.Cu")
		(net "PCIE_TX_CAP_P5")
	)
	(segment
		(start 299.430694 -36.189412)
		(end 299.532294 -36.291012)
		(width 0.1397)
		(layer "In5.Cu")
		(net "PCIE_TX_CAP_P5")
	)
	(segment
		(start 256.501392 -29.383482)
		(end 256.501392 -30.6324)
		(width 0.1016)
		(layer "In5.Cu")
		(net "PCIE_TX_CAP_P5")
	)
	(arc
		(start 299.532294 -36.291012)
		(mid 299.643021 -36.456726)
		(end 299.6819 -36.6522)
		(width 0.1397)
		(layer "In5.Cu")
		(net "PCIE_TX_CAP_P5")
	)
	(arc
		(start 256.501392 -30.6324)
		(mid 256.532745 -30.831463)
		(end 256.623566 -31.011368)
		(width 0.1016)
		(layer "In5.Cu")
		(net "PCIE_TX_CAP_P5")
	)
	(arc
		(start 256.623566 -31.011368)
		(mid 256.655975 -31.05288)
		(end 256.691638 -31.091632)
		(width 0.1016)
		(layer "In5.Cu")
		(net "PCIE_TX_CAP_P5")
	)
	(segment
		(start 173.141386 -211.5312)
		(end 173.141386 -211.287868)
		(width 0.136652)
		(layer "F.Cu")
		(net "PCIE_TX_CAP_P49")
	)
	(segment
		(start 172.792136 -211.975954)
		(end 173.073822 -211.694268)
		(width 0.136652)
		(layer "F.Cu")
		(net "PCIE_TX_CAP_P49")
	)
	(segment
		(start 173.039786 -211.042504)
		(end 172.893736 -210.896454)
		(width 0.136652)
		(layer "F.Cu")
		(net "PCIE_TX_CAP_P49")
	)
	(segment
		(start 238.59998 -64.99987)
		(end 238.100108 -65.499742)
		(width 0.136652)
		(layer "F.Cu")
		(net "PCIE_TX_CAP_P49")
	)
	(via
		(at 238.100108 -65.499742)
		(size 0.4572)
		(drill 0.2032)
		(layers "F.Cu" "B.Cu")
		(net "PCIE_TX_CAP_P49")
	)
	(via
		(at 172.893736 -210.896454)
		(size 0.508)
		(drill 0.254)
		(layers "F.Cu" "B.Cu")
		(net "PCIE_TX_CAP_P49")
	)
	(arc
		(start 173.141386 -211.287868)
		(mid 173.114975 -211.155091)
		(end 173.039786 -211.042504)
		(width 0.136652)
		(layer "F.Cu")
		(net "PCIE_TX_CAP_P49")
	)
	(arc
		(start 173.073822 -211.694268)
		(mid 173.123813 -211.619452)
		(end 173.141386 -211.5312)
		(width 0.136652)
		(layer "F.Cu")
		(net "PCIE_TX_CAP_P49")
	)
	(segment
		(start 237.559088 -96.408494)
		(end 238.194088 -93.233494)
		(width 0.1397)
		(layer "In5.Cu")
		(net "PCIE_TX_CAP_P49")
	)
	(segment
		(start 237.4392 -67.0052)
		(end 237.49381 -66.95059)
		(width 0.1016)
		(layer "In5.Cu")
		(net "PCIE_TX_CAP_P49")
	)
	(segment
		(start 238.194088 -105.933494)
		(end 237.559088 -102.758494)
		(width 0.1397)
		(layer "In5.Cu")
		(net "PCIE_TX_CAP_P49")
	)
	(segment
		(start 173.1518 -210.273392)
		(end 173.1518 -207.798162)
		(width 0.1397)
		(layer "In5.Cu")
		(net "PCIE_TX_CAP_P49")
	)
	(segment
		(start 238.194088 -99.583494)
		(end 237.559088 -96.408494)
		(width 0.1397)
		(layer "In5.Cu")
		(net "PCIE_TX_CAP_P49")
	)
	(segment
		(start 237.559088 -90.058494)
		(end 238.194088 -86.883494)
		(width 0.1397)
		(layer "In5.Cu")
		(net "PCIE_TX_CAP_P49")
	)
	(segment
		(start 237.559088 -102.758494)
		(end 238.194088 -99.583494)
		(width 0.1397)
		(layer "In5.Cu")
		(net "PCIE_TX_CAP_P49")
	)
	(segment
		(start 238.194088 -93.233494)
		(end 237.559088 -90.058494)
		(width 0.1397)
		(layer "In5.Cu")
		(net "PCIE_TX_CAP_P49")
	)
	(segment
		(start 237.49381 -66.95059)
		(end 237.49381 -66.11874)
		(width 0.1016)
		(layer "In5.Cu")
		(net "PCIE_TX_CAP_P49")
	)
	(segment
		(start 238.194088 -74.183494)
		(end 237.4392 -70.409308)
		(width 0.1397)
		(layer "In5.Cu")
		(net "PCIE_TX_CAP_P49")
	)
	(segment
		(start 237.559088 -77.358494)
		(end 238.194088 -74.183494)
		(width 0.1397)
		(layer "In5.Cu")
		(net "PCIE_TX_CAP_P49")
	)
	(segment
		(start 237.559088 -109.108494)
		(end 238.194088 -105.933494)
		(width 0.1397)
		(layer "In5.Cu")
		(net "PCIE_TX_CAP_P49")
	)
	(segment
		(start 238.194088 -86.883494)
		(end 237.559088 -83.708494)
		(width 0.1397)
		(layer "In5.Cu")
		(net "PCIE_TX_CAP_P49")
	)
	(segment
		(start 238.194088 -80.533494)
		(end 237.559088 -77.358494)
		(width 0.1397)
		(layer "In5.Cu")
		(net "PCIE_TX_CAP_P49")
	)
	(segment
		(start 237.578138 -65.914778)
		(end 237.91799 -65.57518)
		(width 0.1016)
		(layer "In5.Cu")
		(net "PCIE_TX_CAP_P49")
	)
	(segment
		(start 173.1518 -207.798162)
		(end 237.459012 -115.957604)
		(width 0.1397)
		(layer "In5.Cu")
		(net "PCIE_TX_CAP_P49")
	)
	(segment
		(start 237.4392 -70.409308)
		(end 237.4392 -67.0052)
		(width 0.1397)
		(layer "In5.Cu")
		(net "PCIE_TX_CAP_P49")
	)
	(segment
		(start 237.459012 -115.957604)
		(end 238.194088 -112.283494)
		(width 0.1397)
		(layer "In5.Cu")
		(net "PCIE_TX_CAP_P49")
	)
	(segment
		(start 238.194088 -112.283494)
		(end 237.559088 -109.108494)
		(width 0.1397)
		(layer "In5.Cu")
		(net "PCIE_TX_CAP_P49")
	)
	(segment
		(start 237.559088 -83.708494)
		(end 238.194088 -80.533494)
		(width 0.1397)
		(layer "In5.Cu")
		(net "PCIE_TX_CAP_P49")
	)
	(arc
		(start 237.49381 -66.11874)
		(mid 237.515672 -66.008362)
		(end 237.578138 -65.914778)
		(width 0.1016)
		(layer "In5.Cu")
		(net "PCIE_TX_CAP_P49")
	)
	(arc
		(start 237.91799 -65.57518)
		(mid 238.001546 -65.519349)
		(end 238.100108 -65.499742)
		(width 0.1016)
		(layer "In5.Cu")
		(net "PCIE_TX_CAP_P49")
	)
	(arc
		(start 172.893736 -210.896454)
		(mid 173.084744 -210.610591)
		(end 173.1518 -210.273392)
		(width 0.1397)
		(layer "In5.Cu")
		(net "PCIE_TX_CAP_P49")
	)
	(segment
		(start 176.341278 -211.5312)
		(end 176.341278 -211.286852)
		(width 0.136652)
		(layer "F.Cu")
		(net "PCIE_TX_CAP_P48")
	)
	(segment
		(start 175.992028 -211.975954)
		(end 176.273714 -211.694268)
		(width 0.136652)
		(layer "F.Cu")
		(net "PCIE_TX_CAP_P48")
	)
	(segment
		(start 176.24044 -211.043012)
		(end 176.093628 -210.896454)
		(width 0.136652)
		(layer "F.Cu")
		(net "PCIE_TX_CAP_P48")
	)
	(segment
		(start 239.599978 -63.999872)
		(end 239.100106 -64.499744)
		(width 0.136652)
		(layer "F.Cu")
		(net "PCIE_TX_CAP_P48")
	)
	(via
		(at 176.093628 -210.896454)
		(size 0.508)
		(drill 0.254)
		(layers "F.Cu" "B.Cu")
		(net "PCIE_TX_CAP_P48")
	)
	(via
		(at 239.100106 -64.499744)
		(size 0.4572)
		(drill 0.2032)
		(layers "F.Cu" "B.Cu")
		(net "PCIE_TX_CAP_P48")
	)
	(arc
		(start 176.273714 -211.694268)
		(mid 176.323705 -211.619452)
		(end 176.341278 -211.5312)
		(width 0.136652)
		(layer "F.Cu")
		(net "PCIE_TX_CAP_P48")
	)
	(arc
		(start 176.341278 -211.286852)
		(mid 176.315124 -211.154896)
		(end 176.24044 -211.043012)
		(width 0.136652)
		(layer "F.Cu")
		(net "PCIE_TX_CAP_P48")
	)
	(segment
		(start 239.204246 -80.533494)
		(end 238.569246 -83.708494)
		(width 0.1397)
		(layer "In5.Cu")
		(net "PCIE_TX_CAP_P48")
	)
	(segment
		(start 238.569246 -77.358494)
		(end 239.204246 -80.533494)
		(width 0.1397)
		(layer "In5.Cu")
		(net "PCIE_TX_CAP_P48")
	)
	(segment
		(start 239.204246 -112.283494)
		(end 238.449612 -116.05641)
		(width 0.1397)
		(layer "In5.Cu")
		(net "PCIE_TX_CAP_P48")
	)
	(segment
		(start 239.204246 -99.583494)
		(end 238.569246 -102.758494)
		(width 0.1397)
		(layer "In5.Cu")
		(net "PCIE_TX_CAP_P48")
	)
	(segment
		(start 239.204246 -74.183494)
		(end 238.569246 -77.358494)
		(width 0.1397)
		(layer "In5.Cu")
		(net "PCIE_TX_CAP_P48")
	)
	(segment
		(start 239.204246 -86.883494)
		(end 238.569246 -90.058494)
		(width 0.1397)
		(layer "In5.Cu")
		(net "PCIE_TX_CAP_P48")
	)
	(segment
		(start 238.4298 -70.310756)
		(end 239.204246 -74.183494)
		(width 0.1397)
		(layer "In5.Cu")
		(net "PCIE_TX_CAP_P48")
	)
	(segment
		(start 238.917988 -64.575182)
		(end 238.578136 -64.91478)
		(width 0.1016)
		(layer "In5.Cu")
		(net "PCIE_TX_CAP_P48")
	)
	(segment
		(start 238.569246 -96.408494)
		(end 239.204246 -99.583494)
		(width 0.1397)
		(layer "In5.Cu")
		(net "PCIE_TX_CAP_P48")
	)
	(segment
		(start 238.493808 -65.118742)
		(end 238.493808 -66.941192)
		(width 0.1016)
		(layer "In5.Cu")
		(net "PCIE_TX_CAP_P48")
	)
	(segment
		(start 238.569246 -83.708494)
		(end 239.204246 -86.883494)
		(width 0.1397)
		(layer "In5.Cu")
		(net "PCIE_TX_CAP_P48")
	)
	(segment
		(start 238.4298 -67.0052)
		(end 238.4298 -70.310756)
		(width 0.1397)
		(layer "In5.Cu")
		(net "PCIE_TX_CAP_P48")
	)
	(segment
		(start 176.3268 -204.77734)
		(end 176.3268 -210.4644)
		(width 0.1397)
		(layer "In5.Cu")
		(net "PCIE_TX_CAP_P48")
	)
	(segment
		(start 238.493808 -66.941192)
		(end 238.4298 -67.0052)
		(width 0.1016)
		(layer "In5.Cu")
		(net "PCIE_TX_CAP_P48")
	)
	(segment
		(start 176.186084 -210.803744)
		(end 176.093628 -210.896454)
		(width 0.1397)
		(layer "In5.Cu")
		(net "PCIE_TX_CAP_P48")
	)
	(segment
		(start 238.569246 -102.758494)
		(end 239.204246 -105.933494)
		(width 0.1397)
		(layer "In5.Cu")
		(net "PCIE_TX_CAP_P48")
	)
	(segment
		(start 239.204246 -93.233494)
		(end 238.569246 -96.408494)
		(width 0.1397)
		(layer "In5.Cu")
		(net "PCIE_TX_CAP_P48")
	)
	(segment
		(start 238.449612 -116.05641)
		(end 176.3268 -204.77734)
		(width 0.1397)
		(layer "In5.Cu")
		(net "PCIE_TX_CAP_P48")
	)
	(segment
		(start 238.569246 -109.108494)
		(end 239.204246 -112.283494)
		(width 0.1397)
		(layer "In5.Cu")
		(net "PCIE_TX_CAP_P48")
	)
	(segment
		(start 239.204246 -105.933494)
		(end 238.569246 -109.108494)
		(width 0.1397)
		(layer "In5.Cu")
		(net "PCIE_TX_CAP_P48")
	)
	(segment
		(start 238.569246 -90.058494)
		(end 239.204246 -93.233494)
		(width 0.1397)
		(layer "In5.Cu")
		(net "PCIE_TX_CAP_P48")
	)
	(arc
		(start 239.100106 -64.499744)
		(mid 239.001544 -64.519349)
		(end 238.917988 -64.575182)
		(width 0.1016)
		(layer "In5.Cu")
		(net "PCIE_TX_CAP_P48")
	)
	(arc
		(start 176.3268 -210.4644)
		(mid 176.290175 -210.648057)
		(end 176.186084 -210.803744)
		(width 0.1397)
		(layer "In5.Cu")
		(net "PCIE_TX_CAP_P48")
	)
	(arc
		(start 238.578136 -64.91478)
		(mid 238.515692 -65.008374)
		(end 238.493808 -65.118742)
		(width 0.1016)
		(layer "In5.Cu")
		(net "PCIE_TX_CAP_P48")
	)
	(segment
		(start 184.341262 -211.5312)
		(end 184.341262 -211.284312)
		(width 0.136652)
		(layer "F.Cu")
		(net "PCIE_TX_CAP_P47")
	)
	(segment
		(start 183.992266 -211.975954)
		(end 183.992012 -211.975954)
		(width 0.136652)
		(layer "F.Cu")
		(net "PCIE_TX_CAP_P47")
	)
	(segment
		(start 184.242202 -211.04479)
		(end 184.093612 -210.896454)
		(width 0.136652)
		(layer "F.Cu")
		(net "PCIE_TX_CAP_P47")
	)
	(segment
		(start 183.992012 -211.975954)
		(end 184.273698 -211.694268)
		(width 0.136652)
		(layer "F.Cu")
		(net "PCIE_TX_CAP_P47")
	)
	(segment
		(start 241.599974 -63.999872)
		(end 242.099846 -64.499744)
		(width 0.136652)
		(layer "F.Cu")
		(net "PCIE_TX_CAP_P47")
	)
	(via
		(at 184.093612 -210.896454)
		(size 0.508)
		(drill 0.254)
		(layers "F.Cu" "B.Cu")
		(net "PCIE_TX_CAP_P47")
	)
	(via
		(at 242.099846 -64.499744)
		(size 0.4572)
		(drill 0.2032)
		(layers "F.Cu" "B.Cu")
		(net "PCIE_TX_CAP_P47")
	)
	(arc
		(start 184.273698 -211.694268)
		(mid 184.323689 -211.619452)
		(end 184.341262 -211.5312)
		(width 0.136652)
		(layer "F.Cu")
		(net "PCIE_TX_CAP_P47")
	)
	(arc
		(start 184.341262 -211.284312)
		(mid 184.315572 -211.154689)
		(end 184.242202 -211.04479)
		(width 0.136652)
		(layer "F.Cu")
		(net "PCIE_TX_CAP_P47")
	)
	(segment
		(start 241.427 -76.363576)
		(end 242.895882 -83.708494)
		(width 0.1397)
		(layer "In5.Cu")
		(net "PCIE_TX_CAP_P47")
	)
	(segment
		(start 186.192668 -195.264786)
		(end 184.334912 -205.800198)
		(width 0.1397)
		(layer "In5.Cu")
		(net "PCIE_TX_CAP_P47")
	)
	(segment
		(start 241.446812 -116.35359)
		(end 186.192668 -195.264786)
		(width 0.1397)
		(layer "In5.Cu")
		(net "PCIE_TX_CAP_P47")
	)
	(segment
		(start 242.895882 -96.408494)
		(end 241.625882 -102.758494)
		(width 0.1397)
		(layer "In5.Cu")
		(net "PCIE_TX_CAP_P47")
	)
	(segment
		(start 241.493548 -66.887852)
		(end 241.427 -66.9544)
		(width 0.1016)
		(layer "In5.Cu")
		(net "PCIE_TX_CAP_P47")
	)
	(segment
		(start 241.427 -66.9544)
		(end 241.427 -76.363576)
		(width 0.1397)
		(layer "In5.Cu")
		(net "PCIE_TX_CAP_P47")
	)
	(segment
		(start 184.334912 -205.800198)
		(end 184.334912 -210.313778)
		(width 0.1397)
		(layer "In5.Cu")
		(net "PCIE_TX_CAP_P47")
	)
	(segment
		(start 241.625882 -90.058494)
		(end 242.895882 -96.408494)
		(width 0.1397)
		(layer "In5.Cu")
		(net "PCIE_TX_CAP_P47")
	)
	(segment
		(start 241.917728 -64.575182)
		(end 241.577876 -64.91478)
		(width 0.1016)
		(layer "In5.Cu")
		(net "PCIE_TX_CAP_P47")
	)
	(segment
		(start 241.493548 -65.118742)
		(end 241.493548 -66.887852)
		(width 0.1016)
		(layer "In5.Cu")
		(net "PCIE_TX_CAP_P47")
	)
	(segment
		(start 242.895882 -83.708494)
		(end 241.625882 -90.058494)
		(width 0.1397)
		(layer "In5.Cu")
		(net "PCIE_TX_CAP_P47")
	)
	(segment
		(start 242.895882 -109.108494)
		(end 241.446812 -116.35359)
		(width 0.1397)
		(layer "In5.Cu")
		(net "PCIE_TX_CAP_P47")
	)
	(segment
		(start 241.625882 -102.758494)
		(end 242.895882 -109.108494)
		(width 0.1397)
		(layer "In5.Cu")
		(net "PCIE_TX_CAP_P47")
	)
	(arc
		(start 184.334912 -210.313778)
		(mid 184.272191 -210.6291)
		(end 184.093612 -210.896454)
		(width 0.1397)
		(layer "In5.Cu")
		(net "PCIE_TX_CAP_P47")
	)
	(arc
		(start 241.577876 -64.91478)
		(mid 241.515432 -65.008374)
		(end 241.493548 -65.118742)
		(width 0.1016)
		(layer "In5.Cu")
		(net "PCIE_TX_CAP_P47")
	)
	(arc
		(start 242.099846 -64.499744)
		(mid 242.001284 -64.519349)
		(end 241.917728 -64.575182)
		(width 0.1016)
		(layer "In5.Cu")
		(net "PCIE_TX_CAP_P47")
	)
	(segment
		(start 242.599972 -64.99987)
		(end 243.099844 -65.499742)
		(width 0.136652)
		(layer "F.Cu")
		(net "PCIE_TX_CAP_P46")
	)
	(segment
		(start 187.442602 -211.045298)
		(end 187.293758 -210.896454)
		(width 0.136652)
		(layer "F.Cu")
		(net "PCIE_TX_CAP_P46")
	)
	(segment
		(start 187.541408 -211.5312)
		(end 187.541408 -211.283804)
		(width 0.136652)
		(layer "F.Cu")
		(net "PCIE_TX_CAP_P46")
	)
	(segment
		(start 187.192158 -211.975954)
		(end 187.473844 -211.694268)
		(width 0.136652)
		(layer "F.Cu")
		(net "PCIE_TX_CAP_P46")
	)
	(via
		(at 187.293758 -210.896454)
		(size 0.508)
		(drill 0.254)
		(layers "F.Cu" "B.Cu")
		(net "PCIE_TX_CAP_P46")
	)
	(via
		(at 243.099844 -65.499742)
		(size 0.4572)
		(drill 0.2032)
		(layers "F.Cu" "B.Cu")
		(net "PCIE_TX_CAP_P46")
	)
	(arc
		(start 187.541408 -211.283804)
		(mid 187.515732 -211.15472)
		(end 187.442602 -211.045298)
		(width 0.136652)
		(layer "F.Cu")
		(net "PCIE_TX_CAP_P46")
	)
	(arc
		(start 187.473844 -211.694268)
		(mid 187.523835 -211.619452)
		(end 187.541408 -211.5312)
		(width 0.136652)
		(layer "F.Cu")
		(net "PCIE_TX_CAP_P46")
	)
	(segment
		(start 242.636294 -102.758494)
		(end 243.906294 -109.108494)
		(width 0.1397)
		(layer "In5.Cu")
		(net "PCIE_TX_CAP_P46")
	)
	(segment
		(start 243.906294 -109.108494)
		(end 242.437412 -116.452142)
		(width 0.1397)
		(layer "In5.Cu")
		(net "PCIE_TX_CAP_P46")
	)
	(segment
		(start 242.493546 -66.853054)
		(end 242.4176 -66.929)
		(width 0.1016)
		(layer "In5.Cu")
		(net "PCIE_TX_CAP_P46")
	)
	(segment
		(start 242.437412 -116.452142)
		(end 190.61811 -190.457582)
		(width 0.1397)
		(layer "In5.Cu")
		(net "PCIE_TX_CAP_P46")
	)
	(segment
		(start 190.61811 -190.457582)
		(end 187.535058 -207.944212)
		(width 0.1397)
		(layer "In5.Cu")
		(net "PCIE_TX_CAP_P46")
	)
	(segment
		(start 242.4176 -66.929)
		(end 242.4176 -76.26477)
		(width 0.1397)
		(layer "In5.Cu")
		(net "PCIE_TX_CAP_P46")
	)
	(segment
		(start 242.636294 -90.058494)
		(end 243.906294 -96.408494)
		(width 0.1397)
		(layer "In5.Cu")
		(net "PCIE_TX_CAP_P46")
	)
	(segment
		(start 187.535058 -207.944212)
		(end 187.535058 -210.313778)
		(width 0.1397)
		(layer "In5.Cu")
		(net "PCIE_TX_CAP_P46")
	)
	(segment
		(start 242.493546 -66.11874)
		(end 242.493546 -66.853054)
		(width 0.1016)
		(layer "In5.Cu")
		(net "PCIE_TX_CAP_P46")
	)
	(segment
		(start 243.906294 -96.408494)
		(end 242.636294 -102.758494)
		(width 0.1397)
		(layer "In5.Cu")
		(net "PCIE_TX_CAP_P46")
	)
	(segment
		(start 242.917726 -65.57518)
		(end 242.577874 -65.914778)
		(width 0.1016)
		(layer "In5.Cu")
		(net "PCIE_TX_CAP_P46")
	)
	(segment
		(start 242.4176 -76.26477)
		(end 243.906294 -83.708494)
		(width 0.1397)
		(layer "In5.Cu")
		(net "PCIE_TX_CAP_P46")
	)
	(segment
		(start 243.906294 -83.708494)
		(end 242.636294 -90.058494)
		(width 0.1397)
		(layer "In5.Cu")
		(net "PCIE_TX_CAP_P46")
	)
	(arc
		(start 242.577874 -65.914778)
		(mid 242.51543 -66.008372)
		(end 242.493546 -66.11874)
		(width 0.1016)
		(layer "In5.Cu")
		(net "PCIE_TX_CAP_P46")
	)
	(arc
		(start 243.099844 -65.499742)
		(mid 243.001282 -65.519347)
		(end 242.917726 -65.57518)
		(width 0.1016)
		(layer "In5.Cu")
		(net "PCIE_TX_CAP_P46")
	)
	(arc
		(start 187.535058 -210.313778)
		(mid 187.472337 -210.6291)
		(end 187.293758 -210.896454)
		(width 0.1397)
		(layer "In5.Cu")
		(net "PCIE_TX_CAP_P46")
	)
	(segment
		(start 190.392304 -211.975954)
		(end 190.392304 -211.9757)
		(width 0.136652)
		(layer "F.Cu")
		(net "PCIE_TX_CAP_P45")
	)
	(segment
		(start 190.392304 -211.9757)
		(end 190.673736 -211.694268)
		(width 0.136652)
		(layer "F.Cu")
		(net "PCIE_TX_CAP_P45")
	)
	(segment
		(start 190.64351 -211.04606)
		(end 190.49365 -210.896454)
		(width 0.136652)
		(layer "F.Cu")
		(net "PCIE_TX_CAP_P45")
	)
	(segment
		(start 190.7413 -211.5312)
		(end 190.7413 -211.282534)
		(width 0.136652)
		(layer "F.Cu")
		(net "PCIE_TX_CAP_P45")
	)
	(segment
		(start 243.59997 -63.999872)
		(end 244.099842 -64.499744)
		(width 0.136652)
		(layer "F.Cu")
		(net "PCIE_TX_CAP_P45")
	)
	(via
		(at 244.099842 -64.499744)
		(size 0.4572)
		(drill 0.2032)
		(layers "F.Cu" "B.Cu")
		(net "PCIE_TX_CAP_P45")
	)
	(via
		(at 190.49365 -210.896454)
		(size 0.508)
		(drill 0.254)
		(layers "F.Cu" "B.Cu")
		(net "PCIE_TX_CAP_P45")
	)
	(arc
		(start 190.7413 -211.282534)
		(mid 190.715939 -211.154563)
		(end 190.64351 -211.04606)
		(width 0.136652)
		(layer "F.Cu")
		(net "PCIE_TX_CAP_P45")
	)
	(arc
		(start 190.673736 -211.694268)
		(mid 190.723727 -211.619452)
		(end 190.7413 -211.5312)
		(width 0.136652)
		(layer "F.Cu")
		(net "PCIE_TX_CAP_P45")
	)
	(segment
		(start 243.917724 -64.575182)
		(end 243.577872 -64.91478)
		(width 0.1016)
		(layer "In5.Cu")
		(net "PCIE_TX_CAP_P45")
	)
	(segment
		(start 243.672614 -102.758494)
		(end 245.009924 -109.445552)
		(width 0.1397)
		(layer "In5.Cu")
		(net "PCIE_TX_CAP_P45")
	)
	(segment
		(start 190.73495 -206.914242)
		(end 190.73495 -210.313778)
		(width 0.1397)
		(layer "In5.Cu")
		(net "PCIE_TX_CAP_P45")
	)
	(segment
		(start 245.009924 -109.445552)
		(end 244.268498 -113.64976)
		(width 0.1397)
		(layer "In5.Cu")
		(net "PCIE_TX_CAP_P45")
	)
	(segment
		(start 244.942614 -83.708494)
		(end 243.672614 -90.058494)
		(width 0.1397)
		(layer "In5.Cu")
		(net "PCIE_TX_CAP_P45")
	)
	(segment
		(start 243.4336 -76.163678)
		(end 244.942614 -83.708494)
		(width 0.1397)
		(layer "In5.Cu")
		(net "PCIE_TX_CAP_P45")
	)
	(segment
		(start 243.493544 -66.945256)
		(end 243.4336 -67.0052)
		(width 0.1016)
		(layer "In5.Cu")
		(net "PCIE_TX_CAP_P45")
	)
	(segment
		(start 244.942614 -96.408494)
		(end 243.672614 -102.758494)
		(width 0.1397)
		(layer "In5.Cu")
		(net "PCIE_TX_CAP_P45")
	)
	(segment
		(start 243.672614 -90.058494)
		(end 244.942614 -96.408494)
		(width 0.1397)
		(layer "In5.Cu")
		(net "PCIE_TX_CAP_P45")
	)
	(segment
		(start 193.955416 -188.64961)
		(end 190.73495 -206.914242)
		(width 0.1397)
		(layer "In5.Cu")
		(net "PCIE_TX_CAP_P45")
	)
	(segment
		(start 244.268498 -113.64976)
		(end 243.527326 -117.85346)
		(width 0.1397)
		(layer "In5.Cu")
		(net "PCIE_TX_CAP_P45")
	)
	(segment
		(start 243.493544 -65.118742)
		(end 243.493544 -66.945256)
		(width 0.1016)
		(layer "In5.Cu")
		(net "PCIE_TX_CAP_P45")
	)
	(segment
		(start 243.527326 -117.85346)
		(end 193.955416 -188.64961)
		(width 0.1397)
		(layer "In5.Cu")
		(net "PCIE_TX_CAP_P45")
	)
	(segment
		(start 243.4336 -67.0052)
		(end 243.4336 -76.163678)
		(width 0.1397)
		(layer "In5.Cu")
		(net "PCIE_TX_CAP_P45")
	)
	(arc
		(start 190.73495 -210.313778)
		(mid 190.672229 -210.6291)
		(end 190.49365 -210.896454)
		(width 0.1397)
		(layer "In5.Cu")
		(net "PCIE_TX_CAP_P45")
	)
	(arc
		(start 243.577872 -64.91478)
		(mid 243.515428 -65.008374)
		(end 243.493544 -65.118742)
		(width 0.1016)
		(layer "In5.Cu")
		(net "PCIE_TX_CAP_P45")
	)
	(arc
		(start 244.099842 -64.499744)
		(mid 244.00128 -64.519349)
		(end 243.917724 -64.575182)
		(width 0.1016)
		(layer "In5.Cu")
		(net "PCIE_TX_CAP_P45")
	)
	(segment
		(start 193.941446 -211.5312)
		(end 193.941446 -211.307172)
		(width 0.136652)
		(layer "F.Cu")
		(net "PCIE_TX_CAP_P44")
	)
	(segment
		(start 244.599968 -64.99987)
		(end 245.09984 -65.499742)
		(width 0.136652)
		(layer "F.Cu")
		(net "PCIE_TX_CAP_P44")
	)
	(segment
		(start 193.82613 -211.028788)
		(end 193.693796 -210.896454)
		(width 0.136652)
		(layer "F.Cu")
		(net "PCIE_TX_CAP_P44")
	)
	(segment
		(start 193.592196 -211.975954)
		(end 193.873882 -211.694268)
		(width 0.136652)
		(layer "F.Cu")
		(net "PCIE_TX_CAP_P44")
	)
	(via
		(at 193.693796 -210.896454)
		(size 0.508)
		(drill 0.254)
		(layers "F.Cu" "B.Cu")
		(net "PCIE_TX_CAP_P44")
	)
	(via
		(at 245.09984 -65.499742)
		(size 0.4572)
		(drill 0.2032)
		(layers "F.Cu" "B.Cu")
		(net "PCIE_TX_CAP_P44")
	)
	(arc
		(start 193.941446 -211.307172)
		(mid 193.911477 -211.15651)
		(end 193.82613 -211.028788)
		(width 0.136652)
		(layer "F.Cu")
		(net "PCIE_TX_CAP_P44")
	)
	(arc
		(start 193.873882 -211.694268)
		(mid 193.923873 -211.619452)
		(end 193.941446 -211.5312)
		(width 0.136652)
		(layer "F.Cu")
		(net "PCIE_TX_CAP_P44")
	)
	(segment
		(start 246.369078 -111.190024)
		(end 245.713504 -114.90833)
		(width 0.1397)
		(layer "In5.Cu")
		(net "PCIE_TX_CAP_P44")
	)
	(segment
		(start 244.917722 -65.57518)
		(end 244.57787 -65.914778)
		(width 0.1016)
		(layer "In5.Cu")
		(net "PCIE_TX_CAP_P44")
	)
	(segment
		(start 245.952772 -83.708494)
		(end 244.682772 -90.058494)
		(width 0.1397)
		(layer "In5.Cu")
		(net "PCIE_TX_CAP_P44")
	)
	(segment
		(start 244.4242 -66.9544)
		(end 244.4242 -76.065126)
		(width 0.1397)
		(layer "In5.Cu")
		(net "PCIE_TX_CAP_P44")
	)
	(segment
		(start 244.682772 -90.058494)
		(end 245.952772 -96.408494)
		(width 0.1397)
		(layer "In5.Cu")
		(net "PCIE_TX_CAP_P44")
	)
	(segment
		(start 244.493542 -66.11874)
		(end 244.493542 -66.885058)
		(width 0.1016)
		(layer "In5.Cu")
		(net "PCIE_TX_CAP_P44")
	)
	(segment
		(start 244.682772 -102.758494)
		(end 246.369078 -111.190024)
		(width 0.1397)
		(layer "In5.Cu")
		(net "PCIE_TX_CAP_P44")
	)
	(segment
		(start 244.4242 -76.065126)
		(end 245.952772 -83.708494)
		(width 0.1397)
		(layer "In5.Cu")
		(net "PCIE_TX_CAP_P44")
	)
	(segment
		(start 197.052946 -187.183268)
		(end 193.935096 -204.867002)
		(width 0.1397)
		(layer "In5.Cu")
		(net "PCIE_TX_CAP_P44")
	)
	(segment
		(start 245.952772 -96.408494)
		(end 244.682772 -102.758494)
		(width 0.1397)
		(layer "In5.Cu")
		(net "PCIE_TX_CAP_P44")
	)
	(segment
		(start 193.935096 -204.867002)
		(end 193.935096 -210.313778)
		(width 0.1397)
		(layer "In5.Cu")
		(net "PCIE_TX_CAP_P44")
	)
	(segment
		(start 245.713504 -114.90833)
		(end 245.057676 -118.626636)
		(width 0.1397)
		(layer "In5.Cu")
		(net "PCIE_TX_CAP_P44")
	)
	(segment
		(start 245.057676 -118.626636)
		(end 197.052946 -187.183268)
		(width 0.1397)
		(layer "In5.Cu")
		(net "PCIE_TX_CAP_P44")
	)
	(segment
		(start 244.493542 -66.885058)
		(end 244.4242 -66.9544)
		(width 0.1016)
		(layer "In5.Cu")
		(net "PCIE_TX_CAP_P44")
	)
	(arc
		(start 245.09984 -65.499742)
		(mid 245.001278 -65.519347)
		(end 244.917722 -65.57518)
		(width 0.1016)
		(layer "In5.Cu")
		(net "PCIE_TX_CAP_P44")
	)
	(arc
		(start 193.935096 -210.313778)
		(mid 193.872375 -210.6291)
		(end 193.693796 -210.896454)
		(width 0.1397)
		(layer "In5.Cu")
		(net "PCIE_TX_CAP_P44")
	)
	(arc
		(start 244.57787 -65.914778)
		(mid 244.515426 -66.008372)
		(end 244.493542 -66.11874)
		(width 0.1016)
		(layer "In5.Cu")
		(net "PCIE_TX_CAP_P44")
	)
	(segment
		(start 197.141338 -211.5312)
		(end 197.141338 -211.284312)
		(width 0.136652)
		(layer "F.Cu")
		(net "PCIE_TX_CAP_P43")
	)
	(segment
		(start 197.042278 -211.04479)
		(end 196.893688 -210.896454)
		(width 0.136652)
		(layer "F.Cu")
		(net "PCIE_TX_CAP_P43")
	)
	(segment
		(start 196.792088 -211.975954)
		(end 197.073774 -211.694268)
		(width 0.136652)
		(layer "F.Cu")
		(net "PCIE_TX_CAP_P43")
	)
	(segment
		(start 245.599966 -63.999872)
		(end 246.099838 -64.499744)
		(width 0.136652)
		(layer "F.Cu")
		(net "PCIE_TX_CAP_P43")
	)
	(via
		(at 246.099838 -64.499744)
		(size 0.4572)
		(drill 0.2032)
		(layers "F.Cu" "B.Cu")
		(net "PCIE_TX_CAP_P43")
	)
	(via
		(at 196.893688 -210.896454)
		(size 0.508)
		(drill 0.254)
		(layers "F.Cu" "B.Cu")
		(net "PCIE_TX_CAP_P43")
	)
	(arc
		(start 197.141338 -211.284312)
		(mid 197.115648 -211.154689)
		(end 197.042278 -211.04479)
		(width 0.136652)
		(layer "F.Cu")
		(net "PCIE_TX_CAP_P43")
	)
	(arc
		(start 197.073774 -211.694268)
		(mid 197.123765 -211.619452)
		(end 197.141338 -211.5312)
		(width 0.136652)
		(layer "F.Cu")
		(net "PCIE_TX_CAP_P43")
	)
	(segment
		(start 247.44934 -111.539782)
		(end 246.067326 -119.37746)
		(width 0.1397)
		(layer "In5.Cu")
		(net "PCIE_TX_CAP_P43")
	)
	(segment
		(start 245.693184 -102.758494)
		(end 247.44934 -111.539782)
		(width 0.1397)
		(layer "In5.Cu")
		(net "PCIE_TX_CAP_P43")
	)
	(segment
		(start 245.49354 -66.92646)
		(end 245.4148 -67.0052)
		(width 0.1016)
		(layer "In5.Cu")
		(net "PCIE_TX_CAP_P43")
	)
	(segment
		(start 246.963184 -96.408494)
		(end 245.693184 -102.758494)
		(width 0.1397)
		(layer "In5.Cu")
		(net "PCIE_TX_CAP_P43")
	)
	(segment
		(start 245.4148 -75.966574)
		(end 246.963184 -83.708494)
		(width 0.1397)
		(layer "In5.Cu")
		(net "PCIE_TX_CAP_P43")
	)
	(segment
		(start 197.134988 -206.67345)
		(end 197.134988 -210.313778)
		(width 0.1397)
		(layer "In5.Cu")
		(net "PCIE_TX_CAP_P43")
	)
	(segment
		(start 245.49354 -65.118742)
		(end 245.49354 -66.92646)
		(width 0.1016)
		(layer "In5.Cu")
		(net "PCIE_TX_CAP_P43")
	)
	(segment
		(start 200.640442 -184.253632)
		(end 196.911214 -205.404466)
		(width 0.1397)
		(layer "In5.Cu")
		(net "PCIE_TX_CAP_P43")
	)
	(segment
		(start 246.067326 -119.37746)
		(end 200.640442 -184.253632)
		(width 0.1397)
		(layer "In5.Cu")
		(net "PCIE_TX_CAP_P43")
	)
	(segment
		(start 246.963184 -83.708494)
		(end 245.693184 -90.058494)
		(width 0.1397)
		(layer "In5.Cu")
		(net "PCIE_TX_CAP_P43")
	)
	(segment
		(start 245.4148 -67.0052)
		(end 245.4148 -75.966574)
		(width 0.1397)
		(layer "In5.Cu")
		(net "PCIE_TX_CAP_P43")
	)
	(segment
		(start 245.693184 -90.058494)
		(end 246.963184 -96.408494)
		(width 0.1397)
		(layer "In5.Cu")
		(net "PCIE_TX_CAP_P43")
	)
	(segment
		(start 196.911214 -205.404466)
		(end 197.134988 -206.67345)
		(width 0.1397)
		(layer "In5.Cu")
		(net "PCIE_TX_CAP_P43")
	)
	(segment
		(start 245.91772 -64.575182)
		(end 245.577868 -64.91478)
		(width 0.1016)
		(layer "In5.Cu")
		(net "PCIE_TX_CAP_P43")
	)
	(arc
		(start 245.577868 -64.91478)
		(mid 245.515424 -65.008374)
		(end 245.49354 -65.118742)
		(width 0.1016)
		(layer "In5.Cu")
		(net "PCIE_TX_CAP_P43")
	)
	(arc
		(start 246.099838 -64.499744)
		(mid 246.001276 -64.519349)
		(end 245.91772 -64.575182)
		(width 0.1016)
		(layer "In5.Cu")
		(net "PCIE_TX_CAP_P43")
	)
	(arc
		(start 197.134988 -210.313778)
		(mid 197.072267 -210.6291)
		(end 196.893688 -210.896454)
		(width 0.1397)
		(layer "In5.Cu")
		(net "PCIE_TX_CAP_P43")
	)
	(segment
		(start 199.99198 -211.975954)
		(end 200.273666 -211.694268)
		(width 0.136652)
		(layer "F.Cu")
		(net "PCIE_TX_CAP_P42")
	)
	(segment
		(start 200.227438 -211.030566)
		(end 200.09358 -210.896454)
		(width 0.136652)
		(layer "F.Cu")
		(net "PCIE_TX_CAP_P42")
	)
	(segment
		(start 200.34123 -211.5312)
		(end 200.34123 -211.304886)
		(width 0.136652)
		(layer "F.Cu")
		(net "PCIE_TX_CAP_P42")
	)
	(segment
		(start 246.599964 -64.99987)
		(end 247.099836 -65.499742)
		(width 0.136652)
		(layer "F.Cu")
		(net "PCIE_TX_CAP_P42")
	)
	(via
		(at 200.09358 -210.896454)
		(size 0.508)
		(drill 0.254)
		(layers "F.Cu" "B.Cu")
		(net "PCIE_TX_CAP_P42")
	)
	(via
		(at 247.099836 -65.499742)
		(size 0.4572)
		(drill 0.2032)
		(layers "F.Cu" "B.Cu")
		(net "PCIE_TX_CAP_P42")
	)
	(arc
		(start 200.273666 -211.694268)
		(mid 200.323657 -211.619452)
		(end 200.34123 -211.5312)
		(width 0.136652)
		(layer "F.Cu")
		(net "PCIE_TX_CAP_P42")
	)
	(arc
		(start 200.34123 -211.304886)
		(mid 200.311604 -211.156416)
		(end 200.227438 -211.030566)
		(width 0.136652)
		(layer "F.Cu")
		(net "PCIE_TX_CAP_P42")
	)
	(segment
		(start 246.493538 -66.891662)
		(end 246.4054 -66.9798)
		(width 0.1016)
		(layer "In5.Cu")
		(net "PCIE_TX_CAP_P42")
	)
	(segment
		(start 200.33488 -209.328766)
		(end 200.33488 -210.313778)
		(width 0.1397)
		(layer "In5.Cu")
		(net "PCIE_TX_CAP_P42")
	)
	(segment
		(start 246.703596 -102.758494)
		(end 248.601992 -112.250982)
		(width 0.1397)
		(layer "In5.Cu")
		(net "PCIE_TX_CAP_P42")
	)
	(segment
		(start 248.601992 -112.250982)
		(end 247.198134 -120.21185)
		(width 0.1397)
		(layer "In5.Cu")
		(net "PCIE_TX_CAP_P42")
	)
	(segment
		(start 203.539344 -182.563008)
		(end 203.029566 -185.45429)
		(width 0.1397)
		(layer "In5.Cu")
		(net "PCIE_TX_CAP_P42")
	)
	(segment
		(start 203.029566 -185.45429)
		(end 200.837546 -197.8914)
		(width 0.1397)
		(layer "In5.Cu")
		(net "PCIE_TX_CAP_P42")
	)
	(segment
		(start 247.973596 -96.408494)
		(end 246.703596 -102.758494)
		(width 0.1397)
		(layer "In5.Cu")
		(net "PCIE_TX_CAP_P42")
	)
	(segment
		(start 246.4054 -66.9798)
		(end 246.4054 -75.868022)
		(width 0.1397)
		(layer "In5.Cu")
		(net "PCIE_TX_CAP_P42")
	)
	(segment
		(start 246.703596 -90.058494)
		(end 247.973596 -96.408494)
		(width 0.1397)
		(layer "In5.Cu")
		(net "PCIE_TX_CAP_P42")
	)
	(segment
		(start 246.917718 -65.57518)
		(end 246.577866 -65.914778)
		(width 0.1016)
		(layer "In5.Cu")
		(net "PCIE_TX_CAP_P42")
	)
	(segment
		(start 246.493538 -66.11874)
		(end 246.493538 -66.891662)
		(width 0.1016)
		(layer "In5.Cu")
		(net "PCIE_TX_CAP_P42")
	)
	(segment
		(start 246.4054 -75.868022)
		(end 247.973596 -83.708494)
		(width 0.1397)
		(layer "In5.Cu")
		(net "PCIE_TX_CAP_P42")
	)
	(segment
		(start 200.837546 -197.8914)
		(end 201.594466 -202.184)
		(width 0.1397)
		(layer "In5.Cu")
		(net "PCIE_TX_CAP_P42")
	)
	(segment
		(start 247.973596 -83.708494)
		(end 246.703596 -90.058494)
		(width 0.1397)
		(layer "In5.Cu")
		(net "PCIE_TX_CAP_P42")
	)
	(segment
		(start 201.594466 -202.184)
		(end 200.33488 -209.328766)
		(width 0.1397)
		(layer "In5.Cu")
		(net "PCIE_TX_CAP_P42")
	)
	(segment
		(start 247.198134 -120.21185)
		(end 203.539344 -182.563008)
		(width 0.1397)
		(layer "In5.Cu")
		(net "PCIE_TX_CAP_P42")
	)
	(arc
		(start 246.577866 -65.914778)
		(mid 246.515422 -66.008372)
		(end 246.493538 -66.11874)
		(width 0.1016)
		(layer "In5.Cu")
		(net "PCIE_TX_CAP_P42")
	)
	(arc
		(start 200.33488 -210.313778)
		(mid 200.272159 -210.6291)
		(end 200.09358 -210.896454)
		(width 0.1397)
		(layer "In5.Cu")
		(net "PCIE_TX_CAP_P42")
	)
	(arc
		(start 247.099836 -65.499742)
		(mid 247.001274 -65.519347)
		(end 246.917718 -65.57518)
		(width 0.1016)
		(layer "In5.Cu")
		(net "PCIE_TX_CAP_P42")
	)
	(segment
		(start 203.446126 -211.048854)
		(end 203.293726 -210.896454)
		(width 0.136652)
		(layer "F.Cu")
		(net "PCIE_TX_CAP_P41")
	)
	(segment
		(start 203.192126 -211.975954)
		(end 203.473812 -211.694268)
		(width 0.136652)
		(layer "F.Cu")
		(net "PCIE_TX_CAP_P41")
	)
	(segment
		(start 247.599962 -63.999872)
		(end 248.099834 -64.499744)
		(width 0.136652)
		(layer "F.Cu")
		(net "PCIE_TX_CAP_P41")
	)
	(segment
		(start 203.541376 -211.5312)
		(end 203.541376 -211.278724)
		(width 0.136652)
		(layer "F.Cu")
		(net "PCIE_TX_CAP_P41")
	)
	(via
		(at 203.293726 -210.896454)
		(size 0.508)
		(drill 0.254)
		(layers "F.Cu" "B.Cu")
		(net "PCIE_TX_CAP_P41")
	)
	(via
		(at 248.099834 -64.499744)
		(size 0.4572)
		(drill 0.2032)
		(layers "F.Cu" "B.Cu")
		(net "PCIE_TX_CAP_P41")
	)
	(arc
		(start 203.473812 -211.694268)
		(mid 203.523803 -211.619452)
		(end 203.541376 -211.5312)
		(width 0.136652)
		(layer "F.Cu")
		(net "PCIE_TX_CAP_P41")
	)
	(arc
		(start 203.541376 -211.278724)
		(mid 203.516628 -211.154306)
		(end 203.446126 -211.048854)
		(width 0.136652)
		(layer "F.Cu")
		(net "PCIE_TX_CAP_P41")
	)
	(segment
		(start 247.739662 -102.758494)
		(end 249.703082 -112.575086)
		(width 0.1397)
		(layer "In5.Cu")
		(net "PCIE_TX_CAP_P41")
	)
	(segment
		(start 247.493536 -65.118742)
		(end 247.493536 -66.882264)
		(width 0.1016)
		(layer "In5.Cu")
		(net "PCIE_TX_CAP_P41")
	)
	(segment
		(start 249.009662 -83.708494)
		(end 247.739662 -90.058494)
		(width 0.1397)
		(layer "In5.Cu")
		(net "PCIE_TX_CAP_P41")
	)
	(segment
		(start 249.009662 -96.408494)
		(end 247.739662 -102.758494)
		(width 0.1397)
		(layer "In5.Cu")
		(net "PCIE_TX_CAP_P41")
	)
	(segment
		(start 203.535026 -207.062832)
		(end 203.535026 -210.313778)
		(width 0.1397)
		(layer "In5.Cu")
		(net "PCIE_TX_CAP_P41")
	)
	(segment
		(start 248.206514 -121.05894)
		(end 206.694532 -180.344826)
		(width 0.1397)
		(layer "In5.Cu")
		(net "PCIE_TX_CAP_P41")
	)
	(segment
		(start 204.421486 -202.03414)
		(end 203.535026 -207.062832)
		(width 0.1397)
		(layer "In5.Cu")
		(net "PCIE_TX_CAP_P41")
	)
	(segment
		(start 247.493536 -66.882264)
		(end 247.4214 -66.9544)
		(width 0.1016)
		(layer "In5.Cu")
		(net "PCIE_TX_CAP_P41")
	)
	(segment
		(start 247.4214 -66.9544)
		(end 247.4214 -75.76693)
		(width 0.1397)
		(layer "In5.Cu")
		(net "PCIE_TX_CAP_P41")
	)
	(segment
		(start 203.64577 -197.634606)
		(end 204.421486 -202.03414)
		(width 0.1397)
		(layer "In5.Cu")
		(net "PCIE_TX_CAP_P41")
	)
	(segment
		(start 247.739662 -90.058494)
		(end 249.009662 -96.408494)
		(width 0.1397)
		(layer "In5.Cu")
		(net "PCIE_TX_CAP_P41")
	)
	(segment
		(start 206.694532 -180.344826)
		(end 203.64577 -197.634606)
		(width 0.1397)
		(layer "In5.Cu")
		(net "PCIE_TX_CAP_P41")
	)
	(segment
		(start 249.703082 -112.575086)
		(end 248.206514 -121.05894)
		(width 0.1397)
		(layer "In5.Cu")
		(net "PCIE_TX_CAP_P41")
	)
	(segment
		(start 247.4214 -75.76693)
		(end 249.009662 -83.708494)
		(width 0.1397)
		(layer "In5.Cu")
		(net "PCIE_TX_CAP_P41")
	)
	(segment
		(start 247.917716 -64.575182)
		(end 247.577864 -64.91478)
		(width 0.1016)
		(layer "In5.Cu")
		(net "PCIE_TX_CAP_P41")
	)
	(arc
		(start 248.099834 -64.499744)
		(mid 248.001272 -64.519349)
		(end 247.917716 -64.575182)
		(width 0.1016)
		(layer "In5.Cu")
		(net "PCIE_TX_CAP_P41")
	)
	(arc
		(start 203.535026 -210.313778)
		(mid 203.472305 -210.6291)
		(end 203.293726 -210.896454)
		(width 0.1397)
		(layer "In5.Cu")
		(net "PCIE_TX_CAP_P41")
	)
	(arc
		(start 247.577864 -64.91478)
		(mid 247.51542 -65.008374)
		(end 247.493536 -65.118742)
		(width 0.1016)
		(layer "In5.Cu")
		(net "PCIE_TX_CAP_P41")
	)
	(segment
		(start 206.392018 -211.975954)
		(end 206.673704 -211.694268)
		(width 0.136652)
		(layer "F.Cu")
		(net "PCIE_TX_CAP_P40")
	)
	(segment
		(start 206.629 -211.031836)
		(end 206.493618 -210.896454)
		(width 0.136652)
		(layer "F.Cu")
		(net "PCIE_TX_CAP_P40")
	)
	(segment
		(start 248.59996 -64.99987)
		(end 249.099832 -65.499742)
		(width 0.136652)
		(layer "F.Cu")
		(net "PCIE_TX_CAP_P40")
	)
	(segment
		(start 206.741268 -211.5312)
		(end 206.741268 -211.302854)
		(width 0.136652)
		(layer "F.Cu")
		(net "PCIE_TX_CAP_P40")
	)
	(via
		(at 206.493618 -210.896454)
		(size 0.508)
		(drill 0.254)
		(layers "F.Cu" "B.Cu")
		(net "PCIE_TX_CAP_P40")
	)
	(via
		(at 249.099832 -65.499742)
		(size 0.4572)
		(drill 0.2032)
		(layers "F.Cu" "B.Cu")
		(net "PCIE_TX_CAP_P40")
	)
	(arc
		(start 206.741268 -211.302854)
		(mid 206.712092 -211.156177)
		(end 206.629 -211.031836)
		(width 0.136652)
		(layer "F.Cu")
		(net "PCIE_TX_CAP_P40")
	)
	(arc
		(start 206.673704 -211.694268)
		(mid 206.723695 -211.619452)
		(end 206.741268 -211.5312)
		(width 0.136652)
		(layer "F.Cu")
		(net "PCIE_TX_CAP_P40")
	)
	(segment
		(start 248.412 -75.668378)
		(end 250.020074 -83.708494)
		(width 0.1397)
		(layer "In5.Cu")
		(net "PCIE_TX_CAP_P40")
	)
	(segment
		(start 248.917714 -65.57518)
		(end 248.577862 -65.914778)
		(width 0.1016)
		(layer "In5.Cu")
		(net "PCIE_TX_CAP_P40")
	)
	(segment
		(start 205.77556 -197.294246)
		(end 207.309466 -205.994)
		(width 0.1397)
		(layer "In5.Cu")
		(net "PCIE_TX_CAP_P40")
	)
	(segment
		(start 248.412 -66.929)
		(end 248.412 -75.668378)
		(width 0.1397)
		(layer "In5.Cu")
		(net "PCIE_TX_CAP_P40")
	)
	(segment
		(start 248.750074 -102.758494)
		(end 250.771406 -112.865408)
		(width 0.1397)
		(layer "In5.Cu")
		(net "PCIE_TX_CAP_P40")
	)
	(segment
		(start 248.493534 -66.11874)
		(end 248.493534 -66.847466)
		(width 0.1016)
		(layer "In5.Cu")
		(net "PCIE_TX_CAP_P40")
	)
	(segment
		(start 206.734918 -209.25282)
		(end 206.734918 -210.313778)
		(width 0.1397)
		(layer "In5.Cu")
		(net "PCIE_TX_CAP_P40")
	)
	(segment
		(start 207.309466 -205.994)
		(end 206.734918 -209.25282)
		(width 0.1397)
		(layer "In5.Cu")
		(net "PCIE_TX_CAP_P40")
	)
	(segment
		(start 249.17019 -121.94413)
		(end 208.927954 -179.41671)
		(width 0.1397)
		(layer "In5.Cu")
		(net "PCIE_TX_CAP_P40")
	)
	(segment
		(start 248.493534 -66.847466)
		(end 248.412 -66.929)
		(width 0.1016)
		(layer "In5.Cu")
		(net "PCIE_TX_CAP_P40")
	)
	(segment
		(start 248.750074 -90.058494)
		(end 250.020074 -96.408494)
		(width 0.1397)
		(layer "In5.Cu")
		(net "PCIE_TX_CAP_P40")
	)
	(segment
		(start 250.771406 -112.865408)
		(end 249.17019 -121.94413)
		(width 0.1397)
		(layer "In5.Cu")
		(net "PCIE_TX_CAP_P40")
	)
	(segment
		(start 208.927954 -179.41671)
		(end 205.77556 -197.294246)
		(width 0.1397)
		(layer "In5.Cu")
		(net "PCIE_TX_CAP_P40")
	)
	(segment
		(start 250.020074 -96.408494)
		(end 248.750074 -102.758494)
		(width 0.1397)
		(layer "In5.Cu")
		(net "PCIE_TX_CAP_P40")
	)
	(segment
		(start 250.020074 -83.708494)
		(end 248.750074 -90.058494)
		(width 0.1397)
		(layer "In5.Cu")
		(net "PCIE_TX_CAP_P40")
	)
	(arc
		(start 206.734918 -210.313778)
		(mid 206.672197 -210.6291)
		(end 206.493618 -210.896454)
		(width 0.1397)
		(layer "In5.Cu")
		(net "PCIE_TX_CAP_P40")
	)
	(arc
		(start 248.577862 -65.914778)
		(mid 248.515418 -66.008372)
		(end 248.493534 -66.11874)
		(width 0.1016)
		(layer "In5.Cu")
		(net "PCIE_TX_CAP_P40")
	)
	(arc
		(start 249.099832 -65.499742)
		(mid 249.00127 -65.519347)
		(end 248.917714 -65.57518)
		(width 0.1016)
		(layer "In5.Cu")
		(net "PCIE_TX_CAP_P40")
	)
	(segment
		(start 294.309038 -35.030664)
		(end 294.159178 -35.18027)
		(width 0.136652)
		(layer "F.Cu")
		(net "PCIE_TX_CAP_P4")
	)
	(segment
		(start 255.599946 -30.999938)
		(end 256.099818 -30.500066)
		(width 0.136652)
		(layer "F.Cu")
		(net "PCIE_TX_CAP_P4")
	)
	(segment
		(start 294.425878 -34.608516)
		(end 294.425878 -34.748216)
		(width 0.136652)
		(layer "F.Cu")
		(net "PCIE_TX_CAP_P4")
	)
	(segment
		(start 294.108378 -34.138616)
		(end 294.318182 -34.348166)
		(width 0.136652)
		(layer "F.Cu")
		(net "PCIE_TX_CAP_P4")
	)
	(via
		(at 256.099818 -30.500066)
		(size 0.4572)
		(drill 0.2032)
		(layers "F.Cu" "B.Cu")
		(net "PCIE_TX_CAP_P4")
	)
	(via
		(at 294.159178 -35.18027)
		(size 0.508)
		(drill 0.254)
		(layers "F.Cu" "B.Cu")
		(net "PCIE_TX_CAP_P4")
	)
	(arc
		(start 294.318182 -34.348166)
		(mid 294.397913 -34.467631)
		(end 294.425878 -34.608516)
		(width 0.136652)
		(layer "F.Cu")
		(net "PCIE_TX_CAP_P4")
	)
	(arc
		(start 294.425878 -34.748216)
		(mid 294.395567 -34.901071)
		(end 294.309038 -35.030664)
		(width 0.136652)
		(layer "F.Cu")
		(net "PCIE_TX_CAP_P4")
	)
	(segment
		(start 281.795474 -34.544762)
		(end 280.423874 -32.58566)
		(width 0.1397)
		(layer "In5.Cu")
		(net "PCIE_TX_CAP_P4")
	)
	(segment
		(start 268.850618 -23.975314)
		(end 267.65885 -24.185626)
		(width 0.1397)
		(layer "In5.Cu")
		(net "PCIE_TX_CAP_P4")
	)
	(segment
		(start 276.152864 -25.263094)
		(end 268.850618 -23.975314)
		(width 0.1397)
		(layer "In5.Cu")
		(net "PCIE_TX_CAP_P4")
	)
	(segment
		(start 255.69164 -30.091634)
		(end 255.759458 -30.159706)
		(width 0.1016)
		(layer "In5.Cu")
		(net "PCIE_TX_CAP_P4")
	)
	(segment
		(start 255.501394 -28.8671)
		(end 255.501394 -29.632402)
		(width 0.1016)
		(layer "In5.Cu")
		(net "PCIE_TX_CAP_P4")
	)
	(segment
		(start 256.40665 -25.565608)
		(end 255.75006 -26.503884)
		(width 0.1397)
		(layer "In5.Cu")
		(net "PCIE_TX_CAP_P4")
	)
	(segment
		(start 294.387778 -35.624516)
		(end 294.387524 -35.624516)
		(width 0.1397)
		(layer "In5.Cu")
		(net "PCIE_TX_CAP_P4")
	)
	(segment
		(start 255.759458 -30.159706)
		(end 256.099818 -30.500066)
		(width 0.1016)
		(layer "In5.Cu")
		(net "PCIE_TX_CAP_P4")
	)
	(segment
		(start 257.39471 -24.873712)
		(end 256.40665 -25.565608)
		(width 0.1397)
		(layer "In5.Cu")
		(net "PCIE_TX_CAP_P4")
	)
	(segment
		(start 255.604772 -28.23464)
		(end 255.668272 -28.29814)
		(width 0.1016)
		(layer "In5.Cu")
		(net "PCIE_TX_CAP_P4")
	)
	(segment
		(start 255.668272 -28.29814)
		(end 255.668272 -28.700222)
		(width 0.1016)
		(layer "In5.Cu")
		(net "PCIE_TX_CAP_P4")
	)
	(segment
		(start 264.541 -24.809196)
		(end 261.366 -24.174196)
		(width 0.1397)
		(layer "In5.Cu")
		(net "PCIE_TX_CAP_P4")
	)
	(segment
		(start 284.836616 -36.674298)
		(end 281.795474 -34.544762)
		(width 0.1397)
		(layer "In5.Cu")
		(net "PCIE_TX_CAP_P4")
	)
	(segment
		(start 294.000936 -36.12896)
		(end 287.874456 -37.20973)
		(width 0.1397)
		(layer "In5.Cu")
		(net "PCIE_TX_CAP_P4")
	)
	(segment
		(start 277.917402 -26.49855)
		(end 276.152864 -25.263094)
		(width 0.1397)
		(layer "In5.Cu")
		(net "PCIE_TX_CAP_P4")
	)
	(segment
		(start 255.668272 -28.700222)
		(end 255.501394 -28.8671)
		(width 0.1016)
		(layer "In5.Cu")
		(net "PCIE_TX_CAP_P4")
	)
	(segment
		(start 259.385054 -24.522938)
		(end 257.39471 -24.873712)
		(width 0.1397)
		(layer "In5.Cu")
		(net "PCIE_TX_CAP_P4")
	)
	(segment
		(start 261.366 -24.174196)
		(end 261.364476 -24.173942)
		(width 0.1397)
		(layer "In5.Cu")
		(net "PCIE_TX_CAP_P4")
	)
	(segment
		(start 280.423874 -32.58566)
		(end 279.832816 -29.233876)
		(width 0.1397)
		(layer "In5.Cu")
		(net "PCIE_TX_CAP_P4")
	)
	(segment
		(start 261.364476 -24.173942)
		(end 259.385054 -24.522938)
		(width 0.1397)
		(layer "In5.Cu")
		(net "PCIE_TX_CAP_P4")
	)
	(segment
		(start 294.159178 -35.18027)
		(end 294.235378 -35.256216)
		(width 0.1397)
		(layer "In5.Cu")
		(net "PCIE_TX_CAP_P4")
	)
	(segment
		(start 255.604772 -27.317446)
		(end 255.604772 -28.20924)
		(width 0.1397)
		(layer "In5.Cu")
		(net "PCIE_TX_CAP_P4")
	)
	(segment
		(start 287.874456 -37.20973)
		(end 284.836616 -36.674298)
		(width 0.1397)
		(layer "In5.Cu")
		(net "PCIE_TX_CAP_P4")
	)
	(segment
		(start 267.65885 -24.185626)
		(end 264.541 -24.809196)
		(width 0.1397)
		(layer "In5.Cu")
		(net "PCIE_TX_CAP_P4")
	)
	(segment
		(start 255.604772 -28.20924)
		(end 255.604772 -28.23464)
		(width 0.1016)
		(layer "In5.Cu")
		(net "PCIE_TX_CAP_P4")
	)
	(segment
		(start 279.832816 -29.233876)
		(end 277.917402 -26.49855)
		(width 0.1397)
		(layer "In5.Cu")
		(net "PCIE_TX_CAP_P4")
	)
	(segment
		(start 255.75006 -26.503884)
		(end 255.604772 -27.317446)
		(width 0.1397)
		(layer "In5.Cu")
		(net "PCIE_TX_CAP_P4")
	)
	(arc
		(start 294.235378 -35.256216)
		(mid 294.348202 -35.425209)
		(end 294.387778 -35.624516)
		(width 0.1397)
		(layer "In5.Cu")
		(net "PCIE_TX_CAP_P4")
	)
	(arc
		(start 255.501394 -29.632402)
		(mid 255.532747 -29.831465)
		(end 255.623568 -30.01137)
		(width 0.1016)
		(layer "In5.Cu")
		(net "PCIE_TX_CAP_P4")
	)
	(arc
		(start 255.623568 -30.01137)
		(mid 255.655977 -30.052882)
		(end 255.69164 -30.091634)
		(width 0.1016)
		(layer "In5.Cu")
		(net "PCIE_TX_CAP_P4")
	)
	(arc
		(start 294.387524 -35.624516)
		(mid 294.279769 -35.942303)
		(end 294.000936 -36.12896)
		(width 0.1397)
		(layer "In5.Cu")
		(net "PCIE_TX_CAP_P4")
	)
	(segment
		(start 213.141306 -211.5312)
		(end 213.141306 -211.301076)
		(width 0.136652)
		(layer "F.Cu")
		(net "PCIE_TX_CAP_P39")
	)
	(segment
		(start 212.792056 -211.975954)
		(end 213.073742 -211.694268)
		(width 0.136652)
		(layer "F.Cu")
		(net "PCIE_TX_CAP_P39")
	)
	(segment
		(start 250.599956 -63.999872)
		(end 251.099828 -64.499744)
		(width 0.136652)
		(layer "F.Cu")
		(net "PCIE_TX_CAP_P39")
	)
	(segment
		(start 213.030308 -211.033106)
		(end 212.893656 -210.896454)
		(width 0.136652)
		(layer "F.Cu")
		(net "PCIE_TX_CAP_P39")
	)
	(via
		(at 251.099828 -64.499744)
		(size 0.4572)
		(drill 0.2032)
		(layers "F.Cu" "B.Cu")
		(net "PCIE_TX_CAP_P39")
	)
	(via
		(at 212.893656 -210.896454)
		(size 0.508)
		(drill 0.254)
		(layers "F.Cu" "B.Cu")
		(net "PCIE_TX_CAP_P39")
	)
	(arc
		(start 213.073742 -211.694268)
		(mid 213.123733 -211.619452)
		(end 213.141306 -211.5312)
		(width 0.136652)
		(layer "F.Cu")
		(net "PCIE_TX_CAP_P39")
	)
	(arc
		(start 213.141306 -211.301076)
		(mid 213.112459 -211.156051)
		(end 213.030308 -211.033106)
		(width 0.136652)
		(layer "F.Cu")
		(net "PCIE_TX_CAP_P39")
	)
	(segment
		(start 250.4186 -75.733148)
		(end 255.054862 -102.01529)
		(width 0.1397)
		(layer "In5.Cu")
		(net "PCIE_TX_CAP_P39")
	)
	(segment
		(start 211.371434 -206.397098)
		(end 213.134956 -208.915508)
		(width 0.1397)
		(layer "In5.Cu")
		(net "PCIE_TX_CAP_P39")
	)
	(segment
		(start 250.91771 -64.575182)
		(end 250.577858 -64.91478)
		(width 0.1016)
		(layer "In5.Cu")
		(net "PCIE_TX_CAP_P39")
	)
	(segment
		(start 250.49353 -65.118742)
		(end 250.49353 -67.015614)
		(width 0.1016)
		(layer "In5.Cu")
		(net "PCIE_TX_CAP_P39")
	)
	(segment
		(start 210.295236 -181.521608)
		(end 208.640172 -190.906654)
		(width 0.1397)
		(layer "In5.Cu")
		(net "PCIE_TX_CAP_P39")
	)
	(segment
		(start 250.49353 -67.015614)
		(end 250.4186 -67.090544)
		(width 0.1016)
		(layer "In5.Cu")
		(net "PCIE_TX_CAP_P39")
	)
	(segment
		(start 250.4186 -67.090544)
		(end 250.4186 -75.733148)
		(width 0.1397)
		(layer "In5.Cu")
		(net "PCIE_TX_CAP_P39")
	)
	(segment
		(start 255.054862 -102.456742)
		(end 251.486416 -122.694192)
		(width 0.1397)
		(layer "In5.Cu")
		(net "PCIE_TX_CAP_P39")
	)
	(segment
		(start 255.054862 -102.01529)
		(end 255.054862 -102.456742)
		(width 0.1397)
		(layer "In5.Cu")
		(net "PCIE_TX_CAP_P39")
	)
	(segment
		(start 213.134956 -208.915508)
		(end 213.134956 -210.313778)
		(width 0.1397)
		(layer "In5.Cu")
		(net "PCIE_TX_CAP_P39")
	)
	(segment
		(start 208.640172 -190.906654)
		(end 211.371434 -206.397098)
		(width 0.1397)
		(layer "In5.Cu")
		(net "PCIE_TX_CAP_P39")
	)
	(segment
		(start 251.486416 -122.694192)
		(end 210.295236 -181.521608)
		(width 0.1397)
		(layer "In5.Cu")
		(net "PCIE_TX_CAP_P39")
	)
	(arc
		(start 251.099828 -64.499744)
		(mid 251.001266 -64.519349)
		(end 250.91771 -64.575182)
		(width 0.1016)
		(layer "In5.Cu")
		(net "PCIE_TX_CAP_P39")
	)
	(arc
		(start 250.577858 -64.91478)
		(mid 250.515414 -65.008374)
		(end 250.49353 -65.118742)
		(width 0.1016)
		(layer "In5.Cu")
		(net "PCIE_TX_CAP_P39")
	)
	(arc
		(start 213.134956 -210.313778)
		(mid 213.072235 -210.6291)
		(end 212.893656 -210.896454)
		(width 0.1397)
		(layer "In5.Cu")
		(net "PCIE_TX_CAP_P39")
	)
	(segment
		(start 216.341198 -211.5312)
		(end 216.341198 -211.274406)
		(width 0.136652)
		(layer "F.Cu")
		(net "PCIE_TX_CAP_P38")
	)
	(segment
		(start 216.248996 -211.052156)
		(end 216.093548 -210.896454)
		(width 0.136652)
		(layer "F.Cu")
		(net "PCIE_TX_CAP_P38")
	)
	(segment
		(start 251.599954 -64.99987)
		(end 252.099826 -65.499742)
		(width 0.136652)
		(layer "F.Cu")
		(net "PCIE_TX_CAP_P38")
	)
	(segment
		(start 215.991948 -211.975954)
		(end 216.273634 -211.694268)
		(width 0.136652)
		(layer "F.Cu")
		(net "PCIE_TX_CAP_P38")
	)
	(via
		(at 252.099826 -65.499742)
		(size 0.4572)
		(drill 0.2032)
		(layers "F.Cu" "B.Cu")
		(net "PCIE_TX_CAP_P38")
	)
	(via
		(at 216.093548 -210.896454)
		(size 0.508)
		(drill 0.254)
		(layers "F.Cu" "B.Cu")
		(net "PCIE_TX_CAP_P38")
	)
	(arc
		(start 216.273634 -211.694268)
		(mid 216.323625 -211.619452)
		(end 216.341198 -211.5312)
		(width 0.136652)
		(layer "F.Cu")
		(net "PCIE_TX_CAP_P38")
	)
	(arc
		(start 216.341198 -211.274406)
		(mid 216.317179 -211.154124)
		(end 216.248996 -211.052156)
		(width 0.136652)
		(layer "F.Cu")
		(net "PCIE_TX_CAP_P38")
	)
	(segment
		(start 216.334848 -208.951068)
		(end 212.532214 -203.520548)
		(width 0.1397)
		(layer "In5.Cu")
		(net "PCIE_TX_CAP_P38")
	)
	(segment
		(start 251.4346 -67.103752)
		(end 251.493528 -67.070732)
		(width 0.1016)
		(layer "In5.Cu")
		(net "PCIE_TX_CAP_P38")
	)
	(segment
		(start 210.374992 -191.287654)
		(end 211.970874 -182.237888)
		(width 0.1397)
		(layer "In5.Cu")
		(net "PCIE_TX_CAP_P38")
	)
	(segment
		(start 251.577856 -65.914778)
		(end 251.917708 -65.57518)
		(width 0.1016)
		(layer "In5.Cu")
		(net "PCIE_TX_CAP_P38")
	)
	(segment
		(start 256.39014 -102.35057)
		(end 251.4346 -74.257154)
		(width 0.1397)
		(layer "In5.Cu")
		(net "PCIE_TX_CAP_P38")
	)
	(segment
		(start 212.532214 -203.520548)
		(end 210.374992 -191.287654)
		(width 0.1397)
		(layer "In5.Cu")
		(net "PCIE_TX_CAP_P38")
	)
	(segment
		(start 216.334848 -210.313778)
		(end 216.334848 -208.951068)
		(width 0.1397)
		(layer "In5.Cu")
		(net "PCIE_TX_CAP_P38")
	)
	(segment
		(start 211.970874 -182.237888)
		(end 252.61824 -124.187458)
		(width 0.1397)
		(layer "In5.Cu")
		(net "PCIE_TX_CAP_P38")
	)
	(segment
		(start 252.61824 -124.187458)
		(end 256.39014 -102.795832)
		(width 0.1397)
		(layer "In5.Cu")
		(net "PCIE_TX_CAP_P38")
	)
	(segment
		(start 251.4346 -74.257154)
		(end 251.4346 -67.129152)
		(width 0.1397)
		(layer "In5.Cu")
		(net "PCIE_TX_CAP_P38")
	)
	(segment
		(start 256.39014 -102.795832)
		(end 256.39014 -102.35057)
		(width 0.1397)
		(layer "In5.Cu")
		(net "PCIE_TX_CAP_P38")
	)
	(segment
		(start 251.4346 -67.129152)
		(end 251.4346 -67.103752)
		(width 0.1016)
		(layer "In5.Cu")
		(net "PCIE_TX_CAP_P38")
	)
	(segment
		(start 251.493528 -67.070732)
		(end 251.493528 -66.11874)
		(width 0.1016)
		(layer "In5.Cu")
		(net "PCIE_TX_CAP_P38")
	)
	(arc
		(start 251.493528 -66.11874)
		(mid 251.51539 -66.008362)
		(end 251.577856 -65.914778)
		(width 0.1016)
		(layer "In5.Cu")
		(net "PCIE_TX_CAP_P38")
	)
	(arc
		(start 251.917708 -65.57518)
		(mid 252.001264 -65.519349)
		(end 252.099826 -65.499742)
		(width 0.1016)
		(layer "In5.Cu")
		(net "PCIE_TX_CAP_P38")
	)
	(arc
		(start 216.093548 -210.896454)
		(mid 216.272175 -210.62912)
		(end 216.334848 -210.313778)
		(width 0.1397)
		(layer "In5.Cu")
		(net "PCIE_TX_CAP_P38")
	)
	(segment
		(start 264.392156 -211.975954)
		(end 264.673842 -211.694268)
		(width 0.136652)
		(layer "F.Cu")
		(net "PCIE_TX_CAP_P37")
	)
	(segment
		(start 264.647172 -211.050124)
		(end 264.493756 -210.896454)
		(width 0.136652)
		(layer "F.Cu")
		(net "PCIE_TX_CAP_P37")
	)
	(segment
		(start 252.599952 -63.999872)
		(end 253.099824 -64.499744)
		(width 0.136652)
		(layer "F.Cu")
		(net "PCIE_TX_CAP_P37")
	)
	(segment
		(start 264.741406 -211.5312)
		(end 264.741406 -211.2772)
		(width 0.136652)
		(layer "F.Cu")
		(net "PCIE_TX_CAP_P37")
	)
	(via
		(at 264.493756 -210.896454)
		(size 0.508)
		(drill 0.254)
		(layers "F.Cu" "B.Cu")
		(net "PCIE_TX_CAP_P37")
	)
	(via
		(at 253.099824 -64.499744)
		(size 0.4572)
		(drill 0.2032)
		(layers "F.Cu" "B.Cu")
		(net "PCIE_TX_CAP_P37")
	)
	(arc
		(start 264.673842 -211.694268)
		(mid 264.723833 -211.619452)
		(end 264.741406 -211.5312)
		(width 0.136652)
		(layer "F.Cu")
		(net "PCIE_TX_CAP_P37")
	)
	(arc
		(start 264.741406 -211.2772)
		(mid 264.716865 -211.154294)
		(end 264.647172 -211.050124)
		(width 0.136652)
		(layer "F.Cu")
		(net "PCIE_TX_CAP_P37")
	)
	(segment
		(start 264.7696 -207.876902)
		(end 264.7696 -210.397598)
		(width 0.1397)
		(layer "In5.Cu")
		(net "PCIE_TX_CAP_P37")
	)
	(segment
		(start 265.504422 -205.872842)
		(end 265.279632 -207.147922)
		(width 0.1397)
		(layer "In5.Cu")
		(net "PCIE_TX_CAP_P37")
	)
	(segment
		(start 252.493526 -66.886074)
		(end 252.4252 -66.9544)
		(width 0.1016)
		(layer "In5.Cu")
		(net "PCIE_TX_CAP_P37")
	)
	(segment
		(start 265.729466 -204.597)
		(end 265.504422 -205.872842)
		(width 0.1397)
		(layer "In5.Cu")
		(net "PCIE_TX_CAP_P37")
	)
	(segment
		(start 268.685772 -160.14446)
		(end 263.288526 -190.754254)
		(width 0.1397)
		(layer "In5.Cu")
		(net "PCIE_TX_CAP_P37")
	)
	(segment
		(start 263.288526 -190.754254)
		(end 265.729466 -204.597)
		(width 0.1397)
		(layer "In5.Cu")
		(net "PCIE_TX_CAP_P37")
	)
	(segment
		(start 265.0363 -207.495902)
		(end 264.7696 -207.876902)
		(width 0.1397)
		(layer "In5.Cu")
		(net "PCIE_TX_CAP_P37")
	)
	(segment
		(start 265.279632 -207.147922)
		(end 265.0363 -207.495902)
		(width 0.1397)
		(layer "In5.Cu")
		(net "PCIE_TX_CAP_P37")
	)
	(segment
		(start 252.4252 -66.9544)
		(end 252.4252 -67.919346)
		(width 0.1397)
		(layer "In5.Cu")
		(net "PCIE_TX_CAP_P37")
	)
	(segment
		(start 252.917706 -64.575182)
		(end 252.577854 -64.91478)
		(width 0.1016)
		(layer "In5.Cu")
		(net "PCIE_TX_CAP_P37")
	)
	(segment
		(start 252.493526 -65.118742)
		(end 252.493526 -66.886074)
		(width 0.1016)
		(layer "In5.Cu")
		(net "PCIE_TX_CAP_P37")
	)
	(segment
		(start 264.611866 -210.778344)
		(end 264.493756 -210.896454)
		(width 0.1397)
		(layer "In5.Cu")
		(net "PCIE_TX_CAP_P37")
	)
	(segment
		(start 252.4252 -67.919346)
		(end 268.685772 -160.14446)
		(width 0.1397)
		(layer "In5.Cu")
		(net "PCIE_TX_CAP_P37")
	)
	(arc
		(start 252.577854 -64.91478)
		(mid 252.51541 -65.008374)
		(end 252.493526 -65.118742)
		(width 0.1016)
		(layer "In5.Cu")
		(net "PCIE_TX_CAP_P37")
	)
	(arc
		(start 253.099824 -64.499744)
		(mid 253.001262 -64.519349)
		(end 252.917706 -64.575182)
		(width 0.1016)
		(layer "In5.Cu")
		(net "PCIE_TX_CAP_P37")
	)
	(arc
		(start 264.7696 -210.397598)
		(mid 264.728611 -210.603665)
		(end 264.611866 -210.778344)
		(width 0.1397)
		(layer "In5.Cu")
		(net "PCIE_TX_CAP_P37")
	)
	(segment
		(start 253.59995 -64.99987)
		(end 254.099822 -65.499742)
		(width 0.136652)
		(layer "F.Cu")
		(net "PCIE_TX_CAP_P36")
	)
	(segment
		(start 267.941298 -211.5312)
		(end 267.941298 -211.30514)
		(width 0.136652)
		(layer "F.Cu")
		(net "PCIE_TX_CAP_P36")
	)
	(segment
		(start 267.592048 -211.975954)
		(end 267.873734 -211.694268)
		(width 0.136652)
		(layer "F.Cu")
		(net "PCIE_TX_CAP_P36")
	)
	(segment
		(start 267.827506 -211.030058)
		(end 267.693648 -210.896454)
		(width 0.136652)
		(layer "F.Cu")
		(net "PCIE_TX_CAP_P36")
	)
	(via
		(at 267.693648 -210.896454)
		(size 0.508)
		(drill 0.254)
		(layers "F.Cu" "B.Cu")
		(net "PCIE_TX_CAP_P36")
	)
	(via
		(at 254.099822 -65.499742)
		(size 0.4572)
		(drill 0.2032)
		(layers "F.Cu" "B.Cu")
		(net "PCIE_TX_CAP_P36")
	)
	(arc
		(start 267.873734 -211.694268)
		(mid 267.923725 -211.619452)
		(end 267.941298 -211.5312)
		(width 0.136652)
		(layer "F.Cu")
		(net "PCIE_TX_CAP_P36")
	)
	(arc
		(start 267.941298 -211.30514)
		(mid 267.91178 -211.156271)
		(end 267.827506 -211.030058)
		(width 0.136652)
		(layer "F.Cu")
		(net "PCIE_TX_CAP_P36")
	)
	(segment
		(start 253.4539 -66.978276)
		(end 253.4539 -68.99021)
		(width 0.1397)
		(layer "In5.Cu")
		(net "PCIE_TX_CAP_P36")
	)
	(segment
		(start 267.934948 -209.98434)
		(end 267.934948 -210.5152)
		(width 0.1397)
		(layer "In5.Cu")
		(net "PCIE_TX_CAP_P36")
	)
	(segment
		(start 265.03122 -190.613538)
		(end 267.890244 -206.829914)
		(width 0.1397)
		(layer "In5.Cu")
		(net "PCIE_TX_CAP_P36")
	)
	(segment
		(start 253.917704 -65.57518)
		(end 253.577852 -65.914778)
		(width 0.1016)
		(layer "In5.Cu")
		(net "PCIE_TX_CAP_P36")
	)
	(segment
		(start 253.493524 -66.11874)
		(end 253.493524 -66.925952)
		(width 0.1016)
		(layer "In5.Cu")
		(net "PCIE_TX_CAP_P36")
	)
	(segment
		(start 267.726922 -207.75549)
		(end 267.634466 -208.28)
		(width 0.1397)
		(layer "In5.Cu")
		(net "PCIE_TX_CAP_P36")
	)
	(segment
		(start 267.835888 -210.75396)
		(end 267.693648 -210.896454)
		(width 0.1397)
		(layer "In5.Cu")
		(net "PCIE_TX_CAP_P36")
	)
	(segment
		(start 269.966694 -162.64001)
		(end 265.03122 -190.613538)
		(width 0.1397)
		(layer "In5.Cu")
		(net "PCIE_TX_CAP_P36")
	)
	(segment
		(start 253.493524 -66.925952)
		(end 253.4539 -66.965576)
		(width 0.1016)
		(layer "In5.Cu")
		(net "PCIE_TX_CAP_P36")
	)
	(segment
		(start 267.634466 -208.28)
		(end 267.934948 -209.98434)
		(width 0.1397)
		(layer "In5.Cu")
		(net "PCIE_TX_CAP_P36")
	)
	(segment
		(start 267.890244 -206.829914)
		(end 267.772388 -207.49768)
		(width 0.1397)
		(layer "In5.Cu")
		(net "PCIE_TX_CAP_P36")
	)
	(segment
		(start 267.772388 -207.49768)
		(end 267.726922 -207.75549)
		(width 0.1397)
		(layer "In5.Cu")
		(net "PCIE_TX_CAP_P36")
	)
	(segment
		(start 253.4539 -66.965576)
		(end 253.4539 -66.978276)
		(width 0.1016)
		(layer "In5.Cu")
		(net "PCIE_TX_CAP_P36")
	)
	(segment
		(start 253.4539 -68.99021)
		(end 269.966694 -162.64001)
		(width 0.1397)
		(layer "In5.Cu")
		(net "PCIE_TX_CAP_P36")
	)
	(arc
		(start 254.099822 -65.499742)
		(mid 254.00126 -65.519347)
		(end 253.917704 -65.57518)
		(width 0.1016)
		(layer "In5.Cu")
		(net "PCIE_TX_CAP_P36")
	)
	(arc
		(start 253.577852 -65.914778)
		(mid 253.515408 -66.008372)
		(end 253.493524 -66.11874)
		(width 0.1016)
		(layer "In5.Cu")
		(net "PCIE_TX_CAP_P36")
	)
	(arc
		(start 267.934948 -210.5152)
		(mid 267.90915 -210.644424)
		(end 267.835888 -210.75396)
		(width 0.1397)
		(layer "In5.Cu")
		(net "PCIE_TX_CAP_P36")
	)
	(segment
		(start 254.599948 -63.999872)
		(end 255.09982 -64.499744)
		(width 0.136652)
		(layer "F.Cu")
		(net "PCIE_TX_CAP_P35")
	)
	(segment
		(start 271.141444 -211.5312)
		(end 271.141444 -211.3026)
		(width 0.136652)
		(layer "F.Cu")
		(net "PCIE_TX_CAP_P35")
	)
	(segment
		(start 270.792194 -211.975954)
		(end 271.07388 -211.694268)
		(width 0.136652)
		(layer "F.Cu")
		(net "PCIE_TX_CAP_P35")
	)
	(segment
		(start 271.02943 -211.03209)
		(end 270.893794 -210.896454)
		(width 0.136652)
		(layer "F.Cu")
		(net "PCIE_TX_CAP_P35")
	)
	(via
		(at 270.893794 -210.896454)
		(size 0.508)
		(drill 0.254)
		(layers "F.Cu" "B.Cu")
		(net "PCIE_TX_CAP_P35")
	)
	(via
		(at 255.09982 -64.499744)
		(size 0.4572)
		(drill 0.2032)
		(layers "F.Cu" "B.Cu")
		(net "PCIE_TX_CAP_P35")
	)
	(arc
		(start 271.141444 -211.3026)
		(mid 271.112326 -211.156214)
		(end 271.02943 -211.03209)
		(width 0.136652)
		(layer "F.Cu")
		(net "PCIE_TX_CAP_P35")
	)
	(arc
		(start 271.07388 -211.694268)
		(mid 271.123871 -211.619452)
		(end 271.141444 -211.5312)
		(width 0.136652)
		(layer "F.Cu")
		(net "PCIE_TX_CAP_P35")
	)
	(segment
		(start 271.011142 -210.779106)
		(end 270.893794 -210.896454)
		(width 0.1397)
		(layer "In5.Cu")
		(net "PCIE_TX_CAP_P35")
	)
	(segment
		(start 254.917702 -64.575182)
		(end 254.57785 -64.91478)
		(width 0.1016)
		(layer "In5.Cu")
		(net "PCIE_TX_CAP_P35")
	)
	(segment
		(start 254.4318 -67.919346)
		(end 273.54657 -176.328832)
		(width 0.1397)
		(layer "In5.Cu")
		(net "PCIE_TX_CAP_P35")
	)
	(segment
		(start 254.4318 -66.8782)
		(end 254.4318 -67.919346)
		(width 0.1397)
		(layer "In5.Cu")
		(net "PCIE_TX_CAP_P35")
	)
	(segment
		(start 254.493522 -66.816478)
		(end 254.4318 -66.8782)
		(width 0.1016)
		(layer "In5.Cu")
		(net "PCIE_TX_CAP_P35")
	)
	(segment
		(start 254.493522 -65.118742)
		(end 254.493522 -66.816478)
		(width 0.1016)
		(layer "In5.Cu")
		(net "PCIE_TX_CAP_P35")
	)
	(segment
		(start 273.54657 -176.328832)
		(end 269.47622 -199.412098)
		(width 0.1397)
		(layer "In5.Cu")
		(net "PCIE_TX_CAP_P35")
	)
	(segment
		(start 269.47622 -199.412098)
		(end 271.162526 -208.977484)
		(width 0.1397)
		(layer "In5.Cu")
		(net "PCIE_TX_CAP_P35")
	)
	(segment
		(start 271.162526 -208.977484)
		(end 271.162526 -210.4136)
		(width 0.1397)
		(layer "In5.Cu")
		(net "PCIE_TX_CAP_P35")
	)
	(arc
		(start 271.162526 -210.4136)
		(mid 271.12318 -210.611405)
		(end 271.011142 -210.779106)
		(width 0.1397)
		(layer "In5.Cu")
		(net "PCIE_TX_CAP_P35")
	)
	(arc
		(start 254.57785 -64.91478)
		(mid 254.515406 -65.008374)
		(end 254.493522 -65.118742)
		(width 0.1016)
		(layer "In5.Cu")
		(net "PCIE_TX_CAP_P35")
	)
	(arc
		(start 255.09982 -64.499744)
		(mid 255.001258 -64.519349)
		(end 254.917702 -64.575182)
		(width 0.1016)
		(layer "In5.Cu")
		(net "PCIE_TX_CAP_P35")
	)
	(segment
		(start 255.599946 -64.99987)
		(end 256.099818 -65.499742)
		(width 0.136652)
		(layer "F.Cu")
		(net "PCIE_TX_CAP_P34")
	)
	(segment
		(start 273.992086 -211.975954)
		(end 274.273772 -211.694268)
		(width 0.136652)
		(layer "F.Cu")
		(net "PCIE_TX_CAP_P34")
	)
	(segment
		(start 274.341336 -211.5312)
		(end 274.341336 -211.2772)
		(width 0.136652)
		(layer "F.Cu")
		(net "PCIE_TX_CAP_P34")
	)
	(segment
		(start 274.247102 -211.050124)
		(end 274.093686 -210.896454)
		(width 0.136652)
		(layer "F.Cu")
		(net "PCIE_TX_CAP_P34")
	)
	(via
		(at 274.093686 -210.896454)
		(size 0.508)
		(drill 0.254)
		(layers "F.Cu" "B.Cu")
		(net "PCIE_TX_CAP_P34")
	)
	(via
		(at 256.099818 -65.499742)
		(size 0.4572)
		(drill 0.2032)
		(layers "F.Cu" "B.Cu")
		(net "PCIE_TX_CAP_P34")
	)
	(arc
		(start 274.273772 -211.694268)
		(mid 274.323763 -211.619452)
		(end 274.341336 -211.5312)
		(width 0.136652)
		(layer "F.Cu")
		(net "PCIE_TX_CAP_P34")
	)
	(arc
		(start 274.341336 -211.2772)
		(mid 274.316795 -211.154294)
		(end 274.247102 -211.050124)
		(width 0.136652)
		(layer "F.Cu")
		(net "PCIE_TX_CAP_P34")
	)
	(segment
		(start 255.9177 -65.57518)
		(end 255.577848 -65.914778)
		(width 0.1016)
		(layer "In5.Cu")
		(net "PCIE_TX_CAP_P34")
	)
	(segment
		(start 255.49352 -66.85788)
		(end 255.4224 -66.929)
		(width 0.1016)
		(layer "In5.Cu")
		(net "PCIE_TX_CAP_P34")
	)
	(segment
		(start 279.794462 -177.419)
		(end 279.52446 -178.583844)
		(width 0.1397)
		(layer "In5.Cu")
		(net "PCIE_TX_CAP_P34")
	)
	(segment
		(start 255.4224 -66.929)
		(end 255.4224 -68.379848)
		(width 0.1397)
		(layer "In5.Cu")
		(net "PCIE_TX_CAP_P34")
	)
	(segment
		(start 274.506944 -204.118972)
		(end 274.334986 -205.094332)
		(width 0.1397)
		(layer "In5.Cu")
		(net "PCIE_TX_CAP_P34")
	)
	(segment
		(start 279.52446 -178.583844)
		(end 274.506944 -204.118972)
		(width 0.1397)
		(layer "In5.Cu")
		(net "PCIE_TX_CAP_P34")
	)
	(segment
		(start 255.4224 -68.379848)
		(end 255.63576 -69.59092)
		(width 0.1397)
		(layer "In5.Cu")
		(net "PCIE_TX_CAP_P34")
	)
	(segment
		(start 255.63576 -69.59092)
		(end 279.794462 -177.419)
		(width 0.1397)
		(layer "In5.Cu")
		(net "PCIE_TX_CAP_P34")
	)
	(segment
		(start 274.334986 -205.094332)
		(end 274.334986 -210.313778)
		(width 0.1397)
		(layer "In5.Cu")
		(net "PCIE_TX_CAP_P34")
	)
	(segment
		(start 255.49352 -66.11874)
		(end 255.49352 -66.85788)
		(width 0.1016)
		(layer "In5.Cu")
		(net "PCIE_TX_CAP_P34")
	)
	(arc
		(start 256.099818 -65.499742)
		(mid 256.001256 -65.519347)
		(end 255.9177 -65.57518)
		(width 0.1016)
		(layer "In5.Cu")
		(net "PCIE_TX_CAP_P34")
	)
	(arc
		(start 274.334986 -210.313778)
		(mid 274.272265 -210.6291)
		(end 274.093686 -210.896454)
		(width 0.1397)
		(layer "In5.Cu")
		(net "PCIE_TX_CAP_P34")
	)
	(arc
		(start 255.577848 -65.914778)
		(mid 255.515404 -66.008372)
		(end 255.49352 -66.11874)
		(width 0.1016)
		(layer "In5.Cu")
		(net "PCIE_TX_CAP_P34")
	)
	(segment
		(start 277.446994 -211.050124)
		(end 277.293578 -210.896454)
		(width 0.136652)
		(layer "F.Cu")
		(net "PCIE_TX_CAP_P33")
	)
	(segment
		(start 256.599944 -63.999872)
		(end 257.099816 -64.499744)
		(width 0.136652)
		(layer "F.Cu")
		(net "PCIE_TX_CAP_P33")
	)
	(segment
		(start 277.191978 -211.975954)
		(end 277.473664 -211.694268)
		(width 0.136652)
		(layer "F.Cu")
		(net "PCIE_TX_CAP_P33")
	)
	(segment
		(start 277.541228 -211.5312)
		(end 277.541228 -211.2772)
		(width 0.136652)
		(layer "F.Cu")
		(net "PCIE_TX_CAP_P33")
	)
	(via
		(at 257.099816 -64.499744)
		(size 0.4572)
		(drill 0.2032)
		(layers "F.Cu" "B.Cu")
		(net "PCIE_TX_CAP_P33")
	)
	(via
		(at 277.293578 -210.896454)
		(size 0.508)
		(drill 0.254)
		(layers "F.Cu" "B.Cu")
		(net "PCIE_TX_CAP_P33")
	)
	(arc
		(start 277.473664 -211.694268)
		(mid 277.523655 -211.619452)
		(end 277.541228 -211.5312)
		(width 0.136652)
		(layer "F.Cu")
		(net "PCIE_TX_CAP_P33")
	)
	(arc
		(start 277.541228 -211.2772)
		(mid 277.516687 -211.154294)
		(end 277.446994 -211.050124)
		(width 0.136652)
		(layer "F.Cu")
		(net "PCIE_TX_CAP_P33")
	)
	(segment
		(start 256.917698 -64.575182)
		(end 256.577846 -64.91478)
		(width 0.1016)
		(layer "In5.Cu")
		(net "PCIE_TX_CAP_P33")
	)
	(segment
		(start 256.723642 -69.682868)
		(end 263.930384 -79.975456)
		(width 0.1397)
		(layer "In5.Cu")
		(net "PCIE_TX_CAP_P33")
	)
	(segment
		(start 278.012906 -206.851504)
		(end 277.534878 -209.562192)
		(width 0.1397)
		(layer "In5.Cu")
		(net "PCIE_TX_CAP_P33")
	)
	(segment
		(start 256.493518 -65.118742)
		(end 256.493518 -66.873882)
		(width 0.1016)
		(layer "In5.Cu")
		(net "PCIE_TX_CAP_P33")
	)
	(segment
		(start 256.559812 -68.75399)
		(end 256.723642 -69.682868)
		(width 0.1397)
		(layer "In5.Cu")
		(net "PCIE_TX_CAP_P33")
	)
	(segment
		(start 263.930384 -79.975456)
		(end 281.173682 -177.767234)
		(width 0.1397)
		(layer "In5.Cu")
		(net "PCIE_TX_CAP_P33")
	)
	(segment
		(start 277.029164 -201.272394)
		(end 278.012906 -206.851504)
		(width 0.1397)
		(layer "In5.Cu")
		(net "PCIE_TX_CAP_P33")
	)
	(segment
		(start 256.413 -67.919092)
		(end 256.559812 -68.75399)
		(width 0.1397)
		(layer "In5.Cu")
		(net "PCIE_TX_CAP_P33")
	)
	(segment
		(start 281.173682 -177.767234)
		(end 277.029164 -201.272394)
		(width 0.1397)
		(layer "In5.Cu")
		(net "PCIE_TX_CAP_P33")
	)
	(segment
		(start 277.534878 -209.562192)
		(end 277.534878 -210.313778)
		(width 0.1397)
		(layer "In5.Cu")
		(net "PCIE_TX_CAP_P33")
	)
	(segment
		(start 256.413 -66.9544)
		(end 256.413 -67.919092)
		(width 0.1397)
		(layer "In5.Cu")
		(net "PCIE_TX_CAP_P33")
	)
	(segment
		(start 256.493518 -66.873882)
		(end 256.413 -66.9544)
		(width 0.1016)
		(layer "In5.Cu")
		(net "PCIE_TX_CAP_P33")
	)
	(arc
		(start 257.099816 -64.499744)
		(mid 257.001254 -64.519349)
		(end 256.917698 -64.575182)
		(width 0.1016)
		(layer "In5.Cu")
		(net "PCIE_TX_CAP_P33")
	)
	(arc
		(start 256.577846 -64.91478)
		(mid 256.515402 -65.008374)
		(end 256.493518 -65.118742)
		(width 0.1016)
		(layer "In5.Cu")
		(net "PCIE_TX_CAP_P33")
	)
	(arc
		(start 277.534878 -210.313778)
		(mid 277.472157 -210.6291)
		(end 277.293578 -210.896454)
		(width 0.1397)
		(layer "In5.Cu")
		(net "PCIE_TX_CAP_P33")
	)
	(segment
		(start 280.392124 -211.975954)
		(end 280.67381 -211.694268)
		(width 0.136652)
		(layer "F.Cu")
		(net "PCIE_TX_CAP_P32")
	)
	(segment
		(start 280.64714 -211.050124)
		(end 280.493724 -210.896454)
		(width 0.136652)
		(layer "F.Cu")
		(net "PCIE_TX_CAP_P32")
	)
	(segment
		(start 257.599942 -64.99987)
		(end 258.099814 -65.499742)
		(width 0.136652)
		(layer "F.Cu")
		(net "PCIE_TX_CAP_P32")
	)
	(segment
		(start 280.741374 -211.5312)
		(end 280.741374 -211.2772)
		(width 0.136652)
		(layer "F.Cu")
		(net "PCIE_TX_CAP_P32")
	)
	(via
		(at 258.099814 -65.499742)
		(size 0.4572)
		(drill 0.2032)
		(layers "F.Cu" "B.Cu")
		(net "PCIE_TX_CAP_P32")
	)
	(via
		(at 280.493724 -210.896454)
		(size 0.508)
		(drill 0.254)
		(layers "F.Cu" "B.Cu")
		(net "PCIE_TX_CAP_P32")
	)
	(arc
		(start 280.741374 -211.2772)
		(mid 280.716833 -211.154294)
		(end 280.64714 -211.050124)
		(width 0.136652)
		(layer "F.Cu")
		(net "PCIE_TX_CAP_P32")
	)
	(arc
		(start 280.67381 -211.694268)
		(mid 280.723801 -211.619452)
		(end 280.741374 -211.5312)
		(width 0.136652)
		(layer "F.Cu")
		(net "PCIE_TX_CAP_P32")
	)
	(segment
		(start 257.493516 -66.864484)
		(end 257.429 -66.929)
		(width 0.1016)
		(layer "In5.Cu")
		(net "PCIE_TX_CAP_P32")
	)
	(segment
		(start 257.429 -67.919346)
		(end 257.6068 -68.92925)
		(width 0.1397)
		(layer "In5.Cu")
		(net "PCIE_TX_CAP_P32")
	)
	(segment
		(start 257.493516 -66.11874)
		(end 257.493516 -66.864484)
		(width 0.1016)
		(layer "In5.Cu")
		(net "PCIE_TX_CAP_P32")
	)
	(segment
		(start 257.429 -66.929)
		(end 257.429 -67.919346)
		(width 0.1397)
		(layer "In5.Cu")
		(net "PCIE_TX_CAP_P32")
	)
	(segment
		(start 280.999184 -208.574894)
		(end 280.735024 -210.073494)
		(width 0.1397)
		(layer "In5.Cu")
		(net "PCIE_TX_CAP_P32")
	)
	(segment
		(start 279.092406 -197.762114)
		(end 280.056082 -203.225908)
		(width 0.1397)
		(layer "In5.Cu")
		(net "PCIE_TX_CAP_P32")
	)
	(segment
		(start 282.70581 -177.268886)
		(end 279.092406 -197.762114)
		(width 0.1397)
		(layer "In5.Cu")
		(net "PCIE_TX_CAP_P32")
	)
	(segment
		(start 265.6205 -80.374236)
		(end 282.70581 -177.268886)
		(width 0.1397)
		(layer "In5.Cu")
		(net "PCIE_TX_CAP_P32")
	)
	(segment
		(start 257.917696 -65.57518)
		(end 257.577844 -65.914778)
		(width 0.1016)
		(layer "In5.Cu")
		(net "PCIE_TX_CAP_P32")
	)
	(segment
		(start 280.735024 -210.073494)
		(end 280.735024 -210.313778)
		(width 0.1397)
		(layer "In5.Cu")
		(net "PCIE_TX_CAP_P32")
	)
	(segment
		(start 257.6068 -68.92925)
		(end 265.6205 -80.374236)
		(width 0.1397)
		(layer "In5.Cu")
		(net "PCIE_TX_CAP_P32")
	)
	(segment
		(start 280.056082 -203.225908)
		(end 280.999184 -208.574894)
		(width 0.1397)
		(layer "In5.Cu")
		(net "PCIE_TX_CAP_P32")
	)
	(arc
		(start 280.735024 -210.313778)
		(mid 280.672303 -210.6291)
		(end 280.493724 -210.896454)
		(width 0.1397)
		(layer "In5.Cu")
		(net "PCIE_TX_CAP_P32")
	)
	(arc
		(start 257.577844 -65.914778)
		(mid 257.5154 -66.008372)
		(end 257.493516 -66.11874)
		(width 0.1016)
		(layer "In5.Cu")
		(net "PCIE_TX_CAP_P32")
	)
	(arc
		(start 258.099814 -65.499742)
		(mid 258.001252 -65.519347)
		(end 257.917696 -65.57518)
		(width 0.1016)
		(layer "In5.Cu")
		(net "PCIE_TX_CAP_P32")
	)
	(segment
		(start 283.847032 -211.050124)
		(end 283.693616 -210.896454)
		(width 0.136652)
		(layer "F.Cu")
		(net "PCIE_TX_CAP_P31")
	)
	(segment
		(start 283.592016 -211.975954)
		(end 283.873702 -211.694268)
		(width 0.136652)
		(layer "F.Cu")
		(net "PCIE_TX_CAP_P31")
	)
	(segment
		(start 283.941266 -211.5312)
		(end 283.941266 -211.2772)
		(width 0.136652)
		(layer "F.Cu")
		(net "PCIE_TX_CAP_P31")
	)
	(segment
		(start 256.599944 -58.999882)
		(end 257.099816 -59.499754)
		(width 0.136652)
		(layer "F.Cu")
		(net "PCIE_TX_CAP_P31")
	)
	(via
		(at 283.693616 -210.896454)
		(size 0.508)
		(drill 0.254)
		(layers "F.Cu" "B.Cu")
		(net "PCIE_TX_CAP_P31")
	)
	(via
		(at 257.099816 -59.499754)
		(size 0.4572)
		(drill 0.2032)
		(layers "F.Cu" "B.Cu")
		(net "PCIE_TX_CAP_P31")
	)
	(arc
		(start 283.941266 -211.2772)
		(mid 283.916725 -211.154294)
		(end 283.847032 -211.050124)
		(width 0.136652)
		(layer "F.Cu")
		(net "PCIE_TX_CAP_P31")
	)
	(arc
		(start 283.873702 -211.694268)
		(mid 283.923693 -211.619452)
		(end 283.941266 -211.5312)
		(width 0.136652)
		(layer "F.Cu")
		(net "PCIE_TX_CAP_P31")
	)
	(segment
		(start 259.7404 -60.170314)
		(end 263.294368 -62.65926)
		(width 0.1397)
		(layer "In5.Cu")
		(net "PCIE_TX_CAP_P31")
	)
	(segment
		(start 258.070096 -60.091828)
		(end 259.389626 -60.091828)
		(width 0.1016)
		(layer "In5.Cu")
		(net "PCIE_TX_CAP_P31")
	)
	(segment
		(start 263.294368 -62.65926)
		(end 265.752326 -66.16954)
		(width 0.1397)
		(layer "In5.Cu")
		(net "PCIE_TX_CAP_P31")
	)
	(segment
		(start 283.195522 -197.94601)
		(end 284.144466 -203.327)
		(width 0.1397)
		(layer "In5.Cu")
		(net "PCIE_TX_CAP_P31")
	)
	(segment
		(start 257.472942 -59.489086)
		(end 257.496056 -59.544712)
		(width 0.1016)
		(layer "In5.Cu")
		(net "PCIE_TX_CAP_P31")
	)
	(segment
		(start 286.091884 -181.520592)
		(end 283.195522 -197.94601)
		(width 0.1397)
		(layer "In5.Cu")
		(net "PCIE_TX_CAP_P31")
	)
	(segment
		(start 257.515106 -59.698128)
		(end 257.526536 -59.75604)
		(width 0.1016)
		(layer "In5.Cu")
		(net "PCIE_TX_CAP_P31")
	)
	(segment
		(start 257.099816 -59.499754)
		(end 257.217926 -59.381644)
		(width 0.1016)
		(layer "In5.Cu")
		(net "PCIE_TX_CAP_P31")
	)
	(segment
		(start 283.934916 -209.804)
		(end 283.934916 -210.313778)
		(width 0.1397)
		(layer "In5.Cu")
		(net "PCIE_TX_CAP_P31")
	)
	(segment
		(start 265.752326 -66.16954)
		(end 286.091884 -181.520592)
		(width 0.1397)
		(layer "In5.Cu")
		(net "PCIE_TX_CAP_P31")
	)
	(segment
		(start 284.144466 -203.327)
		(end 283.468572 -207.159606)
		(width 0.1397)
		(layer "In5.Cu")
		(net "PCIE_TX_CAP_P31")
	)
	(segment
		(start 257.513582 -59.63285)
		(end 257.513582 -59.682634)
		(width 0.1016)
		(layer "In5.Cu")
		(net "PCIE_TX_CAP_P31")
	)
	(segment
		(start 283.468572 -207.159606)
		(end 283.934916 -209.804)
		(width 0.1397)
		(layer "In5.Cu")
		(net "PCIE_TX_CAP_P31")
	)
	(arc
		(start 257.276092 -59.357514)
		(mid 257.301157 -59.358963)
		(end 257.325876 -59.363356)
		(width 0.1016)
		(layer "In5.Cu")
		(net "PCIE_TX_CAP_P31")
	)
	(arc
		(start 257.496056 -59.544712)
		(mid 257.509158 -59.587918)
		(end 257.513582 -59.63285)
		(width 0.1016)
		(layer "In5.Cu")
		(net "PCIE_TX_CAP_P31")
	)
	(arc
		(start 259.389626 -60.091828)
		(mid 259.569351 -60.111686)
		(end 259.7404 -60.170314)
		(width 0.1016)
		(layer "In5.Cu")
		(net "PCIE_TX_CAP_P31")
	)
	(arc
		(start 257.76555 -60.036964)
		(mid 257.915372 -60.077992)
		(end 258.070096 -60.091828)
		(width 0.1016)
		(layer "In5.Cu")
		(net "PCIE_TX_CAP_P31")
	)
	(arc
		(start 257.396742 -59.395106)
		(mid 257.441618 -59.436594)
		(end 257.472942 -59.489086)
		(width 0.1016)
		(layer "In5.Cu")
		(net "PCIE_TX_CAP_P31")
	)
	(arc
		(start 257.325876 -59.363356)
		(mid 257.36276 -59.375988)
		(end 257.396742 -59.395106)
		(width 0.1016)
		(layer "In5.Cu")
		(net "PCIE_TX_CAP_P31")
	)
	(arc
		(start 257.217926 -59.381644)
		(mid 257.244613 -59.363812)
		(end 257.276092 -59.357514)
		(width 0.1016)
		(layer "In5.Cu")
		(net "PCIE_TX_CAP_P31")
	)
	(arc
		(start 283.934916 -210.313778)
		(mid 283.872195 -210.6291)
		(end 283.693616 -210.896454)
		(width 0.1397)
		(layer "In5.Cu")
		(net "PCIE_TX_CAP_P31")
	)
	(arc
		(start 257.526536 -59.75604)
		(mid 257.609465 -59.927619)
		(end 257.76555 -60.036964)
		(width 0.1016)
		(layer "In5.Cu")
		(net "PCIE_TX_CAP_P31")
	)
	(arc
		(start 257.513582 -59.682634)
		(mid 257.513959 -59.690419)
		(end 257.515106 -59.698128)
		(width 0.1016)
		(layer "In5.Cu")
		(net "PCIE_TX_CAP_P31")
	)
	(segment
		(start 257.599942 -57.999884)
		(end 258.099814 -58.499756)
		(width 0.136652)
		(layer "F.Cu")
		(net "PCIE_TX_CAP_P30")
	)
	(segment
		(start 287.141412 -211.5312)
		(end 287.141412 -211.299552)
		(width 0.136652)
		(layer "F.Cu")
		(net "PCIE_TX_CAP_P30")
	)
	(segment
		(start 286.792162 -211.975954)
		(end 287.073848 -211.694268)
		(width 0.136652)
		(layer "F.Cu")
		(net "PCIE_TX_CAP_P30")
	)
	(segment
		(start 287.03143 -211.034376)
		(end 286.893762 -210.896454)
		(width 0.136652)
		(layer "F.Cu")
		(net "PCIE_TX_CAP_P30")
	)
	(via
		(at 286.893762 -210.896454)
		(size 0.508)
		(drill 0.254)
		(layers "F.Cu" "B.Cu")
		(net "PCIE_TX_CAP_P30")
	)
	(via
		(at 258.099814 -58.499756)
		(size 0.4572)
		(drill 0.2032)
		(layers "F.Cu" "B.Cu")
		(net "PCIE_TX_CAP_P30")
	)
	(arc
		(start 287.141412 -211.299552)
		(mid 287.112772 -211.156039)
		(end 287.03143 -211.034376)
		(width 0.136652)
		(layer "F.Cu")
		(net "PCIE_TX_CAP_P30")
	)
	(arc
		(start 287.073848 -211.694268)
		(mid 287.123839 -211.619452)
		(end 287.141412 -211.5312)
		(width 0.136652)
		(layer "F.Cu")
		(net "PCIE_TX_CAP_P30")
	)
	(segment
		(start 258.308856 -58.58637)
		(end 258.875784 -59.153552)
		(width 0.1016)
		(layer "In5.Cu")
		(net "PCIE_TX_CAP_P30")
	)
	(segment
		(start 288.236152 -202.176126)
		(end 287.135062 -208.421224)
		(width 0.1397)
		(layer "In5.Cu")
		(net "PCIE_TX_CAP_P30")
	)
	(segment
		(start 259.938012 -59.210702)
		(end 259.945378 -59.205114)
		(width 0.1397)
		(layer "In5.Cu")
		(net "PCIE_TX_CAP_P30")
	)
	(segment
		(start 259.808726 -59.249818)
		(end 259.839968 -59.229244)
		(width 0.1016)
		(layer "In5.Cu")
		(net "PCIE_TX_CAP_P30")
	)
	(segment
		(start 287.135062 -208.421224)
		(end 287.135062 -210.313778)
		(width 0.1397)
		(layer "In5.Cu")
		(net "PCIE_TX_CAP_P30")
	)
	(segment
		(start 267.337286 -65.751202)
		(end 287.660588 -181.02961)
		(width 0.1397)
		(layer "In5.Cu")
		(net "PCIE_TX_CAP_P30")
	)
	(segment
		(start 260.01472 -59.182)
		(end 261.1755 -59.182)
		(width 0.1397)
		(layer "In5.Cu")
		(net "PCIE_TX_CAP_P30")
	)
	(segment
		(start 287.660588 -181.02961)
		(end 286.882586 -185.44286)
		(width 0.1397)
		(layer "In5.Cu")
		(net "PCIE_TX_CAP_P30")
	)
	(segment
		(start 286.084264 -189.970664)
		(end 288.236152 -202.176126)
		(width 0.1397)
		(layer "In5.Cu")
		(net "PCIE_TX_CAP_P30")
	)
	(segment
		(start 259.239766 -59.304682)
		(end 259.626608 -59.304682)
		(width 0.1016)
		(layer "In5.Cu")
		(net "PCIE_TX_CAP_P30")
	)
	(segment
		(start 286.882586 -185.44286)
		(end 286.084264 -189.970664)
		(width 0.1397)
		(layer "In5.Cu")
		(net "PCIE_TX_CAP_P30")
	)
	(segment
		(start 261.73684 -59.28106)
		(end 263.836404 -60.751212)
		(width 0.1397)
		(layer "In5.Cu")
		(net "PCIE_TX_CAP_P30")
	)
	(segment
		(start 261.1755 -59.182)
		(end 261.73684 -59.28106)
		(width 0.1397)
		(layer "In5.Cu")
		(net "PCIE_TX_CAP_P30")
	)
	(segment
		(start 263.836404 -60.751212)
		(end 267.337286 -65.751202)
		(width 0.1397)
		(layer "In5.Cu")
		(net "PCIE_TX_CAP_P30")
	)
	(arc
		(start 259.892292 -59.219338)
		(mid 259.916005 -59.219575)
		(end 259.938012 -59.210702)
		(width 0.1016)
		(layer "In5.Cu")
		(net "PCIE_TX_CAP_P30")
	)
	(arc
		(start 258.875784 -59.153552)
		(mid 258.907645 -59.182861)
		(end 258.941824 -59.209432)
		(width 0.1016)
		(layer "In5.Cu")
		(net "PCIE_TX_CAP_P30")
	)
	(arc
		(start 259.839968 -59.229244)
		(mid 259.865141 -59.219051)
		(end 259.892292 -59.219338)
		(width 0.1016)
		(layer "In5.Cu")
		(net "PCIE_TX_CAP_P30")
	)
	(arc
		(start 258.099814 -58.499756)
		(mid 258.212957 -58.522261)
		(end 258.308856 -58.58637)
		(width 0.1016)
		(layer "In5.Cu")
		(net "PCIE_TX_CAP_P30")
	)
	(arc
		(start 259.626608 -59.304682)
		(mid 259.72169 -59.29062)
		(end 259.808726 -59.249818)
		(width 0.1016)
		(layer "In5.Cu")
		(net "PCIE_TX_CAP_P30")
	)
	(arc
		(start 259.945378 -59.205114)
		(mid 259.978168 -59.187929)
		(end 260.01472 -59.182)
		(width 0.1397)
		(layer "In5.Cu")
		(net "PCIE_TX_CAP_P30")
	)
	(arc
		(start 287.135062 -210.313778)
		(mid 287.072341 -210.6291)
		(end 286.893762 -210.896454)
		(width 0.1397)
		(layer "In5.Cu")
		(net "PCIE_TX_CAP_P30")
	)
	(arc
		(start 258.941824 -59.209432)
		(mid 259.083367 -59.280293)
		(end 259.239766 -59.304682)
		(width 0.1016)
		(layer "In5.Cu")
		(net "PCIE_TX_CAP_P30")
	)
	(segment
		(start 289.4965 -34.4424)
		(end 289.4965 -34.5821)
		(width 0.136652)
		(layer "F.Cu")
		(net "PCIE_TX_CAP_P3")
	)
	(segment
		(start 254.599948 -31.999936)
		(end 255.09982 -31.500064)
		(width 0.136652)
		(layer "F.Cu")
		(net "PCIE_TX_CAP_P3")
	)
	(segment
		(start 289.37966 -34.864548)
		(end 289.2298 -35.014154)
		(width 0.136652)
		(layer "F.Cu")
		(net "PCIE_TX_CAP_P3")
	)
	(segment
		(start 289.179 -33.9725)
		(end 289.388804 -34.18205)
		(width 0.136652)
		(layer "F.Cu")
		(net "PCIE_TX_CAP_P3")
	)
	(via
		(at 255.09982 -31.500064)
		(size 0.4572)
		(drill 0.2032)
		(layers "F.Cu" "B.Cu")
		(net "PCIE_TX_CAP_P3")
	)
	(via
		(at 289.2298 -35.014154)
		(size 0.508)
		(drill 0.254)
		(layers "F.Cu" "B.Cu")
		(net "PCIE_TX_CAP_P3")
	)
	(arc
		(start 289.4965 -34.5821)
		(mid 289.466189 -34.734955)
		(end 289.37966 -34.864548)
		(width 0.136652)
		(layer "F.Cu")
		(net "PCIE_TX_CAP_P3")
	)
	(arc
		(start 289.388804 -34.18205)
		(mid 289.468535 -34.301515)
		(end 289.4965 -34.4424)
		(width 0.136652)
		(layer "F.Cu")
		(net "PCIE_TX_CAP_P3")
	)
	(segment
		(start 254.501396 -30.008576)
		(end 254.512572 -29.9974)
		(width 0.1016)
		(layer "In5.Cu")
		(net "PCIE_TX_CAP_P3")
	)
	(segment
		(start 288.594038 -35.941)
		(end 288.871152 -35.941)
		(width 0.1397)
		(layer "In5.Cu")
		(net "PCIE_TX_CAP_P3")
	)
	(segment
		(start 260.52145 -22.905466)
		(end 263.934194 -23.63089)
		(width 0.1397)
		(layer "In5.Cu")
		(net "PCIE_TX_CAP_P3")
	)
	(segment
		(start 284.70352 -35.25774)
		(end 288.594038 -35.941)
		(width 0.1397)
		(layer "In5.Cu")
		(net "PCIE_TX_CAP_P3")
	)
	(segment
		(start 255.327404 -25.057862)
		(end 257.478022 -23.552404)
		(width 0.1397)
		(layer "In5.Cu")
		(net "PCIE_TX_CAP_P3")
	)
	(segment
		(start 281.36596 -32.076898)
		(end 282.5242 -33.7312)
		(width 0.1397)
		(layer "In5.Cu")
		(net "PCIE_TX_CAP_P3")
	)
	(segment
		(start 272.578068 -21.793708)
		(end 273.912584 -22.077426)
		(width 0.1397)
		(layer "In5.Cu")
		(net "PCIE_TX_CAP_P3")
	)
	(segment
		(start 257.478022 -23.552404)
		(end 260.52145 -22.905466)
		(width 0.1397)
		(layer "In5.Cu")
		(net "PCIE_TX_CAP_P3")
	)
	(segment
		(start 254.517398 -26.717498)
		(end 254.636016 -26.045414)
		(width 0.1397)
		(layer "In5.Cu")
		(net "PCIE_TX_CAP_P3")
	)
	(segment
		(start 282.5242 -33.7312)
		(end 284.70352 -35.25774)
		(width 0.1397)
		(layer "In5.Cu")
		(net "PCIE_TX_CAP_P3")
	)
	(segment
		(start 254.512572 -29.9974)
		(end 254.512572 -29.845)
		(width 0.1016)
		(layer "In5.Cu")
		(net "PCIE_TX_CAP_P3")
	)
	(segment
		(start 254.501396 -30.6324)
		(end 254.501396 -30.008576)
		(width 0.1016)
		(layer "In5.Cu")
		(net "PCIE_TX_CAP_P3")
	)
	(segment
		(start 254.512572 -29.845)
		(end 254.512572 -26.722324)
		(width 0.1397)
		(layer "In5.Cu")
		(net "PCIE_TX_CAP_P3")
	)
	(segment
		(start 289.306 -35.0901)
		(end 289.2298 -35.014154)
		(width 0.1397)
		(layer "In5.Cu")
		(net "PCIE_TX_CAP_P3")
	)
	(segment
		(start 255.09982 -31.500064)
		(end 255.09982 -31.495492)
		(width 0.1016)
		(layer "In5.Cu")
		(net "PCIE_TX_CAP_P3")
	)
	(segment
		(start 254.636016 -26.045414)
		(end 255.327404 -25.057862)
		(width 0.1397)
		(layer "In5.Cu")
		(net "PCIE_TX_CAP_P3")
	)
	(segment
		(start 289.4584 -35.497008)
		(end 289.4584 -35.4584)
		(width 0.1397)
		(layer "In5.Cu")
		(net "PCIE_TX_CAP_P3")
	)
	(segment
		(start 254.512572 -26.722324)
		(end 254.517398 -26.717498)
		(width 0.1397)
		(layer "In5.Cu")
		(net "PCIE_TX_CAP_P3")
	)
	(segment
		(start 263.934194 -23.63089)
		(end 272.578068 -21.793708)
		(width 0.1397)
		(layer "In5.Cu")
		(net "PCIE_TX_CAP_P3")
	)
	(segment
		(start 278.74468 -25.215342)
		(end 280.680414 -28.196286)
		(width 0.1397)
		(layer "In5.Cu")
		(net "PCIE_TX_CAP_P3")
	)
	(segment
		(start 280.680414 -28.196286)
		(end 281.36596 -32.076898)
		(width 0.1397)
		(layer "In5.Cu")
		(net "PCIE_TX_CAP_P3")
	)
	(segment
		(start 273.912584 -22.077426)
		(end 278.74468 -25.215342)
		(width 0.1397)
		(layer "In5.Cu")
		(net "PCIE_TX_CAP_P3")
	)
	(segment
		(start 255.09982 -31.495492)
		(end 254.66548 -31.060644)
		(width 0.1016)
		(layer "In5.Cu")
		(net "PCIE_TX_CAP_P3")
	)
	(arc
		(start 289.4584 -35.4584)
		(mid 289.418847 -35.259083)
		(end 289.306 -35.0901)
		(width 0.1397)
		(layer "In5.Cu")
		(net "PCIE_TX_CAP_P3")
	)
	(arc
		(start 254.66548 -31.060644)
		(mid 254.643534 -31.036849)
		(end 254.62357 -31.011368)
		(width 0.1016)
		(layer "In5.Cu")
		(net "PCIE_TX_CAP_P3")
	)
	(arc
		(start 289.35807 -35.739324)
		(mid 289.432355 -35.628148)
		(end 289.4584 -35.497008)
		(width 0.1397)
		(layer "In5.Cu")
		(net "PCIE_TX_CAP_P3")
	)
	(arc
		(start 254.62357 -31.011368)
		(mid 254.532676 -30.831487)
		(end 254.501396 -30.6324)
		(width 0.1016)
		(layer "In5.Cu")
		(net "PCIE_TX_CAP_P3")
	)
	(arc
		(start 288.871152 -35.941)
		(mid 289.134666 -35.888584)
		(end 289.35807 -35.739324)
		(width 0.1397)
		(layer "In5.Cu")
		(net "PCIE_TX_CAP_P3")
	)
	(segment
		(start 290.341304 -211.5312)
		(end 290.341304 -211.3026)
		(width 0.136652)
		(layer "F.Cu")
		(net "PCIE_TX_CAP_P29")
	)
	(segment
		(start 289.992054 -211.975954)
		(end 290.27374 -211.694268)
		(width 0.136652)
		(layer "F.Cu")
		(net "PCIE_TX_CAP_P29")
	)
	(segment
		(start 290.22929 -211.03209)
		(end 290.093654 -210.896454)
		(width 0.136652)
		(layer "F.Cu")
		(net "PCIE_TX_CAP_P29")
	)
	(segment
		(start 256.599944 -56.999886)
		(end 257.099816 -57.499758)
		(width 0.136652)
		(layer "F.Cu")
		(net "PCIE_TX_CAP_P29")
	)
	(via
		(at 290.093654 -210.896454)
		(size 0.508)
		(drill 0.254)
		(layers "F.Cu" "B.Cu")
		(net "PCIE_TX_CAP_P29")
	)
	(via
		(at 257.099816 -57.499758)
		(size 0.4572)
		(drill 0.2032)
		(layers "F.Cu" "B.Cu")
		(net "PCIE_TX_CAP_P29")
	)
	(arc
		(start 290.341304 -211.3026)
		(mid 290.312186 -211.156214)
		(end 290.22929 -211.03209)
		(width 0.136652)
		(layer "F.Cu")
		(net "PCIE_TX_CAP_P29")
	)
	(arc
		(start 290.27374 -211.694268)
		(mid 290.323731 -211.619452)
		(end 290.341304 -211.5312)
		(width 0.136652)
		(layer "F.Cu")
		(net "PCIE_TX_CAP_P29")
	)
	(segment
		(start 269.745206 -66.612516)
		(end 290.100512 -182.05323)
		(width 0.1397)
		(layer "In5.Cu")
		(net "PCIE_TX_CAP_P29")
	)
	(segment
		(start 257.099816 -57.499758)
		(end 257.217926 -57.381648)
		(width 0.1016)
		(layer "In5.Cu")
		(net "PCIE_TX_CAP_P29")
	)
	(segment
		(start 290.334954 -208.422494)
		(end 290.334954 -210.313778)
		(width 0.1397)
		(layer "In5.Cu")
		(net "PCIE_TX_CAP_P29")
	)
	(segment
		(start 265.211052 -60.137294)
		(end 269.745206 -66.612516)
		(width 0.1397)
		(layer "In5.Cu")
		(net "PCIE_TX_CAP_P29")
	)
	(segment
		(start 258.069842 -58.091832)
		(end 259.576062 -58.091832)
		(width 0.1016)
		(layer "In5.Cu")
		(net "PCIE_TX_CAP_P29")
	)
	(segment
		(start 260.956044 -58.170318)
		(end 262.888984 -58.51144)
		(width 0.1397)
		(layer "In5.Cu")
		(net "PCIE_TX_CAP_P29")
	)
	(segment
		(start 290.100512 -182.05323)
		(end 288.567368 -190.747396)
		(width 0.1397)
		(layer "In5.Cu")
		(net "PCIE_TX_CAP_P29")
	)
	(segment
		(start 259.7404 -58.170318)
		(end 260.956044 -58.170318)
		(width 0.1397)
		(layer "In5.Cu")
		(net "PCIE_TX_CAP_P29")
	)
	(segment
		(start 257.515106 -57.698132)
		(end 257.526536 -57.756044)
		(width 0.1016)
		(layer "In5.Cu")
		(net "PCIE_TX_CAP_P29")
	)
	(segment
		(start 257.472942 -57.48909)
		(end 257.496056 -57.544716)
		(width 0.1016)
		(layer "In5.Cu")
		(net "PCIE_TX_CAP_P29")
	)
	(segment
		(start 262.888984 -58.51144)
		(end 265.211052 -60.137294)
		(width 0.1397)
		(layer "In5.Cu")
		(net "PCIE_TX_CAP_P29")
	)
	(segment
		(start 288.567368 -190.747396)
		(end 291.009578 -204.597)
		(width 0.1397)
		(layer "In5.Cu")
		(net "PCIE_TX_CAP_P29")
	)
	(segment
		(start 257.513582 -57.632854)
		(end 257.513582 -57.682638)
		(width 0.1016)
		(layer "In5.Cu")
		(net "PCIE_TX_CAP_P29")
	)
	(segment
		(start 291.009578 -204.597)
		(end 290.334954 -208.422494)
		(width 0.1397)
		(layer "In5.Cu")
		(net "PCIE_TX_CAP_P29")
	)
	(arc
		(start 257.217926 -57.381648)
		(mid 257.244613 -57.363816)
		(end 257.276092 -57.357518)
		(width 0.1016)
		(layer "In5.Cu")
		(net "PCIE_TX_CAP_P29")
	)
	(arc
		(start 257.76555 -58.036968)
		(mid 257.91525 -58.077966)
		(end 258.069842 -58.091832)
		(width 0.1016)
		(layer "In5.Cu")
		(net "PCIE_TX_CAP_P29")
	)
	(arc
		(start 257.276092 -57.357518)
		(mid 257.301157 -57.358967)
		(end 257.325876 -57.36336)
		(width 0.1016)
		(layer "In5.Cu")
		(net "PCIE_TX_CAP_P29")
	)
	(arc
		(start 290.334954 -210.313778)
		(mid 290.272233 -210.6291)
		(end 290.093654 -210.896454)
		(width 0.1397)
		(layer "In5.Cu")
		(net "PCIE_TX_CAP_P29")
	)
	(arc
		(start 259.576062 -58.091832)
		(mid 259.667124 -58.112458)
		(end 259.7404 -58.170318)
		(width 0.1016)
		(layer "In5.Cu")
		(net "PCIE_TX_CAP_P29")
	)
	(arc
		(start 257.513582 -57.682638)
		(mid 257.513959 -57.690423)
		(end 257.515106 -57.698132)
		(width 0.1016)
		(layer "In5.Cu")
		(net "PCIE_TX_CAP_P29")
	)
	(arc
		(start 257.526536 -57.756044)
		(mid 257.609465 -57.927623)
		(end 257.76555 -58.036968)
		(width 0.1016)
		(layer "In5.Cu")
		(net "PCIE_TX_CAP_P29")
	)
	(arc
		(start 257.496056 -57.544716)
		(mid 257.509158 -57.587922)
		(end 257.513582 -57.632854)
		(width 0.1016)
		(layer "In5.Cu")
		(net "PCIE_TX_CAP_P29")
	)
	(arc
		(start 257.325876 -57.36336)
		(mid 257.414538 -57.408545)
		(end 257.472942 -57.48909)
		(width 0.1016)
		(layer "In5.Cu")
		(net "PCIE_TX_CAP_P29")
	)
	(segment
		(start 293.541196 -211.5312)
		(end 293.541196 -211.297266)
		(width 0.136652)
		(layer "F.Cu")
		(net "PCIE_TX_CAP_P28")
	)
	(segment
		(start 293.191946 -211.975954)
		(end 293.473632 -211.694268)
		(width 0.136652)
		(layer "F.Cu")
		(net "PCIE_TX_CAP_P28")
	)
	(segment
		(start 257.599942 -55.999888)
		(end 258.099814 -56.49976)
		(width 0.136652)
		(layer "F.Cu")
		(net "PCIE_TX_CAP_P28")
	)
	(segment
		(start 293.432992 -211.035646)
		(end 293.293546 -210.896454)
		(width 0.136652)
		(layer "F.Cu")
		(net "PCIE_TX_CAP_P28")
	)
	(via
		(at 293.293546 -210.896454)
		(size 0.508)
		(drill 0.254)
		(layers "F.Cu" "B.Cu")
		(net "PCIE_TX_CAP_P28")
	)
	(via
		(at 258.099814 -56.49976)
		(size 0.4572)
		(drill 0.2032)
		(layers "F.Cu" "B.Cu")
		(net "PCIE_TX_CAP_P28")
	)
	(arc
		(start 293.541196 -211.297266)
		(mid 293.513128 -211.155687)
		(end 293.432992 -211.035646)
		(width 0.136652)
		(layer "F.Cu")
		(net "PCIE_TX_CAP_P28")
	)
	(arc
		(start 293.473632 -211.694268)
		(mid 293.523623 -211.619452)
		(end 293.541196 -211.5312)
		(width 0.136652)
		(layer "F.Cu")
		(net "PCIE_TX_CAP_P28")
	)
	(segment
		(start 292.588188 -188.940186)
		(end 291.64788 -194.273932)
		(width 0.1397)
		(layer "In5.Cu")
		(net "PCIE_TX_CAP_P28")
	)
	(segment
		(start 260.731762 -57.179718)
		(end 263.40689 -57.65165)
		(width 0.1397)
		(layer "In5.Cu")
		(net "PCIE_TX_CAP_P28")
	)
	(segment
		(start 293.949374 -207.3275)
		(end 293.534846 -209.679286)
		(width 0.1397)
		(layer "In5.Cu")
		(net "PCIE_TX_CAP_P28")
	)
	(segment
		(start 291.64788 -194.273932)
		(end 293.949374 -207.3275)
		(width 0.1397)
		(layer "In5.Cu")
		(net "PCIE_TX_CAP_P28")
	)
	(segment
		(start 259.239766 -57.304686)
		(end 259.725922 -57.304686)
		(width 0.1016)
		(layer "In5.Cu")
		(net "PCIE_TX_CAP_P28")
	)
	(segment
		(start 263.40689 -57.65165)
		(end 266.032488 -59.490102)
		(width 0.1397)
		(layer "In5.Cu")
		(net "PCIE_TX_CAP_P28")
	)
	(segment
		(start 271.018254 -66.610484)
		(end 292.588188 -188.940186)
		(width 0.1397)
		(layer "In5.Cu")
		(net "PCIE_TX_CAP_P28")
	)
	(segment
		(start 293.534846 -209.679286)
		(end 293.534846 -210.313778)
		(width 0.1397)
		(layer "In5.Cu")
		(net "PCIE_TX_CAP_P28")
	)
	(segment
		(start 266.032488 -59.490102)
		(end 271.018254 -66.610484)
		(width 0.1397)
		(layer "In5.Cu")
		(net "PCIE_TX_CAP_P28")
	)
	(segment
		(start 260.027674 -57.179718)
		(end 260.731762 -57.179718)
		(width 0.1397)
		(layer "In5.Cu")
		(net "PCIE_TX_CAP_P28")
	)
	(segment
		(start 258.308856 -56.586374)
		(end 258.875784 -57.153556)
		(width 0.1016)
		(layer "In5.Cu")
		(net "PCIE_TX_CAP_P28")
	)
	(arc
		(start 258.941824 -57.209436)
		(mid 259.083367 -57.280297)
		(end 259.239766 -57.304686)
		(width 0.1016)
		(layer "In5.Cu")
		(net "PCIE_TX_CAP_P28")
	)
	(arc
		(start 259.725922 -57.304686)
		(mid 259.889221 -57.272204)
		(end 260.027674 -57.179718)
		(width 0.1016)
		(layer "In5.Cu")
		(net "PCIE_TX_CAP_P28")
	)
	(arc
		(start 293.534846 -210.313778)
		(mid 293.472125 -210.6291)
		(end 293.293546 -210.896454)
		(width 0.1397)
		(layer "In5.Cu")
		(net "PCIE_TX_CAP_P28")
	)
	(arc
		(start 258.875784 -57.153556)
		(mid 258.907645 -57.182865)
		(end 258.941824 -57.209436)
		(width 0.1016)
		(layer "In5.Cu")
		(net "PCIE_TX_CAP_P28")
	)
	(arc
		(start 258.099814 -56.49976)
		(mid 258.212957 -56.522265)
		(end 258.308856 -56.586374)
		(width 0.1016)
		(layer "In5.Cu")
		(net "PCIE_TX_CAP_P28")
	)
	(segment
		(start 298.792138 -211.975954)
		(end 299.073824 -211.694268)
		(width 0.136652)
		(layer "F.Cu")
		(net "PCIE_TX_CAP_P27")
	)
	(segment
		(start 256.599944 -54.99989)
		(end 257.099816 -55.499762)
		(width 0.136652)
		(layer "F.Cu")
		(net "PCIE_TX_CAP_P27")
	)
	(segment
		(start 299.065188 -211.067904)
		(end 298.893738 -210.896454)
		(width 0.136652)
		(layer "F.Cu")
		(net "PCIE_TX_CAP_P27")
	)
	(segment
		(start 299.141388 -211.5312)
		(end 299.141388 -211.2518)
		(width 0.136652)
		(layer "F.Cu")
		(net "PCIE_TX_CAP_P27")
	)
	(via
		(at 298.893738 -210.896454)
		(size 0.508)
		(drill 0.254)
		(layers "F.Cu" "B.Cu")
		(net "PCIE_TX_CAP_P27")
	)
	(via
		(at 257.099816 -55.499762)
		(size 0.4572)
		(drill 0.2032)
		(layers "F.Cu" "B.Cu")
		(net "PCIE_TX_CAP_P27")
	)
	(arc
		(start 299.141388 -211.2518)
		(mid 299.121589 -211.152266)
		(end 299.065188 -211.067904)
		(width 0.136652)
		(layer "F.Cu")
		(net "PCIE_TX_CAP_P27")
	)
	(arc
		(start 299.073824 -211.694268)
		(mid 299.123815 -211.619452)
		(end 299.141388 -211.5312)
		(width 0.136652)
		(layer "F.Cu")
		(net "PCIE_TX_CAP_P27")
	)
	(segment
		(start 257.526536 -55.756048)
		(end 257.515106 -55.698136)
		(width 0.1016)
		(layer "In5.Cu")
		(net "PCIE_TX_CAP_P27")
	)
	(segment
		(start 257.496056 -55.54472)
		(end 257.472942 -55.489094)
		(width 0.1016)
		(layer "In5.Cu")
		(net "PCIE_TX_CAP_P27")
	)
	(segment
		(start 299.384466 -207.137)
		(end 298.89577 -204.366114)
		(width 0.1397)
		(layer "In5.Cu")
		(net "PCIE_TX_CAP_P27")
	)
	(segment
		(start 264.122408 -56.178704)
		(end 262.89 -55.961534)
		(width 0.1397)
		(layer "In5.Cu")
		(net "PCIE_TX_CAP_P27")
	)
	(segment
		(start 266.7381 -58.010044)
		(end 264.122408 -56.178704)
		(width 0.1397)
		(layer "In5.Cu")
		(net "PCIE_TX_CAP_P27")
	)
	(segment
		(start 272.15592 -65.747392)
		(end 266.7381 -58.010044)
		(width 0.1397)
		(layer "In5.Cu")
		(net "PCIE_TX_CAP_P27")
	)
	(segment
		(start 262.89 -55.961534)
		(end 261.704582 -56.170322)
		(width 0.1397)
		(layer "In5.Cu")
		(net "PCIE_TX_CAP_P27")
	)
	(segment
		(start 257.217926 -55.381652)
		(end 257.099816 -55.499762)
		(width 0.1016)
		(layer "In5.Cu")
		(net "PCIE_TX_CAP_P27")
	)
	(segment
		(start 299.135038 -210.313778)
		(end 299.135038 -208.551272)
		(width 0.1397)
		(layer "In5.Cu")
		(net "PCIE_TX_CAP_P27")
	)
	(segment
		(start 292.333426 -180.181504)
		(end 272.15592 -65.747392)
		(width 0.1397)
		(layer "In5.Cu")
		(net "PCIE_TX_CAP_P27")
	)
	(segment
		(start 257.513582 -55.682642)
		(end 257.513582 -55.632858)
		(width 0.1016)
		(layer "In5.Cu")
		(net "PCIE_TX_CAP_P27")
	)
	(segment
		(start 259.52577 -56.091836)
		(end 258.069842 -56.091836)
		(width 0.1016)
		(layer "In5.Cu")
		(net "PCIE_TX_CAP_P27")
	)
	(segment
		(start 300.019466 -197.993)
		(end 298.408852 -188.858144)
		(width 0.1397)
		(layer "In5.Cu")
		(net "PCIE_TX_CAP_P27")
	)
	(segment
		(start 299.135038 -208.551272)
		(end 299.384466 -207.137)
		(width 0.1397)
		(layer "In5.Cu")
		(net "PCIE_TX_CAP_P27")
	)
	(segment
		(start 298.89577 -204.366114)
		(end 300.019466 -197.993)
		(width 0.1397)
		(layer "In5.Cu")
		(net "PCIE_TX_CAP_P27")
	)
	(segment
		(start 261.704582 -56.170322)
		(end 259.7404 -56.170322)
		(width 0.1397)
		(layer "In5.Cu")
		(net "PCIE_TX_CAP_P27")
	)
	(segment
		(start 298.408852 -188.858144)
		(end 292.333426 -180.181504)
		(width 0.1397)
		(layer "In5.Cu")
		(net "PCIE_TX_CAP_P27")
	)
	(arc
		(start 258.069842 -56.091836)
		(mid 257.915251 -56.077964)
		(end 257.76555 -56.036972)
		(width 0.1016)
		(layer "In5.Cu")
		(net "PCIE_TX_CAP_P27")
	)
	(arc
		(start 259.7404 -56.170322)
		(mid 259.640034 -56.112078)
		(end 259.52577 -56.091836)
		(width 0.1016)
		(layer "In5.Cu")
		(net "PCIE_TX_CAP_P27")
	)
	(arc
		(start 257.513582 -55.632858)
		(mid 257.509158 -55.587926)
		(end 257.496056 -55.54472)
		(width 0.1016)
		(layer "In5.Cu")
		(net "PCIE_TX_CAP_P27")
	)
	(arc
		(start 298.893738 -210.896454)
		(mid 299.072365 -210.62912)
		(end 299.135038 -210.313778)
		(width 0.1397)
		(layer "In5.Cu")
		(net "PCIE_TX_CAP_P27")
	)
	(arc
		(start 257.325876 -55.363364)
		(mid 257.301156 -55.358977)
		(end 257.276092 -55.357522)
		(width 0.1016)
		(layer "In5.Cu")
		(net "PCIE_TX_CAP_P27")
	)
	(arc
		(start 257.276092 -55.357522)
		(mid 257.244599 -55.363786)
		(end 257.217926 -55.381652)
		(width 0.1016)
		(layer "In5.Cu")
		(net "PCIE_TX_CAP_P27")
	)
	(arc
		(start 257.472942 -55.489094)
		(mid 257.414479 -55.408619)
		(end 257.325876 -55.363364)
		(width 0.1016)
		(layer "In5.Cu")
		(net "PCIE_TX_CAP_P27")
	)
	(arc
		(start 257.515106 -55.698136)
		(mid 257.513978 -55.690425)
		(end 257.513582 -55.682642)
		(width 0.1016)
		(layer "In5.Cu")
		(net "PCIE_TX_CAP_P27")
	)
	(arc
		(start 257.76555 -56.036972)
		(mid 257.609448 -55.927642)
		(end 257.526536 -55.756048)
		(width 0.1016)
		(layer "In5.Cu")
		(net "PCIE_TX_CAP_P27")
	)
	(segment
		(start 257.599942 -53.999892)
		(end 258.099814 -54.499764)
		(width 0.136652)
		(layer "F.Cu")
		(net "PCIE_TX_CAP_P26")
	)
	(segment
		(start 302.24349 -211.046568)
		(end 302.09363 -210.896454)
		(width 0.136652)
		(layer "F.Cu")
		(net "PCIE_TX_CAP_P26")
	)
	(segment
		(start 302.34128 -211.5312)
		(end 302.34128 -211.28228)
		(width 0.136652)
		(layer "F.Cu")
		(net "PCIE_TX_CAP_P26")
	)
	(segment
		(start 301.99203 -211.975954)
		(end 302.273716 -211.694268)
		(width 0.136652)
		(layer "F.Cu")
		(net "PCIE_TX_CAP_P26")
	)
	(via
		(at 302.09363 -210.896454)
		(size 0.508)
		(drill 0.254)
		(layers "F.Cu" "B.Cu")
		(net "PCIE_TX_CAP_P26")
	)
	(via
		(at 258.099814 -54.499764)
		(size 0.4572)
		(drill 0.2032)
		(layers "F.Cu" "B.Cu")
		(net "PCIE_TX_CAP_P26")
	)
	(arc
		(start 302.273716 -211.694268)
		(mid 302.323707 -211.619452)
		(end 302.34128 -211.5312)
		(width 0.136652)
		(layer "F.Cu")
		(net "PCIE_TX_CAP_P26")
	)
	(arc
		(start 302.34128 -211.28228)
		(mid 302.315811 -211.154708)
		(end 302.24349 -211.046568)
		(width 0.136652)
		(layer "F.Cu")
		(net "PCIE_TX_CAP_P26")
	)
	(segment
		(start 258.308856 -54.586378)
		(end 258.875784 -55.15356)
		(width 0.1016)
		(layer "In5.Cu")
		(net "PCIE_TX_CAP_P26")
	)
	(segment
		(start 303.194466 -198.882)
		(end 302.037242 -205.445106)
		(width 0.1397)
		(layer "In5.Cu")
		(net "PCIE_TX_CAP_P26")
	)
	(segment
		(start 273.719544 -65.489328)
		(end 292.903656 -174.426118)
		(width 0.1397)
		(layer "In5.Cu")
		(net "PCIE_TX_CAP_P26")
	)
	(segment
		(start 302.550068 -208.35366)
		(end 302.33493 -209.574892)
		(width 0.1397)
		(layer "In5.Cu")
		(net "PCIE_TX_CAP_P26")
	)
	(segment
		(start 260.789674 -55.179722)
		(end 263.526016 -54.697376)
		(width 0.1397)
		(layer "In5.Cu")
		(net "PCIE_TX_CAP_P26")
	)
	(segment
		(start 301.45101 -188.994796)
		(end 303.194466 -198.882)
		(width 0.1397)
		(layer "In5.Cu")
		(net "PCIE_TX_CAP_P26")
	)
	(segment
		(start 292.903656 -174.426118)
		(end 293.51859 -175.739298)
		(width 0.1397)
		(layer "In5.Cu")
		(net "PCIE_TX_CAP_P26")
	)
	(segment
		(start 264.227564 -54.821074)
		(end 268.194536 -57.598818)
		(width 0.1397)
		(layer "In5.Cu")
		(net "PCIE_TX_CAP_P26")
	)
	(segment
		(start 259.239766 -55.30469)
		(end 259.725922 -55.30469)
		(width 0.1016)
		(layer "In5.Cu")
		(net "PCIE_TX_CAP_P26")
	)
	(segment
		(start 295.455086 -180.431186)
		(end 301.45101 -188.994796)
		(width 0.1397)
		(layer "In5.Cu")
		(net "PCIE_TX_CAP_P26")
	)
	(segment
		(start 302.037242 -205.445106)
		(end 302.550068 -208.35366)
		(width 0.1397)
		(layer "In5.Cu")
		(net "PCIE_TX_CAP_P26")
	)
	(segment
		(start 293.5224 -175.746918)
		(end 295.455086 -180.431186)
		(width 0.1397)
		(layer "In5.Cu")
		(net "PCIE_TX_CAP_P26")
	)
	(segment
		(start 293.51859 -175.739298)
		(end 293.518844 -175.739298)
		(width 0.1397)
		(layer "In5.Cu")
		(net "PCIE_TX_CAP_P26")
	)
	(segment
		(start 268.194536 -57.598818)
		(end 273.719544 -65.489328)
		(width 0.1397)
		(layer "In5.Cu")
		(net "PCIE_TX_CAP_P26")
	)
	(segment
		(start 302.33493 -209.574892)
		(end 302.33493 -210.313778)
		(width 0.1397)
		(layer "In5.Cu")
		(net "PCIE_TX_CAP_P26")
	)
	(segment
		(start 293.518844 -175.739298)
		(end 293.52113 -175.744124)
		(width 0.1397)
		(layer "In5.Cu")
		(net "PCIE_TX_CAP_P26")
	)
	(segment
		(start 293.521892 -175.745902)
		(end 293.5224 -175.746918)
		(width 0.1397)
		(layer "In5.Cu")
		(net "PCIE_TX_CAP_P26")
	)
	(segment
		(start 263.877298 -54.759352)
		(end 264.227564 -54.821074)
		(width 0.1397)
		(layer "In5.Cu")
		(net "PCIE_TX_CAP_P26")
	)
	(segment
		(start 260.027674 -55.179722)
		(end 260.789674 -55.179722)
		(width 0.1397)
		(layer "In5.Cu")
		(net "PCIE_TX_CAP_P26")
	)
	(segment
		(start 293.52113 -175.744124)
		(end 293.521892 -175.745902)
		(width 0.1397)
		(layer "In5.Cu")
		(net "PCIE_TX_CAP_P26")
	)
	(segment
		(start 263.526016 -54.697376)
		(end 263.877298 -54.759352)
		(width 0.1397)
		(layer "In5.Cu")
		(net "PCIE_TX_CAP_P26")
	)
	(arc
		(start 258.941824 -55.20944)
		(mid 259.083367 -55.280301)
		(end 259.239766 -55.30469)
		(width 0.1016)
		(layer "In5.Cu")
		(net "PCIE_TX_CAP_P26")
	)
	(arc
		(start 302.33493 -210.313778)
		(mid 302.272209 -210.6291)
		(end 302.09363 -210.896454)
		(width 0.1397)
		(layer "In5.Cu")
		(net "PCIE_TX_CAP_P26")
	)
	(arc
		(start 259.725922 -55.30469)
		(mid 259.889221 -55.272208)
		(end 260.027674 -55.179722)
		(width 0.1016)
		(layer "In5.Cu")
		(net "PCIE_TX_CAP_P26")
	)
	(arc
		(start 258.875784 -55.15356)
		(mid 258.907645 -55.182869)
		(end 258.941824 -55.20944)
		(width 0.1016)
		(layer "In5.Cu")
		(net "PCIE_TX_CAP_P26")
	)
	(arc
		(start 258.099814 -54.499764)
		(mid 258.212957 -54.522269)
		(end 258.308856 -54.586378)
		(width 0.1016)
		(layer "In5.Cu")
		(net "PCIE_TX_CAP_P26")
	)
	(segment
		(start 256.599944 -52.999894)
		(end 257.099816 -53.499766)
		(width 0.136652)
		(layer "F.Cu")
		(net "PCIE_TX_CAP_P25")
	)
	(segment
		(start 309.992014 -211.975954)
		(end 309.992268 -211.975954)
		(width 0.136652)
		(layer "F.Cu")
		(net "PCIE_TX_CAP_P25")
	)
	(segment
		(start 309.992268 -211.975954)
		(end 310.273954 -211.694268)
		(width 0.136652)
		(layer "F.Cu")
		(net "PCIE_TX_CAP_P25")
	)
	(segment
		(start 310.244236 -211.047076)
		(end 310.093868 -210.896454)
		(width 0.136652)
		(layer "F.Cu")
		(net "PCIE_TX_CAP_P25")
	)
	(segment
		(start 310.341518 -211.5312)
		(end 310.341518 -211.281518)
		(width 0.136652)
		(layer "F.Cu")
		(net "PCIE_TX_CAP_P25")
	)
	(via
		(at 257.099816 -53.499766)
		(size 0.4572)
		(drill 0.2032)
		(layers "F.Cu" "B.Cu")
		(net "PCIE_TX_CAP_P25")
	)
	(via
		(at 310.093868 -210.896454)
		(size 0.508)
		(drill 0.254)
		(layers "F.Cu" "B.Cu")
		(net "PCIE_TX_CAP_P25")
	)
	(arc
		(start 310.341518 -211.281518)
		(mid 310.316184 -211.154626)
		(end 310.244236 -211.047076)
		(width 0.136652)
		(layer "F.Cu")
		(net "PCIE_TX_CAP_P25")
	)
	(arc
		(start 310.273954 -211.694268)
		(mid 310.323945 -211.619452)
		(end 310.341518 -211.5312)
		(width 0.136652)
		(layer "F.Cu")
		(net "PCIE_TX_CAP_P25")
	)
	(segment
		(start 258.069842 -54.09184)
		(end 259.550916 -54.09184)
		(width 0.1016)
		(layer "In5.Cu")
		(net "PCIE_TX_CAP_P25")
	)
	(segment
		(start 293.994586 -170.305476)
		(end 308.683406 -191.286384)
		(width 0.1397)
		(layer "In5.Cu")
		(net "PCIE_TX_CAP_P25")
	)
	(segment
		(start 257.472942 -53.489098)
		(end 257.496056 -53.544724)
		(width 0.1016)
		(layer "In5.Cu")
		(net "PCIE_TX_CAP_P25")
	)
	(segment
		(start 264.735818 -54.016148)
		(end 269.12316 -57.088278)
		(width 0.1397)
		(layer "In5.Cu")
		(net "PCIE_TX_CAP_P25")
	)
	(segment
		(start 257.099816 -53.499766)
		(end 257.217926 -53.381656)
		(width 0.1016)
		(layer "In5.Cu")
		(net "PCIE_TX_CAP_P25")
	)
	(segment
		(start 310.795416 -203.263754)
		(end 310.179466 -206.756)
		(width 0.1397)
		(layer "In5.Cu")
		(net "PCIE_TX_CAP_P25")
	)
	(segment
		(start 275.682964 -66.456814)
		(end 293.994586 -170.305476)
		(width 0.1397)
		(layer "In5.Cu")
		(net "PCIE_TX_CAP_P25")
	)
	(segment
		(start 257.513582 -53.632862)
		(end 257.513582 -53.682646)
		(width 0.1016)
		(layer "In5.Cu")
		(net "PCIE_TX_CAP_P25")
	)
	(segment
		(start 263.525 -53.802534)
		(end 264.735818 -54.016148)
		(width 0.1397)
		(layer "In5.Cu")
		(net "PCIE_TX_CAP_P25")
	)
	(segment
		(start 257.515106 -53.69814)
		(end 257.526536 -53.756052)
		(width 0.1016)
		(layer "In5.Cu")
		(net "PCIE_TX_CAP_P25")
	)
	(segment
		(start 310.335168 -210.0326)
		(end 310.335168 -210.313778)
		(width 0.1397)
		(layer "In5.Cu")
		(net "PCIE_TX_CAP_P25")
	)
	(segment
		(start 310.546242 -208.835244)
		(end 310.335676 -210.032092)
		(width 0.1397)
		(layer "In5.Cu")
		(net "PCIE_TX_CAP_P25")
	)
	(segment
		(start 310.335676 -210.032092)
		(end 310.335168 -210.0326)
		(width 0.1397)
		(layer "In5.Cu")
		(net "PCIE_TX_CAP_P25")
	)
	(segment
		(start 259.7404 -54.170326)
		(end 261.437628 -54.170326)
		(width 0.1397)
		(layer "In5.Cu")
		(net "PCIE_TX_CAP_P25")
	)
	(segment
		(start 269.12316 -57.088278)
		(end 275.682964 -66.456814)
		(width 0.1397)
		(layer "In5.Cu")
		(net "PCIE_TX_CAP_P25")
	)
	(segment
		(start 308.683406 -191.286384)
		(end 310.795416 -203.263754)
		(width 0.1397)
		(layer "In5.Cu")
		(net "PCIE_TX_CAP_P25")
	)
	(segment
		(start 261.437628 -54.170326)
		(end 263.525 -53.802534)
		(width 0.1397)
		(layer "In5.Cu")
		(net "PCIE_TX_CAP_P25")
	)
	(segment
		(start 310.179466 -206.756)
		(end 310.546242 -208.835244)
		(width 0.1397)
		(layer "In5.Cu")
		(net "PCIE_TX_CAP_P25")
	)
	(arc
		(start 257.217926 -53.381656)
		(mid 257.244613 -53.363824)
		(end 257.276092 -53.357526)
		(width 0.1016)
		(layer "In5.Cu")
		(net "PCIE_TX_CAP_P25")
	)
	(arc
		(start 257.325876 -53.363368)
		(mid 257.414538 -53.408553)
		(end 257.472942 -53.489098)
		(width 0.1016)
		(layer "In5.Cu")
		(net "PCIE_TX_CAP_P25")
	)
	(arc
		(start 257.76555 -54.036976)
		(mid 257.91525 -54.077974)
		(end 258.069842 -54.09184)
		(width 0.1016)
		(layer "In5.Cu")
		(net "PCIE_TX_CAP_P25")
	)
	(arc
		(start 310.335168 -210.313778)
		(mid 310.272447 -210.6291)
		(end 310.093868 -210.896454)
		(width 0.1397)
		(layer "In5.Cu")
		(net "PCIE_TX_CAP_P25")
	)
	(arc
		(start 257.513582 -53.682646)
		(mid 257.513959 -53.690431)
		(end 257.515106 -53.69814)
		(width 0.1016)
		(layer "In5.Cu")
		(net "PCIE_TX_CAP_P25")
	)
	(arc
		(start 257.276092 -53.357526)
		(mid 257.301157 -53.358975)
		(end 257.325876 -53.363368)
		(width 0.1016)
		(layer "In5.Cu")
		(net "PCIE_TX_CAP_P25")
	)
	(arc
		(start 257.496056 -53.544724)
		(mid 257.509158 -53.58793)
		(end 257.513582 -53.632862)
		(width 0.1016)
		(layer "In5.Cu")
		(net "PCIE_TX_CAP_P25")
	)
	(arc
		(start 257.526536 -53.756052)
		(mid 257.609465 -53.927631)
		(end 257.76555 -54.036976)
		(width 0.1016)
		(layer "In5.Cu")
		(net "PCIE_TX_CAP_P25")
	)
	(arc
		(start 259.550916 -54.09184)
		(mid 259.653464 -54.112238)
		(end 259.7404 -54.170326)
		(width 0.1016)
		(layer "In5.Cu")
		(net "PCIE_TX_CAP_P25")
	)
	(segment
		(start 313.447176 -211.050124)
		(end 313.29376 -210.896454)
		(width 0.136652)
		(layer "F.Cu")
		(net "PCIE_TX_CAP_P24")
	)
	(segment
		(start 257.599942 -51.999896)
		(end 258.099814 -52.499768)
		(width 0.136652)
		(layer "F.Cu")
		(net "PCIE_TX_CAP_P24")
	)
	(segment
		(start 313.54141 -211.5312)
		(end 313.54141 -211.2772)
		(width 0.136652)
		(layer "F.Cu")
		(net "PCIE_TX_CAP_P24")
	)
	(segment
		(start 313.19216 -211.975954)
		(end 313.473846 -211.694268)
		(width 0.136652)
		(layer "F.Cu")
		(net "PCIE_TX_CAP_P24")
	)
	(via
		(at 313.29376 -210.896454)
		(size 0.508)
		(drill 0.254)
		(layers "F.Cu" "B.Cu")
		(net "PCIE_TX_CAP_P24")
	)
	(via
		(at 258.099814 -52.499768)
		(size 0.4572)
		(drill 0.2032)
		(layers "F.Cu" "B.Cu")
		(net "PCIE_TX_CAP_P24")
	)
	(arc
		(start 313.473846 -211.694268)
		(mid 313.523837 -211.619452)
		(end 313.54141 -211.5312)
		(width 0.136652)
		(layer "F.Cu")
		(net "PCIE_TX_CAP_P24")
	)
	(arc
		(start 313.54141 -211.2772)
		(mid 313.516869 -211.154294)
		(end 313.447176 -211.050124)
		(width 0.136652)
		(layer "F.Cu")
		(net "PCIE_TX_CAP_P24")
	)
	(segment
		(start 263.654032 -52.674774)
		(end 265.577066 -53.013864)
		(width 0.1397)
		(layer "In5.Cu")
		(net "PCIE_TX_CAP_P24")
	)
	(segment
		(start 313.055 -206.883)
		(end 313.53506 -209.605626)
		(width 0.1397)
		(layer "In5.Cu")
		(net "PCIE_TX_CAP_P24")
	)
	(segment
		(start 260.789674 -53.179726)
		(end 263.654032 -52.674774)
		(width 0.1397)
		(layer "In5.Cu")
		(net "PCIE_TX_CAP_P24")
	)
	(segment
		(start 270.404336 -56.393842)
		(end 277.406608 -66.393822)
		(width 0.1397)
		(layer "In5.Cu")
		(net "PCIE_TX_CAP_P24")
	)
	(segment
		(start 313.53506 -209.605626)
		(end 313.53506 -210.313778)
		(width 0.1397)
		(layer "In5.Cu")
		(net "PCIE_TX_CAP_P24")
	)
	(segment
		(start 295.336468 -168.07942)
		(end 311.679844 -191.418718)
		(width 0.1397)
		(layer "In5.Cu")
		(net "PCIE_TX_CAP_P24")
	)
	(segment
		(start 313.730894 -203.050394)
		(end 313.055 -206.883)
		(width 0.1397)
		(layer "In5.Cu")
		(net "PCIE_TX_CAP_P24")
	)
	(segment
		(start 258.308856 -52.586382)
		(end 258.875784 -53.153564)
		(width 0.1016)
		(layer "In5.Cu")
		(net "PCIE_TX_CAP_P24")
	)
	(segment
		(start 277.406608 -66.393822)
		(end 295.336468 -168.07942)
		(width 0.1397)
		(layer "In5.Cu")
		(net "PCIE_TX_CAP_P24")
	)
	(segment
		(start 265.577066 -53.013864)
		(end 270.404336 -56.393842)
		(width 0.1397)
		(layer "In5.Cu")
		(net "PCIE_TX_CAP_P24")
	)
	(segment
		(start 311.679844 -191.418718)
		(end 313.730894 -203.050394)
		(width 0.1397)
		(layer "In5.Cu")
		(net "PCIE_TX_CAP_P24")
	)
	(segment
		(start 260.027674 -53.179726)
		(end 260.789674 -53.179726)
		(width 0.1397)
		(layer "In5.Cu")
		(net "PCIE_TX_CAP_P24")
	)
	(segment
		(start 259.239766 -53.304694)
		(end 259.725922 -53.304694)
		(width 0.1016)
		(layer "In5.Cu")
		(net "PCIE_TX_CAP_P24")
	)
	(arc
		(start 258.099814 -52.499768)
		(mid 258.212957 -52.522273)
		(end 258.308856 -52.586382)
		(width 0.1016)
		(layer "In5.Cu")
		(net "PCIE_TX_CAP_P24")
	)
	(arc
		(start 258.941824 -53.209444)
		(mid 259.083367 -53.280305)
		(end 259.239766 -53.304694)
		(width 0.1016)
		(layer "In5.Cu")
		(net "PCIE_TX_CAP_P24")
	)
	(arc
		(start 313.53506 -210.313778)
		(mid 313.472339 -210.6291)
		(end 313.29376 -210.896454)
		(width 0.1397)
		(layer "In5.Cu")
		(net "PCIE_TX_CAP_P24")
	)
	(arc
		(start 258.875784 -53.153564)
		(mid 258.907645 -53.182873)
		(end 258.941824 -53.209444)
		(width 0.1016)
		(layer "In5.Cu")
		(net "PCIE_TX_CAP_P24")
	)
	(arc
		(start 259.725922 -53.304694)
		(mid 259.889221 -53.272212)
		(end 260.027674 -53.179726)
		(width 0.1016)
		(layer "In5.Cu")
		(net "PCIE_TX_CAP_P24")
	)
	(segment
		(start 316.741556 -211.5312)
		(end 316.741556 -211.306156)
		(width 0.136652)
		(layer "F.Cu")
		(net "PCIE_TX_CAP_P23")
	)
	(segment
		(start 316.392306 -211.975954)
		(end 316.673992 -211.694268)
		(width 0.136652)
		(layer "F.Cu")
		(net "PCIE_TX_CAP_P23")
	)
	(segment
		(start 256.599944 -49.9999)
		(end 257.099816 -50.499772)
		(width 0.136652)
		(layer "F.Cu")
		(net "PCIE_TX_CAP_P23")
	)
	(segment
		(start 316.627002 -211.02955)
		(end 316.493906 -210.896454)
		(width 0.136652)
		(layer "F.Cu")
		(net "PCIE_TX_CAP_P23")
	)
	(segment
		(start 316.392052 -211.975954)
		(end 316.392306 -211.975954)
		(width 0.136652)
		(layer "F.Cu")
		(net "PCIE_TX_CAP_P23")
	)
	(via
		(at 316.493906 -210.896454)
		(size 0.508)
		(drill 0.254)
		(layers "F.Cu" "B.Cu")
		(net "PCIE_TX_CAP_P23")
	)
	(via
		(at 257.099816 -50.499772)
		(size 0.4572)
		(drill 0.2032)
		(layers "F.Cu" "B.Cu")
		(net "PCIE_TX_CAP_P23")
	)
	(arc
		(start 316.673992 -211.694268)
		(mid 316.723983 -211.619452)
		(end 316.741556 -211.5312)
		(width 0.136652)
		(layer "F.Cu")
		(net "PCIE_TX_CAP_P23")
	)
	(arc
		(start 316.741556 -211.306156)
		(mid 316.711781 -211.156466)
		(end 316.627002 -211.02955)
		(width 0.136652)
		(layer "F.Cu")
		(net "PCIE_TX_CAP_P23")
	)
	(segment
		(start 261.08025 -51.170332)
		(end 259.7404 -51.170332)
		(width 0.1397)
		(layer "In5.Cu")
		(net "PCIE_TX_CAP_P23")
	)
	(segment
		(start 316.319662 -194.353688)
		(end 296.932096 -166.66464)
		(width 0.1397)
		(layer "In5.Cu")
		(net "PCIE_TX_CAP_P23")
	)
	(segment
		(start 257.217926 -50.381662)
		(end 257.099816 -50.499772)
		(width 0.1016)
		(layer "In5.Cu")
		(net "PCIE_TX_CAP_P23")
	)
	(segment
		(start 257.513582 -50.682652)
		(end 257.513582 -50.632868)
		(width 0.1016)
		(layer "In5.Cu")
		(net "PCIE_TX_CAP_P23")
	)
	(segment
		(start 316.735206 -209.973418)
		(end 316.891924 -209.082386)
		(width 0.1397)
		(layer "In5.Cu")
		(net "PCIE_TX_CAP_P23")
	)
	(segment
		(start 271.337786 -55.37327)
		(end 265.313414 -51.123342)
		(width 0.1397)
		(layer "In5.Cu")
		(net "PCIE_TX_CAP_P23")
	)
	(segment
		(start 279.317958 -66.769996)
		(end 271.337786 -55.37327)
		(width 0.1397)
		(layer "In5.Cu")
		(net "PCIE_TX_CAP_P23")
	)
	(segment
		(start 264.75436 -50.731928)
		(end 261.08025 -51.170332)
		(width 0.1397)
		(layer "In5.Cu")
		(net "PCIE_TX_CAP_P23")
	)
	(segment
		(start 265.313414 -51.123342)
		(end 264.75436 -50.731928)
		(width 0.1397)
		(layer "In5.Cu")
		(net "PCIE_TX_CAP_P23")
	)
	(segment
		(start 316.891924 -209.082386)
		(end 316.505844 -206.891382)
		(width 0.1397)
		(layer "In5.Cu")
		(net "PCIE_TX_CAP_P23")
	)
	(segment
		(start 257.496056 -50.54473)
		(end 257.472942 -50.489104)
		(width 0.1016)
		(layer "In5.Cu")
		(net "PCIE_TX_CAP_P23")
	)
	(segment
		(start 317.518034 -201.150728)
		(end 316.319662 -194.353688)
		(width 0.1397)
		(layer "In5.Cu")
		(net "PCIE_TX_CAP_P23")
	)
	(segment
		(start 259.525516 -51.091846)
		(end 258.069842 -51.091846)
		(width 0.1016)
		(layer "In5.Cu")
		(net "PCIE_TX_CAP_P23")
	)
	(segment
		(start 316.735206 -210.313778)
		(end 316.735206 -209.973418)
		(width 0.1397)
		(layer "In5.Cu")
		(net "PCIE_TX_CAP_P23")
	)
	(segment
		(start 296.932096 -166.66464)
		(end 279.317958 -66.769996)
		(width 0.1397)
		(layer "In5.Cu")
		(net "PCIE_TX_CAP_P23")
	)
	(segment
		(start 257.526536 -50.756058)
		(end 257.515106 -50.698146)
		(width 0.1016)
		(layer "In5.Cu")
		(net "PCIE_TX_CAP_P23")
	)
	(segment
		(start 316.505844 -206.891382)
		(end 317.518034 -201.150728)
		(width 0.1397)
		(layer "In5.Cu")
		(net "PCIE_TX_CAP_P23")
	)
	(arc
		(start 257.76555 -51.036982)
		(mid 257.609448 -50.927652)
		(end 257.526536 -50.756058)
		(width 0.1016)
		(layer "In5.Cu")
		(net "PCIE_TX_CAP_P23")
	)
	(arc
		(start 257.513582 -50.632868)
		(mid 257.509158 -50.587936)
		(end 257.496056 -50.54473)
		(width 0.1016)
		(layer "In5.Cu")
		(net "PCIE_TX_CAP_P23")
	)
	(arc
		(start 259.7404 -51.170332)
		(mid 259.639896 -51.112098)
		(end 259.525516 -51.091846)
		(width 0.1016)
		(layer "In5.Cu")
		(net "PCIE_TX_CAP_P23")
	)
	(arc
		(start 316.493906 -210.896454)
		(mid 316.672533 -210.62912)
		(end 316.735206 -210.313778)
		(width 0.1397)
		(layer "In5.Cu")
		(net "PCIE_TX_CAP_P23")
	)
	(arc
		(start 257.515106 -50.698146)
		(mid 257.513978 -50.690435)
		(end 257.513582 -50.682652)
		(width 0.1016)
		(layer "In5.Cu")
		(net "PCIE_TX_CAP_P23")
	)
	(arc
		(start 258.069842 -51.091846)
		(mid 257.915251 -51.077974)
		(end 257.76555 -51.036982)
		(width 0.1016)
		(layer "In5.Cu")
		(net "PCIE_TX_CAP_P23")
	)
	(arc
		(start 257.276092 -50.357532)
		(mid 257.244599 -50.363796)
		(end 257.217926 -50.381662)
		(width 0.1016)
		(layer "In5.Cu")
		(net "PCIE_TX_CAP_P23")
	)
	(arc
		(start 257.325876 -50.363374)
		(mid 257.301156 -50.358987)
		(end 257.276092 -50.357532)
		(width 0.1016)
		(layer "In5.Cu")
		(net "PCIE_TX_CAP_P23")
	)
	(arc
		(start 257.472942 -50.489104)
		(mid 257.414479 -50.408629)
		(end 257.325876 -50.363374)
		(width 0.1016)
		(layer "In5.Cu")
		(net "PCIE_TX_CAP_P23")
	)
	(segment
		(start 319.827148 -211.030058)
		(end 319.693798 -210.896454)
		(width 0.136652)
		(layer "F.Cu")
		(net "PCIE_TX_CAP_P22")
	)
	(segment
		(start 319.941448 -211.5312)
		(end 319.941448 -211.305648)
		(width 0.136652)
		(layer "F.Cu")
		(net "PCIE_TX_CAP_P22")
	)
	(segment
		(start 319.592198 -211.975954)
		(end 319.873884 -211.694268)
		(width 0.136652)
		(layer "F.Cu")
		(net "PCIE_TX_CAP_P22")
	)
	(segment
		(start 257.599942 -48.999902)
		(end 258.099814 -49.499774)
		(width 0.136652)
		(layer "F.Cu")
		(net "PCIE_TX_CAP_P22")
	)
	(via
		(at 319.693798 -210.896454)
		(size 0.508)
		(drill 0.254)
		(layers "F.Cu" "B.Cu")
		(net "PCIE_TX_CAP_P22")
	)
	(via
		(at 258.099814 -49.499774)
		(size 0.4572)
		(drill 0.2032)
		(layers "F.Cu" "B.Cu")
		(net "PCIE_TX_CAP_P22")
	)
	(arc
		(start 319.873884 -211.694268)
		(mid 319.923875 -211.619452)
		(end 319.941448 -211.5312)
		(width 0.136652)
		(layer "F.Cu")
		(net "PCIE_TX_CAP_P22")
	)
	(arc
		(start 319.941448 -211.305648)
		(mid 319.911686 -211.156497)
		(end 319.827148 -211.030058)
		(width 0.136652)
		(layer "F.Cu")
		(net "PCIE_TX_CAP_P22")
	)
	(segment
		(start 319.85204 -206.426054)
		(end 321.164204 -204.553058)
		(width 0.1397)
		(layer "In5.Cu")
		(net "PCIE_TX_CAP_P22")
	)
	(segment
		(start 297.20794 -158.682436)
		(end 281.042364 -67.004184)
		(width 0.1397)
		(layer "In5.Cu")
		(net "PCIE_TX_CAP_P22")
	)
	(segment
		(start 272.264886 -54.468522)
		(end 265.59891 -49.801018)
		(width 0.1397)
		(layer "In5.Cu")
		(net "PCIE_TX_CAP_P22")
	)
	(segment
		(start 321.531742 -202.468988)
		(end 321.751706 -201.222356)
		(width 0.1397)
		(layer "In5.Cu")
		(net "PCIE_TX_CAP_P22")
	)
	(segment
		(start 264.194544 -49.553368)
		(end 260.64083 -50.179732)
		(width 0.1397)
		(layer "In5.Cu")
		(net "PCIE_TX_CAP_P22")
	)
	(segment
		(start 321.751706 -201.222356)
		(end 321.971162 -199.976232)
		(width 0.1397)
		(layer "In5.Cu")
		(net "PCIE_TX_CAP_P22")
	)
	(segment
		(start 321.164204 -204.553058)
		(end 321.258184 -204.019658)
		(width 0.1397)
		(layer "In5.Cu")
		(net "PCIE_TX_CAP_P22")
	)
	(segment
		(start 321.971162 -199.976232)
		(end 320.574162 -192.05321)
		(width 0.1397)
		(layer "In5.Cu")
		(net "PCIE_TX_CAP_P22")
	)
	(segment
		(start 319.935098 -209.895186)
		(end 319.587626 -207.926686)
		(width 0.1397)
		(layer "In5.Cu")
		(net "PCIE_TX_CAP_P22")
	)
	(segment
		(start 260.64083 -50.179732)
		(end 260.027674 -50.179732)
		(width 0.1397)
		(layer "In5.Cu")
		(net "PCIE_TX_CAP_P22")
	)
	(segment
		(start 320.574162 -192.05321)
		(end 297.20794 -158.682436)
		(width 0.1397)
		(layer "In5.Cu")
		(net "PCIE_TX_CAP_P22")
	)
	(segment
		(start 321.258184 -204.019658)
		(end 321.352418 -203.48575)
		(width 0.1397)
		(layer "In5.Cu")
		(net "PCIE_TX_CAP_P22")
	)
	(segment
		(start 319.935098 -210.313778)
		(end 319.935098 -209.895186)
		(width 0.1397)
		(layer "In5.Cu")
		(net "PCIE_TX_CAP_P22")
	)
	(segment
		(start 258.875784 -50.15357)
		(end 258.308856 -49.586388)
		(width 0.1016)
		(layer "In5.Cu")
		(net "PCIE_TX_CAP_P22")
	)
	(segment
		(start 265.59891 -49.801018)
		(end 264.194544 -49.553368)
		(width 0.1397)
		(layer "In5.Cu")
		(net "PCIE_TX_CAP_P22")
	)
	(segment
		(start 321.352418 -203.48575)
		(end 321.531742 -202.468988)
		(width 0.1397)
		(layer "In5.Cu")
		(net "PCIE_TX_CAP_P22")
	)
	(segment
		(start 319.587626 -207.926686)
		(end 319.85204 -206.426054)
		(width 0.1397)
		(layer "In5.Cu")
		(net "PCIE_TX_CAP_P22")
	)
	(segment
		(start 281.042364 -67.004184)
		(end 272.264886 -54.468522)
		(width 0.1397)
		(layer "In5.Cu")
		(net "PCIE_TX_CAP_P22")
	)
	(segment
		(start 259.725922 -50.3047)
		(end 259.239766 -50.3047)
		(width 0.1016)
		(layer "In5.Cu")
		(net "PCIE_TX_CAP_P22")
	)
	(arc
		(start 260.027674 -50.179732)
		(mid 259.889229 -50.272238)
		(end 259.725922 -50.3047)
		(width 0.1016)
		(layer "In5.Cu")
		(net "PCIE_TX_CAP_P22")
	)
	(arc
		(start 258.941824 -50.20945)
		(mid 258.907632 -50.182895)
		(end 258.875784 -50.15357)
		(width 0.1016)
		(layer "In5.Cu")
		(net "PCIE_TX_CAP_P22")
	)
	(arc
		(start 319.693798 -210.896454)
		(mid 319.872425 -210.62912)
		(end 319.935098 -210.313778)
		(width 0.1397)
		(layer "In5.Cu")
		(net "PCIE_TX_CAP_P22")
	)
	(arc
		(start 258.308856 -49.586388)
		(mid 258.212947 -49.522303)
		(end 258.099814 -49.499774)
		(width 0.1016)
		(layer "In5.Cu")
		(net "PCIE_TX_CAP_P22")
	)
	(arc
		(start 259.239766 -50.3047)
		(mid 259.083368 -50.280308)
		(end 258.941824 -50.20945)
		(width 0.1016)
		(layer "In5.Cu")
		(net "PCIE_TX_CAP_P22")
	)
	(segment
		(start 323.047106 -211.050124)
		(end 322.89369 -210.896454)
		(width 0.136652)
		(layer "F.Cu")
		(net "PCIE_TX_CAP_P21")
	)
	(segment
		(start 256.599944 -47.999904)
		(end 257.099816 -48.499776)
		(width 0.136652)
		(layer "F.Cu")
		(net "PCIE_TX_CAP_P21")
	)
	(segment
		(start 323.14134 -211.5312)
		(end 323.14134 -211.2772)
		(width 0.136652)
		(layer "F.Cu")
		(net "PCIE_TX_CAP_P21")
	)
	(segment
		(start 322.79209 -211.975954)
		(end 323.073776 -211.694268)
		(width 0.136652)
		(layer "F.Cu")
		(net "PCIE_TX_CAP_P21")
	)
	(via
		(at 257.099816 -48.499776)
		(size 0.4572)
		(drill 0.2032)
		(layers "F.Cu" "B.Cu")
		(net "PCIE_TX_CAP_P21")
	)
	(via
		(at 322.89369 -210.896454)
		(size 0.508)
		(drill 0.254)
		(layers "F.Cu" "B.Cu")
		(net "PCIE_TX_CAP_P21")
	)
	(arc
		(start 323.14134 -211.2772)
		(mid 323.116799 -211.154294)
		(end 323.047106 -211.050124)
		(width 0.136652)
		(layer "F.Cu")
		(net "PCIE_TX_CAP_P21")
	)
	(arc
		(start 323.073776 -211.694268)
		(mid 323.123767 -211.619452)
		(end 323.14134 -211.5312)
		(width 0.136652)
		(layer "F.Cu")
		(net "PCIE_TX_CAP_P21")
	)
	(segment
		(start 260.2484 -49.170336)
		(end 259.7404 -49.170336)
		(width 0.1397)
		(layer "In5.Cu")
		(net "PCIE_TX_CAP_P21")
	)
	(segment
		(start 321.632326 -189.74054)
		(end 297.775884 -155.669996)
		(width 0.1397)
		(layer "In5.Cu")
		(net "PCIE_TX_CAP_P21")
	)
	(segment
		(start 257.217926 -48.381666)
		(end 257.099816 -48.499776)
		(width 0.1016)
		(layer "In5.Cu")
		(net "PCIE_TX_CAP_P21")
	)
	(segment
		(start 259.549138 -49.09185)
		(end 258.069842 -49.09185)
		(width 0.1016)
		(layer "In5.Cu")
		(net "PCIE_TX_CAP_P21")
	)
	(segment
		(start 323.13499 -209.7278)
		(end 322.610734 -206.756)
		(width 0.1397)
		(layer "In5.Cu")
		(net "PCIE_TX_CAP_P21")
	)
	(segment
		(start 323.13499 -210.313778)
		(end 323.13499 -209.7278)
		(width 0.1397)
		(layer "In5.Cu")
		(net "PCIE_TX_CAP_P21")
	)
	(segment
		(start 257.513582 -48.682656)
		(end 257.513582 -48.632872)
		(width 0.1016)
		(layer "In5.Cu")
		(net "PCIE_TX_CAP_P21")
	)
	(segment
		(start 265.93546 -48.699674)
		(end 264.4267 -48.433736)
		(width 0.1397)
		(layer "In5.Cu")
		(net "PCIE_TX_CAP_P21")
	)
	(segment
		(start 264.4267 -48.433736)
		(end 260.2484 -49.170336)
		(width 0.1397)
		(layer "In5.Cu")
		(net "PCIE_TX_CAP_P21")
	)
	(segment
		(start 257.496056 -48.544734)
		(end 257.472942 -48.489108)
		(width 0.1016)
		(layer "In5.Cu")
		(net "PCIE_TX_CAP_P21")
	)
	(segment
		(start 257.526536 -48.756062)
		(end 257.515106 -48.69815)
		(width 0.1016)
		(layer "In5.Cu")
		(net "PCIE_TX_CAP_P21")
	)
	(segment
		(start 323.621654 -201.022966)
		(end 321.632326 -189.74054)
		(width 0.1397)
		(layer "In5.Cu")
		(net "PCIE_TX_CAP_P21")
	)
	(segment
		(start 297.775884 -155.669996)
		(end 282.103322 -66.79184)
		(width 0.1397)
		(layer "In5.Cu")
		(net "PCIE_TX_CAP_P21")
	)
	(segment
		(start 322.610734 -206.756)
		(end 323.621654 -201.022966)
		(width 0.1397)
		(layer "In5.Cu")
		(net "PCIE_TX_CAP_P21")
	)
	(segment
		(start 282.103322 -66.79184)
		(end 272.800826 -53.506624)
		(width 0.1397)
		(layer "In5.Cu")
		(net "PCIE_TX_CAP_P21")
	)
	(segment
		(start 272.800826 -53.506624)
		(end 265.93546 -48.699674)
		(width 0.1397)
		(layer "In5.Cu")
		(net "PCIE_TX_CAP_P21")
	)
	(arc
		(start 257.472942 -48.489108)
		(mid 257.414479 -48.408633)
		(end 257.325876 -48.363378)
		(width 0.1016)
		(layer "In5.Cu")
		(net "PCIE_TX_CAP_P21")
	)
	(arc
		(start 257.515106 -48.69815)
		(mid 257.513978 -48.690439)
		(end 257.513582 -48.682656)
		(width 0.1016)
		(layer "In5.Cu")
		(net "PCIE_TX_CAP_P21")
	)
	(arc
		(start 322.89369 -210.896454)
		(mid 323.072317 -210.62912)
		(end 323.13499 -210.313778)
		(width 0.1397)
		(layer "In5.Cu")
		(net "PCIE_TX_CAP_P21")
	)
	(arc
		(start 257.325876 -48.363378)
		(mid 257.301156 -48.358991)
		(end 257.276092 -48.357536)
		(width 0.1016)
		(layer "In5.Cu")
		(net "PCIE_TX_CAP_P21")
	)
	(arc
		(start 257.513582 -48.632872)
		(mid 257.509158 -48.58794)
		(end 257.496056 -48.544734)
		(width 0.1016)
		(layer "In5.Cu")
		(net "PCIE_TX_CAP_P21")
	)
	(arc
		(start 257.276092 -48.357536)
		(mid 257.244599 -48.3638)
		(end 257.217926 -48.381666)
		(width 0.1016)
		(layer "In5.Cu")
		(net "PCIE_TX_CAP_P21")
	)
	(arc
		(start 258.069842 -49.09185)
		(mid 257.915251 -49.077978)
		(end 257.76555 -49.036986)
		(width 0.1016)
		(layer "In5.Cu")
		(net "PCIE_TX_CAP_P21")
	)
	(arc
		(start 259.7404 -49.170336)
		(mid 259.652508 -49.112235)
		(end 259.549138 -49.09185)
		(width 0.1016)
		(layer "In5.Cu")
		(net "PCIE_TX_CAP_P21")
	)
	(arc
		(start 257.76555 -49.036986)
		(mid 257.609448 -48.927656)
		(end 257.526536 -48.756062)
		(width 0.1016)
		(layer "In5.Cu")
		(net "PCIE_TX_CAP_P21")
	)
	(segment
		(start 326.246998 -211.050124)
		(end 326.093582 -210.896454)
		(width 0.136652)
		(layer "F.Cu")
		(net "PCIE_TX_CAP_P20")
	)
	(segment
		(start 326.341232 -211.5312)
		(end 326.341232 -211.2772)
		(width 0.136652)
		(layer "F.Cu")
		(net "PCIE_TX_CAP_P20")
	)
	(segment
		(start 257.599942 -46.999906)
		(end 258.099814 -46.500034)
		(width 0.136652)
		(layer "F.Cu")
		(net "PCIE_TX_CAP_P20")
	)
	(segment
		(start 325.991982 -211.975954)
		(end 326.273668 -211.694268)
		(width 0.136652)
		(layer "F.Cu")
		(net "PCIE_TX_CAP_P20")
	)
	(via
		(at 326.093582 -210.896454)
		(size 0.508)
		(drill 0.254)
		(layers "F.Cu" "B.Cu")
		(net "PCIE_TX_CAP_P20")
	)
	(via
		(at 258.099814 -46.500034)
		(size 0.4572)
		(drill 0.2032)
		(layers "F.Cu" "B.Cu")
		(net "PCIE_TX_CAP_P20")
	)
	(arc
		(start 326.341232 -211.2772)
		(mid 326.316691 -211.154294)
		(end 326.246998 -211.050124)
		(width 0.136652)
		(layer "F.Cu")
		(net "PCIE_TX_CAP_P20")
	)
	(arc
		(start 326.273668 -211.694268)
		(mid 326.323659 -211.619452)
		(end 326.341232 -211.5312)
		(width 0.136652)
		(layer "F.Cu")
		(net "PCIE_TX_CAP_P20")
	)
	(segment
		(start 259.259578 -47.7012)
		(end 263.40562 -46.970188)
		(width 0.1397)
		(layer "In5.Cu")
		(net "PCIE_TX_CAP_P20")
	)
	(segment
		(start 326.334882 -209.616548)
		(end 326.334882 -210.313778)
		(width 0.1397)
		(layer "In5.Cu")
		(net "PCIE_TX_CAP_P20")
	)
	(segment
		(start 324.226174 -189.738254)
		(end 326.689466 -203.708)
		(width 0.1397)
		(layer "In5.Cu")
		(net "PCIE_TX_CAP_P20")
	)
	(segment
		(start 266.770104 -47.56785)
		(end 274.18284 -52.758086)
		(width 0.1397)
		(layer "In5.Cu")
		(net "PCIE_TX_CAP_P20")
	)
	(segment
		(start 326.689466 -203.708)
		(end 325.99122 -207.66786)
		(width 0.1397)
		(layer "In5.Cu")
		(net "PCIE_TX_CAP_P20")
	)
	(segment
		(start 301.031148 -156.61259)
		(end 324.226174 -189.738254)
		(width 0.1397)
		(layer "In5.Cu")
		(net "PCIE_TX_CAP_P20")
	)
	(segment
		(start 258.099814 -46.500034)
		(end 258.341368 -46.741334)
		(width 0.1397)
		(layer "In5.Cu")
		(net "PCIE_TX_CAP_P20")
	)
	(segment
		(start 286.534352 -74.462386)
		(end 301.031148 -156.61259)
		(width 0.1397)
		(layer "In5.Cu")
		(net "PCIE_TX_CAP_P20")
	)
	(segment
		(start 325.99122 -207.66786)
		(end 326.334882 -209.616548)
		(width 0.1397)
		(layer "In5.Cu")
		(net "PCIE_TX_CAP_P20")
	)
	(segment
		(start 274.21713 -52.792376)
		(end 282.35402 -64.41313)
		(width 0.1397)
		(layer "In5.Cu")
		(net "PCIE_TX_CAP_P20")
	)
	(segment
		(start 263.45388 -46.970188)
		(end 266.714478 -47.544736)
		(width 0.1397)
		(layer "In5.Cu")
		(net "PCIE_TX_CAP_P20")
	)
	(segment
		(start 258.582922 -47.341028)
		(end 258.71932 -47.477426)
		(width 0.1397)
		(layer "In5.Cu")
		(net "PCIE_TX_CAP_P20")
	)
	(segment
		(start 258.43484 -46.967394)
		(end 258.43484 -46.98365)
		(width 0.1397)
		(layer "In5.Cu")
		(net "PCIE_TX_CAP_P20")
	)
	(segment
		(start 282.35402 -64.41313)
		(end 286.534352 -74.462386)
		(width 0.1397)
		(layer "In5.Cu")
		(net "PCIE_TX_CAP_P20")
	)
	(arc
		(start 326.334882 -210.313778)
		(mid 326.272161 -210.6291)
		(end 326.093582 -210.896454)
		(width 0.1397)
		(layer "In5.Cu")
		(net "PCIE_TX_CAP_P20")
	)
	(arc
		(start 263.40562 -46.970188)
		(mid 263.42975 -46.968089)
		(end 263.45388 -46.970188)
		(width 0.1397)
		(layer "In5.Cu")
		(net "PCIE_TX_CAP_P20")
	)
	(arc
		(start 274.18284 -52.758086)
		(mid 274.201486 -52.77373)
		(end 274.21713 -52.792376)
		(width 0.1397)
		(layer "In5.Cu")
		(net "PCIE_TX_CAP_P20")
	)
	(arc
		(start 258.43484 -46.98365)
		(mid 258.473316 -47.177081)
		(end 258.582922 -47.341028)
		(width 0.1397)
		(layer "In5.Cu")
		(net "PCIE_TX_CAP_P20")
	)
	(arc
		(start 258.71932 -47.477426)
		(mid 258.967192 -47.643049)
		(end 259.259578 -47.7012)
		(width 0.1397)
		(layer "In5.Cu")
		(net "PCIE_TX_CAP_P20")
	)
	(arc
		(start 258.341368 -46.741334)
		(mid 258.410587 -46.845066)
		(end 258.43484 -46.967394)
		(width 0.1397)
		(layer "In5.Cu")
		(net "PCIE_TX_CAP_P20")
	)
	(arc
		(start 266.714478 -47.544736)
		(mid 266.743563 -47.553238)
		(end 266.770104 -47.56785)
		(width 0.1397)
		(layer "In5.Cu")
		(net "PCIE_TX_CAP_P20")
	)
	(segment
		(start 285.635446 -33.274)
		(end 285.369 -33.274)
		(width 0.136652)
		(layer "F.Cu")
		(net "PCIE_TX_CAP_P2")
	)
	(segment
		(start 253.59995 -30.999938)
		(end 254.099822 -30.500066)
		(width 0.136652)
		(layer "F.Cu")
		(net "PCIE_TX_CAP_P2")
	)
	(segment
		(start 286.0421 -32.9692)
		(end 285.809182 -33.201864)
		(width 0.136652)
		(layer "F.Cu")
		(net "PCIE_TX_CAP_P2")
	)
	(segment
		(start 285.098998 -33.161986)
		(end 284.988254 -33.051496)
		(width 0.136652)
		(layer "F.Cu")
		(net "PCIE_TX_CAP_P2")
	)
	(via
		(at 284.988254 -33.051496)
		(size 0.508)
		(drill 0.254)
		(layers "F.Cu" "B.Cu")
		(net "PCIE_TX_CAP_P2")
	)
	(via
		(at 254.099822 -30.500066)
		(size 0.4572)
		(drill 0.2032)
		(layers "F.Cu" "B.Cu")
		(net "PCIE_TX_CAP_P2")
	)
	(arc
		(start 285.369 -33.274)
		(mid 285.222862 -33.244838)
		(end 285.098998 -33.161986)
		(width 0.136652)
		(layer "F.Cu")
		(net "PCIE_TX_CAP_P2")
	)
	(arc
		(start 285.809182 -33.201864)
		(mid 285.729486 -33.255208)
		(end 285.635446 -33.274)
		(width 0.136652)
		(layer "F.Cu")
		(net "PCIE_TX_CAP_P2")
	)
	(segment
		(start 253.3523 -29.3624)
		(end 253.3523 -29.1211)
		(width 0.1016)
		(layer "In5.Cu")
		(net "PCIE_TX_CAP_P2")
	)
	(segment
		(start 280.081228 -24.529542)
		(end 282.394406 -27.83332)
		(width 0.1397)
		(layer "In5.Cu")
		(net "PCIE_TX_CAP_P2")
	)
	(segment
		(start 254.099822 -30.500066)
		(end 253.617222 -30.017466)
		(width 0.1016)
		(layer "In5.Cu")
		(net "PCIE_TX_CAP_P2")
	)
	(segment
		(start 253.2888 -29.0322)
		(end 253.2888 -26.14803)
		(width 0.1397)
		(layer "In5.Cu")
		(net "PCIE_TX_CAP_P2")
	)
	(segment
		(start 275.071078 -21.275294)
		(end 280.081228 -24.529542)
		(width 0.1397)
		(layer "In5.Cu")
		(net "PCIE_TX_CAP_P2")
	)
	(segment
		(start 257.130042 -22.577806)
		(end 260.39318 -21.884386)
		(width 0.1397)
		(layer "In5.Cu")
		(net "PCIE_TX_CAP_P2")
	)
	(segment
		(start 282.394406 -27.83332)
		(end 283.237178 -32.612584)
		(width 0.1397)
		(layer "In5.Cu")
		(net "PCIE_TX_CAP_P2")
	)
	(segment
		(start 272.422874 -20.712176)
		(end 275.071078 -21.275294)
		(width 0.1397)
		(layer "In5.Cu")
		(net "PCIE_TX_CAP_P2")
	)
	(segment
		(start 254.498094 -24.420322)
		(end 257.130042 -22.577806)
		(width 0.1397)
		(layer "In5.Cu")
		(net "PCIE_TX_CAP_P2")
	)
	(segment
		(start 284.09773 -33.2994)
		(end 284.60446 -33.2994)
		(width 0.1397)
		(layer "In5.Cu")
		(net "PCIE_TX_CAP_P2")
	)
	(segment
		(start 283.237178 -32.612584)
		(end 283.352494 -32.777176)
		(width 0.1397)
		(layer "In5.Cu")
		(net "PCIE_TX_CAP_P2")
	)
	(segment
		(start 253.3523 -29.1211)
		(end 253.2888 -29.0576)
		(width 0.1016)
		(layer "In5.Cu")
		(net "PCIE_TX_CAP_P2")
	)
	(segment
		(start 253.2888 -29.0576)
		(end 253.2888 -29.0322)
		(width 0.1016)
		(layer "In5.Cu")
		(net "PCIE_TX_CAP_P2")
	)
	(segment
		(start 260.39318 -21.884386)
		(end 263.650476 -22.57679)
		(width 0.1397)
		(layer "In5.Cu")
		(net "PCIE_TX_CAP_P2")
	)
	(segment
		(start 283.352494 -32.777176)
		(end 284.09773 -33.2994)
		(width 0.1397)
		(layer "In5.Cu")
		(net "PCIE_TX_CAP_P2")
	)
	(segment
		(start 253.2888 -26.14803)
		(end 254.498094 -24.420322)
		(width 0.1397)
		(layer "In5.Cu")
		(net "PCIE_TX_CAP_P2")
	)
	(segment
		(start 263.650476 -22.57679)
		(end 272.422874 -20.712176)
		(width 0.1397)
		(layer "In5.Cu")
		(net "PCIE_TX_CAP_P2")
	)
	(arc
		(start 284.60446 -33.2994)
		(mid 284.832923 -33.232043)
		(end 284.988254 -33.051496)
		(width 0.1397)
		(layer "In5.Cu")
		(net "PCIE_TX_CAP_P2")
	)
	(arc
		(start 253.617222 -30.017466)
		(mid 253.421067 -29.715703)
		(end 253.3523 -29.3624)
		(width 0.1016)
		(layer "In5.Cu")
		(net "PCIE_TX_CAP_P2")
	)
	(segment
		(start 256.599944 -45.999908)
		(end 257.099816 -45.500036)
		(width 0.136652)
		(layer "F.Cu")
		(net "PCIE_TX_CAP_P19")
	)
	(segment
		(start 332.741524 -211.5312)
		(end 332.741524 -211.3026)
		(width 0.136652)
		(layer "F.Cu")
		(net "PCIE_TX_CAP_P19")
	)
	(segment
		(start 332.392274 -211.975954)
		(end 332.67396 -211.694268)
		(width 0.136652)
		(layer "F.Cu")
		(net "PCIE_TX_CAP_P19")
	)
	(segment
		(start 332.39202 -211.975954)
		(end 332.392274 -211.975954)
		(width 0.136652)
		(layer "F.Cu")
		(net "PCIE_TX_CAP_P19")
	)
	(segment
		(start 332.62951 -211.03209)
		(end 332.493874 -210.896454)
		(width 0.136652)
		(layer "F.Cu")
		(net "PCIE_TX_CAP_P19")
	)
	(via
		(at 257.099816 -45.500036)
		(size 0.4572)
		(drill 0.2032)
		(layers "F.Cu" "B.Cu")
		(net "PCIE_TX_CAP_P19")
	)
	(via
		(at 332.493874 -210.896454)
		(size 0.508)
		(drill 0.254)
		(layers "F.Cu" "B.Cu")
		(net "PCIE_TX_CAP_P19")
	)
	(arc
		(start 332.67396 -211.694268)
		(mid 332.723951 -211.619452)
		(end 332.741524 -211.5312)
		(width 0.136652)
		(layer "F.Cu")
		(net "PCIE_TX_CAP_P19")
	)
	(arc
		(start 332.741524 -211.3026)
		(mid 332.712406 -211.156214)
		(end 332.62951 -211.03209)
		(width 0.136652)
		(layer "F.Cu")
		(net "PCIE_TX_CAP_P19")
	)
	(segment
		(start 303.604168 -158.337504)
		(end 332.735174 -199.941434)
		(width 0.1397)
		(layer "In5.Cu")
		(net "PCIE_TX_CAP_P19")
	)
	(segment
		(start 332.784958 -200.072498)
		(end 333.081884 -201.009504)
		(width 0.1397)
		(layer "In5.Cu")
		(net "PCIE_TX_CAP_P19")
	)
	(segment
		(start 263.554464 -45.58792)
		(end 266.656312 -46.134782)
		(width 0.1397)
		(layer "In5.Cu")
		(net "PCIE_TX_CAP_P19")
	)
	(segment
		(start 332.735174 -199.941434)
		(end 332.775306 -200.067672)
		(width 0.1397)
		(layer "In5.Cu")
		(net "PCIE_TX_CAP_P19")
	)
	(segment
		(start 332.404466 -204.851)
		(end 332.966568 -208.038954)
		(width 0.1397)
		(layer "In5.Cu")
		(net "PCIE_TX_CAP_P19")
	)
	(segment
		(start 259.7404 -46.170596)
		(end 260.2484 -46.170596)
		(width 0.1397)
		(layer "In5.Cu")
		(net "PCIE_TX_CAP_P19")
	)
	(segment
		(start 257.099816 -45.500036)
		(end 257.217926 -45.381926)
		(width 0.1016)
		(layer "In5.Cu")
		(net "PCIE_TX_CAP_P19")
	)
	(segment
		(start 260.2484 -46.170596)
		(end 263.554464 -45.58792)
		(width 0.1397)
		(layer "In5.Cu")
		(net "PCIE_TX_CAP_P19")
	)
	(segment
		(start 257.513582 -45.633132)
		(end 257.513582 -45.682916)
		(width 0.1016)
		(layer "In5.Cu")
		(net "PCIE_TX_CAP_P19")
	)
	(segment
		(start 257.515106 -45.69841)
		(end 257.526536 -45.756322)
		(width 0.1016)
		(layer "In5.Cu")
		(net "PCIE_TX_CAP_P19")
	)
	(segment
		(start 266.656312 -46.134782)
		(end 275.28774 -52.178712)
		(width 0.1397)
		(layer "In5.Cu")
		(net "PCIE_TX_CAP_P19")
	)
	(segment
		(start 332.775306 -200.067672)
		(end 332.784958 -200.072498)
		(width 0.1397)
		(layer "In5.Cu")
		(net "PCIE_TX_CAP_P19")
	)
	(segment
		(start 289.839654 -79.860902)
		(end 303.604168 -158.337504)
		(width 0.1397)
		(layer "In5.Cu")
		(net "PCIE_TX_CAP_P19")
	)
	(segment
		(start 332.735174 -209.351626)
		(end 332.735174 -210.313778)
		(width 0.1397)
		(layer "In5.Cu")
		(net "PCIE_TX_CAP_P19")
	)
	(segment
		(start 275.28774 -52.178712)
		(end 282.768294 -62.862206)
		(width 0.1397)
		(layer "In5.Cu")
		(net "PCIE_TX_CAP_P19")
	)
	(segment
		(start 282.768294 -62.862206)
		(end 289.839654 -79.860902)
		(width 0.1397)
		(layer "In5.Cu")
		(net "PCIE_TX_CAP_P19")
	)
	(segment
		(start 257.472942 -45.489368)
		(end 257.496056 -45.544994)
		(width 0.1016)
		(layer "In5.Cu")
		(net "PCIE_TX_CAP_P19")
	)
	(segment
		(start 333.081884 -201.009504)
		(end 332.404466 -204.851)
		(width 0.1397)
		(layer "In5.Cu")
		(net "PCIE_TX_CAP_P19")
	)
	(segment
		(start 332.966568 -208.038954)
		(end 332.735174 -209.351626)
		(width 0.1397)
		(layer "In5.Cu")
		(net "PCIE_TX_CAP_P19")
	)
	(segment
		(start 258.069842 -46.09211)
		(end 259.574284 -46.09211)
		(width 0.1016)
		(layer "In5.Cu")
		(net "PCIE_TX_CAP_P19")
	)
	(arc
		(start 257.217926 -45.381926)
		(mid 257.244613 -45.364094)
		(end 257.276092 -45.357796)
		(width 0.1016)
		(layer "In5.Cu")
		(net "PCIE_TX_CAP_P19")
	)
	(arc
		(start 259.574284 -46.09211)
		(mid 259.666154 -46.112712)
		(end 259.7404 -46.170596)
		(width 0.1016)
		(layer "In5.Cu")
		(net "PCIE_TX_CAP_P19")
	)
	(arc
		(start 257.526536 -45.756322)
		(mid 257.609465 -45.927901)
		(end 257.76555 -46.037246)
		(width 0.1016)
		(layer "In5.Cu")
		(net "PCIE_TX_CAP_P19")
	)
	(arc
		(start 257.325876 -45.363638)
		(mid 257.414538 -45.408823)
		(end 257.472942 -45.489368)
		(width 0.1016)
		(layer "In5.Cu")
		(net "PCIE_TX_CAP_P19")
	)
	(arc
		(start 257.276092 -45.357796)
		(mid 257.301157 -45.359245)
		(end 257.325876 -45.363638)
		(width 0.1016)
		(layer "In5.Cu")
		(net "PCIE_TX_CAP_P19")
	)
	(arc
		(start 257.496056 -45.544994)
		(mid 257.509158 -45.5882)
		(end 257.513582 -45.633132)
		(width 0.1016)
		(layer "In5.Cu")
		(net "PCIE_TX_CAP_P19")
	)
	(arc
		(start 332.735174 -210.313778)
		(mid 332.672453 -210.6291)
		(end 332.493874 -210.896454)
		(width 0.1397)
		(layer "In5.Cu")
		(net "PCIE_TX_CAP_P19")
	)
	(arc
		(start 257.513582 -45.682916)
		(mid 257.513959 -45.690701)
		(end 257.515106 -45.69841)
		(width 0.1016)
		(layer "In5.Cu")
		(net "PCIE_TX_CAP_P19")
	)
	(arc
		(start 257.76555 -46.037246)
		(mid 257.91525 -46.078244)
		(end 258.069842 -46.09211)
		(width 0.1016)
		(layer "In5.Cu")
		(net "PCIE_TX_CAP_P19")
	)
	(segment
		(start 257.599942 -44.99991)
		(end 258.099814 -44.500038)
		(width 0.136652)
		(layer "F.Cu")
		(net "PCIE_TX_CAP_P18")
	)
	(segment
		(start 335.941416 -211.5312)
		(end 335.941416 -211.2518)
		(width 0.136652)
		(layer "F.Cu")
		(net "PCIE_TX_CAP_P18")
	)
	(segment
		(start 335.865216 -211.067904)
		(end 335.693766 -210.896454)
		(width 0.136652)
		(layer "F.Cu")
		(net "PCIE_TX_CAP_P18")
	)
	(segment
		(start 335.592166 -211.975954)
		(end 335.873852 -211.694268)
		(width 0.136652)
		(layer "F.Cu")
		(net "PCIE_TX_CAP_P18")
	)
	(via
		(at 335.693766 -210.896454)
		(size 0.508)
		(drill 0.254)
		(layers "F.Cu" "B.Cu")
		(net "PCIE_TX_CAP_P18")
	)
	(via
		(at 258.099814 -44.500038)
		(size 0.4572)
		(drill 0.2032)
		(layers "F.Cu" "B.Cu")
		(net "PCIE_TX_CAP_P18")
	)
	(arc
		(start 335.941416 -211.2518)
		(mid 335.921617 -211.152266)
		(end 335.865216 -211.067904)
		(width 0.136652)
		(layer "F.Cu")
		(net "PCIE_TX_CAP_P18")
	)
	(arc
		(start 335.873852 -211.694268)
		(mid 335.923843 -211.619452)
		(end 335.941416 -211.5312)
		(width 0.136652)
		(layer "F.Cu")
		(net "PCIE_TX_CAP_P18")
	)
	(segment
		(start 263.57072 -44.663614)
		(end 267.880592 -45.423582)
		(width 0.1397)
		(layer "In5.Cu")
		(net "PCIE_TX_CAP_P18")
	)
	(segment
		(start 260.64083 -45.179996)
		(end 263.57072 -44.663614)
		(width 0.1397)
		(layer "In5.Cu")
		(net "PCIE_TX_CAP_P18")
	)
	(segment
		(start 275.532088 -50.781204)
		(end 283.04617 -61.512704)
		(width 0.1397)
		(layer "In5.Cu")
		(net "PCIE_TX_CAP_P18")
	)
	(segment
		(start 291.396928 -81.586832)
		(end 304.74539 -157.672278)
		(width 0.1397)
		(layer "In5.Cu")
		(net "PCIE_TX_CAP_P18")
	)
	(segment
		(start 283.04617 -61.512704)
		(end 291.396928 -81.586832)
		(width 0.1397)
		(layer "In5.Cu")
		(net "PCIE_TX_CAP_P18")
	)
	(segment
		(start 260.027674 -45.179996)
		(end 260.64083 -45.179996)
		(width 0.1397)
		(layer "In5.Cu")
		(net "PCIE_TX_CAP_P18")
	)
	(segment
		(start 304.74539 -157.672278)
		(end 335.507838 -201.605896)
		(width 0.1397)
		(layer "In5.Cu")
		(net "PCIE_TX_CAP_P18")
	)
	(segment
		(start 258.308856 -44.586652)
		(end 258.875784 -45.153834)
		(width 0.1016)
		(layer "In5.Cu")
		(net "PCIE_TX_CAP_P18")
	)
	(segment
		(start 259.239766 -45.304964)
		(end 259.725922 -45.304964)
		(width 0.1016)
		(layer "In5.Cu")
		(net "PCIE_TX_CAP_P18")
	)
	(segment
		(start 335.507838 -201.605896)
		(end 335.935066 -204.028294)
		(width 0.1397)
		(layer "In5.Cu")
		(net "PCIE_TX_CAP_P18")
	)
	(segment
		(start 267.880592 -45.423582)
		(end 275.532088 -50.781204)
		(width 0.1397)
		(layer "In5.Cu")
		(net "PCIE_TX_CAP_P18")
	)
	(segment
		(start 335.935066 -204.028294)
		(end 335.935066 -210.313778)
		(width 0.1397)
		(layer "In5.Cu")
		(net "PCIE_TX_CAP_P18")
	)
	(arc
		(start 335.935066 -210.313778)
		(mid 335.872345 -210.6291)
		(end 335.693766 -210.896454)
		(width 0.1397)
		(layer "In5.Cu")
		(net "PCIE_TX_CAP_P18")
	)
	(arc
		(start 259.725922 -45.304964)
		(mid 259.889221 -45.272482)
		(end 260.027674 -45.179996)
		(width 0.1016)
		(layer "In5.Cu")
		(net "PCIE_TX_CAP_P18")
	)
	(arc
		(start 258.099814 -44.500038)
		(mid 258.212957 -44.522543)
		(end 258.308856 -44.586652)
		(width 0.1016)
		(layer "In5.Cu")
		(net "PCIE_TX_CAP_P18")
	)
	(arc
		(start 258.941824 -45.209714)
		(mid 259.083367 -45.280575)
		(end 259.239766 -45.304964)
		(width 0.1016)
		(layer "In5.Cu")
		(net "PCIE_TX_CAP_P18")
	)
	(arc
		(start 258.875784 -45.153834)
		(mid 258.907645 -45.183143)
		(end 258.941824 -45.209714)
		(width 0.1016)
		(layer "In5.Cu")
		(net "PCIE_TX_CAP_P18")
	)
	(segment
		(start 339.141308 -211.5312)
		(end 339.141308 -211.339684)
		(width 0.136652)
		(layer "F.Cu")
		(net "PCIE_TX_CAP_P17")
	)
	(segment
		(start 339.003132 -211.005674)
		(end 338.893658 -210.896454)
		(width 0.136652)
		(layer "F.Cu")
		(net "PCIE_TX_CAP_P17")
	)
	(segment
		(start 338.792058 -211.975954)
		(end 339.073744 -211.694268)
		(width 0.136652)
		(layer "F.Cu")
		(net "PCIE_TX_CAP_P17")
	)
	(segment
		(start 256.599944 -43.999912)
		(end 257.099816 -43.50004)
		(width 0.136652)
		(layer "F.Cu")
		(net "PCIE_TX_CAP_P17")
	)
	(via
		(at 338.893658 -210.896454)
		(size 0.508)
		(drill 0.254)
		(layers "F.Cu" "B.Cu")
		(net "PCIE_TX_CAP_P17")
	)
	(via
		(at 257.099816 -43.50004)
		(size 0.4572)
		(drill 0.2032)
		(layers "F.Cu" "B.Cu")
		(net "PCIE_TX_CAP_P17")
	)
	(arc
		(start 339.073744 -211.694268)
		(mid 339.123735 -211.619452)
		(end 339.141308 -211.5312)
		(width 0.136652)
		(layer "F.Cu")
		(net "PCIE_TX_CAP_P17")
	)
	(arc
		(start 339.141308 -211.339684)
		(mid 339.105448 -211.158933)
		(end 339.003132 -211.005674)
		(width 0.136652)
		(layer "F.Cu")
		(net "PCIE_TX_CAP_P17")
	)
	(segment
		(start 263.595612 -43.580304)
		(end 267.88872 -44.337224)
		(width 0.1397)
		(layer "In5.Cu")
		(net "PCIE_TX_CAP_P17")
	)
	(segment
		(start 257.472942 -43.489372)
		(end 257.496056 -43.544998)
		(width 0.1016)
		(layer "In5.Cu")
		(net "PCIE_TX_CAP_P17")
	)
	(segment
		(start 305.744626 -157.533086)
		(end 339.134958 -205.219046)
		(width 0.1397)
		(layer "In5.Cu")
		(net "PCIE_TX_CAP_P17")
	)
	(segment
		(start 275.984716 -50.00625)
		(end 283.656532 -60.96254)
		(width 0.1397)
		(layer "In5.Cu")
		(net "PCIE_TX_CAP_P17")
	)
	(segment
		(start 259.7404 -44.1706)
		(end 260.2484 -44.1706)
		(width 0.1397)
		(layer "In5.Cu")
		(net "PCIE_TX_CAP_P17")
	)
	(segment
		(start 258.069842 -44.092114)
		(end 258.138168 -44.092114)
		(width 0.1016)
		(layer "In5.Cu")
		(net "PCIE_TX_CAP_P17")
	)
	(segment
		(start 292.439598 -82.075782)
		(end 305.744626 -157.533086)
		(width 0.1397)
		(layer "In5.Cu")
		(net "PCIE_TX_CAP_P17")
	)
	(segment
		(start 267.88872 -44.337224)
		(end 275.984716 -50.00625)
		(width 0.1397)
		(layer "In5.Cu")
		(net "PCIE_TX_CAP_P17")
	)
	(segment
		(start 258.138168 -44.092114)
		(end 258.144518 -44.092368)
		(width 0.1016)
		(layer "In5.Cu")
		(net "PCIE_TX_CAP_P17")
	)
	(segment
		(start 260.2484 -44.1706)
		(end 263.595612 -43.580304)
		(width 0.1397)
		(layer "In5.Cu")
		(net "PCIE_TX_CAP_P17")
	)
	(segment
		(start 257.513582 -43.633136)
		(end 257.513582 -43.68292)
		(width 0.1016)
		(layer "In5.Cu")
		(net "PCIE_TX_CAP_P17")
	)
	(segment
		(start 257.515106 -43.698414)
		(end 257.526536 -43.756326)
		(width 0.1016)
		(layer "In5.Cu")
		(net "PCIE_TX_CAP_P17")
	)
	(segment
		(start 339.134958 -205.219046)
		(end 339.134958 -210.313778)
		(width 0.1397)
		(layer "In5.Cu")
		(net "PCIE_TX_CAP_P17")
	)
	(segment
		(start 258.216146 -44.0944)
		(end 259.556504 -44.0944)
		(width 0.1016)
		(layer "In5.Cu")
		(net "PCIE_TX_CAP_P17")
	)
	(segment
		(start 283.656532 -60.96254)
		(end 292.439598 -82.075782)
		(width 0.1397)
		(layer "In5.Cu")
		(net "PCIE_TX_CAP_P17")
	)
	(segment
		(start 257.099816 -43.50004)
		(end 257.217926 -43.38193)
		(width 0.1016)
		(layer "In5.Cu")
		(net "PCIE_TX_CAP_P17")
	)
	(arc
		(start 257.276092 -43.3578)
		(mid 257.301157 -43.359249)
		(end 257.325876 -43.363642)
		(width 0.1016)
		(layer "In5.Cu")
		(net "PCIE_TX_CAP_P17")
	)
	(arc
		(start 257.513582 -43.68292)
		(mid 257.513959 -43.690705)
		(end 257.515106 -43.698414)
		(width 0.1016)
		(layer "In5.Cu")
		(net "PCIE_TX_CAP_P17")
	)
	(arc
		(start 257.76555 -44.03725)
		(mid 257.91525 -44.078248)
		(end 258.069842 -44.092114)
		(width 0.1016)
		(layer "In5.Cu")
		(net "PCIE_TX_CAP_P17")
	)
	(arc
		(start 257.496056 -43.544998)
		(mid 257.509158 -43.588204)
		(end 257.513582 -43.633136)
		(width 0.1016)
		(layer "In5.Cu")
		(net "PCIE_TX_CAP_P17")
	)
	(arc
		(start 339.134958 -210.313778)
		(mid 339.072237 -210.6291)
		(end 338.893658 -210.896454)
		(width 0.1397)
		(layer "In5.Cu")
		(net "PCIE_TX_CAP_P17")
	)
	(arc
		(start 259.556504 -44.0944)
		(mid 259.656038 -44.114199)
		(end 259.7404 -44.1706)
		(width 0.1016)
		(layer "In5.Cu")
		(net "PCIE_TX_CAP_P17")
	)
	(arc
		(start 258.144518 -44.092368)
		(mid 258.180318 -44.093895)
		(end 258.216146 -44.0944)
		(width 0.1016)
		(layer "In5.Cu")
		(net "PCIE_TX_CAP_P17")
	)
	(arc
		(start 257.526536 -43.756326)
		(mid 257.609465 -43.927905)
		(end 257.76555 -44.03725)
		(width 0.1016)
		(layer "In5.Cu")
		(net "PCIE_TX_CAP_P17")
	)
	(arc
		(start 257.217926 -43.38193)
		(mid 257.244613 -43.364098)
		(end 257.276092 -43.3578)
		(width 0.1016)
		(layer "In5.Cu")
		(net "PCIE_TX_CAP_P17")
	)
	(arc
		(start 257.325876 -43.363642)
		(mid 257.414538 -43.408827)
		(end 257.472942 -43.489372)
		(width 0.1016)
		(layer "In5.Cu")
		(net "PCIE_TX_CAP_P17")
	)
	(segment
		(start 342.3412 -211.469986)
		(end 342.3412 -211.2772)
		(width 0.136652)
		(layer "F.Cu")
		(net "PCIE_TX_CAP_P16")
	)
	(segment
		(start 342.246966 -211.050124)
		(end 342.09355 -210.896454)
		(width 0.136652)
		(layer "F.Cu")
		(net "PCIE_TX_CAP_P16")
	)
	(segment
		(start 341.99195 -211.975954)
		(end 342.230456 -211.737702)
		(width 0.136652)
		(layer "F.Cu")
		(net "PCIE_TX_CAP_P16")
	)
	(segment
		(start 257.599942 -42.999914)
		(end 258.099814 -42.500042)
		(width 0.136652)
		(layer "F.Cu")
		(net "PCIE_TX_CAP_P16")
	)
	(via
		(at 342.09355 -210.896454)
		(size 0.508)
		(drill 0.254)
		(layers "F.Cu" "B.Cu")
		(net "PCIE_TX_CAP_P16")
	)
	(via
		(at 258.099814 -42.500042)
		(size 0.4572)
		(drill 0.2032)
		(layers "F.Cu" "B.Cu")
		(net "PCIE_TX_CAP_P16")
	)
	(arc
		(start 342.230456 -211.737702)
		(mid 342.312445 -211.614858)
		(end 342.3412 -211.469986)
		(width 0.136652)
		(layer "F.Cu")
		(net "PCIE_TX_CAP_P16")
	)
	(arc
		(start 342.3412 -211.2772)
		(mid 342.316659 -211.154294)
		(end 342.246966 -211.050124)
		(width 0.136652)
		(layer "F.Cu")
		(net "PCIE_TX_CAP_P16")
	)
	(segment
		(start 306.70246 -157.246574)
		(end 293.565326 -82.764376)
		(width 0.1397)
		(layer "In5.Cu")
		(net "PCIE_TX_CAP_P16")
	)
	(segment
		(start 259.725922 -43.304968)
		(end 259.239766 -43.304968)
		(width 0.1016)
		(layer "In5.Cu")
		(net "PCIE_TX_CAP_P16")
	)
	(segment
		(start 263.671812 -42.645584)
		(end 260.64083 -43.18)
		(width 0.1397)
		(layer "In5.Cu")
		(net "PCIE_TX_CAP_P16")
	)
	(segment
		(start 342.33485 -208.134966)
		(end 306.70246 -157.246574)
		(width 0.1397)
		(layer "In5.Cu")
		(net "PCIE_TX_CAP_P16")
	)
	(segment
		(start 258.7117 -42.9895)
		(end 258.308856 -42.586656)
		(width 0.1016)
		(layer "In5.Cu")
		(net "PCIE_TX_CAP_P16")
	)
	(segment
		(start 276.335998 -48.996346)
		(end 268.47546 -43.492674)
		(width 0.1397)
		(layer "In5.Cu")
		(net "PCIE_TX_CAP_P16")
	)
	(segment
		(start 284.1752 -60.191904)
		(end 276.335998 -48.996346)
		(width 0.1397)
		(layer "In5.Cu")
		(net "PCIE_TX_CAP_P16")
	)
	(segment
		(start 258.828032 -43.106086)
		(end 258.7117 -42.9895)
		(width 0.1016)
		(layer "In5.Cu")
		(net "PCIE_TX_CAP_P16")
	)
	(segment
		(start 293.565326 -82.764376)
		(end 284.1752 -60.191904)
		(width 0.1397)
		(layer "In5.Cu")
		(net "PCIE_TX_CAP_P16")
	)
	(segment
		(start 342.09355 -210.896454)
		(end 342.21801 -210.772248)
		(width 0.1397)
		(layer "In5.Cu")
		(net "PCIE_TX_CAP_P16")
	)
	(segment
		(start 342.33485 -210.4898)
		(end 342.33485 -208.134966)
		(width 0.1397)
		(layer "In5.Cu")
		(net "PCIE_TX_CAP_P16")
	)
	(segment
		(start 260.64083 -43.18)
		(end 260.027674 -43.18)
		(width 0.1397)
		(layer "In5.Cu")
		(net "PCIE_TX_CAP_P16")
	)
	(segment
		(start 268.47546 -43.492674)
		(end 263.671812 -42.645584)
		(width 0.1397)
		(layer "In5.Cu")
		(net "PCIE_TX_CAP_P16")
	)
	(segment
		(start 258.875784 -43.153838)
		(end 258.828032 -43.106086)
		(width 0.1016)
		(layer "In5.Cu")
		(net "PCIE_TX_CAP_P16")
	)
	(arc
		(start 259.239766 -43.304968)
		(mid 259.210636 -43.304141)
		(end 259.1816 -43.301666)
		(width 0.1016)
		(layer "In5.Cu")
		(net "PCIE_TX_CAP_P16")
	)
	(arc
		(start 259.1816 -43.301666)
		(mid 259.055873 -43.27092)
		(end 258.941824 -43.209718)
		(width 0.1016)
		(layer "In5.Cu")
		(net "PCIE_TX_CAP_P16")
	)
	(arc
		(start 258.308856 -42.586656)
		(mid 258.212947 -42.522571)
		(end 258.099814 -42.500042)
		(width 0.1016)
		(layer "In5.Cu")
		(net "PCIE_TX_CAP_P16")
	)
	(arc
		(start 342.21801 -210.772248)
		(mid 342.304515 -210.642645)
		(end 342.33485 -210.4898)
		(width 0.1397)
		(layer "In5.Cu")
		(net "PCIE_TX_CAP_P16")
	)
	(arc
		(start 258.941824 -43.209718)
		(mid 258.907632 -43.183163)
		(end 258.875784 -43.153838)
		(width 0.1016)
		(layer "In5.Cu")
		(net "PCIE_TX_CAP_P16")
	)
	(arc
		(start 260.027674 -43.18)
		(mid 259.889229 -43.272506)
		(end 259.725922 -43.304968)
		(width 0.1016)
		(layer "In5.Cu")
		(net "PCIE_TX_CAP_P16")
	)
	(segment
		(start 328.642218 -34.347658)
		(end 328.642218 -34.487358)
		(width 0.136652)
		(layer "F.Cu")
		(net "PCIE_TX_CAP_P15")
	)
	(segment
		(start 256.599944 -40.999918)
		(end 257.099816 -40.500046)
		(width 0.136652)
		(layer "F.Cu")
		(net "PCIE_TX_CAP_P15")
	)
	(segment
		(start 328.525378 -34.769806)
		(end 328.375518 -34.919412)
		(width 0.136652)
		(layer "F.Cu")
		(net "PCIE_TX_CAP_P15")
	)
	(segment
		(start 328.324718 -33.877758)
		(end 328.534522 -34.087308)
		(width 0.136652)
		(layer "F.Cu")
		(net "PCIE_TX_CAP_P15")
	)
	(via
		(at 328.375518 -34.919412)
		(size 0.508)
		(drill 0.254)
		(layers "F.Cu" "B.Cu")
		(net "PCIE_TX_CAP_P15")
	)
	(via
		(at 257.099816 -40.500046)
		(size 0.4572)
		(drill 0.2032)
		(layers "F.Cu" "B.Cu")
		(net "PCIE_TX_CAP_P15")
	)
	(arc
		(start 328.642218 -34.487358)
		(mid 328.611907 -34.640213)
		(end 328.525378 -34.769806)
		(width 0.136652)
		(layer "F.Cu")
		(net "PCIE_TX_CAP_P15")
	)
	(arc
		(start 328.534522 -34.087308)
		(mid 328.614253 -34.206773)
		(end 328.642218 -34.347658)
		(width 0.136652)
		(layer "F.Cu")
		(net "PCIE_TX_CAP_P15")
	)
	(segment
		(start 288.43986 -50.037746)
		(end 291.359336 -49.4538)
		(width 0.1397)
		(layer "In5.Cu")
		(net "PCIE_TX_CAP_P15")
	)
	(segment
		(start 259.5372 -40.379142)
		(end 263.267444 -40.379142)
		(width 0.1397)
		(layer "In5.Cu")
		(net "PCIE_TX_CAP_P15")
	)
	(segment
		(start 271.491456 -41.495218)
		(end 272.899124 -43.505882)
		(width 0.1397)
		(layer "In5.Cu")
		(net "PCIE_TX_CAP_P15")
	)
	(segment
		(start 257.902202 -39.901622)
		(end 258.4704 -39.901622)
		(width 0.1016)
		(layer "In5.Cu")
		(net "PCIE_TX_CAP_P15")
	)
	(segment
		(start 259.174996 -40.379142)
		(end 259.5372 -40.379142)
		(width 0.1016)
		(layer "In5.Cu")
		(net "PCIE_TX_CAP_P15")
	)
	(segment
		(start 258.85775 -40.061896)
		(end 259.174996 -40.379142)
		(width 0.1016)
		(layer "In5.Cu")
		(net "PCIE_TX_CAP_P15")
	)
	(segment
		(start 316.332362 -41.986454)
		(end 322.713096 -40.861488)
		(width 0.1397)
		(layer "In5.Cu")
		(net "PCIE_TX_CAP_P15")
	)
	(segment
		(start 263.267444 -40.379142)
		(end 266.86129 -39.745158)
		(width 0.1397)
		(layer "In5.Cu")
		(net "PCIE_TX_CAP_P15")
	)
	(segment
		(start 272.899124 -43.505882)
		(end 280.137108 -48.57369)
		(width 0.1397)
		(layer "In5.Cu")
		(net "PCIE_TX_CAP_P15")
	)
	(segment
		(start 280.137108 -48.57369)
		(end 288.43986 -50.037746)
		(width 0.1397)
		(layer "In5.Cu")
		(net "PCIE_TX_CAP_P15")
	)
	(segment
		(start 322.713096 -40.861488)
		(end 326.949308 -37.89553)
		(width 0.1397)
		(layer "In5.Cu")
		(net "PCIE_TX_CAP_P15")
	)
	(segment
		(start 311.589928 -46.347126)
		(end 313.018932 -44.30649)
		(width 0.1397)
		(layer "In5.Cu")
		(net "PCIE_TX_CAP_P15")
	)
	(segment
		(start 297.709336 -49.4538)
		(end 300.884336 -50.0888)
		(width 0.1397)
		(layer "In5.Cu")
		(net "PCIE_TX_CAP_P15")
	)
	(segment
		(start 257.099816 -40.500046)
		(end 257.553968 -40.045894)
		(width 0.1016)
		(layer "In5.Cu")
		(net "PCIE_TX_CAP_P15")
	)
	(segment
		(start 266.86129 -39.745158)
		(end 269.709392 -40.247316)
		(width 0.1397)
		(layer "In5.Cu")
		(net "PCIE_TX_CAP_P15")
	)
	(segment
		(start 328.637646 -36.207192)
		(end 328.637646 -35.395662)
		(width 0.1397)
		(layer "In5.Cu")
		(net "PCIE_TX_CAP_P15")
	)
	(segment
		(start 269.709392 -40.247316)
		(end 271.491456 -41.495218)
		(width 0.1397)
		(layer "In5.Cu")
		(net "PCIE_TX_CAP_P15")
	)
	(segment
		(start 300.884336 -50.0888)
		(end 308.390544 -48.587406)
		(width 0.1397)
		(layer "In5.Cu")
		(net "PCIE_TX_CAP_P15")
	)
	(segment
		(start 308.390544 -48.587406)
		(end 311.589928 -46.347126)
		(width 0.1397)
		(layer "In5.Cu")
		(net "PCIE_TX_CAP_P15")
	)
	(segment
		(start 294.534336 -50.0888)
		(end 297.709336 -49.4538)
		(width 0.1397)
		(layer "In5.Cu")
		(net "PCIE_TX_CAP_P15")
	)
	(segment
		(start 328.486262 -35.030156)
		(end 328.375518 -34.919412)
		(width 0.1397)
		(layer "In5.Cu")
		(net "PCIE_TX_CAP_P15")
	)
	(segment
		(start 313.018932 -44.30649)
		(end 316.332362 -41.986454)
		(width 0.1397)
		(layer "In5.Cu")
		(net "PCIE_TX_CAP_P15")
	)
	(segment
		(start 291.359336 -49.4538)
		(end 294.534336 -50.0888)
		(width 0.1397)
		(layer "In5.Cu")
		(net "PCIE_TX_CAP_P15")
	)
	(segment
		(start 326.949308 -37.89553)
		(end 328.637646 -36.207192)
		(width 0.1397)
		(layer "In5.Cu")
		(net "PCIE_TX_CAP_P15")
	)
	(arc
		(start 328.637646 -35.395662)
		(mid 328.5983 -35.197857)
		(end 328.486262 -35.030156)
		(width 0.1397)
		(layer "In5.Cu")
		(net "PCIE_TX_CAP_P15")
	)
	(arc
		(start 257.553968 -40.045894)
		(mid 257.655354 -39.967876)
		(end 257.773424 -39.91864)
		(width 0.1016)
		(layer "In5.Cu")
		(net "PCIE_TX_CAP_P15")
	)
	(arc
		(start 258.4704 -39.901622)
		(mid 258.68002 -39.943224)
		(end 258.85775 -40.061896)
		(width 0.1016)
		(layer "In5.Cu")
		(net "PCIE_TX_CAP_P15")
	)
	(arc
		(start 257.773424 -39.91864)
		(mid 257.83725 -39.905877)
		(end 257.902202 -39.901622)
		(width 0.1016)
		(layer "In5.Cu")
		(net "PCIE_TX_CAP_P15")
	)
	(segment
		(start 257.599942 -39.99992)
		(end 258.099814 -39.500048)
		(width 0.136652)
		(layer "F.Cu")
		(net "PCIE_TX_CAP_P14")
	)
	(segment
		(start 326.235822 -34.670492)
		(end 326.235822 -35.52952)
		(width 0.136652)
		(layer "F.Cu")
		(net "PCIE_TX_CAP_P14")
	)
	(segment
		(start 326.118982 -35.811968)
		(end 325.969122 -35.961574)
		(width 0.136652)
		(layer "F.Cu")
		(net "PCIE_TX_CAP_P14")
	)
	(via
		(at 325.969122 -35.961574)
		(size 0.508)
		(drill 0.254)
		(layers "F.Cu" "B.Cu")
		(net "PCIE_TX_CAP_P14")
	)
	(via
		(at 258.099814 -39.500048)
		(size 0.4572)
		(drill 0.2032)
		(layers "F.Cu" "B.Cu")
		(net "PCIE_TX_CAP_P14")
	)
	(arc
		(start 325.918322 -33.90392)
		(mid 326.153325 -34.255626)
		(end 326.235822 -34.670492)
		(width 0.136652)
		(layer "F.Cu")
		(net "PCIE_TX_CAP_P14")
	)
	(arc
		(start 326.235822 -35.52952)
		(mid 326.205511 -35.682375)
		(end 326.118982 -35.811968)
		(width 0.136652)
		(layer "F.Cu")
		(net "PCIE_TX_CAP_P14")
	)
	(segment
		(start 295.125394 -49.0093)
		(end 291.950394 -48.3743)
		(width 0.1397)
		(layer "In5.Cu")
		(net "PCIE_TX_CAP_P14")
	)
	(segment
		(start 322.121022 -40.157908)
		(end 315.249306 -41.369488)
		(width 0.1397)
		(layer "In5.Cu")
		(net "PCIE_TX_CAP_P14")
	)
	(segment
		(start 258.43484 -39.109396)
		(end 258.434586 -39.109396)
		(width 0.1397)
		(layer "In5.Cu")
		(net "PCIE_TX_CAP_P14")
	)
	(segment
		(start 272.425414 -40.694102)
		(end 270.23314 -39.158926)
		(width 0.1397)
		(layer "In5.Cu")
		(net "PCIE_TX_CAP_P14")
	)
	(segment
		(start 326.183752 -36.479734)
		(end 326.183752 -36.81603)
		(width 0.1397)
		(layer "In5.Cu")
		(net "PCIE_TX_CAP_P14")
	)
	(segment
		(start 259.980684 -39.204392)
		(end 259.49148 -38.715188)
		(width 0.1397)
		(layer "In5.Cu")
		(net "PCIE_TX_CAP_P14")
	)
	(segment
		(start 289.015424 -48.961294)
		(end 280.530554 -47.46498)
		(width 0.1397)
		(layer "In5.Cu")
		(net "PCIE_TX_CAP_P14")
	)
	(segment
		(start 259.105654 -38.555422)
		(end 259.00253 -38.555422)
		(width 0.1397)
		(layer "In5.Cu")
		(net "PCIE_TX_CAP_P14")
	)
	(segment
		(start 280.530554 -47.46498)
		(end 273.930872 -42.844212)
		(width 0.1397)
		(layer "In5.Cu")
		(net "PCIE_TX_CAP_P14")
	)
	(segment
		(start 273.930872 -42.844212)
		(end 272.425414 -40.694102)
		(width 0.1397)
		(layer "In5.Cu")
		(net "PCIE_TX_CAP_P14")
	)
	(segment
		(start 263.699244 -39.204392)
		(end 259.980684 -39.204392)
		(width 0.1397)
		(layer "In5.Cu")
		(net "PCIE_TX_CAP_P14")
	)
	(segment
		(start 307.60543 -47.783242)
		(end 301.475394 -49.0093)
		(width 0.1397)
		(layer "In5.Cu")
		(net "PCIE_TX_CAP_P14")
	)
	(segment
		(start 301.475394 -49.0093)
		(end 298.300394 -48.3743)
		(width 0.1397)
		(layer "In5.Cu")
		(net "PCIE_TX_CAP_P14")
	)
	(segment
		(start 326.183752 -36.81603)
		(end 325.57339 -37.755576)
		(width 0.1397)
		(layer "In5.Cu")
		(net "PCIE_TX_CAP_P14")
	)
	(segment
		(start 311.913524 -43.705272)
		(end 310.455564 -45.787564)
		(width 0.1397)
		(layer "In5.Cu")
		(net "PCIE_TX_CAP_P14")
	)
	(segment
		(start 325.57339 -37.755576)
		(end 322.176648 -40.134794)
		(width 0.1397)
		(layer "In5.Cu")
		(net "PCIE_TX_CAP_P14")
	)
	(segment
		(start 291.950394 -48.3743)
		(end 289.015424 -48.961294)
		(width 0.1397)
		(layer "In5.Cu")
		(net "PCIE_TX_CAP_P14")
	)
	(segment
		(start 270.23314 -39.158926)
		(end 267.093954 -38.60546)
		(width 0.1397)
		(layer "In5.Cu")
		(net "PCIE_TX_CAP_P14")
	)
	(segment
		(start 258.434586 -39.109396)
		(end 258.434586 -39.201344)
		(width 0.1397)
		(layer "In5.Cu")
		(net "PCIE_TX_CAP_P14")
	)
	(segment
		(start 258.366514 -39.365682)
		(end 258.32562 -39.406576)
		(width 0.1397)
		(layer "In5.Cu")
		(net "PCIE_TX_CAP_P14")
	)
	(segment
		(start 267.093954 -38.60546)
		(end 263.699244 -39.204392)
		(width 0.1397)
		(layer "In5.Cu")
		(net "PCIE_TX_CAP_P14")
	)
	(segment
		(start 315.249306 -41.369488)
		(end 311.913524 -43.705272)
		(width 0.1397)
		(layer "In5.Cu")
		(net "PCIE_TX_CAP_P14")
	)
	(segment
		(start 310.455564 -45.787564)
		(end 307.60543 -47.783242)
		(width 0.1397)
		(layer "In5.Cu")
		(net "PCIE_TX_CAP_P14")
	)
	(segment
		(start 298.300394 -48.3743)
		(end 295.125394 -49.0093)
		(width 0.1397)
		(layer "In5.Cu")
		(net "PCIE_TX_CAP_P14")
	)
	(arc
		(start 258.32562 -39.406576)
		(mid 258.222005 -39.475746)
		(end 258.099814 -39.500048)
		(width 0.1397)
		(layer "In5.Cu")
		(net "PCIE_TX_CAP_P14")
	)
	(arc
		(start 259.00253 -38.555422)
		(mid 258.918941 -38.561618)
		(end 258.837176 -38.58006)
		(width 0.1397)
		(layer "In5.Cu")
		(net "PCIE_TX_CAP_P14")
	)
	(arc
		(start 258.434586 -39.201344)
		(mid 258.416895 -39.290283)
		(end 258.366514 -39.365682)
		(width 0.1397)
		(layer "In5.Cu")
		(net "PCIE_TX_CAP_P14")
	)
	(arc
		(start 325.969122 -35.961574)
		(mid 326.127971 -36.199308)
		(end 326.183752 -36.479734)
		(width 0.1397)
		(layer "In5.Cu")
		(net "PCIE_TX_CAP_P14")
	)
	(arc
		(start 258.600956 -38.721792)
		(mid 258.480691 -38.89964)
		(end 258.43484 -39.109396)
		(width 0.1397)
		(layer "In5.Cu")
		(net "PCIE_TX_CAP_P14")
	)
	(arc
		(start 259.49148 -38.715188)
		(mid 259.31442 -38.59704)
		(end 259.105654 -38.555422)
		(width 0.1397)
		(layer "In5.Cu")
		(net "PCIE_TX_CAP_P14")
	)
	(arc
		(start 258.837176 -38.58006)
		(mid 258.710363 -38.636418)
		(end 258.600956 -38.721792)
		(width 0.1397)
		(layer "In5.Cu")
		(net "PCIE_TX_CAP_P14")
	)
	(arc
		(start 322.176648 -40.134794)
		(mid 322.1501 -40.149395)
		(end 322.121022 -40.157908)
		(width 0.1397)
		(layer "In5.Cu")
		(net "PCIE_TX_CAP_P14")
	)
	(segment
		(start 323.76237 -34.819336)
		(end 323.61251 -34.968942)
		(width 0.136652)
		(layer "F.Cu")
		(net "PCIE_TX_CAP_P13")
	)
	(segment
		(start 256.599944 -38.999922)
		(end 257.099816 -38.50005)
		(width 0.136652)
		(layer "F.Cu")
		(net "PCIE_TX_CAP_P13")
	)
	(segment
		(start 323.87921 -34.397188)
		(end 323.87921 -34.536888)
		(width 0.136652)
		(layer "F.Cu")
		(net "PCIE_TX_CAP_P13")
	)
	(via
		(at 257.099816 -38.50005)
		(size 0.4572)
		(drill 0.2032)
		(layers "F.Cu" "B.Cu")
		(net "PCIE_TX_CAP_P13")
	)
	(via
		(at 323.61251 -34.968942)
		(size 0.508)
		(drill 0.254)
		(layers "F.Cu" "B.Cu")
		(net "PCIE_TX_CAP_P13")
	)
	(arc
		(start 323.56171 -33.927288)
		(mid 323.792394 -34.113634)
		(end 323.87921 -34.397188)
		(width 0.136652)
		(layer "F.Cu")
		(net "PCIE_TX_CAP_P13")
	)
	(arc
		(start 323.87921 -34.536888)
		(mid 323.848899 -34.689743)
		(end 323.76237 -34.819336)
		(width 0.136652)
		(layer "F.Cu")
		(net "PCIE_TX_CAP_P13")
	)
	(segment
		(start 267.0556 -37.4396)
		(end 264.435082 -37.901626)
		(width 0.1397)
		(layer "In5.Cu")
		(net "PCIE_TX_CAP_P13")
	)
	(segment
		(start 281.119834 -46.3423)
		(end 274.505928 -41.710864)
		(width 0.1397)
		(layer "In5.Cu")
		(net "PCIE_TX_CAP_P13")
	)
	(segment
		(start 323.61251 -34.968942)
		(end 323.649594 -35.005772)
		(width 0.1397)
		(layer "In5.Cu")
		(net "PCIE_TX_CAP_P13")
	)
	(segment
		(start 323.839332 -35.464242)
		(end 323.839332 -35.884104)
		(width 0.1397)
		(layer "In5.Cu")
		(net "PCIE_TX_CAP_P13")
	)
	(segment
		(start 313.905646 -40.8051)
		(end 311.370472 -42.580052)
		(width 0.1397)
		(layer "In5.Cu")
		(net "PCIE_TX_CAP_P13")
	)
	(segment
		(start 311.370472 -42.580052)
		(end 309.693564 -44.974764)
		(width 0.1397)
		(layer "In5.Cu")
		(net "PCIE_TX_CAP_P13")
	)
	(segment
		(start 298.815252 -47.2186)
		(end 295.030652 -47.97552)
		(width 0.1397)
		(layer "In5.Cu")
		(net "PCIE_TX_CAP_P13")
	)
	(segment
		(start 323.839332 -35.884104)
		(end 320.713862 -39.009574)
		(width 0.1397)
		(layer "In5.Cu")
		(net "PCIE_TX_CAP_P13")
	)
	(segment
		(start 309.693564 -44.974764)
		(end 307.01869 -46.84776)
		(width 0.1397)
		(layer "In5.Cu")
		(net "PCIE_TX_CAP_P13")
	)
	(segment
		(start 270.627348 -38.069266)
		(end 267.0556 -37.4396)
		(width 0.1397)
		(layer "In5.Cu")
		(net "PCIE_TX_CAP_P13")
	)
	(segment
		(start 307.01869 -46.84776)
		(end 301.990252 -47.8536)
		(width 0.1397)
		(layer "In5.Cu")
		(net "PCIE_TX_CAP_P13")
	)
	(segment
		(start 319.456562 -39.826184)
		(end 313.905646 -40.8051)
		(width 0.1397)
		(layer "In5.Cu")
		(net "PCIE_TX_CAP_P13")
	)
	(segment
		(start 289.477704 -47.816008)
		(end 281.119834 -46.3423)
		(width 0.1397)
		(layer "In5.Cu")
		(net "PCIE_TX_CAP_P13")
	)
	(segment
		(start 291.855652 -47.34052)
		(end 289.477704 -47.816008)
		(width 0.1397)
		(layer "In5.Cu")
		(net "PCIE_TX_CAP_P13")
	)
	(segment
		(start 257.553968 -38.045898)
		(end 257.099816 -38.50005)
		(width 0.1016)
		(layer "In5.Cu")
		(net "PCIE_TX_CAP_P13")
	)
	(segment
		(start 320.713862 -39.009574)
		(end 319.456562 -39.826184)
		(width 0.1397)
		(layer "In5.Cu")
		(net "PCIE_TX_CAP_P13")
	)
	(segment
		(start 259.770626 -37.901626)
		(end 257.902202 -37.901626)
		(width 0.1016)
		(layer "In5.Cu")
		(net "PCIE_TX_CAP_P13")
	)
	(segment
		(start 264.435082 -37.901626)
		(end 259.770626 -37.901626)
		(width 0.1397)
		(layer "In5.Cu")
		(net "PCIE_TX_CAP_P13")
	)
	(segment
		(start 274.505928 -41.710864)
		(end 273.23415 -39.89451)
		(width 0.1397)
		(layer "In5.Cu")
		(net "PCIE_TX_CAP_P13")
	)
	(segment
		(start 273.23415 -39.89451)
		(end 270.627348 -38.069266)
		(width 0.1397)
		(layer "In5.Cu")
		(net "PCIE_TX_CAP_P13")
	)
	(segment
		(start 301.990252 -47.8536)
		(end 298.815252 -47.2186)
		(width 0.1397)
		(layer "In5.Cu")
		(net "PCIE_TX_CAP_P13")
	)
	(segment
		(start 295.030652 -47.97552)
		(end 291.855652 -47.34052)
		(width 0.1397)
		(layer "In5.Cu")
		(net "PCIE_TX_CAP_P13")
	)
	(arc
		(start 257.902202 -37.901626)
		(mid 257.837247 -37.90586)
		(end 257.773424 -37.918644)
		(width 0.1016)
		(layer "In5.Cu")
		(net "PCIE_TX_CAP_P13")
	)
	(arc
		(start 257.773424 -37.918644)
		(mid 257.655373 -37.967913)
		(end 257.553968 -38.045898)
		(width 0.1016)
		(layer "In5.Cu")
		(net "PCIE_TX_CAP_P13")
	)
	(arc
		(start 323.649594 -35.005772)
		(mid 323.790061 -35.216135)
		(end 323.839332 -35.464242)
		(width 0.1397)
		(layer "In5.Cu")
		(net "PCIE_TX_CAP_P13")
	)
	(segment
		(start 319.987676 -34.718498)
		(end 319.987676 -36.593526)
		(width 0.136652)
		(layer "F.Cu")
		(net "PCIE_TX_CAP_P12")
	)
	(segment
		(start 257.599942 -37.999924)
		(end 258.099814 -37.500052)
		(width 0.136652)
		(layer "F.Cu")
		(net "PCIE_TX_CAP_P12")
	)
	(segment
		(start 319.870836 -36.875974)
		(end 319.720976 -37.02558)
		(width 0.136652)
		(layer "F.Cu")
		(net "PCIE_TX_CAP_P12")
	)
	(via
		(at 319.720976 -37.02558)
		(size 0.508)
		(drill 0.254)
		(layers "F.Cu" "B.Cu")
		(net "PCIE_TX_CAP_P12")
	)
	(via
		(at 258.099814 -37.500052)
		(size 0.4572)
		(drill 0.2032)
		(layers "F.Cu" "B.Cu")
		(net "PCIE_TX_CAP_P12")
	)
	(arc
		(start 319.987676 -36.593526)
		(mid 319.957365 -36.746381)
		(end 319.870836 -36.875974)
		(width 0.136652)
		(layer "F.Cu")
		(net "PCIE_TX_CAP_P12")
	)
	(arc
		(start 319.670176 -33.951926)
		(mid 319.905179 -34.303632)
		(end 319.987676 -34.718498)
		(width 0.136652)
		(layer "F.Cu")
		(net "PCIE_TX_CAP_P12")
	)
	(segment
		(start 310.516778 -42.083736)
		(end 313.389264 -40.073326)
		(width 0.1397)
		(layer "In5.Cu")
		(net "PCIE_TX_CAP_P12")
	)
	(segment
		(start 275.14677 -40.670226)
		(end 281.676602 -45.24248)
		(width 0.1397)
		(layer "In5.Cu")
		(net "PCIE_TX_CAP_P12")
	)
	(segment
		(start 299.38091 -46.1137)
		(end 302.55591 -46.7487)
		(width 0.1397)
		(layer "In5.Cu")
		(net "PCIE_TX_CAP_P12")
	)
	(segment
		(start 260.2484 -36.9824)
		(end 264.233914 -36.9824)
		(width 0.1397)
		(layer "In5.Cu")
		(net "PCIE_TX_CAP_P12")
	)
	(segment
		(start 271.184116 -37.144452)
		(end 274.11426 -39.19601)
		(width 0.1397)
		(layer "In5.Cu")
		(net "PCIE_TX_CAP_P12")
	)
	(segment
		(start 259.715 -36.7538)
		(end 259.728208 -36.766754)
		(width 0.1397)
		(layer "In5.Cu")
		(net "PCIE_TX_CAP_P12")
	)
	(segment
		(start 274.11426 -39.19601)
		(end 275.14677 -40.670226)
		(width 0.1397)
		(layer "In5.Cu")
		(net "PCIE_TX_CAP_P12")
	)
	(segment
		(start 309.007764 -44.238164)
		(end 310.516778 -42.083736)
		(width 0.1397)
		(layer "In5.Cu")
		(net "PCIE_TX_CAP_P12")
	)
	(segment
		(start 281.676602 -45.24248)
		(end 290.02482 -46.714918)
		(width 0.1397)
		(layer "In5.Cu")
		(net "PCIE_TX_CAP_P12")
	)
	(segment
		(start 264.233914 -36.9824)
		(end 267.24991 -36.450778)
		(width 0.1397)
		(layer "In5.Cu")
		(net "PCIE_TX_CAP_P12")
	)
	(segment
		(start 259.00253 -36.555426)
		(end 259.235956 -36.555426)
		(width 0.1397)
		(layer "In5.Cu")
		(net "PCIE_TX_CAP_P12")
	)
	(segment
		(start 267.24991 -36.450778)
		(end 271.184116 -37.144452)
		(width 0.1397)
		(layer "In5.Cu")
		(net "PCIE_TX_CAP_P12")
	)
	(segment
		(start 319.63233 -38.002972)
		(end 319.951862 -37.68344)
		(width 0.1397)
		(layer "In5.Cu")
		(net "PCIE_TX_CAP_P12")
	)
	(segment
		(start 258.434586 -37.1094)
		(end 258.43484 -37.1094)
		(width 0.1397)
		(layer "In5.Cu")
		(net "PCIE_TX_CAP_P12")
	)
	(segment
		(start 306.568602 -45.94606)
		(end 309.007764 -44.238164)
		(width 0.1397)
		(layer "In5.Cu")
		(net "PCIE_TX_CAP_P12")
	)
	(segment
		(start 319.951862 -37.68344)
		(end 319.951862 -37.427154)
		(width 0.1397)
		(layer "In5.Cu")
		(net "PCIE_TX_CAP_P12")
	)
	(segment
		(start 313.389264 -40.073326)
		(end 317.584328 -39.332662)
		(width 0.1397)
		(layer "In5.Cu")
		(net "PCIE_TX_CAP_P12")
	)
	(segment
		(start 295.114218 -46.96714)
		(end 299.38091 -46.1137)
		(width 0.1397)
		(layer "In5.Cu")
		(net "PCIE_TX_CAP_P12")
	)
	(segment
		(start 317.584328 -39.332662)
		(end 319.63233 -38.002972)
		(width 0.1397)
		(layer "In5.Cu")
		(net "PCIE_TX_CAP_P12")
	)
	(segment
		(start 258.434586 -37.201348)
		(end 258.434586 -37.1094)
		(width 0.1397)
		(layer "In5.Cu")
		(net "PCIE_TX_CAP_P12")
	)
	(segment
		(start 258.32562 -37.40658)
		(end 258.366514 -37.365686)
		(width 0.1397)
		(layer "In5.Cu")
		(net "PCIE_TX_CAP_P12")
	)
	(segment
		(start 290.02482 -46.714918)
		(end 291.939218 -46.33214)
		(width 0.1397)
		(layer "In5.Cu")
		(net "PCIE_TX_CAP_P12")
	)
	(segment
		(start 291.939218 -46.33214)
		(end 295.114218 -46.96714)
		(width 0.1397)
		(layer "In5.Cu")
		(net "PCIE_TX_CAP_P12")
	)
	(segment
		(start 302.55591 -46.7487)
		(end 306.568602 -45.94606)
		(width 0.1397)
		(layer "In5.Cu")
		(net "PCIE_TX_CAP_P12")
	)
	(arc
		(start 258.366514 -37.365686)
		(mid 258.416894 -37.290287)
		(end 258.434586 -37.201348)
		(width 0.1397)
		(layer "In5.Cu")
		(net "PCIE_TX_CAP_P12")
	)
	(arc
		(start 258.099814 -37.500052)
		(mid 258.222011 -37.475763)
		(end 258.32562 -37.40658)
		(width 0.1397)
		(layer "In5.Cu")
		(net "PCIE_TX_CAP_P12")
	)
	(arc
		(start 258.43484 -37.1094)
		(mid 258.480623 -36.899615)
		(end 258.600956 -36.721796)
		(width 0.1397)
		(layer "In5.Cu")
		(net "PCIE_TX_CAP_P12")
	)
	(arc
		(start 259.235956 -36.555426)
		(mid 259.495193 -36.606991)
		(end 259.715 -36.7538)
		(width 0.1397)
		(layer "In5.Cu")
		(net "PCIE_TX_CAP_P12")
	)
	(arc
		(start 259.728208 -36.766754)
		(mid 259.966859 -36.926309)
		(end 260.2484 -36.9824)
		(width 0.1397)
		(layer "In5.Cu")
		(net "PCIE_TX_CAP_P12")
	)
	(arc
		(start 258.837176 -36.580064)
		(mid 258.918939 -36.561611)
		(end 259.00253 -36.555426)
		(width 0.1397)
		(layer "In5.Cu")
		(net "PCIE_TX_CAP_P12")
	)
	(arc
		(start 319.951862 -37.427154)
		(mid 319.890018 -37.195558)
		(end 319.720976 -37.02558)
		(width 0.1397)
		(layer "In5.Cu")
		(net "PCIE_TX_CAP_P12")
	)
	(arc
		(start 258.600956 -36.721796)
		(mid 258.710352 -36.636404)
		(end 258.837176 -36.580064)
		(width 0.1397)
		(layer "In5.Cu")
		(net "PCIE_TX_CAP_P12")
	)
	(segment
		(start 315.03366 -34.864548)
		(end 314.8838 -35.014154)
		(width 0.136652)
		(layer "F.Cu")
		(net "PCIE_TX_CAP_P11")
	)
	(segment
		(start 256.599944 -36.999926)
		(end 257.099816 -36.500054)
		(width 0.136652)
		(layer "F.Cu")
		(net "PCIE_TX_CAP_P11")
	)
	(segment
		(start 315.1505 -34.4424)
		(end 315.1505 -34.5821)
		(width 0.136652)
		(layer "F.Cu")
		(net "PCIE_TX_CAP_P11")
	)
	(segment
		(start 314.833 -33.9725)
		(end 315.042804 -34.18205)
		(width 0.136652)
		(layer "F.Cu")
		(net "PCIE_TX_CAP_P11")
	)
	(via
		(at 257.099816 -36.500054)
		(size 0.4572)
		(drill 0.2032)
		(layers "F.Cu" "B.Cu")
		(net "PCIE_TX_CAP_P11")
	)
	(via
		(at 314.8838 -35.014154)
		(size 0.508)
		(drill 0.254)
		(layers "F.Cu" "B.Cu")
		(net "PCIE_TX_CAP_P11")
	)
	(arc
		(start 315.1505 -34.5821)
		(mid 315.120189 -34.734955)
		(end 315.03366 -34.864548)
		(width 0.136652)
		(layer "F.Cu")
		(net "PCIE_TX_CAP_P11")
	)
	(arc
		(start 315.042804 -34.18205)
		(mid 315.122535 -34.301515)
		(end 315.1505 -34.4424)
		(width 0.136652)
		(layer "F.Cu")
		(net "PCIE_TX_CAP_P11")
	)
	(segment
		(start 272.16354 -36.136326)
		(end 267.526262 -35.318954)
		(width 0.1397)
		(layer "In5.Cu")
		(net "PCIE_TX_CAP_P11")
	)
	(segment
		(start 295.316148 -45.922946)
		(end 291.904166 -45.240702)
		(width 0.1397)
		(layer "In5.Cu")
		(net "PCIE_TX_CAP_P11")
	)
	(segment
		(start 286.147002 -44.717716)
		(end 286.147002 -44.717462)
		(width 0.1397)
		(layer "In5.Cu")
		(net "PCIE_TX_CAP_P11")
	)
	(segment
		(start 267.526262 -35.318954)
		(end 264.182606 -35.908488)
		(width 0.1397)
		(layer "In5.Cu")
		(net "PCIE_TX_CAP_P11")
	)
	(segment
		(start 259.835142 -35.90163)
		(end 257.902202 -35.90163)
		(width 0.1016)
		(layer "In5.Cu")
		(net "PCIE_TX_CAP_P11")
	)
	(segment
		(start 259.842 -35.908488)
		(end 259.835142 -35.90163)
		(width 0.1016)
		(layer "In5.Cu")
		(net "PCIE_TX_CAP_P11")
	)
	(segment
		(start 291.904166 -45.240702)
		(end 290.332668 -45.5549)
		(width 0.1397)
		(layer "In5.Cu")
		(net "PCIE_TX_CAP_P11")
	)
	(segment
		(start 290.332668 -45.5549)
		(end 286.147002 -44.717716)
		(width 0.1397)
		(layer "In5.Cu")
		(net "PCIE_TX_CAP_P11")
	)
	(segment
		(start 257.553968 -36.045902)
		(end 257.099816 -36.500054)
		(width 0.1016)
		(layer "In5.Cu")
		(net "PCIE_TX_CAP_P11")
	)
	(segment
		(start 264.182606 -35.908488)
		(end 259.842 -35.908488)
		(width 0.1397)
		(layer "In5.Cu")
		(net "PCIE_TX_CAP_P11")
	)
	(segment
		(start 281.962606 -43.880786)
		(end 276.060662 -39.748206)
		(width 0.1397)
		(layer "In5.Cu")
		(net "PCIE_TX_CAP_P11")
	)
	(segment
		(start 315.1251 -35.59683)
		(end 315.1251 -36.043108)
		(width 0.1397)
		(layer "In5.Cu")
		(net "PCIE_TX_CAP_P11")
	)
	(segment
		(start 313.86272 -38.365684)
		(end 309.983378 -41.08196)
		(width 0.1397)
		(layer "In5.Cu")
		(net "PCIE_TX_CAP_P11")
	)
	(segment
		(start 286.147002 -44.717462)
		(end 281.962606 -43.880786)
		(width 0.1397)
		(layer "In5.Cu")
		(net "PCIE_TX_CAP_P11")
	)
	(segment
		(start 303.032668 -45.5549)
		(end 300.09465 -44.967144)
		(width 0.1397)
		(layer "In5.Cu")
		(net "PCIE_TX_CAP_P11")
	)
	(segment
		(start 274.847558 -38.015672)
		(end 272.16354 -36.136326)
		(width 0.1397)
		(layer "In5.Cu")
		(net "PCIE_TX_CAP_P11")
	)
	(segment
		(start 308.410864 -43.32732)
		(end 306.107846 -44.939712)
		(width 0.1397)
		(layer "In5.Cu")
		(net "PCIE_TX_CAP_P11")
	)
	(segment
		(start 300.09465 -44.967144)
		(end 295.316148 -45.922946)
		(width 0.1397)
		(layer "In5.Cu")
		(net "PCIE_TX_CAP_P11")
	)
	(segment
		(start 309.983378 -41.08196)
		(end 308.410864 -43.32732)
		(width 0.1397)
		(layer "In5.Cu")
		(net "PCIE_TX_CAP_P11")
	)
	(segment
		(start 276.060662 -39.748206)
		(end 274.847558 -38.015672)
		(width 0.1397)
		(layer "In5.Cu")
		(net "PCIE_TX_CAP_P11")
	)
	(segment
		(start 306.107846 -44.939712)
		(end 303.032668 -45.5549)
		(width 0.1397)
		(layer "In5.Cu")
		(net "PCIE_TX_CAP_P11")
	)
	(segment
		(start 315.1251 -36.043108)
		(end 315.002418 -36.737798)
		(width 0.1397)
		(layer "In5.Cu")
		(net "PCIE_TX_CAP_P11")
	)
	(segment
		(start 315.002418 -36.737798)
		(end 313.86272 -38.365684)
		(width 0.1397)
		(layer "In5.Cu")
		(net "PCIE_TX_CAP_P11")
	)
	(arc
		(start 314.8838 -35.014154)
		(mid 315.062427 -35.281488)
		(end 315.1251 -35.59683)
		(width 0.1397)
		(layer "In5.Cu")
		(net "PCIE_TX_CAP_P11")
	)
	(arc
		(start 257.902202 -35.90163)
		(mid 257.837247 -35.905864)
		(end 257.773424 -35.918648)
		(width 0.1016)
		(layer "In5.Cu")
		(net "PCIE_TX_CAP_P11")
	)
	(arc
		(start 257.773424 -35.918648)
		(mid 257.655373 -35.967917)
		(end 257.553968 -36.045902)
		(width 0.1016)
		(layer "In5.Cu")
		(net "PCIE_TX_CAP_P11")
	)
	(segment
		(start 312.942986 -34.76752)
		(end 312.942986 -35.753548)
		(width 0.136652)
		(layer "F.Cu")
		(net "PCIE_TX_CAP_P10")
	)
	(segment
		(start 312.826146 -36.035996)
		(end 312.676286 -36.185602)
		(width 0.136652)
		(layer "F.Cu")
		(net "PCIE_TX_CAP_P10")
	)
	(segment
		(start 257.599942 -35.999928)
		(end 258.099814 -35.500056)
		(width 0.136652)
		(layer "F.Cu")
		(net "PCIE_TX_CAP_P10")
	)
	(via
		(at 312.676286 -36.185602)
		(size 0.508)
		(drill 0.254)
		(layers "F.Cu" "B.Cu")
		(net "PCIE_TX_CAP_P10")
	)
	(via
		(at 258.099814 -35.500056)
		(size 0.4572)
		(drill 0.2032)
		(layers "F.Cu" "B.Cu")
		(net "PCIE_TX_CAP_P10")
	)
	(arc
		(start 312.942986 -35.753548)
		(mid 312.912675 -35.906403)
		(end 312.826146 -36.035996)
		(width 0.136652)
		(layer "F.Cu")
		(net "PCIE_TX_CAP_P10")
	)
	(arc
		(start 312.625486 -34.000948)
		(mid 312.860489 -34.352654)
		(end 312.942986 -34.76752)
		(width 0.136652)
		(layer "F.Cu")
		(net "PCIE_TX_CAP_P10")
	)
	(segment
		(start 291.618416 -44.092622)
		(end 290.720526 -44.2722)
		(width 0.1397)
		(layer "In5.Cu")
		(net "PCIE_TX_CAP_P10")
	)
	(segment
		(start 258.45643 -35.14344)
		(end 258.099814 -35.500056)
		(width 0.1016)
		(layer "In5.Cu")
		(net "PCIE_TX_CAP_P10")
	)
	(segment
		(start 275.771102 -37.398452)
		(end 275.556472 -37.092382)
		(width 0.1397)
		(layer "In5.Cu")
		(net "PCIE_TX_CAP_P10")
	)
	(segment
		(start 260.266688 -34.901632)
		(end 259.013198 -34.901632)
		(width 0.1016)
		(layer "In5.Cu")
		(net "PCIE_TX_CAP_P10")
	)
	(segment
		(start 281.644344 -42.457116)
		(end 277.071074 -39.255192)
		(width 0.1397)
		(layer "In5.Cu")
		(net "PCIE_TX_CAP_P10")
	)
	(segment
		(start 311.327546 -39.119302)
		(end 308.904386 -40.815768)
		(width 0.1397)
		(layer "In5.Cu")
		(net "PCIE_TX_CAP_P10")
	)
	(segment
		(start 308.904386 -40.815768)
		(end 307.816504 -42.369486)
		(width 0.1397)
		(layer "In5.Cu")
		(net "PCIE_TX_CAP_P10")
	)
	(segment
		(start 307.816504 -42.369486)
		(end 306.077874 -43.586908)
		(width 0.1397)
		(layer "In5.Cu")
		(net "PCIE_TX_CAP_P10")
	)
	(segment
		(start 262.756904 -34.909506)
		(end 260.274562 -34.909506)
		(width 0.1397)
		(layer "In5.Cu")
		(net "PCIE_TX_CAP_P10")
	)
	(segment
		(start 277.071074 -39.255192)
		(end 275.95195 -37.65677)
		(width 0.1397)
		(layer "In5.Cu")
		(net "PCIE_TX_CAP_P10")
	)
	(segment
		(start 312.89244 -36.883848)
		(end 311.327546 -39.119302)
		(width 0.1397)
		(layer "In5.Cu")
		(net "PCIE_TX_CAP_P10")
	)
	(segment
		(start 303.050702 -44.120562)
		(end 301.153576 -43.786298)
		(width 0.1397)
		(layer "In5.Cu")
		(net "PCIE_TX_CAP_P10")
	)
	(segment
		(start 290.720526 -44.2722)
		(end 281.644344 -42.457116)
		(width 0.1397)
		(layer "In5.Cu")
		(net "PCIE_TX_CAP_P10")
	)
	(segment
		(start 259.013198 -34.901632)
		(end 259.008626 -34.906204)
		(width 0.1016)
		(layer "In5.Cu")
		(net "PCIE_TX_CAP_P10")
	)
	(segment
		(start 306.077874 -43.586908)
		(end 303.050702 -44.120562)
		(width 0.1397)
		(layer "In5.Cu")
		(net "PCIE_TX_CAP_P10")
	)
	(segment
		(start 267.806424 -34.101786)
		(end 262.756904 -34.909506)
		(width 0.1397)
		(layer "In5.Cu")
		(net "PCIE_TX_CAP_P10")
	)
	(segment
		(start 295.620186 -44.892976)
		(end 291.618416 -44.092622)
		(width 0.1397)
		(layer "In5.Cu")
		(net "PCIE_TX_CAP_P10")
	)
	(segment
		(start 272.457164 -34.921952)
		(end 267.806424 -34.101786)
		(width 0.1397)
		(layer "In5.Cu")
		(net "PCIE_TX_CAP_P10")
	)
	(segment
		(start 260.274562 -34.909506)
		(end 260.266688 -34.901632)
		(width 0.1016)
		(layer "In5.Cu")
		(net "PCIE_TX_CAP_P10")
	)
	(segment
		(start 275.95195 -37.65677)
		(end 275.771102 -37.398452)
		(width 0.1397)
		(layer "In5.Cu")
		(net "PCIE_TX_CAP_P10")
	)
	(segment
		(start 312.89244 -36.707318)
		(end 312.89244 -36.883848)
		(width 0.1397)
		(layer "In5.Cu")
		(net "PCIE_TX_CAP_P10")
	)
	(segment
		(start 275.556472 -37.092382)
		(end 272.457164 -34.921952)
		(width 0.1397)
		(layer "In5.Cu")
		(net "PCIE_TX_CAP_P10")
	)
	(segment
		(start 259.008626 -34.906204)
		(end 258.45643 -35.14344)
		(width 0.1016)
		(layer "In5.Cu")
		(net "PCIE_TX_CAP_P10")
	)
	(segment
		(start 301.153576 -43.786298)
		(end 295.620186 -44.892976)
		(width 0.1397)
		(layer "In5.Cu")
		(net "PCIE_TX_CAP_P10")
	)
	(arc
		(start 312.676286 -36.185602)
		(mid 312.836225 -36.424967)
		(end 312.89244 -36.707318)
		(width 0.1397)
		(layer "In5.Cu")
		(net "PCIE_TX_CAP_P10")
	)
	(segment
		(start 272.5166 -14.7828)
		(end 273.1262 -14.7828)
		(width 0.136652)
		(layer "F.Cu")
		(net "PCIE_TX_CAP_P1")
	)
	(segment
		(start 252.599952 -31.999936)
		(end 253.099824 -31.500064)
		(width 0.136652)
		(layer "F.Cu")
		(net "PCIE_TX_CAP_P1")
	)
	(via
		(at 272.06829 -14.52245)
		(size 0.508)
		(drill 0.254)
		(layers "F.Cu" "B.Cu")
		(net "PCIE_TX_CAP_P1")
	)
	(via
		(at 253.099824 -31.500064)
		(size 0.4572)
		(drill 0.2032)
		(layers "F.Cu" "B.Cu")
		(net "PCIE_TX_CAP_P1")
	)
	(arc
		(start 273.1262 -14.7828)
		(mid 273.365231 -14.696717)
		(end 273.4945 -14.478)
		(width 0.136652)
		(layer "F.Cu")
		(net "PCIE_TX_CAP_P1")
	)
	(arc
		(start 272.06829 -14.52245)
		(mid 272.257384 -14.713003)
		(end 272.5166 -14.7828)
		(width 0.136652)
		(layer "F.Cu")
		(net "PCIE_TX_CAP_P1")
	)
	(segment
		(start 270.273018 -19.821144)
		(end 269.232634 -20.496784)
		(width 0.1397)
		(layer "In5.Cu")
		(net "PCIE_TX_CAP_P1")
	)
	(segment
		(start 270.529304 -15.254478)
		(end 270.528034 -15.256256)
		(width 0.1397)
		(layer "In5.Cu")
		(net "PCIE_TX_CAP_P1")
	)
	(segment
		(start 270.528034 -15.256256)
		(end 270.357092 -16.059404)
		(width 0.1397)
		(layer "In5.Cu")
		(net "PCIE_TX_CAP_P1")
	)
	(segment
		(start 252.4125 -28.20924)
		(end 252.4125 -28.97759)
		(width 0.1016)
		(layer "In5.Cu")
		(net "PCIE_TX_CAP_P1")
	)
	(segment
		(start 270.827246 -18.269712)
		(end 270.606774 -19.307302)
		(width 0.1397)
		(layer "In5.Cu")
		(net "PCIE_TX_CAP_P1")
	)
	(segment
		(start 270.357092 -16.059404)
		(end 270.827246 -18.269712)
		(width 0.1397)
		(layer "In5.Cu")
		(net "PCIE_TX_CAP_P1")
	)
	(segment
		(start 254.174498 -22.927056)
		(end 252.349 -25.535382)
		(width 0.1397)
		(layer "In5.Cu")
		(net "PCIE_TX_CAP_P1")
	)
	(segment
		(start 252.349 -28.12034)
		(end 252.349 -28.14574)
		(width 0.1016)
		(layer "In5.Cu")
		(net "PCIE_TX_CAP_P1")
	)
	(segment
		(start 252.349 -28.14574)
		(end 252.4125 -28.20924)
		(width 0.1016)
		(layer "In5.Cu")
		(net "PCIE_TX_CAP_P1")
	)
	(segment
		(start 268.02715 -20.75307)
		(end 264.27811 -19.956272)
		(width 0.1397)
		(layer "In5.Cu")
		(net "PCIE_TX_CAP_P1")
	)
	(segment
		(start 270.606774 -19.307302)
		(end 270.273018 -19.821144)
		(width 0.1397)
		(layer "In5.Cu")
		(net "PCIE_TX_CAP_P1")
	)
	(segment
		(start 252.499114 -29.064204)
		(end 252.499114 -30.632146)
		(width 0.1016)
		(layer "In5.Cu")
		(net "PCIE_TX_CAP_P1")
	)
	(segment
		(start 271.258538 -14.739874)
		(end 270.736822 -15.053564)
		(width 0.1397)
		(layer "In5.Cu")
		(net "PCIE_TX_CAP_P1")
	)
	(segment
		(start 252.4125 -28.97759)
		(end 252.499114 -29.064204)
		(width 0.1016)
		(layer "In5.Cu")
		(net "PCIE_TX_CAP_P1")
	)
	(segment
		(start 271.703546 -14.739874)
		(end 271.258538 -14.739874)
		(width 0.1397)
		(layer "In5.Cu")
		(net "PCIE_TX_CAP_P1")
	)
	(segment
		(start 255.864106 -21.744178)
		(end 254.174498 -22.927056)
		(width 0.1397)
		(layer "In5.Cu")
		(net "PCIE_TX_CAP_P1")
	)
	(segment
		(start 264.27811 -19.956272)
		(end 255.864106 -21.744178)
		(width 0.1397)
		(layer "In5.Cu")
		(net "PCIE_TX_CAP_P1")
	)
	(segment
		(start 269.232634 -20.496784)
		(end 268.02715 -20.75307)
		(width 0.1397)
		(layer "In5.Cu")
		(net "PCIE_TX_CAP_P1")
	)
	(segment
		(start 252.349 -25.535382)
		(end 252.349 -28.12034)
		(width 0.1397)
		(layer "In5.Cu")
		(net "PCIE_TX_CAP_P1")
	)
	(arc
		(start 272.06829 -14.52245)
		(mid 271.915878 -14.68144)
		(end 271.703546 -14.739874)
		(width 0.1397)
		(layer "In5.Cu")
		(net "PCIE_TX_CAP_P1")
	)
	(arc
		(start 270.736822 -15.053564)
		(mid 270.621599 -15.142179)
		(end 270.529304 -15.254478)
		(width 0.1397)
		(layer "In5.Cu")
		(net "PCIE_TX_CAP_P1")
	)
	(arc
		(start 252.606302 -30.982158)
		(mid 252.831387 -31.261767)
		(end 253.099824 -31.500064)
		(width 0.1016)
		(layer "In5.Cu")
		(net "PCIE_TX_CAP_P1")
	)
	(arc
		(start 252.499114 -30.632146)
		(mid 252.52651 -30.815175)
		(end 252.606302 -30.982158)
		(width 0.1016)
		(layer "In5.Cu")
		(net "PCIE_TX_CAP_P1")
	)
	(segment
		(start 251.599954 -30.999938)
		(end 252.099826 -30.500066)
		(width 0.136652)
		(layer "F.Cu")
		(net "PCIE_TX_CAP_P0")
	)
	(segment
		(start 271.905984 -13.226796)
		(end 272.9738 -13.226796)
		(width 0.136652)
		(layer "F.Cu")
		(net "PCIE_TX_CAP_P0")
	)
	(segment
		(start 273.24431 -13.33881)
		(end 273.4945 -13.589)
		(width 0.136652)
		(layer "F.Cu")
		(net "PCIE_TX_CAP_P0")
	)
	(segment
		(start 269.05839 -14.397736)
		(end 269.171674 -14.391894)
		(width 0.136652)
		(layer "F.Cu")
		(net "PCIE_TX_CAP_P0")
	)
	(via
		(at 252.099826 -30.500066)
		(size 0.4572)
		(drill 0.2032)
		(layers "F.Cu" "B.Cu")
		(net "PCIE_TX_CAP_P0")
	)
	(via
		(at 268.478 -14.6558)
		(size 0.508)
		(drill 0.254)
		(layers "F.Cu" "B.Cu")
		(net "PCIE_TX_CAP_P0")
	)
	(arc
		(start 270.238728 -13.917422)
		(mid 271.003672 -13.406303)
		(end 271.905984 -13.226796)
		(width 0.136652)
		(layer "F.Cu")
		(net "PCIE_TX_CAP_P0")
	)
	(arc
		(start 268.478 -14.6558)
		(mid 268.744247 -14.472908)
		(end 269.05839 -14.397736)
		(width 0.136652)
		(layer "F.Cu")
		(net "PCIE_TX_CAP_P0")
	)
	(arc
		(start 272.9738 -13.226796)
		(mid 273.120186 -13.255914)
		(end 273.24431 -13.33881)
		(width 0.136652)
		(layer "F.Cu")
		(net "PCIE_TX_CAP_P0")
	)
	(arc
		(start 269.171674 -14.391894)
		(mid 269.7492 -14.253625)
		(end 270.238728 -13.917422)
		(width 0.136652)
		(layer "F.Cu")
		(net "PCIE_TX_CAP_P0")
	)
	(segment
		(start 252.099826 -30.105096)
		(end 252.099826 -30.500066)
		(width 0.1016)
		(layer "In5.Cu")
		(net "PCIE_TX_CAP_P0")
	)
	(segment
		(start 251.494036 -28.424886)
		(end 251.494036 -29.64815)
		(width 0.1016)
		(layer "In5.Cu")
		(net "PCIE_TX_CAP_P0")
	)
	(segment
		(start 256.48031 -19.93773)
		(end 251.789438 -22.539452)
		(width 0.1397)
		(layer "In5.Cu")
		(net "PCIE_TX_CAP_P0")
	)
	(segment
		(start 251.427742 -28.358592)
		(end 251.494036 -28.424886)
		(width 0.1016)
		(layer "In5.Cu")
		(net "PCIE_TX_CAP_P0")
	)
	(segment
		(start 251.789438 -22.539452)
		(end 251.427742 -24.591772)
		(width 0.1397)
		(layer "In5.Cu")
		(net "PCIE_TX_CAP_P0")
	)
	(segment
		(start 251.849382 -30.003496)
		(end 251.998226 -30.003496)
		(width 0.1016)
		(layer "In5.Cu")
		(net "PCIE_TX_CAP_P0")
	)
	(segment
		(start 269.243302 -14.464284)
		(end 269.307564 -14.915134)
		(width 0.1397)
		(layer "In5.Cu")
		(net "PCIE_TX_CAP_P0")
	)
	(segment
		(start 267.6652 -16.518382)
		(end 258.865624 -18.388584)
		(width 0.1397)
		(layer "In5.Cu")
		(net "PCIE_TX_CAP_P0")
	)
	(segment
		(start 258.865624 -18.388584)
		(end 256.48031 -19.93773)
		(width 0.1397)
		(layer "In5.Cu")
		(net "PCIE_TX_CAP_P0")
	)
	(segment
		(start 268.706346 -15.842234)
		(end 267.6652 -16.518382)
		(width 0.1397)
		(layer "In5.Cu")
		(net "PCIE_TX_CAP_P0")
	)
	(segment
		(start 269.109698 -14.361414)
		(end 269.243302 -14.464284)
		(width 0.1397)
		(layer "In5.Cu")
		(net "PCIE_TX_CAP_P0")
	)
	(segment
		(start 268.772386 -14.361414)
		(end 269.109698 -14.361414)
		(width 0.1397)
		(layer "In5.Cu")
		(net "PCIE_TX_CAP_P0")
	)
	(segment
		(start 251.427742 -24.591772)
		(end 251.427742 -28.358592)
		(width 0.1397)
		(layer "In5.Cu")
		(net "PCIE_TX_CAP_P0")
	)
	(segment
		(start 269.307564 -14.915134)
		(end 268.706346 -15.842234)
		(width 0.1397)
		(layer "In5.Cu")
		(net "PCIE_TX_CAP_P0")
	)
	(arc
		(start 251.494036 -29.64815)
		(mid 251.598114 -29.899418)
		(end 251.849382 -30.003496)
		(width 0.1016)
		(layer "In5.Cu")
		(net "PCIE_TX_CAP_P0")
	)
	(arc
		(start 268.478 -14.6558)
		(mid 268.564224 -14.447638)
		(end 268.772386 -14.361414)
		(width 0.1397)
		(layer "In5.Cu")
		(net "PCIE_TX_CAP_P0")
	)
	(arc
		(start 251.998226 -30.003496)
		(mid 252.070068 -30.033254)
		(end 252.099826 -30.105096)
		(width 0.1016)
		(layer "In5.Cu")
		(net "PCIE_TX_CAP_P0")
	)
	(segment
		(start 182.72252 -20.1041)
		(end 182.43296 -20.1041)
		(width 0.136652)
		(layer "F.Cu")
		(net "PCIE_TX_CAP_N95")
	)
	(segment
		(start 229.599998 -29.99994)
		(end 229.100126 -29.500068)
		(width 0.136652)
		(layer "F.Cu")
		(net "PCIE_TX_CAP_N95")
	)
	(segment
		(start 182.285132 -20.042632)
		(end 182.0545 -19.812)
		(width 0.136652)
		(layer "F.Cu")
		(net "PCIE_TX_CAP_N95")
	)
	(via
		(at 229.100126 -29.500068)
		(size 0.4572)
		(drill 0.2032)
		(layers "F.Cu" "B.Cu")
		(net "PCIE_TX_CAP_N95")
	)
	(via
		(at 183.0832 -19.8501)
		(size 0.508)
		(drill 0.254)
		(layers "F.Cu" "B.Cu")
		(net "PCIE_TX_CAP_N95")
	)
	(arc
		(start 183.0832 -19.8501)
		(mid 182.943101 -20.034251)
		(end 182.72252 -20.1041)
		(width 0.136652)
		(layer "F.Cu")
		(net "PCIE_TX_CAP_N95")
	)
	(arc
		(start 182.43296 -20.1041)
		(mid 182.352934 -20.08807)
		(end 182.285132 -20.042632)
		(width 0.136652)
		(layer "F.Cu")
		(net "PCIE_TX_CAP_N95")
	)
	(segment
		(start 208.620868 -22.073616)
		(end 208.15935 -21.774912)
		(width 0.1397)
		(layer "In5.Cu")
		(net "PCIE_TX_CAP_N95")
	)
	(segment
		(start 210.436968 -24.281892)
		(end 210.004914 -24.190198)
		(width 0.1397)
		(layer "In5.Cu")
		(net "PCIE_TX_CAP_N95")
	)
	(segment
		(start 192.823592 -21.726398)
		(end 185.158888 -20.100036)
		(width 0.1397)
		(layer "In5.Cu")
		(net "PCIE_TX_CAP_N95")
	)
	(segment
		(start 205.240636 -23.406862)
		(end 205.24089 -23.406862)
		(width 0.1397)
		(layer "In5.Cu")
		(net "PCIE_TX_CAP_N95")
	)
	(segment
		(start 208.960974 -22.596348)
		(end 208.620868 -22.073616)
		(width 0.1397)
		(layer "In5.Cu")
		(net "PCIE_TX_CAP_N95")
	)
	(segment
		(start 228.695504 -29.620718)
		(end 228.695504 -28.735528)
		(width 0.1016)
		(layer "In5.Cu")
		(net "PCIE_TX_CAP_N95")
	)
	(segment
		(start 208.15935 -21.774912)
		(end 207.44688 -21.623274)
		(width 0.1397)
		(layer "In5.Cu")
		(net "PCIE_TX_CAP_N95")
	)
	(segment
		(start 185.158888 -20.100036)
		(end 183.395112 -20.100036)
		(width 0.1397)
		(layer "In5.Cu")
		(net "PCIE_TX_CAP_N95")
	)
	(segment
		(start 205.394814 -23.169626)
		(end 205.240636 -23.406862)
		(width 0.1397)
		(layer "In5.Cu")
		(net "PCIE_TX_CAP_N95")
	)
	(segment
		(start 194.331844 -21.40585)
		(end 192.823592 -21.726398)
		(width 0.1397)
		(layer "In5.Cu")
		(net "PCIE_TX_CAP_N95")
	)
	(segment
		(start 228.759004 -28.582112)
		(end 228.759004 -28.556712)
		(width 0.1016)
		(layer "In5.Cu")
		(net "PCIE_TX_CAP_N95")
	)
	(segment
		(start 228.759004 -26.786078)
		(end 228.68001 -26.336244)
		(width 0.1397)
		(layer "In5.Cu")
		(net "PCIE_TX_CAP_N95")
	)
	(segment
		(start 205.513178 -22.61362)
		(end 205.394814 -23.169626)
		(width 0.1397)
		(layer "In5.Cu")
		(net "PCIE_TX_CAP_N95")
	)
	(segment
		(start 209.140044 -23.440136)
		(end 208.960974 -22.596348)
		(width 0.1397)
		(layer "In5.Cu")
		(net "PCIE_TX_CAP_N95")
	)
	(segment
		(start 194.969892 -21.40585)
		(end 194.331844 -21.40585)
		(width 0.1397)
		(layer "In5.Cu")
		(net "PCIE_TX_CAP_N95")
	)
	(segment
		(start 215.48471 -23.20925)
		(end 210.436968 -24.281892)
		(width 0.1397)
		(layer "In5.Cu")
		(net "PCIE_TX_CAP_N95")
	)
	(segment
		(start 223.752918 -22.78126)
		(end 218.406726 -23.7236)
		(width 0.1397)
		(layer "In5.Cu")
		(net "PCIE_TX_CAP_N95")
	)
	(segment
		(start 229.040944 -29.73451)
		(end 229.04069 -29.734764)
		(width 0.1016)
		(layer "In5.Cu")
		(net "PCIE_TX_CAP_N95")
	)
	(segment
		(start 207.44688 -21.623274)
		(end 206.362554 -21.853906)
		(width 0.1397)
		(layer "In5.Cu")
		(net "PCIE_TX_CAP_N95")
	)
	(segment
		(start 200.445624 -22.569932)
		(end 194.969892 -21.40585)
		(width 0.1397)
		(layer "In5.Cu")
		(net "PCIE_TX_CAP_N95")
	)
	(segment
		(start 228.759004 -28.556712)
		(end 228.759004 -26.786078)
		(width 0.1397)
		(layer "In5.Cu")
		(net "PCIE_TX_CAP_N95")
	)
	(segment
		(start 201.86523 -23.491952)
		(end 200.445624 -22.569932)
		(width 0.1397)
		(layer "In5.Cu")
		(net "PCIE_TX_CAP_N95")
	)
	(segment
		(start 228.896672 -29.7942)
		(end 228.868986 -29.7942)
		(width 0.1016)
		(layer "In5.Cu")
		(net "PCIE_TX_CAP_N95")
	)
	(segment
		(start 229.100126 -29.500068)
		(end 229.100126 -29.591)
		(width 0.1016)
		(layer "In5.Cu")
		(net "PCIE_TX_CAP_N95")
	)
	(segment
		(start 210.004914 -24.190198)
		(end 209.351626 -23.766018)
		(width 0.1397)
		(layer "In5.Cu")
		(net "PCIE_TX_CAP_N95")
	)
	(segment
		(start 203.956158 -23.936198)
		(end 201.86523 -23.491952)
		(width 0.1397)
		(layer "In5.Cu")
		(net "PCIE_TX_CAP_N95")
	)
	(segment
		(start 228.68001 -26.336244)
		(end 228.257608 -25.733502)
		(width 0.1397)
		(layer "In5.Cu")
		(net "PCIE_TX_CAP_N95")
	)
	(segment
		(start 228.257608 -25.733502)
		(end 225.638106 -23.114)
		(width 0.1397)
		(layer "In5.Cu")
		(net "PCIE_TX_CAP_N95")
	)
	(segment
		(start 204.653642 -23.788116)
		(end 203.956158 -23.936198)
		(width 0.1397)
		(layer "In5.Cu")
		(net "PCIE_TX_CAP_N95")
	)
	(segment
		(start 209.351626 -23.766018)
		(end 209.140044 -23.440136)
		(width 0.1397)
		(layer "In5.Cu")
		(net "PCIE_TX_CAP_N95")
	)
	(segment
		(start 218.406726 -23.7236)
		(end 215.48471 -23.20925)
		(width 0.1397)
		(layer "In5.Cu")
		(net "PCIE_TX_CAP_N95")
	)
	(segment
		(start 205.24089 -23.406862)
		(end 204.653642 -23.788116)
		(width 0.1397)
		(layer "In5.Cu")
		(net "PCIE_TX_CAP_N95")
	)
	(segment
		(start 205.746858 -22.253702)
		(end 205.513178 -22.61362)
		(width 0.1397)
		(layer "In5.Cu")
		(net "PCIE_TX_CAP_N95")
	)
	(segment
		(start 225.638106 -23.114)
		(end 223.752918 -22.78126)
		(width 0.1397)
		(layer "In5.Cu")
		(net "PCIE_TX_CAP_N95")
	)
	(segment
		(start 206.362554 -21.853906)
		(end 205.746858 -22.253702)
		(width 0.1397)
		(layer "In5.Cu")
		(net "PCIE_TX_CAP_N95")
	)
	(arc
		(start 228.838506 -29.791406)
		(mid 228.735946 -29.732046)
		(end 228.695504 -29.620718)
		(width 0.1016)
		(layer "In5.Cu")
		(net "PCIE_TX_CAP_N95")
	)
	(arc
		(start 229.100126 -29.591)
		(mid 229.084757 -29.668624)
		(end 229.040944 -29.73451)
		(width 0.1016)
		(layer "In5.Cu")
		(net "PCIE_TX_CAP_N95")
	)
	(arc
		(start 228.695504 -28.735528)
		(mid 228.712001 -28.652504)
		(end 228.759004 -28.582112)
		(width 0.1016)
		(layer "In5.Cu")
		(net "PCIE_TX_CAP_N95")
	)
	(arc
		(start 183.395112 -20.100036)
		(mid 183.25903 -20.072968)
		(end 183.143652 -19.995896)
		(width 0.1397)
		(layer "In5.Cu")
		(net "PCIE_TX_CAP_N95")
	)
	(arc
		(start 228.868986 -29.7942)
		(mid 228.853684 -29.793479)
		(end 228.838506 -29.791406)
		(width 0.1016)
		(layer "In5.Cu")
		(net "PCIE_TX_CAP_N95")
	)
	(arc
		(start 229.04069 -29.734764)
		(mid 228.974599 -29.778832)
		(end 228.896672 -29.7942)
		(width 0.1016)
		(layer "In5.Cu")
		(net "PCIE_TX_CAP_N95")
	)
	(arc
		(start 183.143652 -19.995896)
		(mid 183.098903 -19.929018)
		(end 183.0832 -19.8501)
		(width 0.1397)
		(layer "In5.Cu")
		(net "PCIE_TX_CAP_N95")
	)
	(segment
		(start 182.940706 -23.802594)
		(end 183.0832 -23.6601)
		(width 0.136652)
		(layer "F.Cu")
		(net "PCIE_TX_CAP_N94")
	)
	(segment
		(start 228.6 -30.999938)
		(end 228.100128 -30.500066)
		(width 0.136652)
		(layer "F.Cu")
		(net "PCIE_TX_CAP_N94")
	)
	(segment
		(start 182.499 -23.9141)
		(end 182.671466 -23.9141)
		(width 0.136652)
		(layer "F.Cu")
		(net "PCIE_TX_CAP_N94")
	)
	(segment
		(start 182.0545 -23.622)
		(end 182.23865 -23.806404)
		(width 0.136652)
		(layer "F.Cu")
		(net "PCIE_TX_CAP_N94")
	)
	(via
		(at 183.0832 -23.6601)
		(size 0.508)
		(drill 0.254)
		(layers "F.Cu" "B.Cu")
		(net "PCIE_TX_CAP_N94")
	)
	(via
		(at 228.100128 -30.500066)
		(size 0.4572)
		(drill 0.2032)
		(layers "F.Cu" "B.Cu")
		(net "PCIE_TX_CAP_N94")
	)
	(arc
		(start 182.23865 -23.806404)
		(mid 182.358115 -23.886135)
		(end 182.499 -23.9141)
		(width 0.136652)
		(layer "F.Cu")
		(net "PCIE_TX_CAP_N94")
	)
	(arc
		(start 182.671466 -23.9141)
		(mid 182.817171 -23.885117)
		(end 182.940706 -23.802594)
		(width 0.136652)
		(layer "F.Cu")
		(net "PCIE_TX_CAP_N94")
	)
	(segment
		(start 184.563004 -21.828506)
		(end 185.431684 -21.26361)
		(width 0.1397)
		(layer "In5.Cu")
		(net "PCIE_TX_CAP_N94")
	)
	(segment
		(start 227.753926 -30.732222)
		(end 227.776024 -30.75432)
		(width 0.1016)
		(layer "In5.Cu")
		(net "PCIE_TX_CAP_N94")
	)
	(segment
		(start 226.8855 -26.393394)
		(end 227.67417 -27.519376)
		(width 0.1397)
		(layer "In5.Cu")
		(net "PCIE_TX_CAP_N94")
	)
	(segment
		(start 185.470038 -21.271738)
		(end 187.897008 -21.78431)
		(width 0.1397)
		(layer "In5.Cu")
		(net "PCIE_TX_CAP_N94")
	)
	(segment
		(start 187.99175 -21.80463)
		(end 188.669422 -22.846792)
		(width 0.1397)
		(layer "In5.Cu")
		(net "PCIE_TX_CAP_N94")
	)
	(segment
		(start 189.790578 -23.575264)
		(end 190.584582 -23.74392)
		(width 0.1397)
		(layer "In5.Cu")
		(net "PCIE_TX_CAP_N94")
	)
	(segment
		(start 183.0832 -23.6601)
		(end 183.189626 -23.76678)
		(width 0.1397)
		(layer "In5.Cu")
		(net "PCIE_TX_CAP_N94")
	)
	(segment
		(start 221.737682 -24.0919)
		(end 223.161352 -23.840948)
		(width 0.1397)
		(layer "In5.Cu")
		(net "PCIE_TX_CAP_N94")
	)
	(segment
		(start 224.584006 -24.0919)
		(end 224.9043 -24.412194)
		(width 0.1397)
		(layer "In5.Cu")
		(net "PCIE_TX_CAP_N94")
	)
	(segment
		(start 224.9043 -24.412194)
		(end 225.55708 -25.34412)
		(width 0.1397)
		(layer "In5.Cu")
		(net "PCIE_TX_CAP_N94")
	)
	(segment
		(start 227.847906 -30.784292)
		(end 227.957126 -30.784292)
		(width 0.1016)
		(layer "In5.Cu")
		(net "PCIE_TX_CAP_N94")
	)
	(segment
		(start 227.765356 -28.038044)
		(end 227.765356 -28.668218)
		(width 0.1397)
		(layer "In5.Cu")
		(net "PCIE_TX_CAP_N94")
	)
	(segment
		(start 184.178448 -23.636986)
		(end 184.563004 -21.828506)
		(width 0.1397)
		(layer "In5.Cu")
		(net "PCIE_TX_CAP_N94")
	)
	(segment
		(start 227.67417 -27.519376)
		(end 227.765356 -28.038044)
		(width 0.1397)
		(layer "In5.Cu")
		(net "PCIE_TX_CAP_N94")
	)
	(segment
		(start 215.41359 -24.134572)
		(end 218.661488 -24.707342)
		(width 0.1397)
		(layer "In5.Cu")
		(net "PCIE_TX_CAP_N94")
	)
	(segment
		(start 188.669422 -22.846792)
		(end 189.790578 -23.575264)
		(width 0.1397)
		(layer "In5.Cu")
		(net "PCIE_TX_CAP_N94")
	)
	(segment
		(start 227.701856 -28.847034)
		(end 227.701856 -30.607)
		(width 0.1016)
		(layer "In5.Cu")
		(net "PCIE_TX_CAP_N94")
	)
	(segment
		(start 194.05346 -23.006558)
		(end 207.389222 -25.840944)
		(width 0.1397)
		(layer "In5.Cu")
		(net "PCIE_TX_CAP_N94")
	)
	(segment
		(start 207.389222 -25.840944)
		(end 215.41359 -24.134572)
		(width 0.1397)
		(layer "In5.Cu")
		(net "PCIE_TX_CAP_N94")
	)
	(segment
		(start 184.033922 -23.781512)
		(end 184.178448 -23.636986)
		(width 0.1397)
		(layer "In5.Cu")
		(net "PCIE_TX_CAP_N94")
	)
	(segment
		(start 190.584582 -23.74392)
		(end 194.05346 -23.006558)
		(width 0.1397)
		(layer "In5.Cu")
		(net "PCIE_TX_CAP_N94")
	)
	(segment
		(start 218.661488 -24.707342)
		(end 221.737682 -24.0919)
		(width 0.1397)
		(layer "In5.Cu")
		(net "PCIE_TX_CAP_N94")
	)
	(segment
		(start 185.431684 -21.26361)
		(end 185.470038 -21.271738)
		(width 0.1397)
		(layer "In5.Cu")
		(net "PCIE_TX_CAP_N94")
	)
	(segment
		(start 228.100128 -30.607)
		(end 228.100128 -30.500066)
		(width 0.1016)
		(layer "In5.Cu")
		(net "PCIE_TX_CAP_N94")
	)
	(segment
		(start 183.515 -23.9014)
		(end 183.7436 -23.9014)
		(width 0.1397)
		(layer "In5.Cu")
		(net "PCIE_TX_CAP_N94")
	)
	(segment
		(start 225.55708 -25.34412)
		(end 226.489006 -25.9969)
		(width 0.1397)
		(layer "In5.Cu")
		(net "PCIE_TX_CAP_N94")
	)
	(segment
		(start 223.161352 -23.840948)
		(end 224.584006 -24.0919)
		(width 0.1397)
		(layer "In5.Cu")
		(net "PCIE_TX_CAP_N94")
	)
	(segment
		(start 227.765356 -28.668218)
		(end 227.765356 -28.693618)
		(width 0.1016)
		(layer "In5.Cu")
		(net "PCIE_TX_CAP_N94")
	)
	(segment
		(start 187.897008 -21.78431)
		(end 187.99175 -21.80463)
		(width 0.1397)
		(layer "In5.Cu")
		(net "PCIE_TX_CAP_N94")
	)
	(segment
		(start 226.489006 -25.9969)
		(end 226.8855 -26.393394)
		(width 0.1397)
		(layer "In5.Cu")
		(net "PCIE_TX_CAP_N94")
	)
	(arc
		(start 183.7436 -23.9014)
		(mid 183.818381 -23.894556)
		(end 183.890666 -23.874222)
		(width 0.1397)
		(layer "In5.Cu")
		(net "PCIE_TX_CAP_N94")
	)
	(arc
		(start 183.890666 -23.874222)
		(mid 183.942495 -23.850136)
		(end 183.990488 -23.819104)
		(width 0.1397)
		(layer "In5.Cu")
		(net "PCIE_TX_CAP_N94")
	)
	(arc
		(start 183.990488 -23.819104)
		(mid 184.01287 -23.801076)
		(end 184.033922 -23.781512)
		(width 0.1397)
		(layer "In5.Cu")
		(net "PCIE_TX_CAP_N94")
	)
	(arc
		(start 227.701856 -30.607)
		(mid 227.715434 -30.674793)
		(end 227.753926 -30.732222)
		(width 0.1016)
		(layer "In5.Cu")
		(net "PCIE_TX_CAP_N94")
	)
	(arc
		(start 183.189626 -23.76678)
		(mid 183.338924 -23.866445)
		(end 183.515 -23.9014)
		(width 0.1397)
		(layer "In5.Cu")
		(net "PCIE_TX_CAP_N94")
	)
	(arc
		(start 227.776024 -30.75432)
		(mid 227.808974 -30.776493)
		(end 227.847906 -30.784292)
		(width 0.1016)
		(layer "In5.Cu")
		(net "PCIE_TX_CAP_N94")
	)
	(arc
		(start 227.957126 -30.784292)
		(mid 228.059947 -30.7209)
		(end 228.100128 -30.607)
		(width 0.1016)
		(layer "In5.Cu")
		(net "PCIE_TX_CAP_N94")
	)
	(arc
		(start 227.765356 -28.693618)
		(mid 227.718378 -28.76402)
		(end 227.701856 -28.847034)
		(width 0.1016)
		(layer "In5.Cu")
		(net "PCIE_TX_CAP_N94")
	)
	(segment
		(start 182.499 -26.2001)
		(end 182.646066 -26.2001)
		(width 0.136652)
		(layer "F.Cu")
		(net "PCIE_TX_CAP_N93")
	)
	(segment
		(start 227.600002 -29.99994)
		(end 227.10013 -29.500068)
		(width 0.136652)
		(layer "F.Cu")
		(net "PCIE_TX_CAP_N93")
	)
	(segment
		(start 182.0545 -25.908)
		(end 182.23865 -26.092404)
		(width 0.136652)
		(layer "F.Cu")
		(net "PCIE_TX_CAP_N93")
	)
	(segment
		(start 182.95874 -26.07056)
		(end 183.0832 -25.9461)
		(width 0.136652)
		(layer "F.Cu")
		(net "PCIE_TX_CAP_N93")
	)
	(via
		(at 227.10013 -29.500068)
		(size 0.4572)
		(drill 0.2032)
		(layers "F.Cu" "B.Cu")
		(net "PCIE_TX_CAP_N93")
	)
	(via
		(at 183.0832 -25.9461)
		(size 0.508)
		(drill 0.254)
		(layers "F.Cu" "B.Cu")
		(net "PCIE_TX_CAP_N93")
	)
	(arc
		(start 182.646066 -26.2001)
		(mid 182.815294 -26.166438)
		(end 182.95874 -26.07056)
		(width 0.136652)
		(layer "F.Cu")
		(net "PCIE_TX_CAP_N93")
	)
	(arc
		(start 182.23865 -26.092404)
		(mid 182.358115 -26.172135)
		(end 182.499 -26.2001)
		(width 0.136652)
		(layer "F.Cu")
		(net "PCIE_TX_CAP_N93")
	)
	(segment
		(start 184.57799 -25.745948)
		(end 185.146442 -24.33828)
		(width 0.1397)
		(layer "In5.Cu")
		(net "PCIE_TX_CAP_N93")
	)
	(segment
		(start 215.115394 -25.059894)
		(end 218.497404 -25.736804)
		(width 0.1397)
		(layer "In5.Cu")
		(net "PCIE_TX_CAP_N93")
	)
	(segment
		(start 221.835218 -25.0698)
		(end 222.87357 -24.88692)
		(width 0.1397)
		(layer "In5.Cu")
		(net "PCIE_TX_CAP_N93")
	)
	(segment
		(start 185.146442 -24.33828)
		(end 186.806332 -23.519384)
		(width 0.1397)
		(layer "In5.Cu")
		(net "PCIE_TX_CAP_N93")
	)
	(segment
		(start 226.036378 -26.872438)
		(end 226.758754 -27.918918)
		(width 0.1397)
		(layer "In5.Cu")
		(net "PCIE_TX_CAP_N93")
	)
	(segment
		(start 183.488076 -26.1874)
		(end 184.076086 -26.1874)
		(width 0.1397)
		(layer "In5.Cu")
		(net "PCIE_TX_CAP_N93")
	)
	(segment
		(start 224.959926 -26.11882)
		(end 226.036378 -26.872438)
		(width 0.1397)
		(layer "In5.Cu")
		(net "PCIE_TX_CAP_N93")
	)
	(segment
		(start 226.695254 -29.110686)
		(end 226.695254 -29.608272)
		(width 0.1016)
		(layer "In5.Cu")
		(net "PCIE_TX_CAP_N93")
	)
	(segment
		(start 222.87357 -24.88692)
		(end 223.91116 -25.0698)
		(width 0.1397)
		(layer "In5.Cu")
		(net "PCIE_TX_CAP_N93")
	)
	(segment
		(start 184.076086 -26.1874)
		(end 184.57799 -25.745948)
		(width 0.1397)
		(layer "In5.Cu")
		(net "PCIE_TX_CAP_N93")
	)
	(segment
		(start 189.337696 -24.537162)
		(end 189.33795 -24.537162)
		(width 0.1397)
		(layer "In5.Cu")
		(net "PCIE_TX_CAP_N93")
	)
	(segment
		(start 226.757992 -29.759656)
		(end 226.7585 -29.760164)
		(width 0.1016)
		(layer "In5.Cu")
		(net "PCIE_TX_CAP_N93")
	)
	(segment
		(start 223.91116 -25.0698)
		(end 224.959926 -26.11882)
		(width 0.1397)
		(layer "In5.Cu")
		(net "PCIE_TX_CAP_N93")
	)
	(segment
		(start 186.806332 -23.519384)
		(end 188.240162 -23.824184)
		(width 0.1397)
		(layer "In5.Cu")
		(net "PCIE_TX_CAP_N93")
	)
	(segment
		(start 226.758754 -28.93187)
		(end 226.758754 -28.95727)
		(width 0.1016)
		(layer "In5.Cu")
		(net "PCIE_TX_CAP_N93")
	)
	(segment
		(start 226.908868 -29.822394)
		(end 226.924108 -29.822394)
		(width 0.1016)
		(layer "In5.Cu")
		(net "PCIE_TX_CAP_N93")
	)
	(segment
		(start 188.240162 -23.824184)
		(end 189.337696 -24.537162)
		(width 0.1397)
		(layer "In5.Cu")
		(net "PCIE_TX_CAP_N93")
	)
	(segment
		(start 196.864224 -24.40178)
		(end 207.539844 -26.670762)
		(width 0.1397)
		(layer "In5.Cu")
		(net "PCIE_TX_CAP_N93")
	)
	(segment
		(start 218.497404 -25.736804)
		(end 221.835218 -25.0698)
		(width 0.1397)
		(layer "In5.Cu")
		(net "PCIE_TX_CAP_N93")
	)
	(segment
		(start 189.33795 -24.537162)
		(end 189.541404 -24.669496)
		(width 0.1397)
		(layer "In5.Cu")
		(net "PCIE_TX_CAP_N93")
	)
	(segment
		(start 189.541404 -24.669496)
		(end 192.573148 -25.313894)
		(width 0.1397)
		(layer "In5.Cu")
		(net "PCIE_TX_CAP_N93")
	)
	(segment
		(start 207.539844 -26.670762)
		(end 215.115394 -25.059894)
		(width 0.1397)
		(layer "In5.Cu")
		(net "PCIE_TX_CAP_N93")
	)
	(segment
		(start 227.048568 -29.770832)
		(end 227.070412 -29.748988)
		(width 0.1016)
		(layer "In5.Cu")
		(net "PCIE_TX_CAP_N93")
	)
	(segment
		(start 227.10013 -29.677106)
		(end 227.10013 -29.500068)
		(width 0.1016)
		(layer "In5.Cu")
		(net "PCIE_TX_CAP_N93")
	)
	(segment
		(start 226.758754 -27.918918)
		(end 226.758754 -28.93187)
		(width 0.1397)
		(layer "In5.Cu")
		(net "PCIE_TX_CAP_N93")
	)
	(segment
		(start 192.573148 -25.313894)
		(end 196.864224 -24.40178)
		(width 0.1397)
		(layer "In5.Cu")
		(net "PCIE_TX_CAP_N93")
	)
	(arc
		(start 226.758754 -28.95727)
		(mid 226.711776 -29.027672)
		(end 226.695254 -29.110686)
		(width 0.1016)
		(layer "In5.Cu")
		(net "PCIE_TX_CAP_N93")
	)
	(arc
		(start 226.7585 -29.760164)
		(mid 226.827504 -29.806208)
		(end 226.908868 -29.822394)
		(width 0.1016)
		(layer "In5.Cu")
		(net "PCIE_TX_CAP_N93")
	)
	(arc
		(start 226.695254 -29.608272)
		(mid 226.711553 -29.690213)
		(end 226.757992 -29.759656)
		(width 0.1016)
		(layer "In5.Cu")
		(net "PCIE_TX_CAP_N93")
	)
	(arc
		(start 227.070412 -29.748988)
		(mid 227.092395 -29.715994)
		(end 227.10013 -29.677106)
		(width 0.1016)
		(layer "In5.Cu")
		(net "PCIE_TX_CAP_N93")
	)
	(arc
		(start 226.924108 -29.822394)
		(mid 226.991469 -29.808995)
		(end 227.048568 -29.770832)
		(width 0.1016)
		(layer "In5.Cu")
		(net "PCIE_TX_CAP_N93")
	)
	(arc
		(start 183.0832 -25.9461)
		(mid 183.252402 -26.122526)
		(end 183.488076 -26.1874)
		(width 0.1397)
		(layer "In5.Cu")
		(net "PCIE_TX_CAP_N93")
	)
	(segment
		(start 184.871614 -24.809958)
		(end 184.871614 -23.601934)
		(width 0.136652)
		(layer "F.Cu")
		(net "PCIE_TX_CAP_N92")
	)
	(segment
		(start 226.600004 -30.999938)
		(end 226.100132 -30.500066)
		(width 0.136652)
		(layer "F.Cu")
		(net "PCIE_TX_CAP_N92")
	)
	(segment
		(start 185.17362 -25.187402)
		(end 184.925208 -24.939244)
		(width 0.136652)
		(layer "F.Cu")
		(net "PCIE_TX_CAP_N92")
	)
	(segment
		(start 183.210708 -21.8948)
		(end 182.7276 -21.8948)
		(width 0.136652)
		(layer "F.Cu")
		(net "PCIE_TX_CAP_N92")
	)
	(segment
		(start 185.78957 -25.264364)
		(end 185.358786 -25.264364)
		(width 0.136652)
		(layer "F.Cu")
		(net "PCIE_TX_CAP_N92")
	)
	(segment
		(start 184.605676 -22.96033)
		(end 183.773572 -22.128226)
		(width 0.136652)
		(layer "F.Cu")
		(net "PCIE_TX_CAP_N92")
	)
	(via
		(at 226.100132 -30.500066)
		(size 0.4572)
		(drill 0.2032)
		(layers "F.Cu" "B.Cu")
		(net "PCIE_TX_CAP_N92")
	)
	(via
		(at 186.055 -24.998934)
		(size 0.508)
		(drill 0.254)
		(layers "F.Cu" "B.Cu")
		(net "PCIE_TX_CAP_N92")
	)
	(arc
		(start 186.055 -24.998934)
		(mid 185.977257 -25.186621)
		(end 185.78957 -25.264364)
		(width 0.136652)
		(layer "F.Cu")
		(net "PCIE_TX_CAP_N92")
	)
	(arc
		(start 183.773572 -22.128226)
		(mid 183.515344 -21.955561)
		(end 183.210708 -21.8948)
		(width 0.136652)
		(layer "F.Cu")
		(net "PCIE_TX_CAP_N92")
	)
	(arc
		(start 185.358786 -25.264364)
		(mid 185.258581 -25.244245)
		(end 185.17362 -25.187402)
		(width 0.136652)
		(layer "F.Cu")
		(net "PCIE_TX_CAP_N92")
	)
	(arc
		(start 184.925208 -24.939244)
		(mid 184.88552 -24.879941)
		(end 184.871614 -24.809958)
		(width 0.136652)
		(layer "F.Cu")
		(net "PCIE_TX_CAP_N92")
	)
	(arc
		(start 182.7276 -21.8948)
		(mid 182.358153 -21.815049)
		(end 182.0545 -21.59)
		(width 0.136652)
		(layer "F.Cu")
		(net "PCIE_TX_CAP_N92")
	)
	(arc
		(start 184.871614 -23.601934)
		(mid 184.802449 -23.254686)
		(end 184.605676 -22.96033)
		(width 0.136652)
		(layer "F.Cu")
		(net "PCIE_TX_CAP_N92")
	)
	(segment
		(start 223.505014 -26.1874)
		(end 225.280982 -27.430984)
		(width 0.1397)
		(layer "In5.Cu")
		(net "PCIE_TX_CAP_N92")
	)
	(segment
		(start 205.346808 -28.440126)
		(end 215.675718 -26.374598)
		(width 0.1397)
		(layer "In5.Cu")
		(net "PCIE_TX_CAP_N92")
	)
	(segment
		(start 225.730562 -28.073096)
		(end 225.76536 -28.270454)
		(width 0.1397)
		(layer "In5.Cu")
		(net "PCIE_TX_CAP_N92")
	)
	(segment
		(start 225.76536 -29.1846)
		(end 225.76536 -29.21)
		(width 0.1016)
		(layer "In5.Cu")
		(net "PCIE_TX_CAP_N92")
	)
	(segment
		(start 225.76536 -28.270454)
		(end 225.76536 -29.1846)
		(width 0.1397)
		(layer "In5.Cu")
		(net "PCIE_TX_CAP_N92")
	)
	(segment
		(start 225.84791 -30.784292)
		(end 225.95713 -30.784292)
		(width 0.1016)
		(layer "In5.Cu")
		(net "PCIE_TX_CAP_N92")
	)
	(segment
		(start 192.048892 -26.82494)
		(end 196.71411 -25.675336)
		(width 0.1397)
		(layer "In5.Cu")
		(net "PCIE_TX_CAP_N92")
	)
	(segment
		(start 225.70186 -29.363416)
		(end 225.70186 -30.6197)
		(width 0.1016)
		(layer "In5.Cu")
		(net "PCIE_TX_CAP_N92")
	)
	(segment
		(start 226.100132 -30.607)
		(end 226.100132 -30.500066)
		(width 0.1016)
		(layer "In5.Cu")
		(net "PCIE_TX_CAP_N92")
	)
	(segment
		(start 186.450732 -25.222454)
		(end 187.745878 -25.222454)
		(width 0.1397)
		(layer "In5.Cu")
		(net "PCIE_TX_CAP_N92")
	)
	(segment
		(start 189.888876 -26.436828)
		(end 192.048892 -26.82494)
		(width 0.1397)
		(layer "In5.Cu")
		(net "PCIE_TX_CAP_N92")
	)
	(segment
		(start 225.280982 -27.430984)
		(end 225.730562 -28.073096)
		(width 0.1397)
		(layer "In5.Cu")
		(net "PCIE_TX_CAP_N92")
	)
	(segment
		(start 221.94647 -26.1874)
		(end 223.505014 -26.1874)
		(width 0.1397)
		(layer "In5.Cu")
		(net "PCIE_TX_CAP_N92")
	)
	(segment
		(start 196.71411 -25.675336)
		(end 205.346808 -28.440126)
		(width 0.1397)
		(layer "In5.Cu")
		(net "PCIE_TX_CAP_N92")
	)
	(segment
		(start 187.745878 -25.222454)
		(end 189.888876 -26.436828)
		(width 0.1397)
		(layer "In5.Cu")
		(net "PCIE_TX_CAP_N92")
	)
	(segment
		(start 215.675718 -26.374598)
		(end 218.342972 -26.907998)
		(width 0.1397)
		(layer "In5.Cu")
		(net "PCIE_TX_CAP_N92")
	)
	(segment
		(start 218.342972 -26.907998)
		(end 221.94647 -26.1874)
		(width 0.1397)
		(layer "In5.Cu")
		(net "PCIE_TX_CAP_N92")
	)
	(arc
		(start 225.744278 -30.734762)
		(mid 225.790473 -30.771296)
		(end 225.84791 -30.784292)
		(width 0.1016)
		(layer "In5.Cu")
		(net "PCIE_TX_CAP_N92")
	)
	(arc
		(start 225.95713 -30.784292)
		(mid 226.059951 -30.7209)
		(end 226.100132 -30.607)
		(width 0.1016)
		(layer "In5.Cu")
		(net "PCIE_TX_CAP_N92")
	)
	(arc
		(start 225.70186 -30.6197)
		(mid 225.712814 -30.681006)
		(end 225.744278 -30.734762)
		(width 0.1016)
		(layer "In5.Cu")
		(net "PCIE_TX_CAP_N92")
	)
	(arc
		(start 186.055 -24.998934)
		(mid 186.223479 -25.162728)
		(end 186.450732 -25.222454)
		(width 0.1397)
		(layer "In5.Cu")
		(net "PCIE_TX_CAP_N92")
	)
	(arc
		(start 225.76536 -29.21)
		(mid 225.718382 -29.280402)
		(end 225.70186 -29.363416)
		(width 0.1016)
		(layer "In5.Cu")
		(net "PCIE_TX_CAP_N92")
	)
	(segment
		(start 182.499 -29.2481)
		(end 182.660544 -29.2481)
		(width 0.136652)
		(layer "F.Cu")
		(net "PCIE_TX_CAP_N91")
	)
	(segment
		(start 182.948326 -29.12872)
		(end 183.0832 -28.9941)
		(width 0.136652)
		(layer "F.Cu")
		(net "PCIE_TX_CAP_N91")
	)
	(segment
		(start 182.0545 -28.956)
		(end 182.23865 -29.140404)
		(width 0.136652)
		(layer "F.Cu")
		(net "PCIE_TX_CAP_N91")
	)
	(segment
		(start 225.600006 -29.99994)
		(end 225.100134 -29.500068)
		(width 0.136652)
		(layer "F.Cu")
		(net "PCIE_TX_CAP_N91")
	)
	(via
		(at 183.0832 -28.9941)
		(size 0.508)
		(drill 0.254)
		(layers "F.Cu" "B.Cu")
		(net "PCIE_TX_CAP_N91")
	)
	(via
		(at 225.100134 -29.500068)
		(size 0.4572)
		(drill 0.2032)
		(layers "F.Cu" "B.Cu")
		(net "PCIE_TX_CAP_N91")
	)
	(arc
		(start 182.660544 -29.2481)
		(mid 182.816304 -29.217024)
		(end 182.948326 -29.12872)
		(width 0.136652)
		(layer "F.Cu")
		(net "PCIE_TX_CAP_N91")
	)
	(arc
		(start 182.23865 -29.140404)
		(mid 182.358115 -29.220135)
		(end 182.499 -29.2481)
		(width 0.136652)
		(layer "F.Cu")
		(net "PCIE_TX_CAP_N91")
	)
	(segment
		(start 197.2056 -27.9908)
		(end 198.827136 -27.459178)
		(width 0.1397)
		(layer "In5.Cu")
		(net "PCIE_TX_CAP_N91")
	)
	(segment
		(start 218.4654 -27.997404)
		(end 222.055182 -27.2796)
		(width 0.1397)
		(layer "In5.Cu")
		(net "PCIE_TX_CAP_N91")
	)
	(segment
		(start 184.248552 -29.2354)
		(end 184.792874 -29.139134)
		(width 0.1397)
		(layer "In5.Cu")
		(net "PCIE_TX_CAP_N91")
	)
	(segment
		(start 215.664288 -27.43708)
		(end 218.4654 -27.997404)
		(width 0.1397)
		(layer "In5.Cu")
		(net "PCIE_TX_CAP_N91")
	)
	(segment
		(start 187.399168 -29.598366)
		(end 191.534288 -28.869132)
		(width 0.1397)
		(layer "In5.Cu")
		(net "PCIE_TX_CAP_N91")
	)
	(segment
		(start 193.9798 -27.5336)
		(end 194.818 -27.305)
		(width 0.1397)
		(layer "In5.Cu")
		(net "PCIE_TX_CAP_N91")
	)
	(segment
		(start 224.63252 -28.852622)
		(end 224.63252 -29.53131)
		(width 0.1397)
		(layer "In5.Cu")
		(net "PCIE_TX_CAP_N91")
	)
	(segment
		(start 222.055182 -27.2796)
		(end 223.012762 -27.2796)
		(width 0.1397)
		(layer "In5.Cu")
		(net "PCIE_TX_CAP_N91")
	)
	(segment
		(start 184.792874 -29.139134)
		(end 187.399168 -29.598366)
		(width 0.1397)
		(layer "In5.Cu")
		(net "PCIE_TX_CAP_N91")
	)
	(segment
		(start 223.835976 -27.620468)
		(end 224.32391 -28.108656)
		(width 0.1397)
		(layer "In5.Cu")
		(net "PCIE_TX_CAP_N91")
	)
	(segment
		(start 191.534288 -28.869132)
		(end 193.9798 -27.5336)
		(width 0.1397)
		(layer "In5.Cu")
		(net "PCIE_TX_CAP_N91")
	)
	(segment
		(start 225.100134 -29.53131)
		(end 225.100134 -29.500068)
		(width 0.1397)
		(layer "In5.Cu")
		(net "PCIE_TX_CAP_N91")
	)
	(segment
		(start 183.488076 -29.2354)
		(end 184.248552 -29.2354)
		(width 0.1397)
		(layer "In5.Cu")
		(net "PCIE_TX_CAP_N91")
	)
	(segment
		(start 198.827136 -27.459178)
		(end 205.245208 -29.520896)
		(width 0.1397)
		(layer "In5.Cu")
		(net "PCIE_TX_CAP_N91")
	)
	(segment
		(start 194.818 -27.305)
		(end 197.2056 -27.9908)
		(width 0.1397)
		(layer "In5.Cu")
		(net "PCIE_TX_CAP_N91")
	)
	(segment
		(start 205.245208 -29.520896)
		(end 215.664288 -27.43708)
		(width 0.1397)
		(layer "In5.Cu")
		(net "PCIE_TX_CAP_N91")
	)
	(arc
		(start 224.675192 -29.66593)
		(mid 224.937058 -29.754287)
		(end 225.100134 -29.53131)
		(width 0.1397)
		(layer "In5.Cu")
		(net "PCIE_TX_CAP_N91")
	)
	(arc
		(start 183.0832 -28.9941)
		(mid 183.252402 -29.170526)
		(end 183.488076 -29.2354)
		(width 0.1397)
		(layer "In5.Cu")
		(net "PCIE_TX_CAP_N91")
	)
	(arc
		(start 223.012762 -27.2796)
		(mid 223.458265 -27.36818)
		(end 223.835976 -27.620468)
		(width 0.1397)
		(layer "In5.Cu")
		(net "PCIE_TX_CAP_N91")
	)
	(arc
		(start 224.32391 -28.108656)
		(mid 224.492142 -28.328172)
		(end 224.597468 -28.58389)
		(width 0.1397)
		(layer "In5.Cu")
		(net "PCIE_TX_CAP_N91")
	)
	(arc
		(start 224.597468 -28.58389)
		(mid 224.623718 -28.717118)
		(end 224.63252 -28.852622)
		(width 0.1397)
		(layer "In5.Cu")
		(net "PCIE_TX_CAP_N91")
	)
	(arc
		(start 224.63252 -29.53131)
		(mid 224.643443 -29.601921)
		(end 224.675192 -29.66593)
		(width 0.1397)
		(layer "In5.Cu")
		(net "PCIE_TX_CAP_N91")
	)
	(segment
		(start 161.80308 -34.43224)
		(end 161.80308 -34.60496)
		(width 0.136652)
		(layer "F.Cu")
		(net "PCIE_TX_CAP_N90")
	)
	(segment
		(start 224.600008 -30.999938)
		(end 224.100136 -30.500066)
		(width 0.136652)
		(layer "F.Cu")
		(net "PCIE_TX_CAP_N90")
	)
	(via
		(at 162.0901 -35.02152)
		(size 0.508)
		(drill 0.254)
		(layers "F.Cu" "B.Cu")
		(net "PCIE_TX_CAP_N90")
	)
	(via
		(at 224.100136 -30.500066)
		(size 0.4572)
		(drill 0.2032)
		(layers "F.Cu" "B.Cu")
		(net "PCIE_TX_CAP_N90")
	)
	(arc
		(start 161.80308 -34.60496)
		(mid 161.881784 -34.85789)
		(end 162.0901 -35.02152)
		(width 0.136652)
		(layer "F.Cu")
		(net "PCIE_TX_CAP_N90")
	)
	(arc
		(start 162.052 -33.9725)
		(mid 161.869265 -34.170826)
		(end 161.80308 -34.43224)
		(width 0.136652)
		(layer "F.Cu")
		(net "PCIE_TX_CAP_N90")
	)
	(segment
		(start 224.057972 -30.728158)
		(end 224.040192 -30.750256)
		(width 0.1016)
		(layer "In5.Cu")
		(net "PCIE_TX_CAP_N90")
	)
	(segment
		(start 179.319428 -30.243018)
		(end 173.38167 -31.289752)
		(width 0.1397)
		(layer "In5.Cu")
		(net "PCIE_TX_CAP_N90")
	)
	(segment
		(start 187.474606 -30.620716)
		(end 186.172602 -30.3911)
		(width 0.1397)
		(layer "In5.Cu")
		(net "PCIE_TX_CAP_N90")
	)
	(segment
		(start 168.866058 -34.01441)
		(end 168.514522 -34.24301)
		(width 0.1397)
		(layer "In5.Cu")
		(net "PCIE_TX_CAP_N90")
	)
	(segment
		(start 224.100136 -30.500066)
		(end 224.103438 -30.591252)
		(width 0.1016)
		(layer "In5.Cu")
		(net "PCIE_TX_CAP_N90")
	)
	(segment
		(start 223.960944 -30.788356)
		(end 223.851978 -30.788356)
		(width 0.1016)
		(layer "In5.Cu")
		(net "PCIE_TX_CAP_N90")
	)
	(segment
		(start 170.867578 -32.712914)
		(end 170.516042 -32.94126)
		(width 0.1397)
		(layer "In5.Cu")
		(net "PCIE_TX_CAP_N90")
	)
	(segment
		(start 183.166512 -30.921198)
		(end 181.489096 -30.625542)
		(width 0.1397)
		(layer "In5.Cu")
		(net "PCIE_TX_CAP_N90")
	)
	(segment
		(start 195.88734 -29.573474)
		(end 194.61734 -29.361892)
		(width 0.1397)
		(layer "In5.Cu")
		(net "PCIE_TX_CAP_N90")
	)
	(segment
		(start 200.435464 -29.573474)
		(end 198.712582 -30.040834)
		(width 0.1397)
		(layer "In5.Cu")
		(net "PCIE_TX_CAP_N90")
	)
	(segment
		(start 218.4654 -28.994862)
		(end 216.942416 -28.690316)
		(width 0.1397)
		(layer "In5.Cu")
		(net "PCIE_TX_CAP_N90")
	)
	(segment
		(start 198.712582 -30.040834)
		(end 195.88734 -29.573474)
		(width 0.1397)
		(layer "In5.Cu")
		(net "PCIE_TX_CAP_N90")
	)
	(segment
		(start 223.763078 -28.9814)
		(end 223.763078 -28.704794)
		(width 0.1397)
		(layer "In5.Cu")
		(net "PCIE_TX_CAP_N90")
	)
	(segment
		(start 194.61734 -29.361892)
		(end 187.474606 -30.620716)
		(width 0.1397)
		(layer "In5.Cu")
		(net "PCIE_TX_CAP_N90")
	)
	(segment
		(start 161.936938 -35.174682)
		(end 162.0901 -35.02152)
		(width 0.1397)
		(layer "In5.Cu")
		(net "PCIE_TX_CAP_N90")
	)
	(segment
		(start 186.172602 -30.3911)
		(end 185.230516 -30.556962)
		(width 0.1397)
		(layer "In5.Cu")
		(net "PCIE_TX_CAP_N90")
	)
	(segment
		(start 181.055264 -30.549088)
		(end 179.319428 -30.243018)
		(width 0.1397)
		(layer "In5.Cu")
		(net "PCIE_TX_CAP_N90")
	)
	(segment
		(start 168.514522 -34.24301)
		(end 168.462452 -34.488882)
		(width 0.1397)
		(layer "In5.Cu")
		(net "PCIE_TX_CAP_N90")
	)
	(segment
		(start 173.38167 -31.289752)
		(end 171.11345 -32.764984)
		(width 0.1397)
		(layer "In5.Cu")
		(net "PCIE_TX_CAP_N90")
	)
	(segment
		(start 169.866818 -33.363662)
		(end 169.515282 -33.592262)
		(width 0.1397)
		(layer "In5.Cu")
		(net "PCIE_TX_CAP_N90")
	)
	(segment
		(start 223.705928 -30.623764)
		(end 223.705928 -29.11348)
		(width 0.1016)
		(layer "In5.Cu")
		(net "PCIE_TX_CAP_N90")
	)
	(segment
		(start 185.230516 -30.556962)
		(end 184.345326 -30.712918)
		(width 0.1397)
		(layer "In5.Cu")
		(net "PCIE_TX_CAP_N90")
	)
	(segment
		(start 168.11117 -34.717482)
		(end 164.002466 -35.442144)
		(width 0.1397)
		(layer "In5.Cu")
		(net "PCIE_TX_CAP_N90")
	)
	(segment
		(start 162.869372 -35.978084)
		(end 162.29965 -35.978084)
		(width 0.1397)
		(layer "In5.Cu")
		(net "PCIE_TX_CAP_N90")
	)
	(segment
		(start 169.515282 -33.592262)
		(end 169.463212 -33.838134)
		(width 0.1397)
		(layer "In5.Cu")
		(net "PCIE_TX_CAP_N90")
	)
	(segment
		(start 170.11269 -33.415732)
		(end 169.866818 -33.363662)
		(width 0.1397)
		(layer "In5.Cu")
		(net "PCIE_TX_CAP_N90")
	)
	(segment
		(start 215.2904 -28.359862)
		(end 203.806298 -30.656784)
		(width 0.1397)
		(layer "In5.Cu")
		(net "PCIE_TX_CAP_N90")
	)
	(segment
		(start 170.463972 -33.187386)
		(end 170.11269 -33.415732)
		(width 0.1397)
		(layer "In5.Cu")
		(net "PCIE_TX_CAP_N90")
	)
	(segment
		(start 169.463212 -33.838134)
		(end 169.11193 -34.066734)
		(width 0.1397)
		(layer "In5.Cu")
		(net "PCIE_TX_CAP_N90")
	)
	(segment
		(start 223.759014 -28.985718)
		(end 223.763078 -28.9814)
		(width 0.1016)
		(layer "In5.Cu")
		(net "PCIE_TX_CAP_N90")
	)
	(segment
		(start 222.15221 -28.2575)
		(end 218.4654 -28.994862)
		(width 0.1397)
		(layer "In5.Cu")
		(net "PCIE_TX_CAP_N90")
	)
	(segment
		(start 161.8488 -35.527234)
		(end 161.8488 -35.387534)
		(width 0.1397)
		(layer "In5.Cu")
		(net "PCIE_TX_CAP_N90")
	)
	(segment
		(start 216.942416 -28.690316)
		(end 215.2904 -28.359862)
		(width 0.1397)
		(layer "In5.Cu")
		(net "PCIE_TX_CAP_N90")
	)
	(segment
		(start 168.462452 -34.488882)
		(end 168.11117 -34.717482)
		(width 0.1397)
		(layer "In5.Cu")
		(net "PCIE_TX_CAP_N90")
	)
	(segment
		(start 184.345326 -30.712918)
		(end 183.166512 -30.921198)
		(width 0.1397)
		(layer "In5.Cu")
		(net "PCIE_TX_CAP_N90")
	)
	(segment
		(start 203.806298 -30.656784)
		(end 200.435464 -29.573474)
		(width 0.1397)
		(layer "In5.Cu")
		(net "PCIE_TX_CAP_N90")
	)
	(segment
		(start 181.489096 -30.625542)
		(end 181.055264 -30.549088)
		(width 0.1397)
		(layer "In5.Cu")
		(net "PCIE_TX_CAP_N90")
	)
	(segment
		(start 223.315784 -28.2575)
		(end 222.15221 -28.2575)
		(width 0.1397)
		(layer "In5.Cu")
		(net "PCIE_TX_CAP_N90")
	)
	(segment
		(start 171.11345 -32.764984)
		(end 170.867578 -32.712914)
		(width 0.1397)
		(layer "In5.Cu")
		(net "PCIE_TX_CAP_N90")
	)
	(segment
		(start 223.763078 -28.704794)
		(end 223.315784 -28.2575)
		(width 0.1397)
		(layer "In5.Cu")
		(net "PCIE_TX_CAP_N90")
	)
	(segment
		(start 169.11193 -34.066734)
		(end 168.866058 -34.01441)
		(width 0.1397)
		(layer "In5.Cu")
		(net "PCIE_TX_CAP_N90")
	)
	(segment
		(start 170.516042 -32.94126)
		(end 170.463972 -33.187386)
		(width 0.1397)
		(layer "In5.Cu")
		(net "PCIE_TX_CAP_N90")
	)
	(arc
		(start 161.8488 -35.387534)
		(mid 161.871711 -35.27235)
		(end 161.936938 -35.174682)
		(width 0.1397)
		(layer "In5.Cu")
		(net "PCIE_TX_CAP_N90")
	)
	(arc
		(start 223.748346 -30.738826)
		(mid 223.71683 -30.685089)
		(end 223.705928 -30.623764)
		(width 0.1016)
		(layer "In5.Cu")
		(net "PCIE_TX_CAP_N90")
	)
	(arc
		(start 164.002466 -35.442144)
		(mid 163.66625 -35.556282)
		(end 163.379912 -35.766248)
		(width 0.1397)
		(layer "In5.Cu")
		(net "PCIE_TX_CAP_N90")
	)
	(arc
		(start 223.705928 -29.11348)
		(mid 223.719777 -29.044326)
		(end 223.759014 -28.985718)
		(width 0.1016)
		(layer "In5.Cu")
		(net "PCIE_TX_CAP_N90")
	)
	(arc
		(start 223.823022 -30.785054)
		(mid 223.781733 -30.768309)
		(end 223.748346 -30.738826)
		(width 0.1016)
		(layer "In5.Cu")
		(net "PCIE_TX_CAP_N90")
	)
	(arc
		(start 223.851978 -30.788356)
		(mid 223.837409 -30.7875)
		(end 223.823022 -30.785054)
		(width 0.1016)
		(layer "In5.Cu")
		(net "PCIE_TX_CAP_N90")
	)
	(arc
		(start 224.103438 -30.591252)
		(mid 224.093033 -30.663801)
		(end 224.057972 -30.728158)
		(width 0.1016)
		(layer "In5.Cu")
		(net "PCIE_TX_CAP_N90")
	)
	(arc
		(start 163.379912 -35.766248)
		(mid 163.145704 -35.922927)
		(end 162.869372 -35.978084)
		(width 0.1397)
		(layer "In5.Cu")
		(net "PCIE_TX_CAP_N90")
	)
	(arc
		(start 162.29965 -35.978084)
		(mid 161.980851 -35.846033)
		(end 161.8488 -35.527234)
		(width 0.1397)
		(layer "In5.Cu")
		(net "PCIE_TX_CAP_N90")
	)
	(arc
		(start 224.040192 -30.750256)
		(mid 224.004919 -30.778369)
		(end 223.960944 -30.788356)
		(width 0.1016)
		(layer "In5.Cu")
		(net "PCIE_TX_CAP_N90")
	)
	(segment
		(start 311.263792 -34.000186)
		(end 311.140856 -34.123376)
		(width 0.136652)
		(layer "F.Cu")
		(net "PCIE_TX_CAP_N9")
	)
	(segment
		(start 311.131966 -34.935414)
		(end 311.238392 -35.04184)
		(width 0.136652)
		(layer "F.Cu")
		(net "PCIE_TX_CAP_N9")
	)
	(segment
		(start 310.997092 -34.470086)
		(end 310.997092 -34.609786)
		(width 0.136652)
		(layer "F.Cu")
		(net "PCIE_TX_CAP_N9")
	)
	(segment
		(start 257.599942 -34.99993)
		(end 258.099814 -34.500058)
		(width 0.136652)
		(layer "F.Cu")
		(net "PCIE_TX_CAP_N9")
	)
	(via
		(at 258.099814 -34.500058)
		(size 0.4572)
		(drill 0.2032)
		(layers "F.Cu" "B.Cu")
		(net "PCIE_TX_CAP_N9")
	)
	(via
		(at 311.238392 -35.04184)
		(size 0.508)
		(drill 0.254)
		(layers "F.Cu" "B.Cu")
		(net "PCIE_TX_CAP_N9")
	)
	(arc
		(start 310.997092 -34.609786)
		(mid 311.032146 -34.786012)
		(end 311.131966 -34.935414)
		(width 0.136652)
		(layer "F.Cu")
		(net "PCIE_TX_CAP_N9")
	)
	(arc
		(start 311.140856 -34.123376)
		(mid 311.034485 -34.282433)
		(end 310.997092 -34.470086)
		(width 0.136652)
		(layer "F.Cu")
		(net "PCIE_TX_CAP_N9")
	)
	(segment
		(start 267.858494 -33.203388)
		(end 262.023606 -34.232088)
		(width 0.1397)
		(layer "In5.Cu")
		(net "PCIE_TX_CAP_N9")
	)
	(segment
		(start 262.023606 -34.232088)
		(end 259.469382 -34.232088)
		(width 0.1397)
		(layer "In5.Cu")
		(net "PCIE_TX_CAP_N9")
	)
	(segment
		(start 291.248084 -43.466004)
		(end 282.112212 -41.638982)
		(width 0.1397)
		(layer "In5.Cu")
		(net "PCIE_TX_CAP_N9")
	)
	(segment
		(start 310.951372 -36.299648)
		(end 310.897778 -36.603686)
		(width 0.1397)
		(layer "In5.Cu")
		(net "PCIE_TX_CAP_N9")
	)
	(segment
		(start 276.41677 -36.70808)
		(end 272.607278 -34.040572)
		(width 0.1397)
		(layer "In5.Cu")
		(net "PCIE_TX_CAP_N9")
	)
	(segment
		(start 296.012616 -44.156884)
		(end 291.90315 -43.33494)
		(width 0.1397)
		(layer "In5.Cu")
		(net "PCIE_TX_CAP_N9")
	)
	(segment
		(start 291.90315 -43.33494)
		(end 291.248084 -43.466004)
		(width 0.1397)
		(layer "In5.Cu")
		(net "PCIE_TX_CAP_N9")
	)
	(segment
		(start 259.326888 -34.232088)
		(end 259.199634 -34.104834)
		(width 0.1016)
		(layer "In5.Cu")
		(net "PCIE_TX_CAP_N9")
	)
	(segment
		(start 258.074414 -34.500058)
		(end 258.099814 -34.500058)
		(width 0.1016)
		(layer "In5.Cu")
		(net "PCIE_TX_CAP_N9")
	)
	(segment
		(start 307.98897 -40.886888)
		(end 307.360574 -41.709086)
		(width 0.1397)
		(layer "In5.Cu")
		(net "PCIE_TX_CAP_N9")
	)
	(segment
		(start 308.520084 -39.15791)
		(end 307.98897 -40.886888)
		(width 0.1397)
		(layer "In5.Cu")
		(net "PCIE_TX_CAP_N9")
	)
	(segment
		(start 282.112212 -41.638982)
		(end 277.711916 -38.557708)
		(width 0.1397)
		(layer "In5.Cu")
		(net "PCIE_TX_CAP_N9")
	)
	(segment
		(start 259.469382 -34.232088)
		(end 259.326888 -34.232088)
		(width 0.1016)
		(layer "In5.Cu")
		(net "PCIE_TX_CAP_N9")
	)
	(segment
		(start 277.711916 -38.557708)
		(end 276.41677 -36.70808)
		(width 0.1397)
		(layer "In5.Cu")
		(net "PCIE_TX_CAP_N9")
	)
	(segment
		(start 272.607278 -34.040572)
		(end 267.858494 -33.203388)
		(width 0.1397)
		(layer "In5.Cu")
		(net "PCIE_TX_CAP_N9")
	)
	(segment
		(start 309.675784 -38.348666)
		(end 308.520084 -39.15791)
		(width 0.1397)
		(layer "In5.Cu")
		(net "PCIE_TX_CAP_N9")
	)
	(segment
		(start 306.928266 -41.973754)
		(end 296.012616 -44.156884)
		(width 0.1397)
		(layer "In5.Cu")
		(net "PCIE_TX_CAP_N9")
	)
	(segment
		(start 311.238392 -35.04184)
		(end 311.14365 -35.136582)
		(width 0.1397)
		(layer "In5.Cu")
		(net "PCIE_TX_CAP_N9")
	)
	(segment
		(start 310.897778 -36.603686)
		(end 309.675784 -38.348666)
		(width 0.1397)
		(layer "In5.Cu")
		(net "PCIE_TX_CAP_N9")
	)
	(segment
		(start 307.14315 -41.842182)
		(end 306.928266 -41.973754)
		(width 0.1397)
		(layer "In5.Cu")
		(net "PCIE_TX_CAP_N9")
	)
	(segment
		(start 259.199634 -34.104834)
		(end 258.074414 -34.104834)
		(width 0.1016)
		(layer "In5.Cu")
		(net "PCIE_TX_CAP_N9")
	)
	(segment
		(start 310.9976 -36.03879)
		(end 310.951372 -36.299648)
		(width 0.1397)
		(layer "In5.Cu")
		(net "PCIE_TX_CAP_N9")
	)
	(segment
		(start 310.9976 -35.489134)
		(end 310.9976 -36.03879)
		(width 0.1397)
		(layer "In5.Cu")
		(net "PCIE_TX_CAP_N9")
	)
	(segment
		(start 307.360574 -41.709086)
		(end 307.14315 -41.842182)
		(width 0.1397)
		(layer "In5.Cu")
		(net "PCIE_TX_CAP_N9")
	)
	(arc
		(start 311.14365 -35.136582)
		(mid 311.035571 -35.298334)
		(end 310.9976 -35.489134)
		(width 0.1397)
		(layer "In5.Cu")
		(net "PCIE_TX_CAP_N9")
	)
	(arc
		(start 258.074414 -34.104834)
		(mid 257.876802 -34.302446)
		(end 258.074414 -34.500058)
		(width 0.1016)
		(layer "In5.Cu")
		(net "PCIE_TX_CAP_N9")
	)
	(segment
		(start 223.60001 -29.99994)
		(end 223.100138 -29.500068)
		(width 0.136652)
		(layer "F.Cu")
		(net "PCIE_TX_CAP_N89")
	)
	(segment
		(start 159.180784 -34.43224)
		(end 159.180784 -34.60496)
		(width 0.136652)
		(layer "F.Cu")
		(net "PCIE_TX_CAP_N89")
	)
	(via
		(at 159.467804 -35.02152)
		(size 0.508)
		(drill 0.254)
		(layers "F.Cu" "B.Cu")
		(net "PCIE_TX_CAP_N89")
	)
	(via
		(at 223.100138 -29.500068)
		(size 0.4572)
		(drill 0.2032)
		(layers "F.Cu" "B.Cu")
		(net "PCIE_TX_CAP_N89")
	)
	(arc
		(start 159.429704 -33.9725)
		(mid 159.246969 -34.170826)
		(end 159.180784 -34.43224)
		(width 0.136652)
		(layer "F.Cu")
		(net "PCIE_TX_CAP_N89")
	)
	(arc
		(start 159.180784 -34.60496)
		(mid 159.259488 -34.85789)
		(end 159.467804 -35.02152)
		(width 0.136652)
		(layer "F.Cu")
		(net "PCIE_TX_CAP_N89")
	)
	(segment
		(start 182.855362 -31.834582)
		(end 183.71058 -31.683706)
		(width 0.1397)
		(layer "In5.Cu")
		(net "PCIE_TX_CAP_N89")
	)
	(segment
		(start 179.993798 -31.330646)
		(end 182.855362 -31.834582)
		(width 0.1397)
		(layer "In5.Cu")
		(net "PCIE_TX_CAP_N89")
	)
	(segment
		(start 185.570368 -31.3563)
		(end 187.050934 -31.617158)
		(width 0.1397)
		(layer "In5.Cu")
		(net "PCIE_TX_CAP_N89")
	)
	(segment
		(start 187.050934 -31.617158)
		(end 194.721226 -30.262322)
		(width 0.1397)
		(layer "In5.Cu")
		(net "PCIE_TX_CAP_N89")
	)
	(segment
		(start 174.886366 -32.231076)
		(end 175.030384 -32.025082)
		(width 0.1397)
		(layer "In5.Cu")
		(net "PCIE_TX_CAP_N89")
	)
	(segment
		(start 177.237644 -31.816548)
		(end 177.381916 -31.610554)
		(width 0.1397)
		(layer "In5.Cu")
		(net "PCIE_TX_CAP_N89")
	)
	(segment
		(start 167.3352 -36.685982)
		(end 173.29785 -32.510984)
		(width 0.1397)
		(layer "In5.Cu")
		(net "PCIE_TX_CAP_N89")
	)
	(segment
		(start 184.834276 -31.48584)
		(end 185.17362 -31.42615)
		(width 0.1397)
		(layer "In5.Cu")
		(net "PCIE_TX_CAP_N89")
	)
	(segment
		(start 174.473616 -32.30372)
		(end 174.886366 -32.231076)
		(width 0.1397)
		(layer "In5.Cu")
		(net "PCIE_TX_CAP_N89")
	)
	(segment
		(start 176.061878 -32.023812)
		(end 176.20615 -31.817818)
		(width 0.1397)
		(layer "In5.Cu")
		(net "PCIE_TX_CAP_N89")
	)
	(segment
		(start 160.211516 -36.957)
		(end 166.49065 -36.957)
		(width 0.1397)
		(layer "In5.Cu")
		(net "PCIE_TX_CAP_N89")
	)
	(segment
		(start 194.721226 -30.262322)
		(end 196.180456 -30.519624)
		(width 0.1397)
		(layer "In5.Cu")
		(net "PCIE_TX_CAP_N89")
	)
	(segment
		(start 175.649128 -32.096456)
		(end 176.061878 -32.023812)
		(width 0.1397)
		(layer "In5.Cu")
		(net "PCIE_TX_CAP_N89")
	)
	(segment
		(start 221.4626 -29.83484)
		(end 221.488 -29.83484)
		(width 0.1016)
		(layer "In5.Cu")
		(net "PCIE_TX_CAP_N89")
	)
	(segment
		(start 217.411808 -31.58363)
		(end 219.305378 -31.249874)
		(width 0.1397)
		(layer "In5.Cu")
		(net "PCIE_TX_CAP_N89")
	)
	(segment
		(start 176.6189 -31.74492)
		(end 176.824894 -31.889192)
		(width 0.1397)
		(layer "In5.Cu")
		(net "PCIE_TX_CAP_N89")
	)
	(segment
		(start 221.2086 -29.83484)
		(end 221.4626 -29.83484)
		(width 0.1397)
		(layer "In5.Cu")
		(net "PCIE_TX_CAP_N89")
	)
	(segment
		(start 184.155588 -31.605474)
		(end 184.834276 -31.48584)
		(width 0.1397)
		(layer "In5.Cu")
		(net "PCIE_TX_CAP_N89")
	)
	(segment
		(start 175.030384 -32.025082)
		(end 175.443134 -31.952184)
		(width 0.1397)
		(layer "In5.Cu")
		(net "PCIE_TX_CAP_N89")
	)
	(segment
		(start 176.20615 -31.817818)
		(end 176.6189 -31.74492)
		(width 0.1397)
		(layer "In5.Cu")
		(net "PCIE_TX_CAP_N89")
	)
	(segment
		(start 178.00066 -31.681928)
		(end 179.993798 -31.330646)
		(width 0.1397)
		(layer "In5.Cu")
		(net "PCIE_TX_CAP_N89")
	)
	(segment
		(start 173.7106 -32.43834)
		(end 173.854872 -32.232346)
		(width 0.1397)
		(layer "In5.Cu")
		(net "PCIE_TX_CAP_N89")
	)
	(segment
		(start 215.616536 -31.267146)
		(end 217.411808 -31.58363)
		(width 0.1397)
		(layer "In5.Cu")
		(net "PCIE_TX_CAP_N89")
	)
	(segment
		(start 166.49065 -36.957)
		(end 167.3352 -36.685982)
		(width 0.1397)
		(layer "In5.Cu")
		(net "PCIE_TX_CAP_N89")
	)
	(segment
		(start 183.71058 -31.683706)
		(end 184.155588 -31.605474)
		(width 0.1397)
		(layer "In5.Cu")
		(net "PCIE_TX_CAP_N89")
	)
	(segment
		(start 221.596458 -29.89834)
		(end 222.827088 -29.89834)
		(width 0.1016)
		(layer "In5.Cu")
		(net "PCIE_TX_CAP_N89")
	)
	(segment
		(start 203.722224 -31.684468)
		(end 210.853274 -30.42666)
		(width 0.1397)
		(layer "In5.Cu")
		(net "PCIE_TX_CAP_N89")
	)
	(segment
		(start 200.237852 -30.62097)
		(end 203.722224 -31.684468)
		(width 0.1397)
		(layer "In5.Cu")
		(net "PCIE_TX_CAP_N89")
	)
	(segment
		(start 176.824894 -31.889192)
		(end 177.237644 -31.816548)
		(width 0.1397)
		(layer "In5.Cu")
		(net "PCIE_TX_CAP_N89")
	)
	(segment
		(start 173.29785 -32.510984)
		(end 173.7106 -32.43834)
		(width 0.1397)
		(layer "In5.Cu")
		(net "PCIE_TX_CAP_N89")
	)
	(segment
		(start 159.406082 -36.256722)
		(end 160.031938 -36.882578)
		(width 0.1397)
		(layer "In5.Cu")
		(net "PCIE_TX_CAP_N89")
	)
	(segment
		(start 196.180456 -30.519624)
		(end 198.8185 -30.990032)
		(width 0.1397)
		(layer "In5.Cu")
		(net "PCIE_TX_CAP_N89")
	)
	(segment
		(start 174.267622 -32.159448)
		(end 174.473616 -32.30372)
		(width 0.1397)
		(layer "In5.Cu")
		(net "PCIE_TX_CAP_N89")
	)
	(segment
		(start 159.226504 -35.387534)
		(end 159.226504 -35.823144)
		(width 0.1397)
		(layer "In5.Cu")
		(net "PCIE_TX_CAP_N89")
	)
	(segment
		(start 177.381916 -31.610554)
		(end 177.794666 -31.53791)
		(width 0.1397)
		(layer "In5.Cu")
		(net "PCIE_TX_CAP_N89")
	)
	(segment
		(start 175.443134 -31.952184)
		(end 175.649128 -32.096456)
		(width 0.1397)
		(layer "In5.Cu")
		(net "PCIE_TX_CAP_N89")
	)
	(segment
		(start 185.17362 -31.42615)
		(end 185.570368 -31.3563)
		(width 0.1397)
		(layer "In5.Cu")
		(net "PCIE_TX_CAP_N89")
	)
	(segment
		(start 177.794666 -31.53791)
		(end 178.00066 -31.681928)
		(width 0.1397)
		(layer "In5.Cu")
		(net "PCIE_TX_CAP_N89")
	)
	(segment
		(start 159.467804 -35.02152)
		(end 159.314642 -35.174682)
		(width 0.1397)
		(layer "In5.Cu")
		(net "PCIE_TX_CAP_N89")
	)
	(segment
		(start 219.6973 -30.9753)
		(end 220.576902 -30.095698)
		(width 0.1397)
		(layer "In5.Cu")
		(net "PCIE_TX_CAP_N89")
	)
	(segment
		(start 210.853274 -30.42666)
		(end 215.616536 -31.267146)
		(width 0.1397)
		(layer "In5.Cu")
		(net "PCIE_TX_CAP_N89")
	)
	(segment
		(start 198.8185 -30.990032)
		(end 200.237852 -30.62097)
		(width 0.1397)
		(layer "In5.Cu")
		(net "PCIE_TX_CAP_N89")
	)
	(segment
		(start 219.305378 -31.249874)
		(end 219.6973 -30.9753)
		(width 0.1397)
		(layer "In5.Cu")
		(net "PCIE_TX_CAP_N89")
	)
	(segment
		(start 173.854872 -32.232346)
		(end 174.267622 -32.159448)
		(width 0.1397)
		(layer "In5.Cu")
		(net "PCIE_TX_CAP_N89")
	)
	(segment
		(start 221.488 -29.83484)
		(end 221.51975 -29.86659)
		(width 0.1016)
		(layer "In5.Cu")
		(net "PCIE_TX_CAP_N89")
	)
	(arc
		(start 220.576902 -30.095698)
		(mid 220.654188 -30.026956)
		(end 220.738954 -29.967682)
		(width 0.1397)
		(layer "In5.Cu")
		(net "PCIE_TX_CAP_N89")
	)
	(arc
		(start 220.738954 -29.967682)
		(mid 220.96455 -29.868653)
		(end 221.2086 -29.83484)
		(width 0.1397)
		(layer "In5.Cu")
		(net "PCIE_TX_CAP_N89")
	)
	(arc
		(start 160.031938 -36.882578)
		(mid 160.114315 -36.937684)
		(end 160.211516 -36.957)
		(width 0.1397)
		(layer "In5.Cu")
		(net "PCIE_TX_CAP_N89")
	)
	(arc
		(start 221.51975 -29.86659)
		(mid 221.554944 -29.890106)
		(end 221.596458 -29.89834)
		(width 0.1016)
		(layer "In5.Cu")
		(net "PCIE_TX_CAP_N89")
	)
	(arc
		(start 222.827088 -29.89834)
		(mid 223.068601 -29.771127)
		(end 223.100138 -29.500068)
		(width 0.1016)
		(layer "In5.Cu")
		(net "PCIE_TX_CAP_N89")
	)
	(arc
		(start 159.314642 -35.174682)
		(mid 159.249389 -35.272339)
		(end 159.226504 -35.387534)
		(width 0.1397)
		(layer "In5.Cu")
		(net "PCIE_TX_CAP_N89")
	)
	(arc
		(start 159.226504 -35.823144)
		(mid 159.273178 -36.057789)
		(end 159.406082 -36.256722)
		(width 0.1397)
		(layer "In5.Cu")
		(net "PCIE_TX_CAP_N89")
	)
	(segment
		(start 162.703002 -36.585398)
		(end 163.523676 -35.764724)
		(width 0.136652)
		(layer "F.Cu")
		(net "PCIE_TX_CAP_N88")
	)
	(segment
		(start 163.7919 -35.117024)
		(end 163.7919 -34.4424)
		(width 0.136652)
		(layer "F.Cu")
		(net "PCIE_TX_CAP_N88")
	)
	(segment
		(start 163.91763 -34.13887)
		(end 164.084 -33.9725)
		(width 0.136652)
		(layer "F.Cu")
		(net "PCIE_TX_CAP_N88")
	)
	(segment
		(start 222.600012 -30.999938)
		(end 222.10014 -30.500066)
		(width 0.136652)
		(layer "F.Cu")
		(net "PCIE_TX_CAP_N88")
	)
	(via
		(at 222.10014 -30.500066)
		(size 0.4572)
		(drill 0.2032)
		(layers "F.Cu" "B.Cu")
		(net "PCIE_TX_CAP_N88")
	)
	(via
		(at 162.5981 -38.0111)
		(size 0.508)
		(drill 0.254)
		(layers "F.Cu" "B.Cu")
		(net "PCIE_TX_CAP_N88")
	)
	(arc
		(start 163.523676 -35.764724)
		(mid 163.722183 -35.467542)
		(end 163.7919 -35.117024)
		(width 0.136652)
		(layer "F.Cu")
		(net "PCIE_TX_CAP_N88")
	)
	(arc
		(start 163.7919 -34.4424)
		(mid 163.824575 -34.278129)
		(end 163.91763 -34.13887)
		(width 0.136652)
		(layer "F.Cu")
		(net "PCIE_TX_CAP_N88")
	)
	(arc
		(start 162.37966 -37.36594)
		(mid 162.463688 -36.943502)
		(end 162.703002 -36.585398)
		(width 0.136652)
		(layer "F.Cu")
		(net "PCIE_TX_CAP_N88")
	)
	(arc
		(start 162.5981 -38.0111)
		(mid 162.435754 -37.706508)
		(end 162.37966 -37.36594)
		(width 0.136652)
		(layer "F.Cu")
		(net "PCIE_TX_CAP_N88")
	)
	(segment
		(start 221.987618 -31.07944)
		(end 222.046546 -31.030926)
		(width 0.1397)
		(layer "In5.Cu")
		(net "PCIE_TX_CAP_N88")
	)
	(segment
		(start 186.468258 -32.500316)
		(end 187.07735 -32.607758)
		(width 0.1397)
		(layer "In5.Cu")
		(net "PCIE_TX_CAP_N88")
	)
	(segment
		(start 162.3568 -38.395148)
		(end 162.3568 -38.867588)
		(width 0.1397)
		(layer "In5.Cu")
		(net "PCIE_TX_CAP_N88")
	)
	(segment
		(start 199.314054 -32.037274)
		(end 203.938378 -32.852614)
		(width 0.1397)
		(layer "In5.Cu")
		(net "PCIE_TX_CAP_N88")
	)
	(segment
		(start 219.503244 -32.60725)
		(end 220.088714 -32.197548)
		(width 0.1397)
		(layer "In5.Cu")
		(net "PCIE_TX_CAP_N88")
	)
	(segment
		(start 220.088714 -32.197294)
		(end 220.095318 -32.192722)
		(width 0.1397)
		(layer "In5.Cu")
		(net "PCIE_TX_CAP_N88")
	)
	(segment
		(start 166.086028 -38.831266)
		(end 173.836838 -33.404048)
		(width 0.1397)
		(layer "In5.Cu")
		(net "PCIE_TX_CAP_N88")
	)
	(segment
		(start 162.69843 -39.210996)
		(end 163.376102 -39.370762)
		(width 0.1397)
		(layer "In5.Cu")
		(net "PCIE_TX_CAP_N88")
	)
	(segment
		(start 218.236038 -32.830516)
		(end 219.503244 -32.60725)
		(width 0.1397)
		(layer "In5.Cu")
		(net "PCIE_TX_CAP_N88")
	)
	(segment
		(start 220.095318 -32.192722)
		(end 220.616526 -31.671514)
		(width 0.1397)
		(layer "In5.Cu")
		(net "PCIE_TX_CAP_N88")
	)
	(segment
		(start 220.61678 -31.671514)
		(end 220.839792 -31.448756)
		(width 0.1397)
		(layer "In5.Cu")
		(net "PCIE_TX_CAP_N88")
	)
	(segment
		(start 180.09616 -32.299656)
		(end 183.134 -32.835088)
		(width 0.1397)
		(layer "In5.Cu")
		(net "PCIE_TX_CAP_N88")
	)
	(segment
		(start 162.408616 -38.9763)
		(end 162.69843 -39.210996)
		(width 0.1397)
		(layer "In5.Cu")
		(net "PCIE_TX_CAP_N88")
	)
	(segment
		(start 211.14893 -31.581598)
		(end 215.46693 -32.342582)
		(width 0.1397)
		(layer "In5.Cu")
		(net "PCIE_TX_CAP_N88")
	)
	(segment
		(start 203.938378 -32.852614)
		(end 211.14893 -31.581598)
		(width 0.1397)
		(layer "In5.Cu")
		(net "PCIE_TX_CAP_N88")
	)
	(segment
		(start 163.376102 -39.370762)
		(end 166.086028 -38.831266)
		(width 0.1397)
		(layer "In5.Cu")
		(net "PCIE_TX_CAP_N88")
	)
	(segment
		(start 215.46693 -32.342582)
		(end 216.748868 -32.568642)
		(width 0.1397)
		(layer "In5.Cu")
		(net "PCIE_TX_CAP_N88")
	)
	(segment
		(start 187.07735 -32.607758)
		(end 194.812412 -31.24327)
		(width 0.1397)
		(layer "In5.Cu")
		(net "PCIE_TX_CAP_N88")
	)
	(segment
		(start 173.836838 -33.404048)
		(end 180.09616 -32.300164)
		(width 0.1397)
		(layer "In5.Cu")
		(net "PCIE_TX_CAP_N88")
	)
	(segment
		(start 180.09616 -32.300164)
		(end 180.09616 -32.299656)
		(width 0.1397)
		(layer "In5.Cu")
		(net "PCIE_TX_CAP_N88")
	)
	(segment
		(start 220.616526 -31.671514)
		(end 220.61678 -31.671514)
		(width 0.1397)
		(layer "In5.Cu")
		(net "PCIE_TX_CAP_N88")
	)
	(segment
		(start 183.134 -32.835088)
		(end 185.749946 -32.373824)
		(width 0.1397)
		(layer "In5.Cu")
		(net "PCIE_TX_CAP_N88")
	)
	(segment
		(start 194.812412 -31.24327)
		(end 199.314054 -32.037274)
		(width 0.1397)
		(layer "In5.Cu")
		(net "PCIE_TX_CAP_N88")
	)
	(segment
		(start 185.749946 -32.373824)
		(end 186.468258 -32.500316)
		(width 0.1397)
		(layer "In5.Cu")
		(net "PCIE_TX_CAP_N88")
	)
	(segment
		(start 216.748868 -32.568642)
		(end 218.236038 -32.830516)
		(width 0.1397)
		(layer "In5.Cu")
		(net "PCIE_TX_CAP_N88")
	)
	(segment
		(start 220.088714 -32.197548)
		(end 220.088714 -32.197294)
		(width 0.1397)
		(layer "In5.Cu")
		(net "PCIE_TX_CAP_N88")
	)
	(arc
		(start 162.5981 -38.0111)
		(mid 162.422108 -38.168358)
		(end 162.3568 -38.395148)
		(width 0.1397)
		(layer "In5.Cu")
		(net "PCIE_TX_CAP_N88")
	)
	(arc
		(start 162.3568 -38.867588)
		(mid 162.370416 -38.927803)
		(end 162.408616 -38.9763)
		(width 0.1397)
		(layer "In5.Cu")
		(net "PCIE_TX_CAP_N88")
	)
	(arc
		(start 220.839792 -31.448756)
		(mid 221.228086 -31.299918)
		(end 221.633288 -31.20644)
		(width 0.1397)
		(layer "In5.Cu")
		(net "PCIE_TX_CAP_N88")
	)
	(arc
		(start 221.633288 -31.20644)
		(mid 221.821512 -31.173782)
		(end 221.987618 -31.07944)
		(width 0.1397)
		(layer "In5.Cu")
		(net "PCIE_TX_CAP_N88")
	)
	(arc
		(start 222.046546 -31.030926)
		(mid 222.182595 -30.776552)
		(end 222.10014 -30.500066)
		(width 0.1397)
		(layer "In5.Cu")
		(net "PCIE_TX_CAP_N88")
	)
	(segment
		(start 222.600012 -33.999932)
		(end 222.10014 -33.50006)
		(width 0.136652)
		(layer "F.Cu")
		(net "PCIE_TX_CAP_N87")
	)
	(segment
		(start 153.24328 -34.40684)
		(end 153.24328 -34.57956)
		(width 0.136652)
		(layer "F.Cu")
		(net "PCIE_TX_CAP_N87")
	)
	(via
		(at 153.5303 -34.99612)
		(size 0.508)
		(drill 0.254)
		(layers "F.Cu" "B.Cu")
		(net "PCIE_TX_CAP_N87")
	)
	(via
		(at 222.10014 -33.50006)
		(size 0.4572)
		(drill 0.2032)
		(layers "F.Cu" "B.Cu")
		(net "PCIE_TX_CAP_N87")
	)
	(arc
		(start 153.4922 -33.9471)
		(mid 153.309465 -34.145426)
		(end 153.24328 -34.40684)
		(width 0.136652)
		(layer "F.Cu")
		(net "PCIE_TX_CAP_N87")
	)
	(arc
		(start 153.24328 -34.57956)
		(mid 153.321984 -34.83249)
		(end 153.5303 -34.99612)
		(width 0.136652)
		(layer "F.Cu")
		(net "PCIE_TX_CAP_N87")
	)
	(segment
		(start 219.837254 -33.584388)
		(end 218.3003 -33.854898)
		(width 0.1397)
		(layer "In5.Cu")
		(net "PCIE_TX_CAP_N87")
	)
	(segment
		(start 222.504762 -33.37687)
		(end 222.620078 -33.45053)
		(width 0.1016)
		(layer "In5.Cu")
		(net "PCIE_TX_CAP_N87")
	)
	(segment
		(start 163.4744 -40.43045)
		(end 163.149026 -40.3733)
		(width 0.1397)
		(layer "In5.Cu")
		(net "PCIE_TX_CAP_N87")
	)
	(segment
		(start 155.475686 -36.750498)
		(end 154.195018 -36.524692)
		(width 0.1397)
		(layer "In5.Cu")
		(net "PCIE_TX_CAP_N87")
	)
	(segment
		(start 155.656788 -36.782248)
		(end 155.554172 -36.764214)
		(width 0.1397)
		(layer "In5.Cu")
		(net "PCIE_TX_CAP_N87")
	)
	(segment
		(start 221.2594 -33.835086)
		(end 219.837254 -33.584388)
		(width 0.1397)
		(layer "In5.Cu")
		(net "PCIE_TX_CAP_N87")
	)
	(segment
		(start 153.404824 -35.971988)
		(end 153.289 -35.51428)
		(width 0.1397)
		(layer "In5.Cu")
		(net "PCIE_TX_CAP_N87")
	)
	(segment
		(start 192.407794 -33.15843)
		(end 191.995044 -33.231328)
		(width 0.1397)
		(layer "In5.Cu")
		(net "PCIE_TX_CAP_N87")
	)
	(segment
		(start 191.3763 -33.1597)
		(end 191.232028 -33.365694)
		(width 0.1397)
		(layer "In5.Cu")
		(net "PCIE_TX_CAP_N87")
	)
	(segment
		(start 204.063854 -33.879536)
		(end 196.1896 -32.49168)
		(width 0.1397)
		(layer "In5.Cu")
		(net "PCIE_TX_CAP_N87")
	)
	(segment
		(start 174.382938 -34.33445)
		(end 166.636446 -39.758874)
		(width 0.1397)
		(layer "In5.Cu")
		(net "PCIE_TX_CAP_N87")
	)
	(segment
		(start 191.995044 -33.231328)
		(end 191.78905 -33.087056)
		(width 0.1397)
		(layer "In5.Cu")
		(net "PCIE_TX_CAP_N87")
	)
	(segment
		(start 222.10014 -33.50006)
		(end 222.10014 -33.48863)
		(width 0.1016)
		(layer "In5.Cu")
		(net "PCIE_TX_CAP_N87")
	)
	(segment
		(start 196.1896 -32.49168)
		(end 193.170556 -33.024064)
		(width 0.1397)
		(layer "In5.Cu")
		(net "PCIE_TX_CAP_N87")
	)
	(segment
		(start 153.289 -35.51428)
		(end 153.289 -35.39109)
		(width 0.1397)
		(layer "In5.Cu")
		(net "PCIE_TX_CAP_N87")
	)
	(segment
		(start 221.5642 -33.835086)
		(end 221.2594 -33.835086)
		(width 0.1397)
		(layer "In5.Cu")
		(net "PCIE_TX_CAP_N87")
	)
	(segment
		(start 191.232028 -33.365694)
		(end 188.468 -33.85312)
		(width 0.1397)
		(layer "In5.Cu")
		(net "PCIE_TX_CAP_N87")
	)
	(segment
		(start 222.171768 -33.385252)
		(end 222.26143 -33.35147)
		(width 0.1016)
		(layer "In5.Cu")
		(net "PCIE_TX_CAP_N87")
	)
	(segment
		(start 191.78905 -33.087056)
		(end 191.3763 -33.1597)
		(width 0.1397)
		(layer "In5.Cu")
		(net "PCIE_TX_CAP_N87")
	)
	(segment
		(start 222.633794 -33.73501)
		(end 222.633286 -33.735772)
		(width 0.1016)
		(layer "In5.Cu")
		(net "PCIE_TX_CAP_N87")
	)
	(segment
		(start 183.1721 -33.85058)
		(end 180.1495 -33.317942)
		(width 0.1397)
		(layer "In5.Cu")
		(net "PCIE_TX_CAP_N87")
	)
	(segment
		(start 218.3003 -33.854898)
		(end 211.251546 -32.612584)
		(width 0.1397)
		(layer "In5.Cu")
		(net "PCIE_TX_CAP_N87")
	)
	(segment
		(start 192.964816 -32.879792)
		(end 192.552066 -32.952436)
		(width 0.1397)
		(layer "In5.Cu")
		(net "PCIE_TX_CAP_N87")
	)
	(segment
		(start 154.195018 -36.524692)
		(end 153.404824 -35.971988)
		(width 0.1397)
		(layer "In5.Cu")
		(net "PCIE_TX_CAP_N87")
	)
	(segment
		(start 188.468 -33.85312)
		(end 185.813954 -33.384998)
		(width 0.1397)
		(layer "In5.Cu")
		(net "PCIE_TX_CAP_N87")
	)
	(segment
		(start 221.5896 -33.835086)
		(end 221.5642 -33.835086)
		(width 0.1016)
		(layer "In5.Cu")
		(net "PCIE_TX_CAP_N87")
	)
	(segment
		(start 211.251546 -32.612584)
		(end 204.063854 -33.879536)
		(width 0.1397)
		(layer "In5.Cu")
		(net "PCIE_TX_CAP_N87")
	)
	(segment
		(start 153.397712 -35.128708)
		(end 153.5303 -34.99612)
		(width 0.1397)
		(layer "In5.Cu")
		(net "PCIE_TX_CAP_N87")
	)
	(segment
		(start 163.149026 -40.3733)
		(end 162.14598 -40.160448)
		(width 0.1397)
		(layer "In5.Cu")
		(net "PCIE_TX_CAP_N87")
	)
	(segment
		(start 156.21 -37.33546)
		(end 155.656788 -36.782248)
		(width 0.1397)
		(layer "In5.Cu")
		(net "PCIE_TX_CAP_N87")
	)
	(segment
		(start 222.344234 -33.898586)
		(end 221.743016 -33.898586)
		(width 0.1016)
		(layer "In5.Cu")
		(net "PCIE_TX_CAP_N87")
	)
	(segment
		(start 158.567628 -37.836602)
		(end 156.21 -37.33546)
		(width 0.1397)
		(layer "In5.Cu")
		(net "PCIE_TX_CAP_N87")
	)
	(segment
		(start 193.170556 -33.024064)
		(end 192.964816 -32.879792)
		(width 0.1397)
		(layer "In5.Cu")
		(net "PCIE_TX_CAP_N87")
	)
	(segment
		(start 192.552066 -32.952436)
		(end 192.407794 -33.15843)
		(width 0.1397)
		(layer "In5.Cu")
		(net "PCIE_TX_CAP_N87")
	)
	(segment
		(start 185.813954 -33.384998)
		(end 183.1721 -33.85058)
		(width 0.1397)
		(layer "In5.Cu")
		(net "PCIE_TX_CAP_N87")
	)
	(segment
		(start 162.14598 -40.160448)
		(end 158.567628 -37.836602)
		(width 0.1397)
		(layer "In5.Cu")
		(net "PCIE_TX_CAP_N87")
	)
	(segment
		(start 180.1495 -33.317942)
		(end 174.382938 -34.33445)
		(width 0.1397)
		(layer "In5.Cu")
		(net "PCIE_TX_CAP_N87")
	)
	(segment
		(start 155.554172 -36.764214)
		(end 155.475686 -36.750498)
		(width 0.1397)
		(layer "In5.Cu")
		(net "PCIE_TX_CAP_N87")
	)
	(segment
		(start 166.636446 -39.758874)
		(end 163.4744 -40.43045)
		(width 0.1397)
		(layer "In5.Cu")
		(net "PCIE_TX_CAP_N87")
	)
	(arc
		(start 222.620078 -33.45053)
		(mid 222.664102 -33.590974)
		(end 222.633794 -33.73501)
		(width 0.1016)
		(layer "In5.Cu")
		(net "PCIE_TX_CAP_N87")
	)
	(arc
		(start 153.289 -35.39109)
		(mid 153.317248 -35.249078)
		(end 153.397712 -35.128708)
		(width 0.1397)
		(layer "In5.Cu")
		(net "PCIE_TX_CAP_N87")
	)
	(arc
		(start 222.10014 -33.48863)
		(mid 222.11979 -33.425732)
		(end 222.171768 -33.385252)
		(width 0.1016)
		(layer "In5.Cu")
		(net "PCIE_TX_CAP_N87")
	)
	(arc
		(start 222.26143 -33.35147)
		(mid 222.386092 -33.335418)
		(end 222.504762 -33.37687)
		(width 0.1016)
		(layer "In5.Cu")
		(net "PCIE_TX_CAP_N87")
	)
	(arc
		(start 221.743016 -33.898586)
		(mid 221.659992 -33.882089)
		(end 221.5896 -33.835086)
		(width 0.1016)
		(layer "In5.Cu")
		(net "PCIE_TX_CAP_N87")
	)
	(arc
		(start 222.633286 -33.735772)
		(mid 222.51014 -33.855132)
		(end 222.344234 -33.898586)
		(width 0.1016)
		(layer "In5.Cu")
		(net "PCIE_TX_CAP_N87")
	)
	(segment
		(start 149.168358 -34.855658)
		(end 149.3139 -35.0012)
		(width 0.136652)
		(layer "F.Cu")
		(net "PCIE_TX_CAP_N86")
	)
	(segment
		(start 149.352 -33.9725)
		(end 149.167596 -34.15665)
		(width 0.136652)
		(layer "F.Cu")
		(net "PCIE_TX_CAP_N86")
	)
	(segment
		(start 223.60001 -34.99993)
		(end 223.100138 -34.500058)
		(width 0.136652)
		(layer "F.Cu")
		(net "PCIE_TX_CAP_N86")
	)
	(segment
		(start 149.0599 -34.417)
		(end 149.0599 -34.593784)
		(width 0.136652)
		(layer "F.Cu")
		(net "PCIE_TX_CAP_N86")
	)
	(via
		(at 149.3139 -35.0012)
		(size 0.508)
		(drill 0.254)
		(layers "F.Cu" "B.Cu")
		(net "PCIE_TX_CAP_N86")
	)
	(via
		(at 223.100138 -34.500058)
		(size 0.4572)
		(drill 0.2032)
		(layers "F.Cu" "B.Cu")
		(net "PCIE_TX_CAP_N86")
	)
	(arc
		(start 149.167596 -34.15665)
		(mid 149.087865 -34.276115)
		(end 149.0599 -34.417)
		(width 0.136652)
		(layer "F.Cu")
		(net "PCIE_TX_CAP_N86")
	)
	(arc
		(start 149.0599 -34.593784)
		(mid 149.08809 -34.735504)
		(end 149.168358 -34.855658)
		(width 0.136652)
		(layer "F.Cu")
		(net "PCIE_TX_CAP_N86")
	)
	(segment
		(start 220.9038 -34.835084)
		(end 221.5642 -34.835084)
		(width 0.1397)
		(layer "In5.Cu")
		(net "PCIE_TX_CAP_N86")
	)
	(segment
		(start 151.945848 -36.157408)
		(end 152.082754 -36.368228)
		(width 0.1397)
		(layer "In5.Cu")
		(net "PCIE_TX_CAP_N86")
	)
	(segment
		(start 149.544024 -36.206684)
		(end 149.800818 -36.206684)
		(width 0.1397)
		(layer "In5.Cu")
		(net "PCIE_TX_CAP_N86")
	)
	(segment
		(start 151.535892 -36.070286)
		(end 151.945848 -36.157408)
		(width 0.1397)
		(layer "In5.Cu")
		(net "PCIE_TX_CAP_N86")
	)
	(segment
		(start 223.459802 -34.271458)
		(end 223.214438 -34.271458)
		(width 0.1016)
		(layer "In5.Cu")
		(net "PCIE_TX_CAP_N86")
	)
	(segment
		(start 218.5162 -34.879534)
		(end 219.837 -34.64687)
		(width 0.1397)
		(layer "In5.Cu")
		(net "PCIE_TX_CAP_N86")
	)
	(segment
		(start 223.6216 -34.699448)
		(end 223.6216 -34.433002)
		(width 0.1016)
		(layer "In5.Cu")
		(net "PCIE_TX_CAP_N86")
	)
	(segment
		(start 219.837 -34.64687)
		(end 220.9038 -34.835084)
		(width 0.1397)
		(layer "In5.Cu")
		(net "PCIE_TX_CAP_N86")
	)
	(segment
		(start 188.468 -34.866072)
		(end 191.452246 -34.340038)
		(width 0.1397)
		(layer "In5.Cu")
		(net "PCIE_TX_CAP_N86")
	)
	(segment
		(start 151.325072 -36.207192)
		(end 151.535892 -36.070286)
		(width 0.1397)
		(layer "In5.Cu")
		(net "PCIE_TX_CAP_N86")
	)
	(segment
		(start 149.21611 -36.00831)
		(end 149.32279 -36.11499)
		(width 0.1397)
		(layer "In5.Cu")
		(net "PCIE_TX_CAP_N86")
	)
	(segment
		(start 163.488116 -41.220136)
		(end 167.570404 -40.352726)
		(width 0.1397)
		(layer "In5.Cu")
		(net "PCIE_TX_CAP_N86")
	)
	(segment
		(start 183.2356 -34.870898)
		(end 185.8645 -34.407348)
		(width 0.1397)
		(layer "In5.Cu")
		(net "PCIE_TX_CAP_N86")
	)
	(segment
		(start 196.163692 -33.509458)
		(end 203.9493 -34.88182)
		(width 0.1397)
		(layer "In5.Cu")
		(net "PCIE_TX_CAP_N86")
	)
	(segment
		(start 150.776178 -36.090606)
		(end 151.325072 -36.207192)
		(width 0.1397)
		(layer "In5.Cu")
		(net "PCIE_TX_CAP_N86")
	)
	(segment
		(start 180.1495 -34.32683)
		(end 183.2356 -34.870898)
		(width 0.1397)
		(layer "In5.Cu")
		(net "PCIE_TX_CAP_N86")
	)
	(segment
		(start 175.018446 -35.231324)
		(end 180.1495 -34.32683)
		(width 0.1397)
		(layer "In5.Cu")
		(net "PCIE_TX_CAP_N86")
	)
	(segment
		(start 152.49271 -36.45535)
		(end 154.828748 -37.970968)
		(width 0.1397)
		(layer "In5.Cu")
		(net "PCIE_TX_CAP_N86")
	)
	(segment
		(start 152.082754 -36.368228)
		(end 152.49271 -36.45535)
		(width 0.1397)
		(layer "In5.Cu")
		(net "PCIE_TX_CAP_N86")
	)
	(segment
		(start 163.001198 -41.134284)
		(end 163.488116 -41.220136)
		(width 0.1397)
		(layer "In5.Cu")
		(net "PCIE_TX_CAP_N86")
	)
	(segment
		(start 223.100138 -34.385758)
		(end 223.100138 -34.500058)
		(width 0.1016)
		(layer "In5.Cu")
		(net "PCIE_TX_CAP_N86")
	)
	(segment
		(start 203.9493 -34.88182)
		(end 211.2391 -33.597088)
		(width 0.1397)
		(layer "In5.Cu")
		(net "PCIE_TX_CAP_N86")
	)
	(segment
		(start 211.2391 -33.597088)
		(end 218.5162 -34.879534)
		(width 0.1397)
		(layer "In5.Cu")
		(net "PCIE_TX_CAP_N86")
	)
	(segment
		(start 167.570404 -40.352726)
		(end 169.414698 -39.155116)
		(width 0.1397)
		(layer "In5.Cu")
		(net "PCIE_TX_CAP_N86")
	)
	(segment
		(start 185.8645 -34.407348)
		(end 188.468 -34.866072)
		(width 0.1397)
		(layer "In5.Cu")
		(net "PCIE_TX_CAP_N86")
	)
	(segment
		(start 150.128986 -36.17214)
		(end 150.514812 -36.090352)
		(width 0.1397)
		(layer "In5.Cu")
		(net "PCIE_TX_CAP_N86")
	)
	(segment
		(start 191.452246 -34.340038)
		(end 196.163692 -33.509458)
		(width 0.1397)
		(layer "In5.Cu")
		(net "PCIE_TX_CAP_N86")
	)
	(segment
		(start 221.743016 -34.898584)
		(end 223.422464 -34.898584)
		(width 0.1016)
		(layer "In5.Cu")
		(net "PCIE_TX_CAP_N86")
	)
	(segment
		(start 154.828748 -37.970968)
		(end 158.076138 -38.66134)
		(width 0.1397)
		(layer "In5.Cu")
		(net "PCIE_TX_CAP_N86")
	)
	(segment
		(start 149.098 -35.4838)
		(end 149.098 -35.723322)
		(width 0.1397)
		(layer "In5.Cu")
		(net "PCIE_TX_CAP_N86")
	)
	(segment
		(start 169.414698 -39.155116)
		(end 175.018446 -35.231324)
		(width 0.1397)
		(layer "In5.Cu")
		(net "PCIE_TX_CAP_N86")
	)
	(segment
		(start 158.076138 -38.66134)
		(end 161.341562 -40.781986)
		(width 0.1397)
		(layer "In5.Cu")
		(net "PCIE_TX_CAP_N86")
	)
	(segment
		(start 221.5642 -34.835084)
		(end 221.5896 -34.835084)
		(width 0.1016)
		(layer "In5.Cu")
		(net "PCIE_TX_CAP_N86")
	)
	(segment
		(start 161.341562 -40.781986)
		(end 163.001198 -41.134284)
		(width 0.1397)
		(layer "In5.Cu")
		(net "PCIE_TX_CAP_N86")
	)
	(arc
		(start 223.574356 -34.318956)
		(mid 223.521812 -34.283784)
		(end 223.459802 -34.271458)
		(width 0.1016)
		(layer "In5.Cu")
		(net "PCIE_TX_CAP_N86")
	)
	(arc
		(start 149.098 -35.723322)
		(mid 149.128699 -35.877567)
		(end 149.21611 -36.00831)
		(width 0.1397)
		(layer "In5.Cu")
		(net "PCIE_TX_CAP_N86")
	)
	(arc
		(start 223.545146 -34.85642)
		(mid 223.580146 -34.821215)
		(end 223.605344 -34.778442)
		(width 0.1016)
		(layer "In5.Cu")
		(net "PCIE_TX_CAP_N86")
	)
	(arc
		(start 149.32279 -36.11499)
		(mid 149.424279 -36.182866)
		(end 149.544024 -36.206684)
		(width 0.1397)
		(layer "In5.Cu")
		(net "PCIE_TX_CAP_N86")
	)
	(arc
		(start 221.5896 -34.835084)
		(mid 221.660002 -34.882062)
		(end 221.743016 -34.898584)
		(width 0.1016)
		(layer "In5.Cu")
		(net "PCIE_TX_CAP_N86")
	)
	(arc
		(start 223.422464 -34.898584)
		(mid 223.487343 -34.887792)
		(end 223.545146 -34.85642)
		(width 0.1016)
		(layer "In5.Cu")
		(net "PCIE_TX_CAP_N86")
	)
	(arc
		(start 223.605344 -34.778442)
		(mid 223.617516 -34.739777)
		(end 223.6216 -34.699448)
		(width 0.1016)
		(layer "In5.Cu")
		(net "PCIE_TX_CAP_N86")
	)
	(arc
		(start 223.6216 -34.433002)
		(mid 223.609323 -34.371279)
		(end 223.574356 -34.318956)
		(width 0.1016)
		(layer "In5.Cu")
		(net "PCIE_TX_CAP_N86")
	)
	(arc
		(start 149.800818 -36.206684)
		(mid 149.965807 -36.198003)
		(end 150.128986 -36.17214)
		(width 0.1397)
		(layer "In5.Cu")
		(net "PCIE_TX_CAP_N86")
	)
	(arc
		(start 149.3139 -35.0012)
		(mid 149.154464 -35.219462)
		(end 149.098 -35.4838)
		(width 0.1397)
		(layer "In5.Cu")
		(net "PCIE_TX_CAP_N86")
	)
	(arc
		(start 223.214438 -34.271458)
		(mid 223.133616 -34.304936)
		(end 223.100138 -34.385758)
		(width 0.1016)
		(layer "In5.Cu")
		(net "PCIE_TX_CAP_N86")
	)
	(arc
		(start 150.514812 -36.090352)
		(mid 150.645508 -36.07679)
		(end 150.776178 -36.090606)
		(width 0.1397)
		(layer "In5.Cu")
		(net "PCIE_TX_CAP_N86")
	)
	(segment
		(start 146.4691 -34.38652)
		(end 146.4691 -34.588704)
		(width 0.136652)
		(layer "F.Cu")
		(net "PCIE_TX_CAP_N85")
	)
	(segment
		(start 222.600012 -35.999928)
		(end 222.10014 -35.500056)
		(width 0.136652)
		(layer "F.Cu")
		(net "PCIE_TX_CAP_N85")
	)
	(segment
		(start 146.577558 -34.850578)
		(end 146.7231 -34.99612)
		(width 0.136652)
		(layer "F.Cu")
		(net "PCIE_TX_CAP_N85")
	)
	(segment
		(start 146.74342 -33.96742)
		(end 146.571462 -34.139378)
		(width 0.136652)
		(layer "F.Cu")
		(net "PCIE_TX_CAP_N85")
	)
	(via
		(at 222.10014 -35.500056)
		(size 0.4572)
		(drill 0.2032)
		(layers "F.Cu" "B.Cu")
		(net "PCIE_TX_CAP_N85")
	)
	(via
		(at 146.7231 -34.99612)
		(size 0.508)
		(drill 0.254)
		(layers "F.Cu" "B.Cu")
		(net "PCIE_TX_CAP_N85")
	)
	(arc
		(start 146.571462 -34.139378)
		(mid 146.495697 -34.252768)
		(end 146.4691 -34.38652)
		(width 0.136652)
		(layer "F.Cu")
		(net "PCIE_TX_CAP_N85")
	)
	(arc
		(start 146.4691 -34.588704)
		(mid 146.49729 -34.730424)
		(end 146.577558 -34.850578)
		(width 0.136652)
		(layer "F.Cu")
		(net "PCIE_TX_CAP_N85")
	)
	(segment
		(start 157.979872 -39.522908)
		(end 161.040064 -41.510204)
		(width 0.1397)
		(layer "In5.Cu")
		(net "PCIE_TX_CAP_N85")
	)
	(segment
		(start 204.013308 -35.834828)
		(end 211.5566 -34.504884)
		(width 0.1397)
		(layer "In5.Cu")
		(net "PCIE_TX_CAP_N85")
	)
	(segment
		(start 193.270632 -35.678364)
		(end 193.683382 -35.751262)
		(width 0.1397)
		(layer "In5.Cu")
		(net "PCIE_TX_CAP_N85")
	)
	(segment
		(start 146.686778 -36.0299)
		(end 146.907758 -36.25088)
		(width 0.1397)
		(layer "In5.Cu")
		(net "PCIE_TX_CAP_N85")
	)
	(segment
		(start 147.964398 -36.936934)
		(end 148.837904 -37.122608)
		(width 0.1397)
		(layer "In5.Cu")
		(net "PCIE_TX_CAP_N85")
	)
	(segment
		(start 219.1004 -35.835082)
		(end 221.285562 -35.835082)
		(width 0.1397)
		(layer "In5.Cu")
		(net "PCIE_TX_CAP_N85")
	)
	(segment
		(start 152.201372 -37.213032)
		(end 154.103578 -38.66642)
		(width 0.1397)
		(layer "In5.Cu")
		(net "PCIE_TX_CAP_N85")
	)
	(segment
		(start 211.5566 -34.504884)
		(end 219.1004 -35.835082)
		(width 0.1397)
		(layer "In5.Cu")
		(net "PCIE_TX_CAP_N85")
	)
	(segment
		(start 192.507616 -35.543998)
		(end 192.71361 -35.399726)
		(width 0.1397)
		(layer "In5.Cu")
		(net "PCIE_TX_CAP_N85")
	)
	(segment
		(start 180.391816 -35.283902)
		(end 183.28767 -35.794442)
		(width 0.1397)
		(layer "In5.Cu")
		(net "PCIE_TX_CAP_N85")
	)
	(segment
		(start 193.12636 -35.47237)
		(end 193.270632 -35.678364)
		(width 0.1397)
		(layer "In5.Cu")
		(net "PCIE_TX_CAP_N85")
	)
	(segment
		(start 163.501832 -42.009568)
		(end 168.797478 -40.884348)
		(width 0.1397)
		(layer "In5.Cu")
		(net "PCIE_TX_CAP_N85")
	)
	(segment
		(start 194.301872 -35.679634)
		(end 194.446144 -35.885628)
		(width 0.1397)
		(layer "In5.Cu")
		(net "PCIE_TX_CAP_N85")
	)
	(segment
		(start 192.71361 -35.399726)
		(end 193.12636 -35.47237)
		(width 0.1397)
		(layer "In5.Cu")
		(net "PCIE_TX_CAP_N85")
	)
	(segment
		(start 191.440054 -35.355784)
		(end 192.507616 -35.543998)
		(width 0.1397)
		(layer "In5.Cu")
		(net "PCIE_TX_CAP_N85")
	)
	(segment
		(start 222.504 -35.4076)
		(end 222.323406 -35.4076)
		(width 0.1016)
		(layer "In5.Cu")
		(net "PCIE_TX_CAP_N85")
	)
	(segment
		(start 188.722508 -35.834828)
		(end 191.440054 -35.355784)
		(width 0.1397)
		(layer "In5.Cu")
		(net "PCIE_TX_CAP_N85")
	)
	(segment
		(start 162.85337 -41.895268)
		(end 163.501832 -42.009568)
		(width 0.1397)
		(layer "In5.Cu")
		(net "PCIE_TX_CAP_N85")
	)
	(segment
		(start 194.446144 -35.885628)
		(end 196.03466 -36.165536)
		(width 0.1397)
		(layer "In5.Cu")
		(net "PCIE_TX_CAP_N85")
	)
	(segment
		(start 221.349062 -35.898582)
		(end 222.41637 -35.898582)
		(width 0.1016)
		(layer "In5.Cu")
		(net "PCIE_TX_CAP_N85")
	)
	(segment
		(start 185.8899 -35.335718)
		(end 188.722508 -35.834828)
		(width 0.1397)
		(layer "In5.Cu")
		(net "PCIE_TX_CAP_N85")
	)
	(segment
		(start 200.962514 -35.29711)
		(end 204.013308 -35.834828)
		(width 0.1397)
		(layer "In5.Cu")
		(net "PCIE_TX_CAP_N85")
	)
	(segment
		(start 146.4818 -35.387534)
		(end 146.4818 -35.535108)
		(width 0.1397)
		(layer "In5.Cu")
		(net "PCIE_TX_CAP_N85")
	)
	(segment
		(start 149.606762 -37.28593)
		(end 151.074374 -36.973764)
		(width 0.1397)
		(layer "In5.Cu")
		(net "PCIE_TX_CAP_N85")
	)
	(segment
		(start 146.907758 -36.25088)
		(end 147.964398 -36.936934)
		(width 0.1397)
		(layer "In5.Cu")
		(net "PCIE_TX_CAP_N85")
	)
	(segment
		(start 193.889376 -35.60699)
		(end 194.301872 -35.679634)
		(width 0.1397)
		(layer "In5.Cu")
		(net "PCIE_TX_CAP_N85")
	)
	(segment
		(start 193.683382 -35.751262)
		(end 193.889376 -35.60699)
		(width 0.1397)
		(layer "In5.Cu")
		(net "PCIE_TX_CAP_N85")
	)
	(segment
		(start 161.040064 -41.510204)
		(end 162.85337 -41.895268)
		(width 0.1397)
		(layer "In5.Cu")
		(net "PCIE_TX_CAP_N85")
	)
	(segment
		(start 221.285562 -35.835082)
		(end 221.349062 -35.898582)
		(width 0.1016)
		(layer "In5.Cu")
		(net "PCIE_TX_CAP_N85")
	)
	(segment
		(start 196.03466 -36.165536)
		(end 200.962514 -35.29711)
		(width 0.1397)
		(layer "In5.Cu")
		(net "PCIE_TX_CAP_N85")
	)
	(segment
		(start 154.103578 -38.66642)
		(end 157.979872 -39.522908)
		(width 0.1397)
		(layer "In5.Cu")
		(net "PCIE_TX_CAP_N85")
	)
	(segment
		(start 175.585374 -36.131246)
		(end 180.391816 -35.283902)
		(width 0.1397)
		(layer "In5.Cu")
		(net "PCIE_TX_CAP_N85")
	)
	(segment
		(start 151.074374 -36.973764)
		(end 152.201372 -37.213032)
		(width 0.1397)
		(layer "In5.Cu")
		(net "PCIE_TX_CAP_N85")
	)
	(segment
		(start 146.7231 -34.99612)
		(end 146.587972 -35.131248)
		(width 0.1397)
		(layer "In5.Cu")
		(net "PCIE_TX_CAP_N85")
	)
	(segment
		(start 168.797478 -40.884348)
		(end 175.585374 -36.131246)
		(width 0.1397)
		(layer "In5.Cu")
		(net "PCIE_TX_CAP_N85")
	)
	(segment
		(start 183.28767 -35.794442)
		(end 185.8899 -35.335718)
		(width 0.1397)
		(layer "In5.Cu")
		(net "PCIE_TX_CAP_N85")
	)
	(segment
		(start 148.837904 -37.122608)
		(end 149.606762 -37.28593)
		(width 0.1397)
		(layer "In5.Cu")
		(net "PCIE_TX_CAP_N85")
	)
	(arc
		(start 222.323406 -35.4076)
		(mid 222.202584 -35.431633)
		(end 222.10014 -35.500056)
		(width 0.1016)
		(layer "In5.Cu")
		(net "PCIE_TX_CAP_N85")
	)
	(arc
		(start 222.562928 -35.858958)
		(mid 222.6451 -35.787482)
		(end 222.695262 -35.69081)
		(width 0.1016)
		(layer "In5.Cu")
		(net "PCIE_TX_CAP_N85")
	)
	(arc
		(start 222.695262 -35.69081)
		(mid 222.666673 -35.503949)
		(end 222.504 -35.4076)
		(width 0.1016)
		(layer "In5.Cu")
		(net "PCIE_TX_CAP_N85")
	)
	(arc
		(start 222.41637 -35.898582)
		(mid 222.492284 -35.888509)
		(end 222.562928 -35.858958)
		(width 0.1016)
		(layer "In5.Cu")
		(net "PCIE_TX_CAP_N85")
	)
	(arc
		(start 146.587972 -35.131248)
		(mid 146.509404 -35.248833)
		(end 146.4818 -35.387534)
		(width 0.1397)
		(layer "In5.Cu")
		(net "PCIE_TX_CAP_N85")
	)
	(arc
		(start 146.4818 -35.535108)
		(mid 146.535067 -35.802898)
		(end 146.686778 -36.0299)
		(width 0.1397)
		(layer "In5.Cu")
		(net "PCIE_TX_CAP_N85")
	)
	(segment
		(start 151.2189 -34.737548)
		(end 151.2189 -35.628072)
		(width 0.136652)
		(layer "F.Cu")
		(net "PCIE_TX_CAP_N84")
	)
	(segment
		(start 151.4602 -36.210748)
		(end 151.4602 -37.5158)
		(width 0.136652)
		(layer "F.Cu")
		(net "PCIE_TX_CAP_N84")
	)
	(segment
		(start 223.60001 -36.999926)
		(end 223.100138 -36.500054)
		(width 0.136652)
		(layer "F.Cu")
		(net "PCIE_TX_CAP_N84")
	)
	(via
		(at 223.100138 -36.500054)
		(size 0.4572)
		(drill 0.2032)
		(layers "F.Cu" "B.Cu")
		(net "PCIE_TX_CAP_N84")
	)
	(via
		(at 151.7269 -38.0873)
		(size 0.508)
		(drill 0.254)
		(layers "F.Cu" "B.Cu")
		(net "PCIE_TX_CAP_N84")
	)
	(arc
		(start 151.2189 -35.628072)
		(mid 151.250261 -35.785733)
		(end 151.33955 -35.91941)
		(width 0.136652)
		(layer "F.Cu")
		(net "PCIE_TX_CAP_N84")
	)
	(arc
		(start 151.511 -33.9725)
		(mid 151.294389 -34.328086)
		(end 151.2189 -34.737548)
		(width 0.136652)
		(layer "F.Cu")
		(net "PCIE_TX_CAP_N84")
	)
	(arc
		(start 151.33955 -35.91941)
		(mid 151.428863 -36.053077)
		(end 151.4602 -36.210748)
		(width 0.136652)
		(layer "F.Cu")
		(net "PCIE_TX_CAP_N84")
	)
	(arc
		(start 151.4602 -37.5158)
		(mid 151.530152 -37.831139)
		(end 151.7269 -38.0873)
		(width 0.136652)
		(layer "F.Cu")
		(net "PCIE_TX_CAP_N84")
	)
	(segment
		(start 189.98946 -37.056314)
		(end 191.685164 -36.695888)
		(width 0.1397)
		(layer "In5.Cu")
		(net "PCIE_TX_CAP_N84")
	)
	(segment
		(start 223.388174 -36.193222)
		(end 223.38792 -36.193222)
		(width 0.1016)
		(layer "In5.Cu")
		(net "PCIE_TX_CAP_N84")
	)
	(segment
		(start 211.297774 -35.460686)
		(end 219.093796 -36.83508)
		(width 0.1397)
		(layer "In5.Cu")
		(net "PCIE_TX_CAP_N84")
	)
	(segment
		(start 156.118814 -40.72509)
		(end 157.318202 -41.57599)
		(width 0.1397)
		(layer "In5.Cu")
		(net "PCIE_TX_CAP_N84")
	)
	(segment
		(start 185.802778 -36.166298)
		(end 189.98946 -37.056314)
		(width 0.1397)
		(layer "In5.Cu")
		(net "PCIE_TX_CAP_N84")
	)
	(segment
		(start 151.4856 -39.193216)
		(end 151.591264 -39.456106)
		(width 0.1397)
		(layer "In5.Cu")
		(net "PCIE_TX_CAP_N84")
	)
	(segment
		(start 204.120496 -36.726114)
		(end 211.297774 -35.460686)
		(width 0.1397)
		(layer "In5.Cu")
		(net "PCIE_TX_CAP_N84")
	)
	(segment
		(start 151.591264 -39.456106)
		(end 152.216104 -39.894002)
		(width 0.1397)
		(layer "In5.Cu")
		(net "PCIE_TX_CAP_N84")
	)
	(segment
		(start 152.216104 -39.894002)
		(end 156.118814 -40.72509)
		(width 0.1397)
		(layer "In5.Cu")
		(net "PCIE_TX_CAP_N84")
	)
	(segment
		(start 168.963848 -41.764712)
		(end 173.585124 -38.763448)
		(width 0.1397)
		(layer "In5.Cu")
		(net "PCIE_TX_CAP_N84")
	)
	(segment
		(start 163.579302 -42.908982)
		(end 168.963848 -41.764712)
		(width 0.1397)
		(layer "In5.Cu")
		(net "PCIE_TX_CAP_N84")
	)
	(segment
		(start 221.5134 -36.83508)
		(end 221.5769 -36.89858)
		(width 0.1016)
		(layer "In5.Cu")
		(net "PCIE_TX_CAP_N84")
	)
	(segment
		(start 192.691258 -36.518342)
		(end 196.138292 -37.125656)
		(width 0.1397)
		(layer "In5.Cu")
		(net "PCIE_TX_CAP_N84")
	)
	(segment
		(start 157.318202 -41.57599)
		(end 163.579302 -42.908982)
		(width 0.1397)
		(layer "In5.Cu")
		(net "PCIE_TX_CAP_N84")
	)
	(segment
		(start 196.138292 -37.125656)
		(end 201.26198 -36.222432)
		(width 0.1397)
		(layer "In5.Cu")
		(net "PCIE_TX_CAP_N84")
	)
	(segment
		(start 201.26198 -36.222432)
		(end 204.120496 -36.726114)
		(width 0.1397)
		(layer "In5.Cu")
		(net "PCIE_TX_CAP_N84")
	)
	(segment
		(start 221.5769 -36.89858)
		(end 223.442276 -36.89858)
		(width 0.1016)
		(layer "In5.Cu")
		(net "PCIE_TX_CAP_N84")
	)
	(segment
		(start 173.585124 -38.763448)
		(end 185.802778 -36.166298)
		(width 0.1397)
		(layer "In5.Cu")
		(net "PCIE_TX_CAP_N84")
	)
	(segment
		(start 219.093796 -36.83508)
		(end 221.5134 -36.83508)
		(width 0.1397)
		(layer "In5.Cu")
		(net "PCIE_TX_CAP_N84")
	)
	(segment
		(start 223.100138 -36.481004)
		(end 223.100138 -36.500054)
		(width 0.1016)
		(layer "In5.Cu")
		(net "PCIE_TX_CAP_N84")
	)
	(segment
		(start 191.685164 -36.695888)
		(end 192.691258 -36.518342)
		(width 0.1397)
		(layer "In5.Cu")
		(net "PCIE_TX_CAP_N84")
	)
	(segment
		(start 151.4856 -38.500304)
		(end 151.4856 -39.193216)
		(width 0.1397)
		(layer "In5.Cu")
		(net "PCIE_TX_CAP_N84")
	)
	(segment
		(start 223.675956 -36.6649)
		(end 223.675956 -36.481004)
		(width 0.1016)
		(layer "In5.Cu")
		(net "PCIE_TX_CAP_N84")
	)
	(arc
		(start 151.7269 -38.0873)
		(mid 151.55039 -38.261156)
		(end 151.4856 -38.500304)
		(width 0.1397)
		(layer "In5.Cu")
		(net "PCIE_TX_CAP_N84")
	)
	(arc
		(start 223.38792 -36.193222)
		(mid 223.184427 -36.277511)
		(end 223.100138 -36.481004)
		(width 0.1016)
		(layer "In5.Cu")
		(net "PCIE_TX_CAP_N84")
	)
	(arc
		(start 223.675956 -36.481004)
		(mid 223.591667 -36.277511)
		(end 223.388174 -36.193222)
		(width 0.1016)
		(layer "In5.Cu")
		(net "PCIE_TX_CAP_N84")
	)
	(arc
		(start 223.442276 -36.89858)
		(mid 223.607513 -36.830137)
		(end 223.675956 -36.6649)
		(width 0.1016)
		(layer "In5.Cu")
		(net "PCIE_TX_CAP_N84")
	)
	(segment
		(start 138.1252 -34.430462)
		(end 138.1252 -34.682176)
		(width 0.136652)
		(layer "F.Cu")
		(net "PCIE_TX_CAP_N83")
	)
	(segment
		(start 138.4173 -33.98774)
		(end 138.231626 -34.17316)
		(width 0.136652)
		(layer "F.Cu")
		(net "PCIE_TX_CAP_N83")
	)
	(segment
		(start 222.600012 -37.999924)
		(end 222.10014 -37.500052)
		(width 0.136652)
		(layer "F.Cu")
		(net "PCIE_TX_CAP_N83")
	)
	(via
		(at 222.10014 -37.500052)
		(size 0.4572)
		(drill 0.2032)
		(layers "F.Cu" "B.Cu")
		(net "PCIE_TX_CAP_N83")
	)
	(via
		(at 138.3792 -34.993326)
		(size 0.508)
		(drill 0.254)
		(layers "F.Cu" "B.Cu")
		(net "PCIE_TX_CAP_N83")
	)
	(arc
		(start 138.231626 -34.17316)
		(mid 138.15283 -34.291226)
		(end 138.1252 -34.430462)
		(width 0.136652)
		(layer "F.Cu")
		(net "PCIE_TX_CAP_N83")
	)
	(arc
		(start 138.1252 -34.682176)
		(mid 138.19677 -34.882986)
		(end 138.3792 -34.993326)
		(width 0.136652)
		(layer "F.Cu")
		(net "PCIE_TX_CAP_N83")
	)
	(segment
		(start 140.119608 -36.202112)
		(end 143.275812 -36.873434)
		(width 0.1397)
		(layer "In5.Cu")
		(net "PCIE_TX_CAP_N83")
	)
	(segment
		(start 147.46859 -39.88308)
		(end 155.718002 -41.639998)
		(width 0.1397)
		(layer "In5.Cu")
		(net "PCIE_TX_CAP_N83")
	)
	(segment
		(start 143.275812 -36.873434)
		(end 145.417032 -38.410134)
		(width 0.1397)
		(layer "In5.Cu")
		(net "PCIE_TX_CAP_N83")
	)
	(segment
		(start 155.718002 -41.639998)
		(end 156.917136 -42.490644)
		(width 0.1397)
		(layer "In5.Cu")
		(net "PCIE_TX_CAP_N83")
	)
	(segment
		(start 182.97525 -39.248588)
		(end 183.193182 -39.400988)
		(width 0.1397)
		(layer "In5.Cu")
		(net "PCIE_TX_CAP_N83")
	)
	(segment
		(start 178.823366 -40.17264)
		(end 178.975766 -39.954708)
		(width 0.1397)
		(layer "In5.Cu")
		(net "PCIE_TX_CAP_N83")
	)
	(segment
		(start 180.171344 -39.743634)
		(end 180.584094 -39.670736)
		(width 0.1397)
		(layer "In5.Cu")
		(net "PCIE_TX_CAP_N83")
	)
	(segment
		(start 163.707064 -43.936412)
		(end 169.812462 -42.642028)
		(width 0.1397)
		(layer "In5.Cu")
		(net "PCIE_TX_CAP_N83")
	)
	(segment
		(start 180.584094 -39.670736)
		(end 180.801772 -39.823136)
		(width 0.1397)
		(layer "In5.Cu")
		(net "PCIE_TX_CAP_N83")
	)
	(segment
		(start 193.263266 -37.623242)
		(end 196.557392 -38.203886)
		(width 0.1397)
		(layer "In5.Cu")
		(net "PCIE_TX_CAP_N83")
	)
	(segment
		(start 145.66519 -38.369494)
		(end 146.00555 -38.613842)
		(width 0.1397)
		(layer "In5.Cu")
		(net "PCIE_TX_CAP_N83")
	)
	(segment
		(start 182.562754 -39.321486)
		(end 182.97525 -39.248588)
		(width 0.1397)
		(layer "In5.Cu")
		(net "PCIE_TX_CAP_N83")
	)
	(segment
		(start 180.801772 -39.823136)
		(end 181.214522 -39.750492)
		(width 0.1397)
		(layer "In5.Cu")
		(net "PCIE_TX_CAP_N83")
	)
	(segment
		(start 139.906502 -36.124642)
		(end 139.906502 -36.124896)
		(width 0.1397)
		(layer "In5.Cu")
		(net "PCIE_TX_CAP_N83")
	)
	(segment
		(start 221.5261 -37.9222)
		(end 222.188024 -37.9222)
		(width 0.1016)
		(layer "In5.Cu")
		(net "PCIE_TX_CAP_N83")
	)
	(segment
		(start 146.634962 -39.065708)
		(end 146.975322 -39.310056)
		(width 0.1397)
		(layer "In5.Cu")
		(net "PCIE_TX_CAP_N83")
	)
	(segment
		(start 146.975322 -39.310056)
		(end 147.015962 -39.558214)
		(width 0.1397)
		(layer "In5.Cu")
		(net "PCIE_TX_CAP_N83")
	)
	(segment
		(start 179.388516 -39.882064)
		(end 179.606194 -40.034464)
		(width 0.1397)
		(layer "In5.Cu")
		(net "PCIE_TX_CAP_N83")
	)
	(segment
		(start 181.214522 -39.750492)
		(end 181.366922 -39.53256)
		(width 0.1397)
		(layer "In5.Cu")
		(net "PCIE_TX_CAP_N83")
	)
	(segment
		(start 211.553552 -36.509452)
		(end 219.21597 -37.8587)
		(width 0.1397)
		(layer "In5.Cu")
		(net "PCIE_TX_CAP_N83")
	)
	(segment
		(start 171.670472 -41.435528)
		(end 178.823366 -40.17264)
		(width 0.1397)
		(layer "In5.Cu")
		(net "PCIE_TX_CAP_N83")
	)
	(segment
		(start 196.557392 -38.203886)
		(end 201.332338 -37.362638)
		(width 0.1397)
		(layer "In5.Cu")
		(net "PCIE_TX_CAP_N83")
	)
	(segment
		(start 222.386652 -37.500052)
		(end 222.10014 -37.500052)
		(width 0.1016)
		(layer "In5.Cu")
		(net "PCIE_TX_CAP_N83")
	)
	(segment
		(start 147.015962 -39.558214)
		(end 147.46859 -39.88308)
		(width 0.1397)
		(layer "In5.Cu")
		(net "PCIE_TX_CAP_N83")
	)
	(segment
		(start 139.906502 -36.124896)
		(end 139.907264 -36.125404)
		(width 0.1397)
		(layer "In5.Cu")
		(net "PCIE_TX_CAP_N83")
	)
	(segment
		(start 146.386804 -39.106348)
		(end 146.634962 -39.065708)
		(width 0.1397)
		(layer "In5.Cu")
		(net "PCIE_TX_CAP_N83")
	)
	(segment
		(start 182.410354 -39.539418)
		(end 182.562754 -39.321486)
		(width 0.1397)
		(layer "In5.Cu")
		(net "PCIE_TX_CAP_N83")
	)
	(segment
		(start 178.975766 -39.954708)
		(end 179.388516 -39.882064)
		(width 0.1397)
		(layer "In5.Cu")
		(net "PCIE_TX_CAP_N83")
	)
	(segment
		(start 221.4372 -37.8587)
		(end 221.4626 -37.8587)
		(width 0.1016)
		(layer "In5.Cu")
		(net "PCIE_TX_CAP_N83")
	)
	(segment
		(start 204.001878 -37.832792)
		(end 211.553552 -36.509452)
		(width 0.1397)
		(layer "In5.Cu")
		(net "PCIE_TX_CAP_N83")
	)
	(segment
		(start 221.4626 -37.8587)
		(end 221.5261 -37.9222)
		(width 0.1016)
		(layer "In5.Cu")
		(net "PCIE_TX_CAP_N83")
	)
	(segment
		(start 181.366922 -39.53256)
		(end 181.779672 -39.459662)
		(width 0.1397)
		(layer "In5.Cu")
		(net "PCIE_TX_CAP_N83")
	)
	(segment
		(start 145.417032 -38.410134)
		(end 145.66519 -38.369494)
		(width 0.1397)
		(layer "In5.Cu")
		(net "PCIE_TX_CAP_N83")
	)
	(segment
		(start 156.917136 -42.490644)
		(end 163.707064 -43.936412)
		(width 0.1397)
		(layer "In5.Cu")
		(net "PCIE_TX_CAP_N83")
	)
	(segment
		(start 139.455398 -35.836098)
		(end 139.842494 -36.087558)
		(width 0.1397)
		(layer "In5.Cu")
		(net "PCIE_TX_CAP_N83")
	)
	(segment
		(start 219.21597 -37.8587)
		(end 221.4372 -37.8587)
		(width 0.1397)
		(layer "In5.Cu")
		(net "PCIE_TX_CAP_N83")
	)
	(segment
		(start 183.193182 -39.400988)
		(end 193.263266 -37.623242)
		(width 0.1397)
		(layer "In5.Cu")
		(net "PCIE_TX_CAP_N83")
	)
	(segment
		(start 181.997604 -39.612062)
		(end 182.410354 -39.539418)
		(width 0.1397)
		(layer "In5.Cu")
		(net "PCIE_TX_CAP_N83")
	)
	(segment
		(start 146.00555 -38.613842)
		(end 146.04619 -38.862)
		(width 0.1397)
		(layer "In5.Cu")
		(net "PCIE_TX_CAP_N83")
	)
	(segment
		(start 138.1379 -35.200336)
		(end 138.1379 -35.49777)
		(width 0.1397)
		(layer "In5.Cu")
		(net "PCIE_TX_CAP_N83")
	)
	(segment
		(start 139.842494 -36.087558)
		(end 139.842748 -36.087558)
		(width 0.1397)
		(layer "In5.Cu")
		(net "PCIE_TX_CAP_N83")
	)
	(segment
		(start 169.812462 -42.642028)
		(end 171.670472 -41.435528)
		(width 0.1397)
		(layer "In5.Cu")
		(net "PCIE_TX_CAP_N83")
	)
	(segment
		(start 201.332338 -37.362638)
		(end 204.001878 -37.832792)
		(width 0.1397)
		(layer "In5.Cu")
		(net "PCIE_TX_CAP_N83")
	)
	(segment
		(start 138.30427 -35.66414)
		(end 138.873992 -35.66414)
		(width 0.1397)
		(layer "In5.Cu")
		(net "PCIE_TX_CAP_N83")
	)
	(segment
		(start 179.606194 -40.034464)
		(end 180.018944 -39.961566)
		(width 0.1397)
		(layer "In5.Cu")
		(net "PCIE_TX_CAP_N83")
	)
	(segment
		(start 146.04619 -38.862)
		(end 146.386804 -39.106348)
		(width 0.1397)
		(layer "In5.Cu")
		(net "PCIE_TX_CAP_N83")
	)
	(segment
		(start 181.779672 -39.459662)
		(end 181.997604 -39.612062)
		(width 0.1397)
		(layer "In5.Cu")
		(net "PCIE_TX_CAP_N83")
	)
	(segment
		(start 138.3792 -34.993326)
		(end 138.34491 -34.993326)
		(width 0.1397)
		(layer "In5.Cu")
		(net "PCIE_TX_CAP_N83")
	)
	(segment
		(start 180.018944 -39.961566)
		(end 180.171344 -39.743634)
		(width 0.1397)
		(layer "In5.Cu")
		(net "PCIE_TX_CAP_N83")
	)
	(arc
		(start 138.1379 -35.49777)
		(mid 138.186629 -35.615411)
		(end 138.30427 -35.66414)
		(width 0.1397)
		(layer "In5.Cu")
		(net "PCIE_TX_CAP_N83")
	)
	(arc
		(start 138.34491 -34.993326)
		(mid 138.198532 -35.053958)
		(end 138.1379 -35.200336)
		(width 0.1397)
		(layer "In5.Cu")
		(net "PCIE_TX_CAP_N83")
	)
	(arc
		(start 138.873992 -35.66414)
		(mid 139.177149 -35.708002)
		(end 139.455398 -35.836098)
		(width 0.1397)
		(layer "In5.Cu")
		(net "PCIE_TX_CAP_N83")
	)
	(arc
		(start 222.188024 -37.9222)
		(mid 222.407501 -37.831289)
		(end 222.498412 -37.611812)
		(width 0.1016)
		(layer "In5.Cu")
		(net "PCIE_TX_CAP_N83")
	)
	(arc
		(start 139.842748 -36.087558)
		(mid 139.874208 -36.106816)
		(end 139.906502 -36.124642)
		(width 0.1397)
		(layer "In5.Cu")
		(net "PCIE_TX_CAP_N83")
	)
	(arc
		(start 222.498412 -37.611812)
		(mid 222.465678 -37.532786)
		(end 222.386652 -37.500052)
		(width 0.1016)
		(layer "In5.Cu")
		(net "PCIE_TX_CAP_N83")
	)
	(arc
		(start 139.907264 -36.125404)
		(mid 140.010791 -36.171082)
		(end 140.119608 -36.202112)
		(width 0.1397)
		(layer "In5.Cu")
		(net "PCIE_TX_CAP_N83")
	)
	(segment
		(start 133.872478 -34.548826)
		(end 134.219442 -34.89579)
		(width 0.136652)
		(layer "F.Cu")
		(net "PCIE_TX_CAP_N82")
	)
	(segment
		(start 223.60001 -38.999922)
		(end 223.100138 -38.50005)
		(width 0.136652)
		(layer "F.Cu")
		(net "PCIE_TX_CAP_N82")
	)
	(segment
		(start 134.41045 -35.331654)
		(end 134.414514 -35.433)
		(width 0.136652)
		(layer "F.Cu")
		(net "PCIE_TX_CAP_N82")
	)
	(via
		(at 134.664958 -35.739832)
		(size 0.508)
		(drill 0.254)
		(layers "F.Cu" "B.Cu")
		(net "PCIE_TX_CAP_N82")
	)
	(via
		(at 223.100138 -38.50005)
		(size 0.4572)
		(drill 0.2032)
		(layers "F.Cu" "B.Cu")
		(net "PCIE_TX_CAP_N82")
	)
	(arc
		(start 134.414514 -35.433)
		(mid 134.488507 -35.628243)
		(end 134.664958 -35.739832)
		(width 0.136652)
		(layer "F.Cu")
		(net "PCIE_TX_CAP_N82")
	)
	(arc
		(start 134.0993 -33.98774)
		(mid 133.887858 -34.14238)
		(end 133.8072 -34.3916)
		(width 0.136652)
		(layer "F.Cu")
		(net "PCIE_TX_CAP_N82")
	)
	(arc
		(start 134.219442 -34.89579)
		(mid 134.355956 -35.095746)
		(end 134.41045 -35.331654)
		(width 0.136652)
		(layer "F.Cu")
		(net "PCIE_TX_CAP_N82")
	)
	(arc
		(start 133.8072 -34.3916)
		(mid 133.82422 -34.476695)
		(end 133.872478 -34.548826)
		(width 0.136652)
		(layer "F.Cu")
		(net "PCIE_TX_CAP_N82")
	)
	(segment
		(start 152.59812 -42.325544)
		(end 152.188164 -42.238168)
		(width 0.1397)
		(layer "In5.Cu")
		(net "PCIE_TX_CAP_N82")
	)
	(segment
		(start 136.850882 -36.2839)
		(end 136.431782 -36.2839)
		(width 0.1397)
		(layer "In5.Cu")
		(net "PCIE_TX_CAP_N82")
	)
	(segment
		(start 221.5896 -38.835076)
		(end 219.2274 -38.835076)
		(width 0.1397)
		(layer "In5.Cu")
		(net "PCIE_TX_CAP_N82")
	)
	(segment
		(start 150.39975 -42.03954)
		(end 150.262844 -41.82872)
		(width 0.1397)
		(layer "In5.Cu")
		(net "PCIE_TX_CAP_N82")
	)
	(segment
		(start 149.232112 -41.791128)
		(end 149.095206 -41.580308)
		(width 0.1397)
		(layer "In5.Cu")
		(net "PCIE_TX_CAP_N82")
	)
	(segment
		(start 151.977344 -42.375074)
		(end 151.567388 -42.287952)
		(width 0.1397)
		(layer "In5.Cu")
		(net "PCIE_TX_CAP_N82")
	)
	(segment
		(start 211.721192 -37.511482)
		(end 204.1144 -38.85311)
		(width 0.1397)
		(layer "In5.Cu")
		(net "PCIE_TX_CAP_N82")
	)
	(segment
		(start 192.785746 -38.494716)
		(end 172.494194 -42.077386)
		(width 0.1397)
		(layer "In5.Cu")
		(net "PCIE_TX_CAP_N82")
	)
	(segment
		(start 149.642068 -41.87825)
		(end 149.232112 -41.791128)
		(width 0.1397)
		(layer "In5.Cu")
		(net "PCIE_TX_CAP_N82")
	)
	(segment
		(start 149.852888 -41.741344)
		(end 149.642068 -41.87825)
		(width 0.1397)
		(layer "In5.Cu")
		(net "PCIE_TX_CAP_N82")
	)
	(segment
		(start 148.68525 -41.492932)
		(end 148.47443 -41.629838)
		(width 0.1397)
		(layer "In5.Cu")
		(net "PCIE_TX_CAP_N82")
	)
	(segment
		(start 196.647054 -39.175436)
		(end 192.785746 -38.494716)
		(width 0.1397)
		(layer "In5.Cu")
		(net "PCIE_TX_CAP_N82")
	)
	(segment
		(start 221.615 -38.835076)
		(end 221.5896 -38.835076)
		(width 0.1016)
		(layer "In5.Cu")
		(net "PCIE_TX_CAP_N82")
	)
	(segment
		(start 223.303084 -38.898576)
		(end 221.723458 -38.898576)
		(width 0.1016)
		(layer "In5.Cu")
		(net "PCIE_TX_CAP_N82")
	)
	(segment
		(start 151.567388 -42.287952)
		(end 151.430482 -42.077132)
		(width 0.1397)
		(layer "In5.Cu")
		(net "PCIE_TX_CAP_N82")
	)
	(segment
		(start 150.262844 -41.82872)
		(end 149.852888 -41.741344)
		(width 0.1397)
		(layer "In5.Cu")
		(net "PCIE_TX_CAP_N82")
	)
	(segment
		(start 136.431782 -36.2839)
		(end 136.253982 -36.4617)
		(width 0.1397)
		(layer "In5.Cu")
		(net "PCIE_TX_CAP_N82")
	)
	(segment
		(start 150.809706 -42.126662)
		(end 150.39975 -42.03954)
		(width 0.1397)
		(layer "In5.Cu")
		(net "PCIE_TX_CAP_N82")
	)
	(segment
		(start 135.060182 -36.4617)
		(end 134.641082 -36.4617)
		(width 0.1397)
		(layer "In5.Cu")
		(net "PCIE_TX_CAP_N82")
	)
	(segment
		(start 148.47443 -41.629838)
		(end 148.064474 -41.542716)
		(width 0.1397)
		(layer "In5.Cu")
		(net "PCIE_TX_CAP_N82")
	)
	(segment
		(start 135.657082 -36.2839)
		(end 135.237982 -36.2839)
		(width 0.1397)
		(layer "In5.Cu")
		(net "PCIE_TX_CAP_N82")
	)
	(segment
		(start 204.1144 -38.85311)
		(end 201.295254 -38.356032)
		(width 0.1397)
		(layer "In5.Cu")
		(net "PCIE_TX_CAP_N82")
	)
	(segment
		(start 219.2274 -38.835076)
		(end 211.721192 -37.511482)
		(width 0.1397)
		(layer "In5.Cu")
		(net "PCIE_TX_CAP_N82")
	)
	(segment
		(start 170.2689 -43.522392)
		(end 163.816538 -44.893738)
		(width 0.1397)
		(layer "In5.Cu")
		(net "PCIE_TX_CAP_N82")
	)
	(segment
		(start 135.834882 -36.4617)
		(end 135.657082 -36.2839)
		(width 0.1397)
		(layer "In5.Cu")
		(net "PCIE_TX_CAP_N82")
	)
	(segment
		(start 136.253982 -36.4617)
		(end 135.834882 -36.4617)
		(width 0.1397)
		(layer "In5.Cu")
		(net "PCIE_TX_CAP_N82")
	)
	(segment
		(start 201.295254 -38.356032)
		(end 196.647054 -39.175436)
		(width 0.1397)
		(layer "In5.Cu")
		(net "PCIE_TX_CAP_N82")
	)
	(segment
		(start 134.423658 -36.244276)
		(end 134.423658 -35.946842)
		(width 0.1397)
		(layer "In5.Cu")
		(net "PCIE_TX_CAP_N82")
	)
	(segment
		(start 152.188164 -42.238168)
		(end 151.977344 -42.375074)
		(width 0.1397)
		(layer "In5.Cu")
		(net "PCIE_TX_CAP_N82")
	)
	(segment
		(start 172.494194 -42.077386)
		(end 170.2689 -43.522392)
		(width 0.1397)
		(layer "In5.Cu")
		(net "PCIE_TX_CAP_N82")
	)
	(segment
		(start 223.49841 -38.61181)
		(end 223.49841 -38.70325)
		(width 0.1016)
		(layer "In5.Cu")
		(net "PCIE_TX_CAP_N82")
	)
	(segment
		(start 152.735026 -42.536364)
		(end 152.59812 -42.325544)
		(width 0.1397)
		(layer "In5.Cu")
		(net "PCIE_TX_CAP_N82")
	)
	(segment
		(start 137.028682 -36.4617)
		(end 136.850882 -36.2839)
		(width 0.1397)
		(layer "In5.Cu")
		(net "PCIE_TX_CAP_N82")
	)
	(segment
		(start 134.630668 -35.739832)
		(end 134.664958 -35.739832)
		(width 0.1397)
		(layer "In5.Cu")
		(net "PCIE_TX_CAP_N82")
	)
	(segment
		(start 223.100138 -38.50005)
		(end 223.38665 -38.50005)
		(width 0.1016)
		(layer "In5.Cu")
		(net "PCIE_TX_CAP_N82")
	)
	(segment
		(start 135.237982 -36.2839)
		(end 135.060182 -36.4617)
		(width 0.1397)
		(layer "In5.Cu")
		(net "PCIE_TX_CAP_N82")
	)
	(segment
		(start 148.064474 -41.542716)
		(end 141.579854 -37.331396)
		(width 0.1397)
		(layer "In5.Cu")
		(net "PCIE_TX_CAP_N82")
	)
	(segment
		(start 151.430482 -42.077132)
		(end 151.020526 -41.989756)
		(width 0.1397)
		(layer "In5.Cu")
		(net "PCIE_TX_CAP_N82")
	)
	(segment
		(start 221.64675 -38.866826)
		(end 221.615 -38.835076)
		(width 0.1016)
		(layer "In5.Cu")
		(net "PCIE_TX_CAP_N82")
	)
	(segment
		(start 163.816538 -44.893738)
		(end 152.735026 -42.536364)
		(width 0.1397)
		(layer "In5.Cu")
		(net "PCIE_TX_CAP_N82")
	)
	(segment
		(start 151.020526 -41.989756)
		(end 150.809706 -42.126662)
		(width 0.1397)
		(layer "In5.Cu")
		(net "PCIE_TX_CAP_N82")
	)
	(segment
		(start 138.409426 -36.4617)
		(end 137.028682 -36.4617)
		(width 0.1397)
		(layer "In5.Cu")
		(net "PCIE_TX_CAP_N82")
	)
	(segment
		(start 149.095206 -41.580308)
		(end 148.68525 -41.492932)
		(width 0.1397)
		(layer "In5.Cu")
		(net "PCIE_TX_CAP_N82")
	)
	(segment
		(start 141.579854 -37.331396)
		(end 139.167108 -36.819078)
		(width 0.1397)
		(layer "In5.Cu")
		(net "PCIE_TX_CAP_N82")
	)
	(arc
		(start 221.723458 -38.898576)
		(mid 221.681953 -38.89032)
		(end 221.64675 -38.866826)
		(width 0.1016)
		(layer "In5.Cu")
		(net "PCIE_TX_CAP_N82")
	)
	(arc
		(start 134.641082 -36.4617)
		(mid 134.48734 -36.398018)
		(end 134.423658 -36.244276)
		(width 0.1397)
		(layer "In5.Cu")
		(net "PCIE_TX_CAP_N82")
	)
	(arc
		(start 223.49841 -38.70325)
		(mid 223.4412 -38.841366)
		(end 223.303084 -38.898576)
		(width 0.1016)
		(layer "In5.Cu")
		(net "PCIE_TX_CAP_N82")
	)
	(arc
		(start 139.167108 -36.819078)
		(mid 138.985288 -36.751967)
		(end 138.83005 -36.635944)
		(width 0.1397)
		(layer "In5.Cu")
		(net "PCIE_TX_CAP_N82")
	)
	(arc
		(start 138.83005 -36.635944)
		(mid 138.637066 -36.506996)
		(end 138.409426 -36.4617)
		(width 0.1397)
		(layer "In5.Cu")
		(net "PCIE_TX_CAP_N82")
	)
	(arc
		(start 223.38665 -38.50005)
		(mid 223.465676 -38.532784)
		(end 223.49841 -38.61181)
		(width 0.1016)
		(layer "In5.Cu")
		(net "PCIE_TX_CAP_N82")
	)
	(arc
		(start 134.423658 -35.946842)
		(mid 134.48429 -35.800464)
		(end 134.630668 -35.739832)
		(width 0.1397)
		(layer "In5.Cu")
		(net "PCIE_TX_CAP_N82")
	)
	(segment
		(start 222.600012 -39.99992)
		(end 222.10014 -39.500048)
		(width 0.136652)
		(layer "F.Cu")
		(net "PCIE_TX_CAP_N81")
	)
	(segment
		(start 131.76123 -34.166556)
		(end 131.9403 -33.98774)
		(width 0.136652)
		(layer "F.Cu")
		(net "PCIE_TX_CAP_N81")
	)
	(segment
		(start 131.6482 -35.019234)
		(end 131.6482 -34.43986)
		(width 0.136652)
		(layer "F.Cu")
		(net "PCIE_TX_CAP_N81")
	)
	(via
		(at 222.10014 -39.500048)
		(size 0.4572)
		(drill 0.2032)
		(layers "F.Cu" "B.Cu")
		(net "PCIE_TX_CAP_N81")
	)
	(via
		(at 131.9022 -35.273234)
		(size 0.508)
		(drill 0.254)
		(layers "F.Cu" "B.Cu")
		(net "PCIE_TX_CAP_N81")
	)
	(arc
		(start 131.6482 -34.43986)
		(mid 131.677525 -34.291963)
		(end 131.76123 -34.166556)
		(width 0.136652)
		(layer "F.Cu")
		(net "PCIE_TX_CAP_N81")
	)
	(arc
		(start 131.9022 -35.273234)
		(mid 131.722595 -35.198839)
		(end 131.6482 -35.019234)
		(width 0.136652)
		(layer "F.Cu")
		(net "PCIE_TX_CAP_N81")
	)
	(segment
		(start 192.218818 -39.394892)
		(end 173.358302 -42.724832)
		(width 0.1397)
		(layer "In5.Cu")
		(net "PCIE_TX_CAP_N81")
	)
	(segment
		(start 142.110206 -38.852856)
		(end 141.75867 -38.62451)
		(width 0.1397)
		(layer "In5.Cu")
		(net "PCIE_TX_CAP_N81")
	)
	(segment
		(start 222.35795 -39.898574)
		(end 221.41942 -39.898574)
		(width 0.1016)
		(layer "In5.Cu")
		(net "PCIE_TX_CAP_N81")
	)
	(segment
		(start 143.163798 -39.748968)
		(end 143.111474 -39.502842)
		(width 0.1397)
		(layer "In5.Cu")
		(net "PCIE_TX_CAP_N81")
	)
	(segment
		(start 196.349366 -40.12311)
		(end 192.218818 -39.394892)
		(width 0.1397)
		(layer "In5.Cu")
		(net "PCIE_TX_CAP_N81")
	)
	(segment
		(start 219.5068 -39.835074)
		(end 211.8868 -38.491668)
		(width 0.1397)
		(layer "In5.Cu")
		(net "PCIE_TX_CAP_N81")
	)
	(segment
		(start 137.643616 -37.3126)
		(end 133.258306 -37.3126)
		(width 0.1397)
		(layer "In5.Cu")
		(net "PCIE_TX_CAP_N81")
	)
	(segment
		(start 142.514066 -39.327074)
		(end 142.16253 -39.098728)
		(width 0.1397)
		(layer "In5.Cu")
		(net "PCIE_TX_CAP_N81")
	)
	(segment
		(start 221.342712 -39.866824)
		(end 221.310962 -39.835074)
		(width 0.1016)
		(layer "In5.Cu")
		(net "PCIE_TX_CAP_N81")
	)
	(segment
		(start 201.048874 -39.294562)
		(end 196.349366 -40.12311)
		(width 0.1397)
		(layer "In5.Cu")
		(net "PCIE_TX_CAP_N81")
	)
	(segment
		(start 147.194524 -42.366184)
		(end 143.163798 -39.748968)
		(width 0.1397)
		(layer "In5.Cu")
		(net "PCIE_TX_CAP_N81")
	)
	(segment
		(start 211.8868 -38.491668)
		(end 204.1906 -39.848536)
		(width 0.1397)
		(layer "In5.Cu")
		(net "PCIE_TX_CAP_N81")
	)
	(segment
		(start 142.16253 -39.098728)
		(end 142.110206 -38.852856)
		(width 0.1397)
		(layer "In5.Cu")
		(net "PCIE_TX_CAP_N81")
	)
	(segment
		(start 132.664708 -37.066474)
		(end 131.758182 -36.160202)
		(width 0.1397)
		(layer "In5.Cu")
		(net "PCIE_TX_CAP_N81")
	)
	(segment
		(start 163.45408 -45.822108)
		(end 147.194524 -42.366184)
		(width 0.1397)
		(layer "In5.Cu")
		(net "PCIE_TX_CAP_N81")
	)
	(segment
		(start 221.310962 -39.835074)
		(end 221.285562 -39.835074)
		(width 0.1016)
		(layer "In5.Cu")
		(net "PCIE_TX_CAP_N81")
	)
	(segment
		(start 142.759938 -39.27475)
		(end 142.514066 -39.327074)
		(width 0.1397)
		(layer "In5.Cu")
		(net "PCIE_TX_CAP_N81")
	)
	(segment
		(start 141.512798 -38.676834)
		(end 140.2715 -37.870892)
		(width 0.1397)
		(layer "In5.Cu")
		(net "PCIE_TX_CAP_N81")
	)
	(segment
		(start 143.111474 -39.502842)
		(end 142.759938 -39.27475)
		(width 0.1397)
		(layer "In5.Cu")
		(net "PCIE_TX_CAP_N81")
	)
	(segment
		(start 141.75867 -38.62451)
		(end 141.512798 -38.676834)
		(width 0.1397)
		(layer "In5.Cu")
		(net "PCIE_TX_CAP_N81")
	)
	(segment
		(start 173.358302 -42.724832)
		(end 171.086526 -44.200318)
		(width 0.1397)
		(layer "In5.Cu")
		(net "PCIE_TX_CAP_N81")
	)
	(segment
		(start 140.2715 -37.870892)
		(end 137.643616 -37.3126)
		(width 0.1397)
		(layer "In5.Cu")
		(net "PCIE_TX_CAP_N81")
	)
	(segment
		(start 131.86791 -35.273234)
		(end 131.9022 -35.273234)
		(width 0.1397)
		(layer "In5.Cu")
		(net "PCIE_TX_CAP_N81")
	)
	(segment
		(start 204.1906 -39.848536)
		(end 201.048874 -39.294562)
		(width 0.1397)
		(layer "In5.Cu")
		(net "PCIE_TX_CAP_N81")
	)
	(segment
		(start 171.086526 -44.200318)
		(end 163.45408 -45.822108)
		(width 0.1397)
		(layer "In5.Cu")
		(net "PCIE_TX_CAP_N81")
	)
	(segment
		(start 221.285562 -39.835074)
		(end 219.5068 -39.835074)
		(width 0.1397)
		(layer "In5.Cu")
		(net "PCIE_TX_CAP_N81")
	)
	(segment
		(start 131.6609 -35.925252)
		(end 131.6609 -35.480244)
		(width 0.1397)
		(layer "In5.Cu")
		(net "PCIE_TX_CAP_N81")
	)
	(arc
		(start 222.663258 -39.579804)
		(mid 222.670458 -39.655196)
		(end 222.664274 -39.73068)
		(width 0.1016)
		(layer "In5.Cu")
		(net "PCIE_TX_CAP_N81")
	)
	(arc
		(start 221.41942 -39.898574)
		(mid 221.377915 -39.890318)
		(end 221.342712 -39.866824)
		(width 0.1016)
		(layer "In5.Cu")
		(net "PCIE_TX_CAP_N81")
	)
	(arc
		(start 131.758182 -36.160202)
		(mid 131.686155 -36.052406)
		(end 131.6609 -35.925252)
		(width 0.1397)
		(layer "In5.Cu")
		(net "PCIE_TX_CAP_N81")
	)
	(arc
		(start 133.258306 -37.3126)
		(mid 132.937011 -37.248597)
		(end 132.664708 -37.066474)
		(width 0.1397)
		(layer "In5.Cu")
		(net "PCIE_TX_CAP_N81")
	)
	(arc
		(start 222.664274 -39.73068)
		(mid 222.612002 -39.825282)
		(end 222.52305 -39.886636)
		(width 0.1016)
		(layer "In5.Cu")
		(net "PCIE_TX_CAP_N81")
	)
	(arc
		(start 131.6609 -35.480244)
		(mid 131.721532 -35.333866)
		(end 131.86791 -35.273234)
		(width 0.1397)
		(layer "In5.Cu")
		(net "PCIE_TX_CAP_N81")
	)
	(arc
		(start 222.52305 -39.886636)
		(mid 222.440716 -39.895586)
		(end 222.35795 -39.898574)
		(width 0.1016)
		(layer "In5.Cu")
		(net "PCIE_TX_CAP_N81")
	)
	(arc
		(start 222.10014 -39.500048)
		(mid 222.410423 -39.337519)
		(end 222.663258 -39.579804)
		(width 0.1016)
		(layer "In5.Cu")
		(net "PCIE_TX_CAP_N81")
	)
	(segment
		(start 136.894062 -36.4617)
		(end 137.613898 -36.4617)
		(width 0.136652)
		(layer "F.Cu")
		(net "PCIE_TX_CAP_N80")
	)
	(segment
		(start 135.9662 -34.476436)
		(end 135.9662 -35.487356)
		(width 0.136652)
		(layer "F.Cu")
		(net "PCIE_TX_CAP_N80")
	)
	(segment
		(start 136.2583 -33.98774)
		(end 136.105138 -34.140648)
		(width 0.136652)
		(layer "F.Cu")
		(net "PCIE_TX_CAP_N80")
	)
	(segment
		(start 223.60001 -40.999918)
		(end 223.100138 -40.500046)
		(width 0.136652)
		(layer "F.Cu")
		(net "PCIE_TX_CAP_N80")
	)
	(segment
		(start 139.091162 -37.766244)
		(end 139.091162 -38.33876)
		(width 0.136652)
		(layer "F.Cu")
		(net "PCIE_TX_CAP_N80")
	)
	(segment
		(start 138.41349 -36.792916)
		(end 138.88212 -37.261546)
		(width 0.136652)
		(layer "F.Cu")
		(net "PCIE_TX_CAP_N80")
	)
	(segment
		(start 136.152128 -35.936428)
		(end 136.524238 -36.308538)
		(width 0.136652)
		(layer "F.Cu")
		(net "PCIE_TX_CAP_N80")
	)
	(via
		(at 139.3698 -38.6588)
		(size 0.508)
		(drill 0.254)
		(layers "F.Cu" "B.Cu")
		(net "PCIE_TX_CAP_N80")
	)
	(via
		(at 223.100138 -40.500046)
		(size 0.4572)
		(drill 0.2032)
		(layers "F.Cu" "B.Cu")
		(net "PCIE_TX_CAP_N80")
	)
	(arc
		(start 136.524238 -36.308538)
		(mid 136.693915 -36.421912)
		(end 136.894062 -36.4617)
		(width 0.136652)
		(layer "F.Cu")
		(net "PCIE_TX_CAP_N80")
	)
	(arc
		(start 135.9662 -35.487356)
		(mid 136.014536 -35.73036)
		(end 136.152128 -35.936428)
		(width 0.136652)
		(layer "F.Cu")
		(net "PCIE_TX_CAP_N80")
	)
	(arc
		(start 139.091162 -38.33876)
		(mid 139.170584 -38.550922)
		(end 139.3698 -38.6588)
		(width 0.136652)
		(layer "F.Cu")
		(net "PCIE_TX_CAP_N80")
	)
	(arc
		(start 136.105138 -34.140648)
		(mid 136.002281 -34.294724)
		(end 135.9662 -34.476436)
		(width 0.136652)
		(layer "F.Cu")
		(net "PCIE_TX_CAP_N80")
	)
	(arc
		(start 137.613898 -36.4617)
		(mid 138.046639 -36.547778)
		(end 138.41349 -36.792916)
		(width 0.136652)
		(layer "F.Cu")
		(net "PCIE_TX_CAP_N80")
	)
	(arc
		(start 138.88212 -37.261546)
		(mid 139.036842 -37.493103)
		(end 139.091162 -37.766244)
		(width 0.136652)
		(layer "F.Cu")
		(net "PCIE_TX_CAP_N80")
	)
	(segment
		(start 213.686644 -39.727124)
		(end 213.273894 -39.65448)
		(width 0.1397)
		(layer "In5.Cu")
		(net "PCIE_TX_CAP_N80")
	)
	(segment
		(start 223.49841 -40.601646)
		(end 223.49841 -40.703246)
		(width 0.1016)
		(layer "In5.Cu")
		(net "PCIE_TX_CAP_N80")
	)
	(segment
		(start 211.517484 -39.525194)
		(end 204.070966 -40.838374)
		(width 0.1397)
		(layer "In5.Cu")
		(net "PCIE_TX_CAP_N80")
	)
	(segment
		(start 215.006428 -40.140382)
		(end 214.86241 -39.934388)
		(width 0.1397)
		(layer "In5.Cu")
		(net "PCIE_TX_CAP_N80")
	)
	(segment
		(start 163.627054 -46.710854)
		(end 145.522696 -42.862246)
		(width 0.1397)
		(layer "In5.Cu")
		(net "PCIE_TX_CAP_N80")
	)
	(segment
		(start 142.661386 -41.005506)
		(end 142.047214 -40.60698)
		(width 0.1397)
		(layer "In5.Cu")
		(net "PCIE_TX_CAP_N80")
	)
	(segment
		(start 213.273894 -39.65448)
		(end 213.0679 -39.798752)
		(width 0.1397)
		(layer "In5.Cu")
		(net "PCIE_TX_CAP_N80")
	)
	(segment
		(start 139.561824 -39.958518)
		(end 139.280646 -39.67734)
		(width 0.1397)
		(layer "In5.Cu")
		(net "PCIE_TX_CAP_N80")
	)
	(segment
		(start 191.93764 -40.29583)
		(end 173.757844 -43.498516)
		(width 0.1397)
		(layer "In5.Cu")
		(net "PCIE_TX_CAP_N80")
	)
	(segment
		(start 204.070966 -40.838374)
		(end 200.914254 -40.28186)
		(width 0.1397)
		(layer "In5.Cu")
		(net "PCIE_TX_CAP_N80")
	)
	(segment
		(start 213.0679 -39.798752)
		(end 211.517484 -39.525194)
		(width 0.1397)
		(layer "In5.Cu")
		(net "PCIE_TX_CAP_N80")
	)
	(segment
		(start 200.914254 -40.28186)
		(end 196.385942 -41.079928)
		(width 0.1397)
		(layer "In5.Cu")
		(net "PCIE_TX_CAP_N80")
	)
	(segment
		(start 143.90878 -41.602914)
		(end 143.662908 -41.655238)
		(width 0.1397)
		(layer "In5.Cu")
		(net "PCIE_TX_CAP_N80")
	)
	(segment
		(start 139.1412 -39.34079)
		(end 139.1412 -38.8874)
		(width 0.1397)
		(layer "In5.Cu")
		(net "PCIE_TX_CAP_N80")
	)
	(segment
		(start 142.047214 -40.60698)
		(end 141.641576 -40.501062)
		(width 0.1397)
		(layer "In5.Cu")
		(net "PCIE_TX_CAP_N80")
	)
	(segment
		(start 221.6531 -40.898572)
		(end 221.5896 -40.835072)
		(width 0.1016)
		(layer "In5.Cu")
		(net "PCIE_TX_CAP_N80")
	)
	(segment
		(start 142.907258 -40.953182)
		(end 142.661386 -41.005506)
		(width 0.1397)
		(layer "In5.Cu")
		(net "PCIE_TX_CAP_N80")
	)
	(segment
		(start 171.364402 -45.052488)
		(end 171.347638 -45.069252)
		(width 0.1397)
		(layer "In5.Cu")
		(net "PCIE_TX_CAP_N80")
	)
	(segment
		(start 223.303084 -40.898572)
		(end 221.6531 -40.898572)
		(width 0.1016)
		(layer "In5.Cu")
		(net "PCIE_TX_CAP_N80")
	)
	(segment
		(start 143.662908 -41.655238)
		(end 143.311372 -41.427146)
		(width 0.1397)
		(layer "In5.Cu")
		(net "PCIE_TX_CAP_N80")
	)
	(segment
		(start 171.347638 -45.069252)
		(end 163.627054 -46.710854)
		(width 0.1397)
		(layer "In5.Cu")
		(net "PCIE_TX_CAP_N80")
	)
	(segment
		(start 144.260316 -41.831006)
		(end 143.90878 -41.602914)
		(width 0.1397)
		(layer "In5.Cu")
		(net "PCIE_TX_CAP_N80")
	)
	(segment
		(start 173.757844 -43.498516)
		(end 171.364402 -45.052488)
		(width 0.1397)
		(layer "In5.Cu")
		(net "PCIE_TX_CAP_N80")
	)
	(segment
		(start 196.385942 -41.079928)
		(end 191.93764 -40.29583)
		(width 0.1397)
		(layer "In5.Cu")
		(net "PCIE_TX_CAP_N80")
	)
	(segment
		(start 141.108938 -40.178482)
		(end 140.892022 -40.305482)
		(width 0.1397)
		(layer "In5.Cu")
		(net "PCIE_TX_CAP_N80")
	)
	(segment
		(start 143.258794 -41.181274)
		(end 142.907258 -40.953182)
		(width 0.1397)
		(layer "In5.Cu")
		(net "PCIE_TX_CAP_N80")
	)
	(segment
		(start 144.312894 -42.077132)
		(end 144.260316 -41.831006)
		(width 0.1397)
		(layer "In5.Cu")
		(net "PCIE_TX_CAP_N80")
	)
	(segment
		(start 214.86241 -39.934388)
		(end 214.44966 -39.861744)
		(width 0.1397)
		(layer "In5.Cu")
		(net "PCIE_TX_CAP_N80")
	)
	(segment
		(start 218.946222 -40.835072)
		(end 215.006428 -40.140382)
		(width 0.1397)
		(layer "In5.Cu")
		(net "PCIE_TX_CAP_N80")
	)
	(segment
		(start 143.311372 -41.427146)
		(end 143.258794 -41.181274)
		(width 0.1397)
		(layer "In5.Cu")
		(net "PCIE_TX_CAP_N80")
	)
	(segment
		(start 214.243666 -40.006016)
		(end 213.830916 -39.933118)
		(width 0.1397)
		(layer "In5.Cu")
		(net "PCIE_TX_CAP_N80")
	)
	(segment
		(start 140.892022 -40.305482)
		(end 139.561824 -39.958518)
		(width 0.1397)
		(layer "In5.Cu")
		(net "PCIE_TX_CAP_N80")
	)
	(segment
		(start 145.522696 -42.862246)
		(end 144.312894 -42.077132)
		(width 0.1397)
		(layer "In5.Cu")
		(net "PCIE_TX_CAP_N80")
	)
	(segment
		(start 213.830916 -39.933118)
		(end 213.686644 -39.727124)
		(width 0.1397)
		(layer "In5.Cu")
		(net "PCIE_TX_CAP_N80")
	)
	(segment
		(start 141.514576 -40.284146)
		(end 141.108938 -40.178482)
		(width 0.1397)
		(layer "In5.Cu")
		(net "PCIE_TX_CAP_N80")
	)
	(segment
		(start 221.5896 -40.835072)
		(end 218.946222 -40.835072)
		(width 0.1397)
		(layer "In5.Cu")
		(net "PCIE_TX_CAP_N80")
	)
	(segment
		(start 214.44966 -39.861744)
		(end 214.243666 -40.006016)
		(width 0.1397)
		(layer "In5.Cu")
		(net "PCIE_TX_CAP_N80")
	)
	(segment
		(start 223.100138 -40.500046)
		(end 223.39681 -40.500046)
		(width 0.1016)
		(layer "In5.Cu")
		(net "PCIE_TX_CAP_N80")
	)
	(segment
		(start 141.641576 -40.501062)
		(end 141.514576 -40.284146)
		(width 0.1397)
		(layer "In5.Cu")
		(net "PCIE_TX_CAP_N80")
	)
	(arc
		(start 223.49841 -40.703246)
		(mid 223.4412 -40.841362)
		(end 223.303084 -40.898572)
		(width 0.1016)
		(layer "In5.Cu")
		(net "PCIE_TX_CAP_N80")
	)
	(arc
		(start 139.1412 -38.8874)
		(mid 139.208155 -38.725755)
		(end 139.3698 -38.6588)
		(width 0.1397)
		(layer "In5.Cu")
		(net "PCIE_TX_CAP_N80")
	)
	(arc
		(start 223.39681 -40.500046)
		(mid 223.468652 -40.529804)
		(end 223.49841 -40.601646)
		(width 0.1016)
		(layer "In5.Cu")
		(net "PCIE_TX_CAP_N80")
	)
	(arc
		(start 139.280646 -39.67734)
		(mid 139.177419 -39.522944)
		(end 139.1412 -39.34079)
		(width 0.1397)
		(layer "In5.Cu")
		(net "PCIE_TX_CAP_N80")
	)
	(segment
		(start 258.59994 -33.999932)
		(end 259.099812 -33.50006)
		(width 0.136652)
		(layer "F.Cu")
		(net "PCIE_TX_CAP_N8")
	)
	(segment
		(start 306.819046 -33.95472)
		(end 306.660804 -34.112708)
		(width 0.136652)
		(layer "F.Cu")
		(net "PCIE_TX_CAP_N8")
	)
	(segment
		(start 306.524406 -34.4424)
		(end 306.524406 -36.017708)
		(width 0.136652)
		(layer "F.Cu")
		(net "PCIE_TX_CAP_N8")
	)
	(segment
		(start 306.321714 -36.2204)
		(end 306.321714 -39.55542)
		(width 0.136652)
		(layer "F.Cu")
		(net "PCIE_TX_CAP_N8")
	)
	(segment
		(start 306.524406 -36.017708)
		(end 306.321714 -36.2204)
		(width 0.136652)
		(layer "F.Cu")
		(net "PCIE_TX_CAP_N8")
	)
	(segment
		(start 306.321714 -39.55542)
		(end 306.575714 -39.80942)
		(width 0.136652)
		(layer "F.Cu")
		(net "PCIE_TX_CAP_N8")
	)
	(via
		(at 259.099812 -33.50006)
		(size 0.4572)
		(drill 0.2032)
		(layers "F.Cu" "B.Cu")
		(net "PCIE_TX_CAP_N8")
	)
	(via
		(at 306.575714 -39.80942)
		(size 0.508)
		(drill 0.254)
		(layers "F.Cu" "B.Cu")
		(net "PCIE_TX_CAP_N8")
	)
	(arc
		(start 306.660804 -34.112708)
		(mid 306.559816 -34.263987)
		(end 306.524406 -34.4424)
		(width 0.136652)
		(layer "F.Cu")
		(net "PCIE_TX_CAP_N8")
	)
	(segment
		(start 273.487642 -33.208976)
		(end 267.708634 -32.189928)
		(width 0.1397)
		(layer "In5.Cu")
		(net "PCIE_TX_CAP_N8")
	)
	(segment
		(start 259.558536 -33.104836)
		(end 259.074412 -33.104836)
		(width 0.1016)
		(layer "In5.Cu")
		(net "PCIE_TX_CAP_N8")
	)
	(segment
		(start 306.334414 -40.05072)
		(end 306.334414 -40.532558)
		(width 0.1397)
		(layer "In5.Cu")
		(net "PCIE_TX_CAP_N8")
	)
	(segment
		(start 260.233922 -33.204912)
		(end 259.658612 -33.204912)
		(width 0.1016)
		(layer "In5.Cu")
		(net "PCIE_TX_CAP_N8")
	)
	(segment
		(start 259.074412 -33.50006)
		(end 259.099812 -33.50006)
		(width 0.1016)
		(layer "In5.Cu")
		(net "PCIE_TX_CAP_N8")
	)
	(segment
		(start 306.334414 -40.532558)
		(end 305.731164 -41.136062)
		(width 0.1397)
		(layer "In5.Cu")
		(net "PCIE_TX_CAP_N8")
	)
	(segment
		(start 292.390068 -42.129202)
		(end 291.278056 -42.32529)
		(width 0.1397)
		(layer "In5.Cu")
		(net "PCIE_TX_CAP_N8")
	)
	(segment
		(start 304.892456 -41.550844)
		(end 296.586148 -43.090338)
		(width 0.1397)
		(layer "In5.Cu")
		(net "PCIE_TX_CAP_N8")
	)
	(segment
		(start 291.278056 -42.32529)
		(end 282.47975 -40.565578)
		(width 0.1397)
		(layer "In5.Cu")
		(net "PCIE_TX_CAP_N8")
	)
	(segment
		(start 260.297422 -33.268412)
		(end 260.233922 -33.204912)
		(width 0.1016)
		(layer "In5.Cu")
		(net "PCIE_TX_CAP_N8")
	)
	(segment
		(start 259.658612 -33.204912)
		(end 259.558536 -33.104836)
		(width 0.1016)
		(layer "In5.Cu")
		(net "PCIE_TX_CAP_N8")
	)
	(segment
		(start 278.580088 -37.835078)
		(end 277.123144 -35.75431)
		(width 0.1397)
		(layer "In5.Cu")
		(net "PCIE_TX_CAP_N8")
	)
	(segment
		(start 296.586148 -43.090338)
		(end 292.390068 -42.129202)
		(width 0.1397)
		(layer "In5.Cu")
		(net "PCIE_TX_CAP_N8")
	)
	(segment
		(start 267.708634 -32.189928)
		(end 261.590536 -33.268412)
		(width 0.1397)
		(layer "In5.Cu")
		(net "PCIE_TX_CAP_N8")
	)
	(segment
		(start 261.590536 -33.268412)
		(end 260.322822 -33.268412)
		(width 0.1397)
		(layer "In5.Cu")
		(net "PCIE_TX_CAP_N8")
	)
	(segment
		(start 305.731164 -41.136062)
		(end 304.892456 -41.550844)
		(width 0.1397)
		(layer "In5.Cu")
		(net "PCIE_TX_CAP_N8")
	)
	(segment
		(start 277.123144 -35.75431)
		(end 273.487642 -33.208976)
		(width 0.1397)
		(layer "In5.Cu")
		(net "PCIE_TX_CAP_N8")
	)
	(segment
		(start 306.575714 -39.80942)
		(end 306.334414 -40.05072)
		(width 0.1397)
		(layer "In5.Cu")
		(net "PCIE_TX_CAP_N8")
	)
	(segment
		(start 260.322822 -33.268412)
		(end 260.297422 -33.268412)
		(width 0.1016)
		(layer "In5.Cu")
		(net "PCIE_TX_CAP_N8")
	)
	(segment
		(start 282.47975 -40.565578)
		(end 278.580088 -37.835078)
		(width 0.1397)
		(layer "In5.Cu")
		(net "PCIE_TX_CAP_N8")
	)
	(arc
		(start 259.074412 -33.104836)
		(mid 258.8768 -33.302448)
		(end 259.074412 -33.50006)
		(width 0.1016)
		(layer "In5.Cu")
		(net "PCIE_TX_CAP_N8")
	)
	(segment
		(start 223.60001 -45.999908)
		(end 223.402398 -45.802042)
		(width 0.136652)
		(layer "F.Cu")
		(net "PCIE_TX_CAP_N76")
	)
	(segment
		(start 22.437598 -112.367568)
		(end 22.43836 -112.36706)
		(width 0.136652)
		(layer "F.Cu")
		(net "PCIE_TX_CAP_N76")
	)
	(segment
		(start 215.644222 -48.23333)
		(end 215.243156 -48.31842)
		(width 0.136652)
		(layer "F.Cu")
		(net "PCIE_TX_CAP_N76")
	)
	(segment
		(start 223.267016 -45.72889)
		(end 221.464378 -45.72889)
		(width 0.136652)
		(layer "F.Cu")
		(net "PCIE_TX_CAP_N76")
	)
	(segment
		(start 200.7743 -48.941228)
		(end 200.7743 -49.2506)
		(width 0.136652)
		(layer "F.Cu")
		(net "PCIE_TX_CAP_N76")
	)
	(segment
		(start 217.455496 -47.848266)
		(end 217.335608 -48.03267)
		(width 0.136652)
		(layer "F.Cu")
		(net "PCIE_TX_CAP_N76")
	)
	(segment
		(start 216.934542 -48.118014)
		(end 216.750392 -47.998126)
		(width 0.136652)
		(layer "F.Cu")
		(net "PCIE_TX_CAP_N76")
	)
	(segment
		(start 18.960084 -118.72595)
		(end 18.960084 -118.548912)
		(width 0.136652)
		(layer "F.Cu")
		(net "PCIE_TX_CAP_N76")
	)
	(segment
		(start 216.750392 -47.998126)
		(end 216.349326 -48.08347)
		(width 0.136652)
		(layer "F.Cu")
		(net "PCIE_TX_CAP_N76")
	)
	(segment
		(start 216.229438 -48.26762)
		(end 215.828626 -48.352964)
		(width 0.136652)
		(layer "F.Cu")
		(net "PCIE_TX_CAP_N76")
	)
	(segment
		(start 201.033888 -48.353218)
		(end 200.833736 -48.66132)
		(width 0.136652)
		(layer "F.Cu")
		(net "PCIE_TX_CAP_N76")
	)
	(segment
		(start 21.617686 -123.705874)
		(end 19.712432 -121.80062)
		(width 0.136652)
		(layer "F.Cu")
		(net "PCIE_TX_CAP_N76")
	)
	(segment
		(start 221.464378 -45.72889)
		(end 218.864942 -47.5488)
		(width 0.136652)
		(layer "F.Cu")
		(net "PCIE_TX_CAP_N76")
	)
	(segment
		(start 215.828626 -48.352964)
		(end 215.644222 -48.23333)
		(width 0.136652)
		(layer "F.Cu")
		(net "PCIE_TX_CAP_N76")
	)
	(segment
		(start 18.994628 -118.185184)
		(end 19.40941 -116.23294)
		(width 0.136652)
		(layer "F.Cu")
		(net "PCIE_TX_CAP_N76")
	)
	(segment
		(start 18.960084 -118.548912)
		(end 18.994628 -118.185184)
		(width 0.136652)
		(layer "F.Cu")
		(net "PCIE_TX_CAP_N76")
	)
	(segment
		(start 21.271484 -113.182908)
		(end 22.40534 -112.388142)
		(width 0.136652)
		(layer "F.Cu")
		(net "PCIE_TX_CAP_N76")
	)
	(segment
		(start 202.75804 -47.234602)
		(end 201.033888 -48.353218)
		(width 0.136652)
		(layer "F.Cu")
		(net "PCIE_TX_CAP_N76")
	)
	(segment
		(start 21.9837 -123.746006)
		(end 21.71446 -123.746006)
		(width 0.136652)
		(layer "F.Cu")
		(net "PCIE_TX_CAP_N76")
	)
	(segment
		(start 23.549356 -112.098836)
		(end 23.6474 -112.1156)
		(width 0.136652)
		(layer "F.Cu")
		(net "PCIE_TX_CAP_N76")
	)
	(segment
		(start 215.243156 -48.31842)
		(end 206.451708 -46.449488)
		(width 0.136652)
		(layer "F.Cu")
		(net "PCIE_TX_CAP_N76")
	)
	(segment
		(start 217.335608 -48.03267)
		(end 216.934542 -48.118014)
		(width 0.136652)
		(layer "F.Cu")
		(net "PCIE_TX_CAP_N76")
	)
	(segment
		(start 22.28469 -123.445016)
		(end 21.9837 -123.746006)
		(width 0.136652)
		(layer "F.Cu")
		(net "PCIE_TX_CAP_N76")
	)
	(segment
		(start 218.864942 -47.5488)
		(end 217.455496 -47.848266)
		(width 0.136652)
		(layer "F.Cu")
		(net "PCIE_TX_CAP_N76")
	)
	(segment
		(start 200.833736 -48.66132)
		(end 200.7743 -48.941228)
		(width 0.136652)
		(layer "F.Cu")
		(net "PCIE_TX_CAP_N76")
	)
	(segment
		(start 19.61896 -115.726972)
		(end 21.271484 -113.182908)
		(width 0.136652)
		(layer "F.Cu")
		(net "PCIE_TX_CAP_N76")
	)
	(segment
		(start 22.728174 -112.228376)
		(end 23.363936 -112.101376)
		(width 0.136652)
		(layer "F.Cu")
		(net "PCIE_TX_CAP_N76")
	)
	(segment
		(start 22.43836 -112.36706)
		(end 22.568154 -112.289844)
		(width 0.136652)
		(layer "F.Cu")
		(net "PCIE_TX_CAP_N76")
	)
	(segment
		(start 216.349326 -48.08347)
		(end 216.229438 -48.26762)
		(width 0.136652)
		(layer "F.Cu")
		(net "PCIE_TX_CAP_N76")
	)
	(segment
		(start 206.451708 -46.449488)
		(end 202.75804 -47.234602)
		(width 0.136652)
		(layer "F.Cu")
		(net "PCIE_TX_CAP_N76")
	)
	(segment
		(start 19.565874 -121.531634)
		(end 18.960084 -118.72595)
		(width 0.136652)
		(layer "F.Cu")
		(net "PCIE_TX_CAP_N76")
	)
	(via
		(at 201.168 -49.727612)
		(size 0.508)
		(drill 0.254)
		(layers "F.Cu" "B.Cu")
		(net "PCIE_TX_CAP_N76")
	)
	(via
		(at 24.473154 -112.522)
		(size 0.508)
		(drill 0.254)
		(layers "F.Cu" "B.Cu")
		(net "PCIE_TX_CAP_N76")
	)
	(arc
		(start 200.7743 -49.2506)
		(mid 200.894152 -49.552637)
		(end 201.168 -49.727612)
		(width 0.136652)
		(layer "F.Cu")
		(net "PCIE_TX_CAP_N76")
	)
	(arc
		(start 223.303846 -45.736256)
		(mid 223.285792 -45.730778)
		(end 223.267016 -45.72889)
		(width 0.136652)
		(layer "F.Cu")
		(net "PCIE_TX_CAP_N76")
	)
	(arc
		(start 22.568154 -112.289844)
		(mid 22.64555 -112.252303)
		(end 22.728174 -112.228376)
		(width 0.136652)
		(layer "F.Cu")
		(net "PCIE_TX_CAP_N76")
	)
	(arc
		(start 23.363936 -112.101376)
		(mid 23.456529 -112.09157)
		(end 23.549356 -112.098836)
		(width 0.136652)
		(layer "F.Cu")
		(net "PCIE_TX_CAP_N76")
	)
	(arc
		(start 21.71446 -123.746006)
		(mid 21.662083 -123.73557)
		(end 21.617686 -123.705874)
		(width 0.136652)
		(layer "F.Cu")
		(net "PCIE_TX_CAP_N76")
	)
	(arc
		(start 19.40941 -116.23294)
		(mid 19.490931 -115.970325)
		(end 19.61896 -115.726972)
		(width 0.136652)
		(layer "F.Cu")
		(net "PCIE_TX_CAP_N76")
	)
	(arc
		(start 23.6474 -112.1156)
		(mid 24.107575 -112.2227)
		(end 24.473154 -112.522)
		(width 0.136652)
		(layer "F.Cu")
		(net "PCIE_TX_CAP_N76")
	)
	(arc
		(start 22.40534 -112.388142)
		(mid 22.421275 -112.37755)
		(end 22.437598 -112.367568)
		(width 0.136652)
		(layer "F.Cu")
		(net "PCIE_TX_CAP_N76")
	)
	(arc
		(start 223.402398 -45.802042)
		(mid 223.356371 -45.764281)
		(end 223.303846 -45.736256)
		(width 0.136652)
		(layer "F.Cu")
		(net "PCIE_TX_CAP_N76")
	)
	(arc
		(start 19.712432 -121.80062)
		(mid 19.619789 -121.676682)
		(end 19.565874 -121.531634)
		(width 0.136652)
		(layer "F.Cu")
		(net "PCIE_TX_CAP_N76")
	)
	(segment
		(start 164.118544 -104.44607)
		(end 153.231342 -102.526592)
		(width 0.1397)
		(layer "In2.Cu")
		(net "PCIE_TX_CAP_N76")
	)
	(segment
		(start 139.20089 -104.864408)
		(end 138.849354 -105.0925)
		(width 0.1397)
		(layer "In2.Cu")
		(net "PCIE_TX_CAP_N76")
	)
	(segment
		(start 138.251946 -105.268522)
		(end 138.199622 -105.514648)
		(width 0.1397)
		(layer "In2.Cu")
		(net "PCIE_TX_CAP_N76")
	)
	(segment
		(start 200.573132 -50.99431)
		(end 195.840096 -54.068218)
		(width 0.1397)
		(layer "In2.Cu")
		(net "PCIE_TX_CAP_N76")
	)
	(segment
		(start 39.225982 -103.017828)
		(end 36.912296 -103.509572)
		(width 0.1397)
		(layer "In2.Cu")
		(net "PCIE_TX_CAP_N76")
	)
	(segment
		(start 149.704552 -101.9048)
		(end 149.498558 -102.049072)
		(width 0.1397)
		(layer "In2.Cu")
		(net "PCIE_TX_CAP_N76")
	)
	(segment
		(start 165.42893 -104.21493)
		(end 164.118544 -104.44607)
		(width 0.1397)
		(layer "In2.Cu")
		(net "PCIE_TX_CAP_N76")
	)
	(segment
		(start 137.250678 -105.918762)
		(end 137.198354 -106.164634)
		(width 0.1397)
		(layer "In2.Cu")
		(net "PCIE_TX_CAP_N76")
	)
	(segment
		(start 141.969998 -102.853998)
		(end 139.25296 -104.618282)
		(width 0.1397)
		(layer "In2.Cu")
		(net "PCIE_TX_CAP_N76")
	)
	(segment
		(start 25.420828 -112.1283)
		(end 24.924766 -112.1283)
		(width 0.1397)
		(layer "In2.Cu")
		(net "PCIE_TX_CAP_N76")
	)
	(segment
		(start 134.43204 -107.749086)
		(end 127.296926 -109.26572)
		(width 0.1397)
		(layer "In2.Cu")
		(net "PCIE_TX_CAP_N76")
	)
	(segment
		(start 28.335732 -110.316772)
		(end 25.92324 -111.987584)
		(width 0.1397)
		(layer "In2.Cu")
		(net "PCIE_TX_CAP_N76")
	)
	(segment
		(start 169.161968 -103.73741)
		(end 168.955974 -103.593392)
		(width 0.1397)
		(layer "In2.Cu")
		(net "PCIE_TX_CAP_N76")
	)
	(segment
		(start 200.787 -50.1904)
		(end 200.787 -50.600102)
		(width 0.1397)
		(layer "In2.Cu")
		(net "PCIE_TX_CAP_N76")
	)
	(segment
		(start 63.254128 -104.106726)
		(end 59.843162 -103.505508)
		(width 0.1397)
		(layer "In2.Cu")
		(net "PCIE_TX_CAP_N76")
	)
	(segment
		(start 149.498558 -102.049072)
		(end 149.085808 -101.976174)
		(width 0.1397)
		(layer "In2.Cu")
		(net "PCIE_TX_CAP_N76")
	)
	(segment
		(start 24.82596 -112.169194)
		(end 24.473154 -112.522)
		(width 0.1397)
		(layer "In2.Cu")
		(net "PCIE_TX_CAP_N76")
	)
	(segment
		(start 151.849836 -102.4636)
		(end 151.437086 -102.390956)
		(width 0.1397)
		(layer "In2.Cu")
		(net "PCIE_TX_CAP_N76")
	)
	(segment
		(start 28.33624 -110.31601)
		(end 28.33624 -110.316264)
		(width 0.1397)
		(layer "In2.Cu")
		(net "PCIE_TX_CAP_N76")
	)
	(segment
		(start 148.941536 -101.77018)
		(end 148.528786 -101.697536)
		(width 0.1397)
		(layer "In2.Cu")
		(net "PCIE_TX_CAP_N76")
	)
	(segment
		(start 137.198354 -106.164634)
		(end 136.846818 -106.39298)
		(width 0.1397)
		(layer "In2.Cu")
		(net "PCIE_TX_CAP_N76")
	)
	(segment
		(start 167.22344 -104.079294)
		(end 166.81069 -104.151938)
		(width 0.1397)
		(layer "In2.Cu")
		(net "PCIE_TX_CAP_N76")
	)
	(segment
		(start 166.191946 -104.080564)
		(end 166.047674 -104.286558)
		(width 0.1397)
		(layer "In2.Cu")
		(net "PCIE_TX_CAP_N76")
	)
	(segment
		(start 165.634924 -104.359202)
		(end 165.42893 -104.21493)
		(width 0.1397)
		(layer "In2.Cu")
		(net "PCIE_TX_CAP_N76")
	)
	(segment
		(start 201.168 -49.727612)
		(end 200.96226 -49.86401)
		(width 0.1397)
		(layer "In2.Cu")
		(net "PCIE_TX_CAP_N76")
	)
	(segment
		(start 121.78792 -108.09478)
		(end 117.488462 -109.008926)
		(width 0.1397)
		(layer "In2.Cu")
		(net "PCIE_TX_CAP_N76")
	)
	(segment
		(start 34.739326 -103.0478)
		(end 34.05251 -103.19385)
		(width 0.1397)
		(layer "In2.Cu")
		(net "PCIE_TX_CAP_N76")
	)
	(segment
		(start 150.117302 -101.977698)
		(end 149.704552 -101.9048)
		(width 0.1397)
		(layer "In2.Cu")
		(net "PCIE_TX_CAP_N76")
	)
	(segment
		(start 137.848086 -105.74274)
		(end 137.602214 -105.690416)
		(width 0.1397)
		(layer "In2.Cu")
		(net "PCIE_TX_CAP_N76")
	)
	(segment
		(start 166.047674 -104.286558)
		(end 165.634924 -104.359202)
		(width 0.1397)
		(layer "In2.Cu")
		(net "PCIE_TX_CAP_N76")
	)
	(segment
		(start 43.510708 -102.386638)
		(end 42.481246 -102.605586)
		(width 0.1397)
		(layer "In2.Cu")
		(net "PCIE_TX_CAP_N76")
	)
	(segment
		(start 42.481246 -102.605586)
		(end 40.740076 -102.235254)
		(width 0.1397)
		(layer "In2.Cu")
		(net "PCIE_TX_CAP_N76")
	)
	(segment
		(start 28.33624 -110.316264)
		(end 28.335732 -110.316772)
		(width 0.1397)
		(layer "In2.Cu")
		(net "PCIE_TX_CAP_N76")
	)
	(segment
		(start 193.23558 -60.643008)
		(end 194.220338 -66.233548)
		(width 0.1397)
		(layer "In2.Cu")
		(net "PCIE_TX_CAP_N76")
	)
	(segment
		(start 138.849354 -105.0925)
		(end 138.603228 -105.04043)
		(width 0.1397)
		(layer "In2.Cu")
		(net "PCIE_TX_CAP_N76")
	)
	(segment
		(start 149.085808 -101.976174)
		(end 148.941536 -101.77018)
		(width 0.1397)
		(layer "In2.Cu")
		(net "PCIE_TX_CAP_N76")
	)
	(segment
		(start 192.485772 -76.073)
		(end 175.26254 -100.696014)
		(width 0.1397)
		(layer "In2.Cu")
		(net "PCIE_TX_CAP_N76")
	)
	(segment
		(start 152.612852 -102.59822)
		(end 152.46858 -102.392226)
		(width 0.1397)
		(layer "In2.Cu")
		(net "PCIE_TX_CAP_N76")
	)
	(segment
		(start 34.05251 -103.19385)
		(end 32.84855 -103.975662)
		(width 0.1397)
		(layer "In2.Cu")
		(net "PCIE_TX_CAP_N76")
	)
	(segment
		(start 171.854368 -103.082344)
		(end 169.71899 -103.458772)
		(width 0.1397)
		(layer "In2.Cu")
		(net "PCIE_TX_CAP_N76")
	)
	(segment
		(start 150.26132 -102.183438)
		(end 150.117302 -101.977698)
		(width 0.1397)
		(layer "In2.Cu")
		(net "PCIE_TX_CAP_N76")
	)
	(segment
		(start 168.543224 -103.666036)
		(end 168.398952 -103.87203)
		(width 0.1397)
		(layer "In2.Cu")
		(net "PCIE_TX_CAP_N76")
	)
	(segment
		(start 150.880064 -102.112064)
		(end 150.67407 -102.256336)
		(width 0.1397)
		(layer "In2.Cu")
		(net "PCIE_TX_CAP_N76")
	)
	(segment
		(start 56.891936 -101.439726)
		(end 56.891936 -101.440234)
		(width 0.1397)
		(layer "In2.Cu")
		(net "PCIE_TX_CAP_N76")
	)
	(segment
		(start 166.604696 -104.007666)
		(end 166.191946 -104.080564)
		(width 0.1397)
		(layer "In2.Cu")
		(net "PCIE_TX_CAP_N76")
	)
	(segment
		(start 135.599678 -106.990896)
		(end 134.43204 -107.749086)
		(width 0.1397)
		(layer "In2.Cu")
		(net "PCIE_TX_CAP_N76")
	)
	(segment
		(start 138.603228 -105.04043)
		(end 138.251946 -105.268522)
		(width 0.1397)
		(layer "In2.Cu")
		(net "PCIE_TX_CAP_N76")
	)
	(segment
		(start 152.46858 -102.392226)
		(end 152.05583 -102.319328)
		(width 0.1397)
		(layer "In2.Cu")
		(net "PCIE_TX_CAP_N76")
	)
	(segment
		(start 195.801742 -54.105302)
		(end 193.911474 -56.804306)
		(width 0.1397)
		(layer "In2.Cu")
		(net "PCIE_TX_CAP_N76")
	)
	(segment
		(start 153.231342 -102.526592)
		(end 153.025602 -102.670864)
		(width 0.1397)
		(layer "In2.Cu")
		(net "PCIE_TX_CAP_N76")
	)
	(segment
		(start 136.24941 -106.569002)
		(end 136.197086 -106.814874)
		(width 0.1397)
		(layer "In2.Cu")
		(net "PCIE_TX_CAP_N76")
	)
	(segment
		(start 36.912296 -103.509572)
		(end 34.739326 -103.0478)
		(width 0.1397)
		(layer "In2.Cu")
		(net "PCIE_TX_CAP_N76")
	)
	(segment
		(start 28.577794 -110.074456)
		(end 28.33624 -110.31601)
		(width 0.1397)
		(layer "In2.Cu")
		(net "PCIE_TX_CAP_N76")
	)
	(segment
		(start 167.986202 -103.944674)
		(end 167.780208 -103.800656)
		(width 0.1397)
		(layer "In2.Cu")
		(net "PCIE_TX_CAP_N76")
	)
	(segment
		(start 136.197086 -106.814874)
		(end 135.84555 -107.04322)
		(width 0.1397)
		(layer "In2.Cu")
		(net "PCIE_TX_CAP_N76")
	)
	(segment
		(start 150.67407 -102.256336)
		(end 150.26132 -102.183438)
		(width 0.1397)
		(layer "In2.Cu")
		(net "PCIE_TX_CAP_N76")
	)
	(segment
		(start 135.84555 -107.04322)
		(end 135.599678 -106.990896)
		(width 0.1397)
		(layer "In2.Cu")
		(net "PCIE_TX_CAP_N76")
	)
	(segment
		(start 136.846818 -106.39298)
		(end 136.600946 -106.340656)
		(width 0.1397)
		(layer "In2.Cu")
		(net "PCIE_TX_CAP_N76")
	)
	(segment
		(start 56.891936 -101.440234)
		(end 50.899568 -100.41636)
		(width 0.1397)
		(layer "In2.Cu")
		(net "PCIE_TX_CAP_N76")
	)
	(segment
		(start 167.367458 -103.8733)
		(end 167.22344 -104.079294)
		(width 0.1397)
		(layer "In2.Cu")
		(net "PCIE_TX_CAP_N76")
	)
	(segment
		(start 87.631778 -103.744014)
		(end 83.488784 -104.624886)
		(width 0.1397)
		(layer "In2.Cu")
		(net "PCIE_TX_CAP_N76")
	)
	(segment
		(start 168.398952 -103.87203)
		(end 167.986202 -103.944674)
		(width 0.1397)
		(layer "In2.Cu")
		(net "PCIE_TX_CAP_N76")
	)
	(segment
		(start 193.911474 -56.804306)
		(end 193.23558 -60.643008)
		(width 0.1397)
		(layer "In2.Cu")
		(net "PCIE_TX_CAP_N76")
	)
	(segment
		(start 50.899568 -100.41636)
		(end 44.426124 -101.792278)
		(width 0.1397)
		(layer "In2.Cu")
		(net "PCIE_TX_CAP_N76")
	)
	(segment
		(start 152.05583 -102.319328)
		(end 151.849836 -102.4636)
		(width 0.1397)
		(layer "In2.Cu")
		(net "PCIE_TX_CAP_N76")
	)
	(segment
		(start 44.426124 -101.792278)
		(end 43.510708 -102.386638)
		(width 0.1397)
		(layer "In2.Cu")
		(net "PCIE_TX_CAP_N76")
	)
	(segment
		(start 151.437086 -102.390956)
		(end 151.292814 -102.184962)
		(width 0.1397)
		(layer "In2.Cu")
		(net "PCIE_TX_CAP_N76")
	)
	(segment
		(start 167.780208 -103.800656)
		(end 167.367458 -103.8733)
		(width 0.1397)
		(layer "In2.Cu")
		(net "PCIE_TX_CAP_N76")
	)
	(segment
		(start 127.296926 -109.26572)
		(end 121.78792 -108.09478)
		(width 0.1397)
		(layer "In2.Cu")
		(net "PCIE_TX_CAP_N76")
	)
	(segment
		(start 78.24851 -103.511096)
		(end 75.852274 -104.020366)
		(width 0.1397)
		(layer "In2.Cu")
		(net "PCIE_TX_CAP_N76")
	)
	(segment
		(start 169.574718 -103.664766)
		(end 169.161968 -103.73741)
		(width 0.1397)
		(layer "In2.Cu")
		(net "PCIE_TX_CAP_N76")
	)
	(segment
		(start 175.26254 -100.696014)
		(end 171.854368 -103.082344)
		(width 0.1397)
		(layer "In2.Cu")
		(net "PCIE_TX_CAP_N76")
	)
	(segment
		(start 117.488462 -109.008926)
		(end 87.631778 -103.744014)
		(width 0.1397)
		(layer "In2.Cu")
		(net "PCIE_TX_CAP_N76")
	)
	(segment
		(start 32.84855 -103.975662)
		(end 28.577794 -110.074456)
		(width 0.1397)
		(layer "In2.Cu")
		(net "PCIE_TX_CAP_N76")
	)
	(segment
		(start 83.488784 -104.624886)
		(end 78.24851 -103.511096)
		(width 0.1397)
		(layer "In2.Cu")
		(net "PCIE_TX_CAP_N76")
	)
	(segment
		(start 137.602214 -105.690416)
		(end 137.250678 -105.918762)
		(width 0.1397)
		(layer "In2.Cu")
		(net "PCIE_TX_CAP_N76")
	)
	(segment
		(start 168.955974 -103.593392)
		(end 168.543224 -103.666036)
		(width 0.1397)
		(layer "In2.Cu")
		(net "PCIE_TX_CAP_N76")
	)
	(segment
		(start 69.756782 -102.724712)
		(end 63.254128 -104.106726)
		(width 0.1397)
		(layer "In2.Cu")
		(net "PCIE_TX_CAP_N76")
	)
	(segment
		(start 59.843162 -103.505508)
		(end 56.891936 -101.439726)
		(width 0.1397)
		(layer "In2.Cu")
		(net "PCIE_TX_CAP_N76")
	)
	(segment
		(start 169.71899 -103.458772)
		(end 169.574718 -103.664766)
		(width 0.1397)
		(layer "In2.Cu")
		(net "PCIE_TX_CAP_N76")
	)
	(segment
		(start 166.81069 -104.151938)
		(end 166.604696 -104.007666)
		(width 0.1397)
		(layer "In2.Cu")
		(net "PCIE_TX_CAP_N76")
	)
	(segment
		(start 138.199622 -105.514648)
		(end 137.848086 -105.74274)
		(width 0.1397)
		(layer "In2.Cu")
		(net "PCIE_TX_CAP_N76")
	)
	(segment
		(start 153.025602 -102.670864)
		(end 152.612852 -102.59822)
		(width 0.1397)
		(layer "In2.Cu")
		(net "PCIE_TX_CAP_N76")
	)
	(segment
		(start 151.292814 -102.184962)
		(end 150.880064 -102.112064)
		(width 0.1397)
		(layer "In2.Cu")
		(net "PCIE_TX_CAP_N76")
	)
	(segment
		(start 148.528786 -101.697536)
		(end 141.969998 -102.853998)
		(width 0.1397)
		(layer "In2.Cu")
		(net "PCIE_TX_CAP_N76")
	)
	(segment
		(start 194.220338 -66.233548)
		(end 192.485772 -76.073)
		(width 0.1397)
		(layer "In2.Cu")
		(net "PCIE_TX_CAP_N76")
	)
	(segment
		(start 40.280844 -102.33279)
		(end 39.225982 -103.017828)
		(width 0.1397)
		(layer "In2.Cu")
		(net "PCIE_TX_CAP_N76")
	)
	(segment
		(start 75.852274 -104.020366)
		(end 69.756782 -102.724712)
		(width 0.1397)
		(layer "In2.Cu")
		(net "PCIE_TX_CAP_N76")
	)
	(segment
		(start 136.600946 -106.340656)
		(end 136.24941 -106.569002)
		(width 0.1397)
		(layer "In2.Cu")
		(net "PCIE_TX_CAP_N76")
	)
	(segment
		(start 139.25296 -104.618282)
		(end 139.20089 -104.864408)
		(width 0.1397)
		(layer "In2.Cu")
		(net "PCIE_TX_CAP_N76")
	)
	(segment
		(start 40.740076 -102.235254)
		(end 40.280844 -102.33279)
		(width 0.1397)
		(layer "In2.Cu")
		(net "PCIE_TX_CAP_N76")
	)
	(arc
		(start 200.787 -50.600102)
		(mid 200.730082 -50.824335)
		(end 200.573132 -50.99431)
		(width 0.1397)
		(layer "In2.Cu")
		(net "PCIE_TX_CAP_N76")
	)
	(arc
		(start 200.96226 -49.86401)
		(mid 200.833543 -50.005152)
		(end 200.787 -50.1904)
		(width 0.1397)
		(layer "In2.Cu")
		(net "PCIE_TX_CAP_N76")
	)
	(arc
		(start 24.924766 -112.1283)
		(mid 24.871305 -112.138934)
		(end 24.82596 -112.169194)
		(width 0.1397)
		(layer "In2.Cu")
		(net "PCIE_TX_CAP_N76")
	)
	(arc
		(start 25.92324 -111.987584)
		(mid 25.681702 -112.09246)
		(end 25.420828 -112.1283)
		(width 0.1397)
		(layer "In2.Cu")
		(net "PCIE_TX_CAP_N76")
	)
	(arc
		(start 195.840096 -54.068218)
		(mid 195.819142 -54.08492)
		(end 195.801742 -54.105302)
		(width 0.1397)
		(layer "In2.Cu")
		(net "PCIE_TX_CAP_N76")
	)
	(segment
		(start 49.04613 -211.5312)
		(end 49.04613 -211.289392)
		(width 0.136652)
		(layer "F.Cu")
		(net "PCIE_TX_CAP_N75")
	)
	(segment
		(start 49.40808 -211.975954)
		(end 49.104804 -211.672424)
		(width 0.136652)
		(layer "F.Cu")
		(net "PCIE_TX_CAP_N75")
	)
	(segment
		(start 222.600012 -46.999906)
		(end 222.600012 -46.644306)
		(width 0.136652)
		(layer "F.Cu")
		(net "PCIE_TX_CAP_N75")
	)
	(segment
		(start 222.593408 -46.611032)
		(end 222.586296 -46.594014)
		(width 0.136652)
		(layer "F.Cu")
		(net "PCIE_TX_CAP_N75")
	)
	(segment
		(start 49.139856 -211.063078)
		(end 49.30648 -210.896454)
		(width 0.136652)
		(layer "F.Cu")
		(net "PCIE_TX_CAP_N75")
	)
	(segment
		(start 222.380556 -46.4566)
		(end 222.205042 -46.4566)
		(width 0.136652)
		(layer "F.Cu")
		(net "PCIE_TX_CAP_N75")
	)
	(via
		(at 222.10014 -46.500034)
		(size 0.4572)
		(drill 0.2032)
		(layers "F.Cu" "B.Cu")
		(net "PCIE_TX_CAP_N75")
	)
	(via
		(at 49.30648 -210.896454)
		(size 0.508)
		(drill 0.254)
		(layers "F.Cu" "B.Cu")
		(net "PCIE_TX_CAP_N75")
	)
	(arc
		(start 222.586296 -46.594014)
		(mid 222.504255 -46.494126)
		(end 222.380556 -46.4566)
		(width 0.136652)
		(layer "F.Cu")
		(net "PCIE_TX_CAP_N75")
	)
	(arc
		(start 49.04613 -211.289392)
		(mid 49.070492 -211.166918)
		(end 49.139856 -211.063078)
		(width 0.136652)
		(layer "F.Cu")
		(net "PCIE_TX_CAP_N75")
	)
	(arc
		(start 49.104804 -211.672424)
		(mid 49.061427 -211.607645)
		(end 49.04613 -211.5312)
		(width 0.136652)
		(layer "F.Cu")
		(net "PCIE_TX_CAP_N75")
	)
	(arc
		(start 222.205042 -46.4566)
		(mid 222.148276 -46.467891)
		(end 222.10014 -46.500034)
		(width 0.136652)
		(layer "F.Cu")
		(net "PCIE_TX_CAP_N75")
	)
	(arc
		(start 222.600012 -46.644306)
		(mid 222.598379 -46.627336)
		(end 222.593408 -46.611032)
		(width 0.136652)
		(layer "F.Cu")
		(net "PCIE_TX_CAP_N75")
	)
	(segment
		(start 219.24518 -47.187104)
		(end 220.937074 -46.002448)
		(width 0.1397)
		(layer "In5.Cu")
		(net "PCIE_TX_CAP_N75")
	)
	(segment
		(start 196.67093 -68.070476)
		(end 198.193406 -67.004438)
		(width 0.1397)
		(layer "In5.Cu")
		(net "PCIE_TX_CAP_N75")
	)
	(segment
		(start 206.739236 -57.614566)
		(end 211.332318 -51.055016)
		(width 0.1397)
		(layer "In5.Cu")
		(net "PCIE_TX_CAP_N75")
	)
	(segment
		(start 205.105 -64.643)
		(end 205.63078 -63.892176)
		(width 0.1397)
		(layer "In5.Cu")
		(net "PCIE_TX_CAP_N75")
	)
	(segment
		(start 195.506594 -71.376032)
		(end 195.89369 -69.180456)
		(width 0.1397)
		(layer "In5.Cu")
		(net "PCIE_TX_CAP_N75")
	)
	(segment
		(start 222.296482 -46.648116)
		(end 222.267526 -46.634146)
		(width 0.1016)
		(layer "In5.Cu")
		(net "PCIE_TX_CAP_N75")
	)
	(segment
		(start 194.60972 -91.951556)
		(end 196.872352 -79.121508)
		(width 0.1397)
		(layer "In5.Cu")
		(net "PCIE_TX_CAP_N75")
	)
	(segment
		(start 56.458866 -201.452226)
		(end 71.755 -198.755)
		(width 0.1397)
		(layer "In5.Cu")
		(net "PCIE_TX_CAP_N75")
	)
	(segment
		(start 222.550228 -46.23943)
		(end 222.661734 -46.384718)
		(width 0.1016)
		(layer "In5.Cu")
		(net "PCIE_TX_CAP_N75")
	)
	(segment
		(start 49.06518 -210.22945)
		(end 49.06518 -210.106768)
		(width 0.1397)
		(layer "In5.Cu")
		(net "PCIE_TX_CAP_N75")
	)
	(segment
		(start 71.755 -198.755)
		(end 74.851768 -196.586602)
		(width 0.1397)
		(layer "In5.Cu")
		(net "PCIE_TX_CAP_N75")
	)
	(segment
		(start 222.529654 -46.217078)
		(end 222.546418 -46.236128)
		(width 0.1016)
		(layer "In5.Cu")
		(net "PCIE_TX_CAP_N75")
	)
	(segment
		(start 217.145616 -48.094138)
		(end 218.170506 -47.376842)
		(width 0.1397)
		(layer "In5.Cu")
		(net "PCIE_TX_CAP_N75")
	)
	(segment
		(start 222.508064 -46.66488)
		(end 222.37065 -46.66488)
		(width 0.1016)
		(layer "In5.Cu")
		(net "PCIE_TX_CAP_N75")
	)
	(segment
		(start 220.937074 -46.002448)
		(end 220.942916 -46.001432)
		(width 0.1397)
		(layer "In5.Cu")
		(net "PCIE_TX_CAP_N75")
	)
	(segment
		(start 74.851768 -196.586602)
		(end 84.580476 -194.87134)
		(width 0.1397)
		(layer "In5.Cu")
		(net "PCIE_TX_CAP_N75")
	)
	(segment
		(start 220.942916 -46.001432)
		(end 221.344998 -46.001432)
		(width 0.1397)
		(layer "In5.Cu")
		(net "PCIE_TX_CAP_N75")
	)
	(segment
		(start 198.193406 -67.004438)
		(end 202.923394 -66.170556)
		(width 0.1397)
		(layer "In5.Cu")
		(net "PCIE_TX_CAP_N75")
	)
	(segment
		(start 48.5902 -208.960212)
		(end 48.5902 -208.293462)
		(width 0.1397)
		(layer "In5.Cu")
		(net "PCIE_TX_CAP_N75")
	)
	(segment
		(start 159.061404 -142.72006)
		(end 194.60972 -91.951556)
		(width 0.1397)
		(layer "In5.Cu")
		(net "PCIE_TX_CAP_N75")
	)
	(segment
		(start 202.923394 -66.170556)
		(end 205.105 -64.643)
		(width 0.1397)
		(layer "In5.Cu")
		(net "PCIE_TX_CAP_N75")
	)
	(segment
		(start 222.153226 -46.55312)
		(end 222.10014 -46.500034)
		(width 0.1016)
		(layer "In5.Cu")
		(net "PCIE_TX_CAP_N75")
	)
	(segment
		(start 215.178132 -48.441102)
		(end 217.145616 -48.094138)
		(width 0.1397)
		(layer "In5.Cu")
		(net "PCIE_TX_CAP_N75")
	)
	(segment
		(start 218.170506 -47.376842)
		(end 219.24518 -47.187104)
		(width 0.1397)
		(layer "In5.Cu")
		(net "PCIE_TX_CAP_N75")
	)
	(segment
		(start 222.547688 -46.237652)
		(end 222.550228 -46.23943)
		(width 0.1016)
		(layer "In5.Cu")
		(net "PCIE_TX_CAP_N75")
	)
	(segment
		(start 222.688404 -46.470316)
		(end 222.688404 -46.471332)
		(width 0.1016)
		(layer "In5.Cu")
		(net "PCIE_TX_CAP_N75")
	)
	(segment
		(start 195.89369 -69.180456)
		(end 196.67093 -68.070476)
		(width 0.1397)
		(layer "In5.Cu")
		(net "PCIE_TX_CAP_N75")
	)
	(segment
		(start 48.5902 -208.293462)
		(end 48.716692 -207.57642)
		(width 0.1397)
		(layer "In5.Cu")
		(net "PCIE_TX_CAP_N75")
	)
	(segment
		(start 221.728284 -45.93209)
		(end 222.282766 -46.029626)
		(width 0.1016)
		(layer "In5.Cu")
		(net "PCIE_TX_CAP_N75")
	)
	(segment
		(start 222.546418 -46.236128)
		(end 222.547688 -46.237652)
		(width 0.1016)
		(layer "In5.Cu")
		(net "PCIE_TX_CAP_N75")
	)
	(segment
		(start 48.716692 -207.57642)
		(end 49.239424 -206.829914)
		(width 0.1397)
		(layer "In5.Cu")
		(net "PCIE_TX_CAP_N75")
	)
	(segment
		(start 222.48241 -46.169834)
		(end 222.529654 -46.217078)
		(width 0.1016)
		(layer "In5.Cu")
		(net "PCIE_TX_CAP_N75")
	)
	(segment
		(start 49.239424 -206.829914)
		(end 49.6824 -206.1972)
		(width 0.1397)
		(layer "In5.Cu")
		(net "PCIE_TX_CAP_N75")
	)
	(segment
		(start 222.282766 -46.029626)
		(end 222.48241 -46.169834)
		(width 0.1016)
		(layer "In5.Cu")
		(net "PCIE_TX_CAP_N75")
	)
	(segment
		(start 84.580476 -194.87134)
		(end 159.061404 -142.72006)
		(width 0.1397)
		(layer "In5.Cu")
		(net "PCIE_TX_CAP_N75")
	)
	(segment
		(start 196.872352 -79.121508)
		(end 195.506594 -71.376032)
		(width 0.1397)
		(layer "In5.Cu")
		(net "PCIE_TX_CAP_N75")
	)
	(segment
		(start 221.512384 -45.93209)
		(end 221.728284 -45.93209)
		(width 0.1016)
		(layer "In5.Cu")
		(net "PCIE_TX_CAP_N75")
	)
	(segment
		(start 211.332318 -51.055016)
		(end 215.178132 -48.441102)
		(width 0.1397)
		(layer "In5.Cu")
		(net "PCIE_TX_CAP_N75")
	)
	(segment
		(start 49.6824 -206.1972)
		(end 56.458866 -201.452226)
		(width 0.1397)
		(layer "In5.Cu")
		(net "PCIE_TX_CAP_N75")
	)
	(segment
		(start 205.63078 -63.892176)
		(end 206.739236 -57.614566)
		(width 0.1397)
		(layer "In5.Cu")
		(net "PCIE_TX_CAP_N75")
	)
	(arc
		(start 222.688404 -46.471332)
		(mid 222.666518 -46.558149)
		(end 222.606108 -46.62424)
		(width 0.1016)
		(layer "In5.Cu")
		(net "PCIE_TX_CAP_N75")
	)
	(arc
		(start 222.606108 -46.62424)
		(mid 222.561125 -46.654297)
		(end 222.508064 -46.66488)
		(width 0.1016)
		(layer "In5.Cu")
		(net "PCIE_TX_CAP_N75")
	)
	(arc
		(start 222.661734 -46.384718)
		(mid 222.682655 -46.425154)
		(end 222.688404 -46.470316)
		(width 0.1016)
		(layer "In5.Cu")
		(net "PCIE_TX_CAP_N75")
	)
	(arc
		(start 222.267526 -46.634146)
		(mid 222.206952 -46.598465)
		(end 222.153226 -46.55312)
		(width 0.1016)
		(layer "In5.Cu")
		(net "PCIE_TX_CAP_N75")
	)
	(arc
		(start 49.30648 -210.896454)
		(mid 49.127342 -210.584109)
		(end 49.06518 -210.22945)
		(width 0.1397)
		(layer "In5.Cu")
		(net "PCIE_TX_CAP_N75")
	)
	(arc
		(start 221.344998 -46.001432)
		(mid 221.421795 -45.950118)
		(end 221.512384 -45.93209)
		(width 0.1016)
		(layer "In5.Cu")
		(net "PCIE_TX_CAP_N75")
	)
	(arc
		(start 48.82769 -209.53349)
		(mid 48.651944 -209.270468)
		(end 48.5902 -208.960212)
		(width 0.1397)
		(layer "In5.Cu")
		(net "PCIE_TX_CAP_N75")
	)
	(arc
		(start 222.37065 -46.66488)
		(mid 222.332623 -46.660667)
		(end 222.296482 -46.648116)
		(width 0.1016)
		(layer "In5.Cu")
		(net "PCIE_TX_CAP_N75")
	)
	(arc
		(start 49.06518 -210.106768)
		(mid 49.003464 -209.796501)
		(end 48.82769 -209.53349)
		(width 0.1397)
		(layer "In5.Cu")
		(net "PCIE_TX_CAP_N75")
	)
	(segment
		(start 52.356766 -211.046314)
		(end 52.506372 -210.896454)
		(width 0.136652)
		(layer "F.Cu")
		(net "PCIE_TX_CAP_N74")
	)
	(segment
		(start 223.60001 -47.999904)
		(end 223.100138 -48.499776)
		(width 0.136652)
		(layer "F.Cu")
		(net "PCIE_TX_CAP_N74")
	)
	(segment
		(start 52.246022 -211.5312)
		(end 52.246022 -211.313268)
		(width 0.136652)
		(layer "F.Cu")
		(net "PCIE_TX_CAP_N74")
	)
	(segment
		(start 52.607972 -211.975954)
		(end 52.304696 -211.672424)
		(width 0.136652)
		(layer "F.Cu")
		(net "PCIE_TX_CAP_N74")
	)
	(via
		(at 223.100138 -48.499776)
		(size 0.4572)
		(drill 0.2032)
		(layers "F.Cu" "B.Cu")
		(net "PCIE_TX_CAP_N74")
	)
	(via
		(at 52.506372 -210.896454)
		(size 0.508)
		(drill 0.254)
		(layers "F.Cu" "B.Cu")
		(net "PCIE_TX_CAP_N74")
	)
	(arc
		(start 52.246022 -211.313268)
		(mid 52.274855 -211.168783)
		(end 52.356766 -211.046314)
		(width 0.136652)
		(layer "F.Cu")
		(net "PCIE_TX_CAP_N74")
	)
	(arc
		(start 52.304696 -211.672424)
		(mid 52.261319 -211.607645)
		(end 52.246022 -211.5312)
		(width 0.136652)
		(layer "F.Cu")
		(net "PCIE_TX_CAP_N74")
	)
	(segment
		(start 60.17514 -202.097132)
		(end 83.055968 -198.062596)
		(width 0.1397)
		(layer "In5.Cu")
		(net "PCIE_TX_CAP_N74")
	)
	(segment
		(start 205.045818 -80.4926)
		(end 206.156814 -74.191368)
		(width 0.1397)
		(layer "In5.Cu")
		(net "PCIE_TX_CAP_N74")
	)
	(segment
		(start 55.25389 -205.54315)
		(end 55.823612 -205.144116)
		(width 0.1397)
		(layer "In5.Cu")
		(net "PCIE_TX_CAP_N74")
	)
	(segment
		(start 160.72104 -143.680688)
		(end 160.986978 -143.415004)
		(width 0.1397)
		(layer "In5.Cu")
		(net "PCIE_TX_CAP_N74")
	)
	(segment
		(start 56.818276 -204.447648)
		(end 57.079896 -204.493876)
		(width 0.1397)
		(layer "In5.Cu")
		(net "PCIE_TX_CAP_N74")
	)
	(segment
		(start 206.156814 -74.191368)
		(end 205.380082 -69.7865)
		(width 0.1397)
		(layer "In5.Cu")
		(net "PCIE_TX_CAP_N74")
	)
	(segment
		(start 56.42864 -204.949806)
		(end 56.474868 -204.687932)
		(width 0.1397)
		(layer "In5.Cu")
		(net "PCIE_TX_CAP_N74")
	)
	(segment
		(start 58.463942 -203.29525)
		(end 60.17514 -202.097132)
		(width 0.1397)
		(layer "In5.Cu")
		(net "PCIE_TX_CAP_N74")
	)
	(segment
		(start 83.055968 -198.062596)
		(end 160.72104 -143.680688)
		(width 0.1397)
		(layer "In5.Cu")
		(net "PCIE_TX_CAP_N74")
	)
	(segment
		(start 217.743024 -48.893222)
		(end 218.080082 -48.657256)
		(width 0.1397)
		(layer "In5.Cu")
		(net "PCIE_TX_CAP_N74")
	)
	(segment
		(start 55.823612 -205.144116)
		(end 56.085486 -205.19009)
		(width 0.1397)
		(layer "In5.Cu")
		(net "PCIE_TX_CAP_N74")
	)
	(segment
		(start 221.10065 -48.124364)
		(end 221.102428 -48.12411)
		(width 0.1397)
		(layer "In5.Cu")
		(net "PCIE_TX_CAP_N74")
	)
	(segment
		(start 160.986978 -143.415004)
		(end 205.045818 -80.4926)
		(width 0.1397)
		(layer "In5.Cu")
		(net "PCIE_TX_CAP_N74")
	)
	(segment
		(start 217.440256 -48.946562)
		(end 217.44051 -48.946562)
		(width 0.1397)
		(layer "In5.Cu")
		(net "PCIE_TX_CAP_N74")
	)
	(segment
		(start 56.085486 -205.19009)
		(end 56.42864 -204.949806)
		(width 0.1397)
		(layer "In5.Cu")
		(net "PCIE_TX_CAP_N74")
	)
	(segment
		(start 223.100138 -48.50003)
		(end 223.100138 -48.499776)
		(width 0.1016)
		(layer "In5.Cu")
		(net "PCIE_TX_CAP_N74")
	)
	(segment
		(start 57.469532 -203.991718)
		(end 58.463942 -203.29525)
		(width 0.1397)
		(layer "In5.Cu")
		(net "PCIE_TX_CAP_N74")
	)
	(segment
		(start 218.080082 -48.657256)
		(end 221.10065 -48.124364)
		(width 0.1397)
		(layer "In5.Cu")
		(net "PCIE_TX_CAP_N74")
	)
	(segment
		(start 207.472788 -57.91835)
		(end 211.784438 -51.760628)
		(width 0.1397)
		(layer "In5.Cu")
		(net "PCIE_TX_CAP_N74")
	)
	(segment
		(start 52.265072 -210.22945)
		(end 52.265072 -209.811366)
		(width 0.1397)
		(layer "In5.Cu")
		(net "PCIE_TX_CAP_N74")
	)
	(segment
		(start 57.423304 -204.253338)
		(end 57.469532 -203.991718)
		(width 0.1397)
		(layer "In5.Cu")
		(net "PCIE_TX_CAP_N74")
	)
	(segment
		(start 221.102428 -48.12411)
		(end 222.419164 -48.001682)
		(width 0.1397)
		(layer "In5.Cu")
		(net "PCIE_TX_CAP_N74")
	)
	(segment
		(start 222.419164 -48.001682)
		(end 222.43034 -48.012858)
		(width 0.1016)
		(layer "In5.Cu")
		(net "PCIE_TX_CAP_N74")
	)
	(segment
		(start 223.27108 -48.670972)
		(end 223.100138 -48.50003)
		(width 0.1016)
		(layer "In5.Cu")
		(net "PCIE_TX_CAP_N74")
	)
	(segment
		(start 52.265072 -209.811366)
		(end 55.25389 -205.54315)
		(width 0.1397)
		(layer "In5.Cu")
		(net "PCIE_TX_CAP_N74")
	)
	(segment
		(start 57.079896 -204.493876)
		(end 57.423304 -204.253338)
		(width 0.1397)
		(layer "In5.Cu")
		(net "PCIE_TX_CAP_N74")
	)
	(segment
		(start 217.44051 -48.946562)
		(end 217.743024 -48.893222)
		(width 0.1397)
		(layer "In5.Cu")
		(net "PCIE_TX_CAP_N74")
	)
	(segment
		(start 223.616774 -48.397922)
		(end 223.62287 -48.514254)
		(width 0.1016)
		(layer "In5.Cu")
		(net "PCIE_TX_CAP_N74")
	)
	(segment
		(start 222.849948 -48.012858)
		(end 223.325436 -48.096678)
		(width 0.1016)
		(layer "In5.Cu")
		(net "PCIE_TX_CAP_N74")
	)
	(segment
		(start 56.474868 -204.687932)
		(end 56.818276 -204.447648)
		(width 0.1397)
		(layer "In5.Cu")
		(net "PCIE_TX_CAP_N74")
	)
	(segment
		(start 211.784438 -51.760628)
		(end 215.252554 -49.332134)
		(width 0.1397)
		(layer "In5.Cu")
		(net "PCIE_TX_CAP_N74")
	)
	(segment
		(start 215.252554 -49.332134)
		(end 217.440256 -48.946562)
		(width 0.1397)
		(layer "In5.Cu")
		(net "PCIE_TX_CAP_N74")
	)
	(segment
		(start 223.49714 -48.186086)
		(end 223.542606 -48.231552)
		(width 0.1016)
		(layer "In5.Cu")
		(net "PCIE_TX_CAP_N74")
	)
	(segment
		(start 222.43034 -48.012858)
		(end 222.849948 -48.012858)
		(width 0.1016)
		(layer "In5.Cu")
		(net "PCIE_TX_CAP_N74")
	)
	(segment
		(start 205.380082 -69.7865)
		(end 207.472788 -57.91835)
		(width 0.1397)
		(layer "In5.Cu")
		(net "PCIE_TX_CAP_N74")
	)
	(arc
		(start 52.506372 -210.896454)
		(mid 52.327234 -210.584109)
		(end 52.265072 -210.22945)
		(width 0.1397)
		(layer "In5.Cu")
		(net "PCIE_TX_CAP_N74")
	)
	(arc
		(start 223.542606 -48.231552)
		(mid 223.595077 -48.307874)
		(end 223.616774 -48.397922)
		(width 0.1016)
		(layer "In5.Cu")
		(net "PCIE_TX_CAP_N74")
	)
	(arc
		(start 223.62287 -48.514254)
		(mid 223.500837 -48.7136)
		(end 223.27108 -48.670972)
		(width 0.1016)
		(layer "In5.Cu")
		(net "PCIE_TX_CAP_N74")
	)
	(arc
		(start 223.325436 -48.096678)
		(mid 223.418151 -48.128197)
		(end 223.49714 -48.186086)
		(width 0.1016)
		(layer "In5.Cu")
		(net "PCIE_TX_CAP_N74")
	)
	(segment
		(start 55.446168 -211.5312)
		(end 55.446168 -211.282788)
		(width 0.136652)
		(layer "F.Cu")
		(net "PCIE_TX_CAP_N73")
	)
	(segment
		(start 55.808118 -211.975954)
		(end 55.504842 -211.672424)
		(width 0.136652)
		(layer "F.Cu")
		(net "PCIE_TX_CAP_N73")
	)
	(segment
		(start 55.535322 -211.067904)
		(end 55.706518 -210.896454)
		(width 0.136652)
		(layer "F.Cu")
		(net "PCIE_TX_CAP_N73")
	)
	(segment
		(start 222.600012 -48.999902)
		(end 222.10014 -49.499774)
		(width 0.136652)
		(layer "F.Cu")
		(net "PCIE_TX_CAP_N73")
	)
	(via
		(at 55.706518 -210.896454)
		(size 0.508)
		(drill 0.254)
		(layers "F.Cu" "B.Cu")
		(net "PCIE_TX_CAP_N73")
	)
	(via
		(at 222.10014 -49.499774)
		(size 0.4572)
		(drill 0.2032)
		(layers "F.Cu" "B.Cu")
		(net "PCIE_TX_CAP_N73")
	)
	(arc
		(start 55.504842 -211.672424)
		(mid 55.461465 -211.607645)
		(end 55.446168 -211.5312)
		(width 0.136652)
		(layer "F.Cu")
		(net "PCIE_TX_CAP_N73")
	)
	(arc
		(start 55.446168 -211.282788)
		(mid 55.469394 -211.166491)
		(end 55.535322 -211.067904)
		(width 0.136652)
		(layer "F.Cu")
		(net "PCIE_TX_CAP_N73")
	)
	(segment
		(start 58.420508 -205.104238)
		(end 58.682382 -205.150466)
		(width 0.1397)
		(layer "In5.Cu")
		(net "PCIE_TX_CAP_N73")
	)
	(segment
		(start 222.654876 -49.466246)
		(end 222.654876 -49.473612)
		(width 0.1016)
		(layer "In5.Cu")
		(net "PCIE_TX_CAP_N73")
	)
	(segment
		(start 59.676792 -204.453998)
		(end 60.0202 -204.213714)
		(width 0.1397)
		(layer "In5.Cu")
		(net "PCIE_TX_CAP_N73")
	)
	(segment
		(start 57.15 -205.994)
		(end 58.420508 -205.104238)
		(width 0.1397)
		(layer "In5.Cu")
		(net "PCIE_TX_CAP_N73")
	)
	(segment
		(start 205.890876 -80.641444)
		(end 207.01 -74.295)
		(width 0.1397)
		(layer "In5.Cu")
		(net "PCIE_TX_CAP_N73")
	)
	(segment
		(start 82.952082 -199.081644)
		(end 161.440368 -144.12341)
		(width 0.1397)
		(layer "In5.Cu")
		(net "PCIE_TX_CAP_N73")
	)
	(segment
		(start 59.071764 -204.648308)
		(end 59.415172 -204.408024)
		(width 0.1397)
		(layer "In5.Cu")
		(net "PCIE_TX_CAP_N73")
	)
	(segment
		(start 221.557088 -49.02581)
		(end 221.694756 -49.050194)
		(width 0.1397)
		(layer "In5.Cu")
		(net "PCIE_TX_CAP_N73")
	)
	(segment
		(start 222.153226 -49.55286)
		(end 222.10014 -49.499774)
		(width 0.1016)
		(layer "In5.Cu")
		(net "PCIE_TX_CAP_N73")
	)
	(segment
		(start 55.465218 -210.22945)
		(end 55.465218 -208.400142)
		(width 0.1397)
		(layer "In5.Cu")
		(net "PCIE_TX_CAP_N73")
	)
	(segment
		(start 222.477584 -49.66462)
		(end 222.37065 -49.66462)
		(width 0.1016)
		(layer "In5.Cu")
		(net "PCIE_TX_CAP_N73")
	)
	(segment
		(start 221.837758 -49.01057)
		(end 222.325438 -49.096676)
		(width 0.1016)
		(layer "In5.Cu")
		(net "PCIE_TX_CAP_N73")
	)
	(segment
		(start 207.01 -74.295)
		(end 206.248762 -69.977)
		(width 0.1397)
		(layer "In5.Cu")
		(net "PCIE_TX_CAP_N73")
	)
	(segment
		(start 222.296482 -49.647856)
		(end 222.267526 -49.633886)
		(width 0.1016)
		(layer "In5.Cu")
		(net "PCIE_TX_CAP_N73")
	)
	(segment
		(start 208.317592 -58.242962)
		(end 212.370924 -52.453286)
		(width 0.1397)
		(layer "In5.Cu")
		(net "PCIE_TX_CAP_N73")
	)
	(segment
		(start 221.694756 -49.050194)
		(end 221.719648 -49.054512)
		(width 0.1016)
		(layer "In5.Cu")
		(net "PCIE_TX_CAP_N73")
	)
	(segment
		(start 58.682382 -205.150466)
		(end 59.025536 -204.910182)
		(width 0.1397)
		(layer "In5.Cu")
		(net "PCIE_TX_CAP_N73")
	)
	(segment
		(start 60.066428 -203.95184)
		(end 61.660024 -202.836018)
		(width 0.1397)
		(layer "In5.Cu")
		(net "PCIE_TX_CAP_N73")
	)
	(segment
		(start 206.248762 -69.977)
		(end 208.317592 -58.242962)
		(width 0.1397)
		(layer "In5.Cu")
		(net "PCIE_TX_CAP_N73")
	)
	(segment
		(start 61.660024 -202.836018)
		(end 82.952082 -199.081644)
		(width 0.1397)
		(layer "In5.Cu")
		(net "PCIE_TX_CAP_N73")
	)
	(segment
		(start 161.440368 -144.12341)
		(end 205.890876 -80.641444)
		(width 0.1397)
		(layer "In5.Cu")
		(net "PCIE_TX_CAP_N73")
	)
	(segment
		(start 212.370924 -52.453286)
		(end 215.820498 -50.037746)
		(width 0.1397)
		(layer "In5.Cu")
		(net "PCIE_TX_CAP_N73")
	)
	(segment
		(start 221.719648 -49.054512)
		(end 221.756478 -49.028604)
		(width 0.1016)
		(layer "In5.Cu")
		(net "PCIE_TX_CAP_N73")
	)
	(segment
		(start 55.465218 -208.400142)
		(end 57.15 -205.994)
		(width 0.1397)
		(layer "In5.Cu")
		(net "PCIE_TX_CAP_N73")
	)
	(segment
		(start 60.0202 -204.213714)
		(end 60.066428 -203.95184)
		(width 0.1397)
		(layer "In5.Cu")
		(net "PCIE_TX_CAP_N73")
	)
	(segment
		(start 222.497142 -49.186084)
		(end 222.568262 -49.257204)
		(width 0.1016)
		(layer "In5.Cu")
		(net "PCIE_TX_CAP_N73")
	)
	(segment
		(start 215.820498 -50.037746)
		(end 221.557088 -49.02581)
		(width 0.1397)
		(layer "In5.Cu")
		(net "PCIE_TX_CAP_N73")
	)
	(segment
		(start 59.025536 -204.910182)
		(end 59.071764 -204.648308)
		(width 0.1397)
		(layer "In5.Cu")
		(net "PCIE_TX_CAP_N73")
	)
	(segment
		(start 222.56496 -49.640998)
		(end 222.536258 -49.652936)
		(width 0.1016)
		(layer "In5.Cu")
		(net "PCIE_TX_CAP_N73")
	)
	(segment
		(start 59.415172 -204.408024)
		(end 59.676792 -204.453998)
		(width 0.1397)
		(layer "In5.Cu")
		(net "PCIE_TX_CAP_N73")
	)
	(arc
		(start 222.325438 -49.096676)
		(mid 222.418153 -49.128195)
		(end 222.497142 -49.186084)
		(width 0.1016)
		(layer "In5.Cu")
		(net "PCIE_TX_CAP_N73")
	)
	(arc
		(start 222.37065 -49.66462)
		(mid 222.332623 -49.660407)
		(end 222.296482 -49.647856)
		(width 0.1016)
		(layer "In5.Cu")
		(net "PCIE_TX_CAP_N73")
	)
	(arc
		(start 222.568262 -49.257204)
		(mid 222.632347 -49.353113)
		(end 222.654876 -49.466246)
		(width 0.1016)
		(layer "In5.Cu")
		(net "PCIE_TX_CAP_N73")
	)
	(arc
		(start 55.706518 -210.896454)
		(mid 55.52738 -210.584109)
		(end 55.465218 -210.22945)
		(width 0.1397)
		(layer "In5.Cu")
		(net "PCIE_TX_CAP_N73")
	)
	(arc
		(start 222.536258 -49.652936)
		(mid 222.507496 -49.661675)
		(end 222.477584 -49.66462)
		(width 0.1016)
		(layer "In5.Cu")
		(net "PCIE_TX_CAP_N73")
	)
	(arc
		(start 222.267526 -49.633886)
		(mid 222.206952 -49.598205)
		(end 222.153226 -49.55286)
		(width 0.1016)
		(layer "In5.Cu")
		(net "PCIE_TX_CAP_N73")
	)
	(arc
		(start 221.756478 -49.028604)
		(mid 221.795317 -49.011498)
		(end 221.837758 -49.01057)
		(width 0.1016)
		(layer "In5.Cu")
		(net "PCIE_TX_CAP_N73")
	)
	(arc
		(start 222.654876 -49.473612)
		(mid 222.622223 -49.563919)
		(end 222.56496 -49.640998)
		(width 0.1016)
		(layer "In5.Cu")
		(net "PCIE_TX_CAP_N73")
	)
	(segment
		(start 58.74004 -211.062824)
		(end 58.90641 -210.896454)
		(width 0.136652)
		(layer "F.Cu")
		(net "PCIE_TX_CAP_N72")
	)
	(segment
		(start 59.00801 -211.975954)
		(end 58.704734 -211.672424)
		(width 0.136652)
		(layer "F.Cu")
		(net "PCIE_TX_CAP_N72")
	)
	(segment
		(start 58.64606 -211.5312)
		(end 58.64606 -211.289646)
		(width 0.136652)
		(layer "F.Cu")
		(net "PCIE_TX_CAP_N72")
	)
	(segment
		(start 223.60001 -49.9999)
		(end 223.100138 -50.499772)
		(width 0.136652)
		(layer "F.Cu")
		(net "PCIE_TX_CAP_N72")
	)
	(via
		(at 58.90641 -210.896454)
		(size 0.508)
		(drill 0.254)
		(layers "F.Cu" "B.Cu")
		(net "PCIE_TX_CAP_N72")
	)
	(via
		(at 223.100138 -50.499772)
		(size 0.4572)
		(drill 0.2032)
		(layers "F.Cu" "B.Cu")
		(net "PCIE_TX_CAP_N72")
	)
	(arc
		(start 58.64606 -211.289646)
		(mid 58.67048 -211.16688)
		(end 58.74004 -211.062824)
		(width 0.136652)
		(layer "F.Cu")
		(net "PCIE_TX_CAP_N72")
	)
	(arc
		(start 58.704734 -211.672424)
		(mid 58.661357 -211.607645)
		(end 58.64606 -211.5312)
		(width 0.136652)
		(layer "F.Cu")
		(net "PCIE_TX_CAP_N72")
	)
	(segment
		(start 60.325 -205.994)
		(end 58.66511 -208.364582)
		(width 0.1397)
		(layer "In5.Cu")
		(net "PCIE_TX_CAP_N72")
	)
	(segment
		(start 223.466152 -50.646076)
		(end 223.48698 -50.636424)
		(width 0.1016)
		(layer "In5.Cu")
		(net "PCIE_TX_CAP_N72")
	)
	(segment
		(start 216.375742 -51.166776)
		(end 214.123524 -52.743608)
		(width 0.1397)
		(layer "In5.Cu")
		(net "PCIE_TX_CAP_N72")
	)
	(segment
		(start 69.542914 -202.26274)
		(end 69.390514 -202.480672)
		(width 0.1397)
		(layer "In5.Cu")
		(net "PCIE_TX_CAP_N72")
	)
	(segment
		(start 68.347336 -202.47356)
		(end 68.194682 -202.691492)
		(width 0.1397)
		(layer "In5.Cu")
		(net "PCIE_TX_CAP_N72")
	)
	(segment
		(start 68.759832 -202.400916)
		(end 68.347336 -202.47356)
		(width 0.1397)
		(layer "In5.Cu")
		(net "PCIE_TX_CAP_N72")
	)
	(segment
		(start 223.38157 -50.661824)
		(end 223.410526 -50.660046)
		(width 0.1016)
		(layer "In5.Cu")
		(net "PCIE_TX_CAP_N72")
	)
	(segment
		(start 69.390514 -202.480672)
		(end 68.977764 -202.553316)
		(width 0.1397)
		(layer "In5.Cu")
		(net "PCIE_TX_CAP_N72")
	)
	(segment
		(start 223.550226 -50.239168)
		(end 223.465898 -50.15484)
		(width 0.1016)
		(layer "In5.Cu")
		(net "PCIE_TX_CAP_N72")
	)
	(segment
		(start 162.480244 -145.292572)
		(end 85.0138 -199.535034)
		(width 0.1397)
		(layer "In5.Cu")
		(net "PCIE_TX_CAP_N72")
	)
	(segment
		(start 213.207346 -54.051962)
		(end 208.777586 -79.17307)
		(width 0.1397)
		(layer "In5.Cu")
		(net "PCIE_TX_CAP_N72")
	)
	(segment
		(start 85.0138 -199.535034)
		(end 69.542914 -202.26274)
		(width 0.1397)
		(layer "In5.Cu")
		(net "PCIE_TX_CAP_N72")
	)
	(segment
		(start 223.327722 -50.654966)
		(end 223.345502 -50.65903)
		(width 0.1016)
		(layer "In5.Cu")
		(net "PCIE_TX_CAP_N72")
	)
	(segment
		(start 67.564254 -202.611736)
		(end 64.34455 -203.179426)
		(width 0.1397)
		(layer "In5.Cu")
		(net "PCIE_TX_CAP_N72")
	)
	(segment
		(start 64.34455 -203.179426)
		(end 60.325 -205.994)
		(width 0.1397)
		(layer "In5.Cu")
		(net "PCIE_TX_CAP_N72")
	)
	(segment
		(start 223.100138 -50.499772)
		(end 223.153224 -50.552858)
		(width 0.1016)
		(layer "In5.Cu")
		(net "PCIE_TX_CAP_N72")
	)
	(segment
		(start 214.123524 -52.743608)
		(end 213.207346 -54.051962)
		(width 0.1397)
		(layer "In5.Cu")
		(net "PCIE_TX_CAP_N72")
	)
	(segment
		(start 208.777586 -79.17307)
		(end 162.480244 -145.292572)
		(width 0.1397)
		(layer "In5.Cu")
		(net "PCIE_TX_CAP_N72")
	)
	(segment
		(start 222.183706 -50.242724)
		(end 221.628462 -50.797968)
		(width 0.1397)
		(layer "In5.Cu")
		(net "PCIE_TX_CAP_N72")
	)
	(segment
		(start 68.194682 -202.691492)
		(end 67.781932 -202.764136)
		(width 0.1397)
		(layer "In5.Cu")
		(net "PCIE_TX_CAP_N72")
	)
	(segment
		(start 67.781932 -202.764136)
		(end 67.564254 -202.611736)
		(width 0.1397)
		(layer "In5.Cu")
		(net "PCIE_TX_CAP_N72")
	)
	(segment
		(start 218.467432 -50.797968)
		(end 216.375742 -51.166776)
		(width 0.1397)
		(layer "In5.Cu")
		(net "PCIE_TX_CAP_N72")
	)
	(segment
		(start 223.325436 -50.096674)
		(end 222.664528 -50.096674)
		(width 0.1016)
		(layer "In5.Cu")
		(net "PCIE_TX_CAP_N72")
	)
	(segment
		(start 221.628462 -50.797968)
		(end 218.467432 -50.797968)
		(width 0.1397)
		(layer "In5.Cu")
		(net "PCIE_TX_CAP_N72")
	)
	(segment
		(start 58.66511 -208.364582)
		(end 58.66511 -210.22945)
		(width 0.1397)
		(layer "In5.Cu")
		(net "PCIE_TX_CAP_N72")
	)
	(segment
		(start 68.977764 -202.553316)
		(end 68.759832 -202.400916)
		(width 0.1397)
		(layer "In5.Cu")
		(net "PCIE_TX_CAP_N72")
	)
	(arc
		(start 223.410526 -50.660046)
		(mid 223.438996 -50.655674)
		(end 223.466152 -50.646076)
		(width 0.1016)
		(layer "In5.Cu")
		(net "PCIE_TX_CAP_N72")
	)
	(arc
		(start 223.561148 -50.570384)
		(mid 223.595499 -50.468882)
		(end 223.607122 -50.362358)
		(width 0.1016)
		(layer "In5.Cu")
		(net "PCIE_TX_CAP_N72")
	)
	(arc
		(start 223.607122 -50.362358)
		(mid 223.583831 -50.298381)
		(end 223.550226 -50.239168)
		(width 0.1016)
		(layer "In5.Cu")
		(net "PCIE_TX_CAP_N72")
	)
	(arc
		(start 58.66511 -210.22945)
		(mid 58.727294 -210.584101)
		(end 58.90641 -210.896454)
		(width 0.1397)
		(layer "In5.Cu")
		(net "PCIE_TX_CAP_N72")
	)
	(arc
		(start 222.664528 -50.096674)
		(mid 222.413268 -50.133988)
		(end 222.183706 -50.242724)
		(width 0.1016)
		(layer "In5.Cu")
		(net "PCIE_TX_CAP_N72")
	)
	(arc
		(start 223.465898 -50.15484)
		(mid 223.401453 -50.11178)
		(end 223.325436 -50.096674)
		(width 0.1016)
		(layer "In5.Cu")
		(net "PCIE_TX_CAP_N72")
	)
	(arc
		(start 223.345502 -50.65903)
		(mid 223.363435 -50.661736)
		(end 223.38157 -50.661824)
		(width 0.1016)
		(layer "In5.Cu")
		(net "PCIE_TX_CAP_N72")
	)
	(arc
		(start 223.153224 -50.552858)
		(mid 223.206937 -50.598222)
		(end 223.267524 -50.633884)
		(width 0.1016)
		(layer "In5.Cu")
		(net "PCIE_TX_CAP_N72")
	)
	(arc
		(start 223.267524 -50.633884)
		(mid 223.297021 -50.646147)
		(end 223.327722 -50.654966)
		(width 0.1016)
		(layer "In5.Cu")
		(net "PCIE_TX_CAP_N72")
	)
	(arc
		(start 223.48698 -50.636424)
		(mid 223.529037 -50.608988)
		(end 223.561148 -50.570384)
		(width 0.1016)
		(layer "In5.Cu")
		(net "PCIE_TX_CAP_N72")
	)
	(segment
		(start 64.245998 -211.5312)
		(end 64.245998 -211.325206)
		(width 0.136652)
		(layer "F.Cu")
		(net "PCIE_TX_CAP_N71")
	)
	(segment
		(start 64.607948 -211.975954)
		(end 64.304672 -211.672424)
		(width 0.136652)
		(layer "F.Cu")
		(net "PCIE_TX_CAP_N71")
	)
	(segment
		(start 222.600012 -51.999896)
		(end 222.10014 -52.499768)
		(width 0.136652)
		(layer "F.Cu")
		(net "PCIE_TX_CAP_N71")
	)
	(segment
		(start 64.365124 -211.037678)
		(end 64.506348 -210.896454)
		(width 0.136652)
		(layer "F.Cu")
		(net "PCIE_TX_CAP_N71")
	)
	(via
		(at 222.10014 -52.499768)
		(size 0.4572)
		(drill 0.2032)
		(layers "F.Cu" "B.Cu")
		(net "PCIE_TX_CAP_N71")
	)
	(via
		(at 64.506348 -210.896454)
		(size 0.508)
		(drill 0.254)
		(layers "F.Cu" "B.Cu")
		(net "PCIE_TX_CAP_N71")
	)
	(arc
		(start 64.245998 -211.325206)
		(mid 64.276953 -211.169586)
		(end 64.365124 -211.037678)
		(width 0.136652)
		(layer "F.Cu")
		(net "PCIE_TX_CAP_N71")
	)
	(arc
		(start 64.304672 -211.672424)
		(mid 64.261295 -211.607645)
		(end 64.245998 -211.5312)
		(width 0.136652)
		(layer "F.Cu")
		(net "PCIE_TX_CAP_N71")
	)
	(segment
		(start 76.055474 -202.71486)
		(end 75.642724 -202.787758)
		(width 0.1397)
		(layer "In5.Cu")
		(net "PCIE_TX_CAP_N71")
	)
	(segment
		(start 84.60359 -201.01687)
		(end 77.528166 -202.264518)
		(width 0.1397)
		(layer "In5.Cu")
		(net "PCIE_TX_CAP_N71")
	)
	(segment
		(start 75.642724 -202.787758)
		(end 75.425046 -202.635358)
		(width 0.1397)
		(layer "In5.Cu")
		(net "PCIE_TX_CAP_N71")
	)
	(segment
		(start 68.080128 -203.930504)
		(end 66.04 -205.359)
		(width 0.1397)
		(layer "In5.Cu")
		(net "PCIE_TX_CAP_N71")
	)
	(segment
		(start 75.425046 -202.635358)
		(end 75.012296 -202.708002)
		(width 0.1397)
		(layer "In5.Cu")
		(net "PCIE_TX_CAP_N71")
	)
	(segment
		(start 76.208128 -202.497182)
		(end 76.055474 -202.71486)
		(width 0.1397)
		(layer "In5.Cu")
		(net "PCIE_TX_CAP_N71")
	)
	(segment
		(start 75.012296 -202.708002)
		(end 74.859896 -202.92568)
		(width 0.1397)
		(layer "In5.Cu")
		(net "PCIE_TX_CAP_N71")
	)
	(segment
		(start 77.528166 -202.264518)
		(end 76.493878 -202.44689)
		(width 0.1397)
		(layer "In5.Cu")
		(net "PCIE_TX_CAP_N71")
	)
	(segment
		(start 221.6404 -52.1208)
		(end 218.7702 -52.1208)
		(width 0.1397)
		(layer "In5.Cu")
		(net "PCIE_TX_CAP_N71")
	)
	(segment
		(start 215.398858 -53.259482)
		(end 213.984332 -55.279798)
		(width 0.1397)
		(layer "In5.Cu")
		(net "PCIE_TX_CAP_N71")
	)
	(segment
		(start 74.859896 -202.92568)
		(end 74.447146 -202.998578)
		(width 0.1397)
		(layer "In5.Cu")
		(net "PCIE_TX_CAP_N71")
	)
	(segment
		(start 213.984332 -55.279798)
		(end 209.592672 -80.185768)
		(width 0.1397)
		(layer "In5.Cu")
		(net "PCIE_TX_CAP_N71")
	)
	(segment
		(start 74.447146 -202.998578)
		(end 74.229468 -202.846178)
		(width 0.1397)
		(layer "In5.Cu")
		(net "PCIE_TX_CAP_N71")
	)
	(segment
		(start 222.10014 -52.499768)
		(end 222.153226 -52.552854)
		(width 0.1016)
		(layer "In5.Cu")
		(net "PCIE_TX_CAP_N71")
	)
	(segment
		(start 222.506286 -52.195222)
		(end 222.4659 -52.154836)
		(width 0.1016)
		(layer "In5.Cu")
		(net "PCIE_TX_CAP_N71")
	)
	(segment
		(start 218.7702 -52.1208)
		(end 216.437464 -52.53228)
		(width 0.1397)
		(layer "In5.Cu")
		(net "PCIE_TX_CAP_N71")
	)
	(segment
		(start 66.04 -205.359)
		(end 64.265048 -207.89392)
		(width 0.1397)
		(layer "In5.Cu")
		(net "PCIE_TX_CAP_N71")
	)
	(segment
		(start 163.83 -145.542)
		(end 84.60359 -201.01687)
		(width 0.1397)
		(layer "In5.Cu")
		(net "PCIE_TX_CAP_N71")
	)
	(segment
		(start 74.229468 -202.846178)
		(end 68.080128 -203.930504)
		(width 0.1397)
		(layer "In5.Cu")
		(net "PCIE_TX_CAP_N71")
	)
	(segment
		(start 209.592672 -80.185768)
		(end 163.83 -145.542)
		(width 0.1397)
		(layer "In5.Cu")
		(net "PCIE_TX_CAP_N71")
	)
	(segment
		(start 222.267526 -52.63388)
		(end 222.296482 -52.64785)
		(width 0.1016)
		(layer "In5.Cu")
		(net "PCIE_TX_CAP_N71")
	)
	(segment
		(start 222.37065 -52.664614)
		(end 222.482918 -52.664614)
		(width 0.1016)
		(layer "In5.Cu")
		(net "PCIE_TX_CAP_N71")
	)
	(segment
		(start 216.437464 -52.53228)
		(end 215.398858 -53.259482)
		(width 0.1397)
		(layer "In5.Cu")
		(net "PCIE_TX_CAP_N71")
	)
	(segment
		(start 222.325438 -52.09667)
		(end 221.698566 -52.09667)
		(width 0.1016)
		(layer "In5.Cu")
		(net "PCIE_TX_CAP_N71")
	)
	(segment
		(start 222.531432 -52.654962)
		(end 222.556578 -52.644548)
		(width 0.1016)
		(layer "In5.Cu")
		(net "PCIE_TX_CAP_N71")
	)
	(segment
		(start 64.265048 -207.89392)
		(end 64.265048 -210.22945)
		(width 0.1397)
		(layer "In5.Cu")
		(net "PCIE_TX_CAP_N71")
	)
	(segment
		(start 76.493878 -202.44689)
		(end 76.208128 -202.497182)
		(width 0.1397)
		(layer "In5.Cu")
		(net "PCIE_TX_CAP_N71")
	)
	(arc
		(start 222.556578 -52.644548)
		(mid 222.620623 -52.555154)
		(end 222.655892 -52.451)
		(width 0.1016)
		(layer "In5.Cu")
		(net "PCIE_TX_CAP_N71")
	)
	(arc
		(start 222.588074 -52.28844)
		(mid 222.548701 -52.240496)
		(end 222.506286 -52.195222)
		(width 0.1016)
		(layer "In5.Cu")
		(net "PCIE_TX_CAP_N71")
	)
	(arc
		(start 221.698566 -52.09667)
		(mid 221.667073 -52.102934)
		(end 221.6404 -52.1208)
		(width 0.1016)
		(layer "In5.Cu")
		(net "PCIE_TX_CAP_N71")
	)
	(arc
		(start 222.153226 -52.552854)
		(mid 222.206939 -52.598218)
		(end 222.267526 -52.63388)
		(width 0.1016)
		(layer "In5.Cu")
		(net "PCIE_TX_CAP_N71")
	)
	(arc
		(start 64.265048 -210.22945)
		(mid 64.327232 -210.584101)
		(end 64.506348 -210.896454)
		(width 0.1397)
		(layer "In5.Cu")
		(net "PCIE_TX_CAP_N71")
	)
	(arc
		(start 222.4659 -52.154836)
		(mid 222.401455 -52.111776)
		(end 222.325438 -52.09667)
		(width 0.1016)
		(layer "In5.Cu")
		(net "PCIE_TX_CAP_N71")
	)
	(arc
		(start 222.296482 -52.64785)
		(mid 222.332626 -52.66039)
		(end 222.37065 -52.664614)
		(width 0.1016)
		(layer "In5.Cu")
		(net "PCIE_TX_CAP_N71")
	)
	(arc
		(start 222.655892 -52.451)
		(mid 222.632624 -52.365277)
		(end 222.588074 -52.28844)
		(width 0.1016)
		(layer "In5.Cu")
		(net "PCIE_TX_CAP_N71")
	)
	(arc
		(start 222.482918 -52.664614)
		(mid 222.50765 -52.662178)
		(end 222.531432 -52.654962)
		(width 0.1016)
		(layer "In5.Cu")
		(net "PCIE_TX_CAP_N71")
	)
	(segment
		(start 223.60001 -52.999894)
		(end 223.100138 -53.499766)
		(width 0.136652)
		(layer "F.Cu")
		(net "PCIE_TX_CAP_N70")
	)
	(segment
		(start 67.808094 -211.975954)
		(end 67.504818 -211.672424)
		(width 0.136652)
		(layer "F.Cu")
		(net "PCIE_TX_CAP_N70")
	)
	(segment
		(start 67.446144 -211.5312)
		(end 67.446144 -211.299298)
		(width 0.136652)
		(layer "F.Cu")
		(net "PCIE_TX_CAP_N70")
	)
	(segment
		(start 67.545204 -211.057998)
		(end 67.706494 -210.896454)
		(width 0.136652)
		(layer "F.Cu")
		(net "PCIE_TX_CAP_N70")
	)
	(via
		(at 223.100138 -53.499766)
		(size 0.4572)
		(drill 0.2032)
		(layers "F.Cu" "B.Cu")
		(net "PCIE_TX_CAP_N70")
	)
	(via
		(at 67.706494 -210.896454)
		(size 0.508)
		(drill 0.254)
		(layers "F.Cu" "B.Cu")
		(net "PCIE_TX_CAP_N70")
	)
	(arc
		(start 67.446144 -211.299298)
		(mid 67.446145 -211.298028)
		(end 67.446144 -211.296758)
		(width 0.136652)
		(layer "F.Cu")
		(net "PCIE_TX_CAP_N70")
	)
	(arc
		(start 67.446144 -211.296758)
		(mid 67.471942 -211.167534)
		(end 67.545204 -211.057998)
		(width 0.136652)
		(layer "F.Cu")
		(net "PCIE_TX_CAP_N70")
	)
	(arc
		(start 67.504818 -211.672424)
		(mid 67.461441 -211.607645)
		(end 67.446144 -211.5312)
		(width 0.136652)
		(layer "F.Cu")
		(net "PCIE_TX_CAP_N70")
	)
	(segment
		(start 72.1741 -204.525372)
		(end 71.956168 -204.372718)
		(width 0.1397)
		(layer "In5.Cu")
		(net "PCIE_TX_CAP_N70")
	)
	(segment
		(start 221.742 -53.1368)
		(end 219.1004 -53.1368)
		(width 0.1397)
		(layer "In5.Cu")
		(net "PCIE_TX_CAP_N70")
	)
	(segment
		(start 85.09 -202.057)
		(end 83.543394 -202.329542)
		(width 0.1397)
		(layer "In5.Cu")
		(net "PCIE_TX_CAP_N70")
	)
	(segment
		(start 73.152 -204.161898)
		(end 72.73925 -204.234796)
		(width 0.1397)
		(layer "In5.Cu")
		(net "PCIE_TX_CAP_N70")
	)
	(segment
		(start 74.211434 -203.975208)
		(end 73.934828 -204.023976)
		(width 0.1397)
		(layer "In5.Cu")
		(net "PCIE_TX_CAP_N70")
	)
	(segment
		(start 219.1004 -53.1368)
		(end 217.787474 -53.368194)
		(width 0.1397)
		(layer "In5.Cu")
		(net "PCIE_TX_CAP_N70")
	)
	(segment
		(start 223.325436 -53.096668)
		(end 221.838774 -53.096668)
		(width 0.1016)
		(layer "In5.Cu")
		(net "PCIE_TX_CAP_N70")
	)
	(segment
		(start 223.516952 -53.650896)
		(end 223.55175 -53.613304)
		(width 0.1016)
		(layer "In5.Cu")
		(net "PCIE_TX_CAP_N70")
	)
	(segment
		(start 83.543394 -202.329542)
		(end 80.133444 -202.931014)
		(width 0.1397)
		(layer "In5.Cu")
		(net "PCIE_TX_CAP_N70")
	)
	(segment
		(start 73.934828 -204.023976)
		(end 73.782428 -204.241654)
		(width 0.1397)
		(layer "In5.Cu")
		(net "PCIE_TX_CAP_N70")
	)
	(segment
		(start 68.966842 -205.913736)
		(end 67.465194 -208.058258)
		(width 0.1397)
		(layer "In5.Cu")
		(net "PCIE_TX_CAP_N70")
	)
	(segment
		(start 70.902322 -204.558646)
		(end 68.966842 -205.913736)
		(width 0.1397)
		(layer "In5.Cu")
		(net "PCIE_TX_CAP_N70")
	)
	(segment
		(start 223.563434 -53.27269)
		(end 223.465898 -53.154834)
		(width 0.1016)
		(layer "In5.Cu")
		(net "PCIE_TX_CAP_N70")
	)
	(segment
		(start 73.782428 -204.241654)
		(end 73.369678 -204.314552)
		(width 0.1397)
		(layer "In5.Cu")
		(net "PCIE_TX_CAP_N70")
	)
	(segment
		(start 214.502238 -56.806592)
		(end 210.225894 -81.05902)
		(width 0.1397)
		(layer "In5.Cu")
		(net "PCIE_TX_CAP_N70")
	)
	(segment
		(start 216.065354 -54.574186)
		(end 214.502238 -56.806592)
		(width 0.1397)
		(layer "In5.Cu")
		(net "PCIE_TX_CAP_N70")
	)
	(segment
		(start 75.13066 -203.813156)
		(end 74.211434 -203.975208)
		(width 0.1397)
		(layer "In5.Cu")
		(net "PCIE_TX_CAP_N70")
	)
	(segment
		(start 72.58685 -204.452474)
		(end 72.1741 -204.525372)
		(width 0.1397)
		(layer "In5.Cu")
		(net "PCIE_TX_CAP_N70")
	)
	(segment
		(start 217.787474 -53.368194)
		(end 216.065354 -54.574186)
		(width 0.1397)
		(layer "In5.Cu")
		(net "PCIE_TX_CAP_N70")
	)
	(segment
		(start 72.73925 -204.234796)
		(end 72.58685 -204.452474)
		(width 0.1397)
		(layer "In5.Cu")
		(net "PCIE_TX_CAP_N70")
	)
	(segment
		(start 67.465194 -208.058258)
		(end 67.465194 -210.22945)
		(width 0.1397)
		(layer "In5.Cu")
		(net "PCIE_TX_CAP_N70")
	)
	(segment
		(start 164.366702 -146.546824)
		(end 85.09 -202.057)
		(width 0.1397)
		(layer "In5.Cu")
		(net "PCIE_TX_CAP_N70")
	)
	(segment
		(start 73.369678 -204.314552)
		(end 73.152 -204.161898)
		(width 0.1397)
		(layer "In5.Cu")
		(net "PCIE_TX_CAP_N70")
	)
	(segment
		(start 71.956168 -204.372718)
		(end 70.902322 -204.558646)
		(width 0.1397)
		(layer "In5.Cu")
		(net "PCIE_TX_CAP_N70")
	)
	(segment
		(start 210.225894 -81.05902)
		(end 164.366702 -146.546824)
		(width 0.1397)
		(layer "In5.Cu")
		(net "PCIE_TX_CAP_N70")
	)
	(segment
		(start 80.133444 -202.931014)
		(end 75.13066 -203.813156)
		(width 0.1397)
		(layer "In5.Cu")
		(net "PCIE_TX_CAP_N70")
	)
	(arc
		(start 223.465898 -53.154834)
		(mid 223.401453 -53.111774)
		(end 223.325436 -53.096668)
		(width 0.1016)
		(layer "In5.Cu")
		(net "PCIE_TX_CAP_N70")
	)
	(arc
		(start 221.838774 -53.096668)
		(mid 221.786382 -53.107089)
		(end 221.742 -53.1368)
		(width 0.1016)
		(layer "In5.Cu")
		(net "PCIE_TX_CAP_N70")
	)
	(arc
		(start 223.414082 -53.6956)
		(mid 223.47019 -53.683995)
		(end 223.516952 -53.650896)
		(width 0.1016)
		(layer "In5.Cu")
		(net "PCIE_TX_CAP_N70")
	)
	(arc
		(start 67.465194 -210.22945)
		(mid 67.527378 -210.584101)
		(end 67.706494 -210.896454)
		(width 0.1397)
		(layer "In5.Cu")
		(net "PCIE_TX_CAP_N70")
	)
	(arc
		(start 223.6216 -53.444648)
		(mid 223.608355 -53.353306)
		(end 223.563434 -53.27269)
		(width 0.1016)
		(layer "In5.Cu")
		(net "PCIE_TX_CAP_N70")
	)
	(arc
		(start 223.100138 -53.499766)
		(mid 223.181843 -53.607324)
		(end 223.298258 -53.675788)
		(width 0.1016)
		(layer "In5.Cu")
		(net "PCIE_TX_CAP_N70")
	)
	(arc
		(start 223.55175 -53.613304)
		(mid 223.601766 -53.535231)
		(end 223.6216 -53.444648)
		(width 0.1016)
		(layer "In5.Cu")
		(net "PCIE_TX_CAP_N70")
	)
	(arc
		(start 223.298258 -53.675788)
		(mid 223.35533 -53.690609)
		(end 223.414082 -53.6956)
		(width 0.1016)
		(layer "In5.Cu")
		(net "PCIE_TX_CAP_N70")
	)
	(segment
		(start 304.4063 -34.61639)
		(end 304.4063 -35.8521)
		(width 0.136652)
		(layer "F.Cu")
		(net "PCIE_TX_CAP_N7")
	)
	(segment
		(start 304.541174 -36.177728)
		(end 304.6476 -36.284154)
		(width 0.136652)
		(layer "F.Cu")
		(net "PCIE_TX_CAP_N7")
	)
	(segment
		(start 258.59994 -30.999938)
		(end 259.099812 -30.500066)
		(width 0.136652)
		(layer "F.Cu")
		(net "PCIE_TX_CAP_N7")
	)
	(via
		(at 259.099812 -30.500066)
		(size 0.4572)
		(drill 0.2032)
		(layers "F.Cu" "B.Cu")
		(net "PCIE_TX_CAP_N7")
	)
	(via
		(at 304.6476 -36.284154)
		(size 0.508)
		(drill 0.254)
		(layers "F.Cu" "B.Cu")
		(net "PCIE_TX_CAP_N7")
	)
	(arc
		(start 304.4063 -35.8521)
		(mid 304.441354 -36.028326)
		(end 304.541174 -36.177728)
		(width 0.136652)
		(layer "F.Cu")
		(net "PCIE_TX_CAP_N7")
	)
	(arc
		(start 304.673 -33.9725)
		(mid 304.475607 -34.267919)
		(end 304.4063 -34.61639)
		(width 0.136652)
		(layer "F.Cu")
		(net "PCIE_TX_CAP_N7")
	)
	(segment
		(start 273.525234 -31.294324)
		(end 268.09192 -30.336236)
		(width 0.1397)
		(layer "In5.Cu")
		(net "PCIE_TX_CAP_N7")
	)
	(segment
		(start 259.607558 -31.398464)
		(end 259.341112 -31.132018)
		(width 0.1397)
		(layer "In5.Cu")
		(net "PCIE_TX_CAP_N7")
	)
	(segment
		(start 297.07713 -41.874186)
		(end 292.130226 -41.002204)
		(width 0.1397)
		(layer "In5.Cu")
		(net "PCIE_TX_CAP_N7")
	)
	(segment
		(start 277.50643 -34.082228)
		(end 273.525234 -31.294324)
		(width 0.1397)
		(layer "In5.Cu")
		(net "PCIE_TX_CAP_N7")
	)
	(segment
		(start 304.4063 -37.421058)
		(end 304.204624 -38.175438)
		(width 0.1397)
		(layer "In5.Cu")
		(net "PCIE_TX_CAP_N7")
	)
	(segment
		(start 265.352022 -30.819344)
		(end 265.20775 -31.025338)
		(width 0.1397)
		(layer "In5.Cu")
		(net "PCIE_TX_CAP_N7")
	)
	(segment
		(start 268.09192 -30.336236)
		(end 265.352022 -30.819344)
		(width 0.1397)
		(layer "In5.Cu")
		(net "PCIE_TX_CAP_N7")
	)
	(segment
		(start 283.06395 -39.564818)
		(end 283.063188 -39.564564)
		(width 0.1397)
		(layer "In5.Cu")
		(net "PCIE_TX_CAP_N7")
	)
	(segment
		(start 264.795 -31.097982)
		(end 264.589006 -30.953964)
		(width 0.1397)
		(layer "In5.Cu")
		(net "PCIE_TX_CAP_N7")
	)
	(segment
		(start 264.176256 -31.026608)
		(end 264.031984 -31.232602)
		(width 0.1397)
		(layer "In5.Cu")
		(net "PCIE_TX_CAP_N7")
	)
	(segment
		(start 262.067548 -31.398464)
		(end 259.607558 -31.398464)
		(width 0.1397)
		(layer "In5.Cu")
		(net "PCIE_TX_CAP_N7")
	)
	(segment
		(start 259.341112 -30.741366)
		(end 259.099812 -30.500066)
		(width 0.1397)
		(layer "In5.Cu")
		(net "PCIE_TX_CAP_N7")
	)
	(segment
		(start 303.383442 -39.81577)
		(end 301.644812 -41.0337)
		(width 0.1397)
		(layer "In5.Cu")
		(net "PCIE_TX_CAP_N7")
	)
	(segment
		(start 304.4063 -37.062156)
		(end 304.4063 -37.421058)
		(width 0.1397)
		(layer "In5.Cu")
		(net "PCIE_TX_CAP_N7")
	)
	(segment
		(start 259.341112 -31.132018)
		(end 259.341112 -30.741366)
		(width 0.1397)
		(layer "In5.Cu")
		(net "PCIE_TX_CAP_N7")
	)
	(segment
		(start 265.20775 -31.025338)
		(end 264.795 -31.097982)
		(width 0.1397)
		(layer "In5.Cu")
		(net "PCIE_TX_CAP_N7")
	)
	(segment
		(start 263.41324 -31.161228)
		(end 262.067548 -31.398464)
		(width 0.1397)
		(layer "In5.Cu")
		(net "PCIE_TX_CAP_N7")
	)
	(segment
		(start 264.589006 -30.953964)
		(end 264.176256 -31.026608)
		(width 0.1397)
		(layer "In5.Cu")
		(net "PCIE_TX_CAP_N7")
	)
	(segment
		(start 304.204624 -38.175438)
		(end 303.383442 -39.81577)
		(width 0.1397)
		(layer "In5.Cu")
		(net "PCIE_TX_CAP_N7")
	)
	(segment
		(start 292.130226 -41.002204)
		(end 291.2237 -41.16197)
		(width 0.1397)
		(layer "In5.Cu")
		(net "PCIE_TX_CAP_N7")
	)
	(segment
		(start 263.619234 -31.3055)
		(end 263.41324 -31.161228)
		(width 0.1397)
		(layer "In5.Cu")
		(net "PCIE_TX_CAP_N7")
	)
	(segment
		(start 264.031984 -31.232602)
		(end 263.619234 -31.3055)
		(width 0.1397)
		(layer "In5.Cu")
		(net "PCIE_TX_CAP_N7")
	)
	(segment
		(start 291.2237 -41.16197)
		(end 283.06395 -39.564818)
		(width 0.1397)
		(layer "In5.Cu")
		(net "PCIE_TX_CAP_N7")
	)
	(segment
		(start 301.644812 -41.0337)
		(end 297.07713 -41.874186)
		(width 0.1397)
		(layer "In5.Cu")
		(net "PCIE_TX_CAP_N7")
	)
	(segment
		(start 279.692608 -37.204142)
		(end 277.50643 -34.082228)
		(width 0.1397)
		(layer "In5.Cu")
		(net "PCIE_TX_CAP_N7")
	)
	(segment
		(start 283.063188 -39.564564)
		(end 279.692608 -37.204142)
		(width 0.1397)
		(layer "In5.Cu")
		(net "PCIE_TX_CAP_N7")
	)
	(arc
		(start 304.6476 -36.284154)
		(mid 304.468014 -36.654875)
		(end 304.4063 -37.062156)
		(width 0.1397)
		(layer "In5.Cu")
		(net "PCIE_TX_CAP_N7")
	)
	(segment
		(start 71.007986 -211.975954)
		(end 70.70471 -211.672424)
		(width 0.136652)
		(layer "F.Cu")
		(net "PCIE_TX_CAP_N69")
	)
	(segment
		(start 222.600012 -53.999892)
		(end 222.10014 -54.499764)
		(width 0.136652)
		(layer "F.Cu")
		(net "PCIE_TX_CAP_N69")
	)
	(segment
		(start 70.646036 -211.5312)
		(end 70.646036 -211.313776)
		(width 0.136652)
		(layer "F.Cu")
		(net "PCIE_TX_CAP_N69")
	)
	(segment
		(start 70.757034 -211.045806)
		(end 70.906386 -210.896454)
		(width 0.136652)
		(layer "F.Cu")
		(net "PCIE_TX_CAP_N69")
	)
	(via
		(at 70.906386 -210.896454)
		(size 0.508)
		(drill 0.254)
		(layers "F.Cu" "B.Cu")
		(net "PCIE_TX_CAP_N69")
	)
	(via
		(at 222.10014 -54.499764)
		(size 0.4572)
		(drill 0.2032)
		(layers "F.Cu" "B.Cu")
		(net "PCIE_TX_CAP_N69")
	)
	(arc
		(start 70.646036 -211.313776)
		(mid 70.674883 -211.168751)
		(end 70.757034 -211.045806)
		(width 0.136652)
		(layer "F.Cu")
		(net "PCIE_TX_CAP_N69")
	)
	(arc
		(start 70.70471 -211.672424)
		(mid 70.661333 -211.607645)
		(end 70.646036 -211.5312)
		(width 0.136652)
		(layer "F.Cu")
		(net "PCIE_TX_CAP_N69")
	)
	(segment
		(start 71.755 -206.629)
		(end 70.665086 -208.185512)
		(width 0.1397)
		(layer "In5.Cu")
		(net "PCIE_TX_CAP_N69")
	)
	(segment
		(start 77.70749 -204.692504)
		(end 77.29474 -204.765402)
		(width 0.1397)
		(layer "In5.Cu")
		(net "PCIE_TX_CAP_N69")
	)
	(segment
		(start 78.27264 -204.402182)
		(end 77.85989 -204.474826)
		(width 0.1397)
		(layer "In5.Cu")
		(net "PCIE_TX_CAP_N69")
	)
	(segment
		(start 222.267526 -54.633876)
		(end 222.296482 -54.647846)
		(width 0.1016)
		(layer "In5.Cu")
		(net "PCIE_TX_CAP_N69")
	)
	(segment
		(start 221.799404 -54.145942)
		(end 221.7928 -54.1528)
		(width 0.1016)
		(layer "In5.Cu")
		(net "PCIE_TX_CAP_N69")
	)
	(segment
		(start 73.8124 -205.188566)
		(end 71.755 -206.629)
		(width 0.1397)
		(layer "In5.Cu")
		(net "PCIE_TX_CAP_N69")
	)
	(segment
		(start 79.055722 -204.264006)
		(end 78.27264 -204.402182)
		(width 0.1397)
		(layer "In5.Cu")
		(net "PCIE_TX_CAP_N69")
	)
	(segment
		(start 77.077062 -204.613002)
		(end 76.664312 -204.685646)
		(width 0.1397)
		(layer "In5.Cu")
		(net "PCIE_TX_CAP_N69")
	)
	(segment
		(start 218.37142 -54.348634)
		(end 216.845642 -55.416958)
		(width 0.1397)
		(layer "In5.Cu")
		(net "PCIE_TX_CAP_N69")
	)
	(segment
		(start 76.099162 -204.976222)
		(end 75.881484 -204.823822)
		(width 0.1397)
		(layer "In5.Cu")
		(net "PCIE_TX_CAP_N69")
	)
	(segment
		(start 222.37065 -54.66461)
		(end 222.43796 -54.66461)
		(width 0.1016)
		(layer "In5.Cu")
		(net "PCIE_TX_CAP_N69")
	)
	(segment
		(start 76.664312 -204.685646)
		(end 76.511912 -204.903324)
		(width 0.1397)
		(layer "In5.Cu")
		(net "PCIE_TX_CAP_N69")
	)
	(segment
		(start 222.325438 -54.096666)
		(end 221.918784 -54.096666)
		(width 0.1016)
		(layer "In5.Cu")
		(net "PCIE_TX_CAP_N69")
	)
	(segment
		(start 76.511912 -204.903324)
		(end 76.099162 -204.976222)
		(width 0.1397)
		(layer "In5.Cu")
		(net "PCIE_TX_CAP_N69")
	)
	(segment
		(start 219.4814 -54.1528)
		(end 218.37142 -54.348634)
		(width 0.1397)
		(layer "In5.Cu")
		(net "PCIE_TX_CAP_N69")
	)
	(segment
		(start 211.494878 -80.988916)
		(end 165.196012 -147.10918)
		(width 0.1397)
		(layer "In5.Cu")
		(net "PCIE_TX_CAP_N69")
	)
	(segment
		(start 77.85989 -204.474826)
		(end 77.70749 -204.692504)
		(width 0.1397)
		(layer "In5.Cu")
		(net "PCIE_TX_CAP_N69")
	)
	(segment
		(start 70.665086 -208.185512)
		(end 70.665086 -210.1088)
		(width 0.1397)
		(layer "In5.Cu")
		(net "PCIE_TX_CAP_N69")
	)
	(segment
		(start 215.720168 -57.02427)
		(end 211.494878 -80.988916)
		(width 0.1397)
		(layer "In5.Cu")
		(net "PCIE_TX_CAP_N69")
	)
	(segment
		(start 221.7928 -54.1528)
		(end 219.4814 -54.1528)
		(width 0.1397)
		(layer "In5.Cu")
		(net "PCIE_TX_CAP_N69")
	)
	(segment
		(start 222.56877 -54.59984)
		(end 222.589598 -54.572408)
		(width 0.1016)
		(layer "In5.Cu")
		(net "PCIE_TX_CAP_N69")
	)
	(segment
		(start 165.196012 -147.10918)
		(end 85.09 -203.2)
		(width 0.1397)
		(layer "In5.Cu")
		(net "PCIE_TX_CAP_N69")
	)
	(segment
		(start 77.29474 -204.765402)
		(end 77.077062 -204.613002)
		(width 0.1397)
		(layer "In5.Cu")
		(net "PCIE_TX_CAP_N69")
	)
	(segment
		(start 85.09 -203.2)
		(end 79.055722 -204.264006)
		(width 0.1397)
		(layer "In5.Cu")
		(net "PCIE_TX_CAP_N69")
	)
	(segment
		(start 222.10014 -54.499764)
		(end 222.153226 -54.55285)
		(width 0.1016)
		(layer "In5.Cu")
		(net "PCIE_TX_CAP_N69")
	)
	(segment
		(start 75.881484 -204.823822)
		(end 73.8124 -205.188566)
		(width 0.1397)
		(layer "In5.Cu")
		(net "PCIE_TX_CAP_N69")
	)
	(segment
		(start 216.845642 -55.416958)
		(end 215.720168 -57.02427)
		(width 0.1397)
		(layer "In5.Cu")
		(net "PCIE_TX_CAP_N69")
	)
	(arc
		(start 222.59925 -54.316122)
		(mid 222.536389 -54.232324)
		(end 222.4659 -54.154832)
		(width 0.1016)
		(layer "In5.Cu")
		(net "PCIE_TX_CAP_N69")
	)
	(arc
		(start 70.665086 -210.1088)
		(mid 70.726765 -210.520692)
		(end 70.906386 -210.896454)
		(width 0.1397)
		(layer "In5.Cu")
		(net "PCIE_TX_CAP_N69")
	)
	(arc
		(start 222.153226 -54.55285)
		(mid 222.206939 -54.598214)
		(end 222.267526 -54.633876)
		(width 0.1016)
		(layer "In5.Cu")
		(net "PCIE_TX_CAP_N69")
	)
	(arc
		(start 222.296482 -54.647846)
		(mid 222.332626 -54.660386)
		(end 222.37065 -54.66461)
		(width 0.1016)
		(layer "In5.Cu")
		(net "PCIE_TX_CAP_N69")
	)
	(arc
		(start 222.589598 -54.572408)
		(mid 222.63642 -54.445863)
		(end 222.59925 -54.316122)
		(width 0.1016)
		(layer "In5.Cu")
		(net "PCIE_TX_CAP_N69")
	)
	(arc
		(start 222.4659 -54.154832)
		(mid 222.401455 -54.111772)
		(end 222.325438 -54.096666)
		(width 0.1016)
		(layer "In5.Cu")
		(net "PCIE_TX_CAP_N69")
	)
	(arc
		(start 222.43796 -54.66461)
		(mid 222.51098 -54.647593)
		(end 222.56877 -54.59984)
		(width 0.1016)
		(layer "In5.Cu")
		(net "PCIE_TX_CAP_N69")
	)
	(arc
		(start 221.918784 -54.096666)
		(mid 221.854188 -54.109421)
		(end 221.799404 -54.145942)
		(width 0.1016)
		(layer "In5.Cu")
		(net "PCIE_TX_CAP_N69")
	)
	(segment
		(start 80.607916 -211.975954)
		(end 80.30464 -211.672424)
		(width 0.136652)
		(layer "F.Cu")
		(net "PCIE_TX_CAP_N68")
	)
	(segment
		(start 80.321404 -211.081366)
		(end 80.506316 -210.896454)
		(width 0.136652)
		(layer "F.Cu")
		(net "PCIE_TX_CAP_N68")
	)
	(segment
		(start 223.60001 -54.99989)
		(end 223.100138 -55.499762)
		(width 0.136652)
		(layer "F.Cu")
		(net "PCIE_TX_CAP_N68")
	)
	(segment
		(start 80.245966 -211.5312)
		(end 80.245966 -211.263484)
		(width 0.136652)
		(layer "F.Cu")
		(net "PCIE_TX_CAP_N68")
	)
	(via
		(at 223.100138 -55.499762)
		(size 0.4572)
		(drill 0.2032)
		(layers "F.Cu" "B.Cu")
		(net "PCIE_TX_CAP_N68")
	)
	(via
		(at 80.506316 -210.896454)
		(size 0.508)
		(drill 0.254)
		(layers "F.Cu" "B.Cu")
		(net "PCIE_TX_CAP_N68")
	)
	(arc
		(start 80.245966 -211.263484)
		(mid 80.265571 -211.164922)
		(end 80.321404 -211.081366)
		(width 0.136652)
		(layer "F.Cu")
		(net "PCIE_TX_CAP_N68")
	)
	(arc
		(start 80.30464 -211.672424)
		(mid 80.261263 -211.607645)
		(end 80.245966 -211.5312)
		(width 0.136652)
		(layer "F.Cu")
		(net "PCIE_TX_CAP_N68")
	)
	(segment
		(start 164.833554 -149.280118)
		(end 85.02269 -205.16469)
		(width 0.1397)
		(layer "In5.Cu")
		(net "PCIE_TX_CAP_N68")
	)
	(segment
		(start 212.717888 -81.281778)
		(end 212.717888 -81.282032)
		(width 0.1397)
		(layer "In5.Cu")
		(net "PCIE_TX_CAP_N68")
	)
	(segment
		(start 83.263994 -206.398876)
		(end 83.218274 -206.660496)
		(width 0.1397)
		(layer "In5.Cu")
		(net "PCIE_TX_CAP_N68")
	)
	(segment
		(start 165.3667 -148.906992)
		(end 164.833554 -149.280118)
		(width 0.1397)
		(layer "In5.Cu")
		(net "PCIE_TX_CAP_N68")
	)
	(segment
		(start 221.7674 -55.1688)
		(end 219.671138 -55.1688)
		(width 0.1397)
		(layer "In5.Cu")
		(net "PCIE_TX_CAP_N68")
	)
	(segment
		(start 219.671138 -55.1688)
		(end 218.992958 -55.288434)
		(width 0.1397)
		(layer "In5.Cu")
		(net "PCIE_TX_CAP_N68")
	)
	(segment
		(start 85.02269 -205.16469)
		(end 83.263994 -206.398876)
		(width 0.1397)
		(layer "In5.Cu")
		(net "PCIE_TX_CAP_N68")
	)
	(segment
		(start 212.717888 -81.282032)
		(end 165.3667 -148.906992)
		(width 0.1397)
		(layer "In5.Cu")
		(net "PCIE_TX_CAP_N68")
	)
	(segment
		(start 223.267524 -55.633874)
		(end 223.29648 -55.647844)
		(width 0.1016)
		(layer "In5.Cu")
		(net "PCIE_TX_CAP_N68")
	)
	(segment
		(start 81.881218 -207.598772)
		(end 81.619598 -207.552798)
		(width 0.1397)
		(layer "In5.Cu")
		(net "PCIE_TX_CAP_N68")
	)
	(segment
		(start 80.265016 -209.20329)
		(end 80.265016 -210.22945)
		(width 0.1397)
		(layer "In5.Cu")
		(net "PCIE_TX_CAP_N68")
	)
	(segment
		(start 81.619598 -207.552798)
		(end 81.228946 -207.826864)
		(width 0.1397)
		(layer "In5.Cu")
		(net "PCIE_TX_CAP_N68")
	)
	(segment
		(start 223.568768 -55.599838)
		(end 223.589596 -55.572406)
		(width 0.1016)
		(layer "In5.Cu")
		(net "PCIE_TX_CAP_N68")
	)
	(segment
		(start 82.224372 -207.35798)
		(end 81.881218 -207.598772)
		(width 0.1397)
		(layer "In5.Cu")
		(net "PCIE_TX_CAP_N68")
	)
	(segment
		(start 83.218274 -206.660496)
		(end 82.87512 -206.901288)
		(width 0.1397)
		(layer "In5.Cu")
		(net "PCIE_TX_CAP_N68")
	)
	(segment
		(start 81.228946 -207.826864)
		(end 80.265016 -209.20329)
		(width 0.1397)
		(layer "In5.Cu")
		(net "PCIE_TX_CAP_N68")
	)
	(segment
		(start 82.87512 -206.901288)
		(end 82.613246 -206.855314)
		(width 0.1397)
		(layer "In5.Cu")
		(net "PCIE_TX_CAP_N68")
	)
	(segment
		(start 217.926158 -56.035448)
		(end 216.914984 -57.479438)
		(width 0.1397)
		(layer "In5.Cu")
		(net "PCIE_TX_CAP_N68")
	)
	(segment
		(start 223.370648 -55.664608)
		(end 223.437958 -55.664608)
		(width 0.1016)
		(layer "In5.Cu")
		(net "PCIE_TX_CAP_N68")
	)
	(segment
		(start 82.613246 -206.855314)
		(end 82.270346 -207.096106)
		(width 0.1397)
		(layer "In5.Cu")
		(net "PCIE_TX_CAP_N68")
	)
	(segment
		(start 223.100138 -55.499762)
		(end 223.153224 -55.552848)
		(width 0.1016)
		(layer "In5.Cu")
		(net "PCIE_TX_CAP_N68")
	)
	(segment
		(start 82.270346 -207.096106)
		(end 82.224372 -207.35798)
		(width 0.1397)
		(layer "In5.Cu")
		(net "PCIE_TX_CAP_N68")
	)
	(segment
		(start 223.325436 -55.096664)
		(end 221.941644 -55.096664)
		(width 0.1016)
		(layer "In5.Cu")
		(net "PCIE_TX_CAP_N68")
	)
	(segment
		(start 216.914984 -57.479438)
		(end 212.717888 -81.281778)
		(width 0.1397)
		(layer "In5.Cu")
		(net "PCIE_TX_CAP_N68")
	)
	(segment
		(start 218.992958 -55.288434)
		(end 217.926158 -56.035448)
		(width 0.1397)
		(layer "In5.Cu")
		(net "PCIE_TX_CAP_N68")
	)
	(arc
		(start 223.599248 -55.31612)
		(mid 223.536387 -55.232322)
		(end 223.465898 -55.15483)
		(width 0.1016)
		(layer "In5.Cu")
		(net "PCIE_TX_CAP_N68")
	)
	(arc
		(start 221.941644 -55.096664)
		(mid 221.847358 -55.115419)
		(end 221.7674 -55.1688)
		(width 0.1016)
		(layer "In5.Cu")
		(net "PCIE_TX_CAP_N68")
	)
	(arc
		(start 223.29648 -55.647844)
		(mid 223.332624 -55.660384)
		(end 223.370648 -55.664608)
		(width 0.1016)
		(layer "In5.Cu")
		(net "PCIE_TX_CAP_N68")
	)
	(arc
		(start 223.437958 -55.664608)
		(mid 223.510978 -55.647591)
		(end 223.568768 -55.599838)
		(width 0.1016)
		(layer "In5.Cu")
		(net "PCIE_TX_CAP_N68")
	)
	(arc
		(start 223.465898 -55.15483)
		(mid 223.401453 -55.11177)
		(end 223.325436 -55.096664)
		(width 0.1016)
		(layer "In5.Cu")
		(net "PCIE_TX_CAP_N68")
	)
	(arc
		(start 223.589596 -55.572406)
		(mid 223.636418 -55.445861)
		(end 223.599248 -55.31612)
		(width 0.1016)
		(layer "In5.Cu")
		(net "PCIE_TX_CAP_N68")
	)
	(arc
		(start 223.153224 -55.552848)
		(mid 223.206937 -55.598212)
		(end 223.267524 -55.633874)
		(width 0.1016)
		(layer "In5.Cu")
		(net "PCIE_TX_CAP_N68")
	)
	(arc
		(start 80.265016 -210.22945)
		(mid 80.3272 -210.584101)
		(end 80.506316 -210.896454)
		(width 0.1397)
		(layer "In5.Cu")
		(net "PCIE_TX_CAP_N68")
	)
	(segment
		(start 83.446112 -211.5312)
		(end 83.446112 -211.313522)
		(width 0.136652)
		(layer "F.Cu")
		(net "PCIE_TX_CAP_N67")
	)
	(segment
		(start 222.600012 -55.999888)
		(end 222.10014 -56.49976)
		(width 0.136652)
		(layer "F.Cu")
		(net "PCIE_TX_CAP_N67")
	)
	(segment
		(start 83.808062 -211.975954)
		(end 83.504786 -211.672424)
		(width 0.136652)
		(layer "F.Cu")
		(net "PCIE_TX_CAP_N67")
	)
	(segment
		(start 83.556856 -211.045806)
		(end 83.706462 -210.896454)
		(width 0.136652)
		(layer "F.Cu")
		(net "PCIE_TX_CAP_N67")
	)
	(via
		(at 83.706462 -210.896454)
		(size 0.508)
		(drill 0.254)
		(layers "F.Cu" "B.Cu")
		(net "PCIE_TX_CAP_N67")
	)
	(via
		(at 222.10014 -56.49976)
		(size 0.4572)
		(drill 0.2032)
		(layers "F.Cu" "B.Cu")
		(net "PCIE_TX_CAP_N67")
	)
	(arc
		(start 83.446112 -211.313522)
		(mid 83.474838 -211.168638)
		(end 83.556856 -211.045806)
		(width 0.136652)
		(layer "F.Cu")
		(net "PCIE_TX_CAP_N67")
	)
	(arc
		(start 83.504786 -211.672424)
		(mid 83.461409 -211.607645)
		(end 83.446112 -211.5312)
		(width 0.136652)
		(layer "F.Cu")
		(net "PCIE_TX_CAP_N67")
	)
	(segment
		(start 217.826844 -58.11774)
		(end 218.656408 -56.933084)
		(width 0.1397)
		(layer "In5.Cu")
		(net "PCIE_TX_CAP_N67")
	)
	(segment
		(start 219.659962 -56.23052)
		(end 220.063822 -56.1594)
		(width 0.1397)
		(layer "In5.Cu")
		(net "PCIE_TX_CAP_N67")
	)
	(segment
		(start 85.725 -205.867)
		(end 166.068756 -149.60981)
		(width 0.1397)
		(layer "In5.Cu")
		(net "PCIE_TX_CAP_N67")
	)
	(segment
		(start 220.063822 -56.1594)
		(end 221.7674 -56.1594)
		(width 0.1397)
		(layer "In5.Cu")
		(net "PCIE_TX_CAP_N67")
	)
	(segment
		(start 83.465162 -209.09407)
		(end 83.81492 -208.594452)
		(width 0.1397)
		(layer "In5.Cu")
		(net "PCIE_TX_CAP_N67")
	)
	(segment
		(start 84.317078 -208.20507)
		(end 84.271104 -207.943196)
		(width 0.1397)
		(layer "In5.Cu")
		(net "PCIE_TX_CAP_N67")
	)
	(segment
		(start 84.076794 -208.548478)
		(end 84.317078 -208.20507)
		(width 0.1397)
		(layer "In5.Cu")
		(net "PCIE_TX_CAP_N67")
	)
	(segment
		(start 221.918784 -56.096662)
		(end 222.325438 -56.096662)
		(width 0.1016)
		(layer "In5.Cu")
		(net "PCIE_TX_CAP_N67")
	)
	(segment
		(start 83.465162 -210.22945)
		(end 83.465162 -209.09407)
		(width 0.1397)
		(layer "In5.Cu")
		(net "PCIE_TX_CAP_N67")
	)
	(segment
		(start 84.271104 -207.943196)
		(end 84.511388 -207.600042)
		(width 0.1397)
		(layer "In5.Cu")
		(net "PCIE_TX_CAP_N67")
	)
	(segment
		(start 84.511388 -207.600042)
		(end 84.773262 -207.553814)
		(width 0.1397)
		(layer "In5.Cu")
		(net "PCIE_TX_CAP_N67")
	)
	(segment
		(start 222.4659 -56.154828)
		(end 222.614236 -56.303164)
		(width 0.1016)
		(layer "In5.Cu")
		(net "PCIE_TX_CAP_N67")
	)
	(segment
		(start 222.588074 -56.563514)
		(end 222.569278 -56.58231)
		(width 0.1016)
		(layer "In5.Cu")
		(net "PCIE_TX_CAP_N67")
	)
	(segment
		(start 213.68512 -81.60639)
		(end 217.826844 -58.11774)
		(width 0.1397)
		(layer "In5.Cu")
		(net "PCIE_TX_CAP_N67")
	)
	(segment
		(start 83.81492 -208.594452)
		(end 84.076794 -208.548478)
		(width 0.1397)
		(layer "In5.Cu")
		(net "PCIE_TX_CAP_N67")
	)
	(segment
		(start 84.773262 -207.553814)
		(end 85.013546 -207.21066)
		(width 0.1397)
		(layer "In5.Cu")
		(net "PCIE_TX_CAP_N67")
	)
	(segment
		(start 166.068756 -149.60981)
		(end 213.68512 -81.60639)
		(width 0.1397)
		(layer "In5.Cu")
		(net "PCIE_TX_CAP_N67")
	)
	(segment
		(start 84.967572 -206.948786)
		(end 85.725 -205.867)
		(width 0.1397)
		(layer "In5.Cu")
		(net "PCIE_TX_CAP_N67")
	)
	(segment
		(start 222.296482 -56.647842)
		(end 222.267526 -56.633872)
		(width 0.1016)
		(layer "In5.Cu")
		(net "PCIE_TX_CAP_N67")
	)
	(segment
		(start 222.662242 -56.418988)
		(end 222.662242 -56.43626)
		(width 0.1016)
		(layer "In5.Cu")
		(net "PCIE_TX_CAP_N67")
	)
	(segment
		(start 222.153226 -56.552846)
		(end 222.10014 -56.49976)
		(width 0.1016)
		(layer "In5.Cu")
		(net "PCIE_TX_CAP_N67")
	)
	(segment
		(start 218.656408 -56.933084)
		(end 219.659962 -56.23052)
		(width 0.1397)
		(layer "In5.Cu")
		(net "PCIE_TX_CAP_N67")
	)
	(segment
		(start 85.013546 -207.21066)
		(end 84.967572 -206.948786)
		(width 0.1397)
		(layer "In5.Cu")
		(net "PCIE_TX_CAP_N67")
	)
	(arc
		(start 222.267526 -56.633872)
		(mid 222.206952 -56.598191)
		(end 222.153226 -56.552846)
		(width 0.1016)
		(layer "In5.Cu")
		(net "PCIE_TX_CAP_N67")
	)
	(arc
		(start 222.656146 -56.466994)
		(mid 222.627481 -56.519041)
		(end 222.588074 -56.563514)
		(width 0.1016)
		(layer "In5.Cu")
		(net "PCIE_TX_CAP_N67")
	)
	(arc
		(start 222.614236 -56.303164)
		(mid 222.649743 -56.356305)
		(end 222.662242 -56.418988)
		(width 0.1016)
		(layer "In5.Cu")
		(net "PCIE_TX_CAP_N67")
	)
	(arc
		(start 83.706462 -210.896454)
		(mid 83.527324 -210.584109)
		(end 83.465162 -210.22945)
		(width 0.1397)
		(layer "In5.Cu")
		(net "PCIE_TX_CAP_N67")
	)
	(arc
		(start 222.569278 -56.58231)
		(mid 222.478147 -56.643202)
		(end 222.37065 -56.664606)
		(width 0.1016)
		(layer "In5.Cu")
		(net "PCIE_TX_CAP_N67")
	)
	(arc
		(start 222.37065 -56.664606)
		(mid 222.332623 -56.660393)
		(end 222.296482 -56.647842)
		(width 0.1016)
		(layer "In5.Cu")
		(net "PCIE_TX_CAP_N67")
	)
	(arc
		(start 222.662242 -56.43626)
		(mid 222.660703 -56.451926)
		(end 222.656146 -56.466994)
		(width 0.1016)
		(layer "In5.Cu")
		(net "PCIE_TX_CAP_N67")
	)
	(arc
		(start 221.7674 -56.1594)
		(mid 221.836856 -56.112991)
		(end 221.918784 -56.096662)
		(width 0.1016)
		(layer "In5.Cu")
		(net "PCIE_TX_CAP_N67")
	)
	(arc
		(start 222.325438 -56.096662)
		(mid 222.40145 -56.111782)
		(end 222.4659 -56.154828)
		(width 0.1016)
		(layer "In5.Cu")
		(net "PCIE_TX_CAP_N67")
	)
	(segment
		(start 86.646004 -211.5312)
		(end 86.646004 -211.313522)
		(width 0.136652)
		(layer "F.Cu")
		(net "PCIE_TX_CAP_N66")
	)
	(segment
		(start 223.60001 -56.999886)
		(end 223.100138 -57.499758)
		(width 0.136652)
		(layer "F.Cu")
		(net "PCIE_TX_CAP_N66")
	)
	(segment
		(start 87.007954 -211.975954)
		(end 86.704678 -211.672424)
		(width 0.136652)
		(layer "F.Cu")
		(net "PCIE_TX_CAP_N66")
	)
	(segment
		(start 86.756748 -211.045806)
		(end 86.906354 -210.896454)
		(width 0.136652)
		(layer "F.Cu")
		(net "PCIE_TX_CAP_N66")
	)
	(via
		(at 86.906354 -210.896454)
		(size 0.508)
		(drill 0.254)
		(layers "F.Cu" "B.Cu")
		(net "PCIE_TX_CAP_N66")
	)
	(via
		(at 223.100138 -57.499758)
		(size 0.4572)
		(drill 0.2032)
		(layers "F.Cu" "B.Cu")
		(net "PCIE_TX_CAP_N66")
	)
	(arc
		(start 86.646004 -211.313522)
		(mid 86.67473 -211.168638)
		(end 86.756748 -211.045806)
		(width 0.136652)
		(layer "F.Cu")
		(net "PCIE_TX_CAP_N66")
	)
	(arc
		(start 86.704678 -211.672424)
		(mid 86.661301 -211.607645)
		(end 86.646004 -211.5312)
		(width 0.136652)
		(layer "F.Cu")
		(net "PCIE_TX_CAP_N66")
	)
	(segment
		(start 223.437958 -57.664604)
		(end 223.370648 -57.664604)
		(width 0.1016)
		(layer "In5.Cu")
		(net "PCIE_TX_CAP_N66")
	)
	(segment
		(start 218.78036 -58.594752)
		(end 219.217494 -57.970674)
		(width 0.1397)
		(layer "In5.Cu")
		(net "PCIE_TX_CAP_N66")
	)
	(segment
		(start 220.27007 -57.233566)
		(end 220.74378 -57.15)
		(width 0.1397)
		(layer "In5.Cu")
		(net "PCIE_TX_CAP_N66")
	)
	(segment
		(start 218.621864 -60.576714)
		(end 218.46921 -60.359036)
		(width 0.1397)
		(layer "In5.Cu")
		(net "PCIE_TX_CAP_N66")
	)
	(segment
		(start 216.67851 -70.514718)
		(end 217.27414 -67.137026)
		(width 0.1397)
		(layer "In5.Cu")
		(net "PCIE_TX_CAP_N66")
	)
	(segment
		(start 88.542368 -205.4352)
		(end 167.005 -150.495)
		(width 0.1397)
		(layer "In5.Cu")
		(net "PCIE_TX_CAP_N66")
	)
	(segment
		(start 217.71991 -64.609472)
		(end 217.753438 -64.418972)
		(width 0.1397)
		(layer "In5.Cu")
		(net "PCIE_TX_CAP_N66")
	)
	(segment
		(start 219.217494 -57.970674)
		(end 220.27007 -57.233566)
		(width 0.1397)
		(layer "In5.Cu")
		(net "PCIE_TX_CAP_N66")
	)
	(segment
		(start 215.830658 -75.323446)
		(end 216.67851 -70.514718)
		(width 0.1397)
		(layer "In5.Cu")
		(net "PCIE_TX_CAP_N66")
	)
	(segment
		(start 218.68003 -59.163204)
		(end 218.78036 -58.594752)
		(width 0.1397)
		(layer "In5.Cu")
		(net "PCIE_TX_CAP_N66")
	)
	(segment
		(start 217.559382 -65.5193)
		(end 217.71991 -64.609472)
		(width 0.1397)
		(layer "In5.Cu")
		(net "PCIE_TX_CAP_N66")
	)
	(segment
		(start 218.46921 -60.359036)
		(end 218.542108 -59.946286)
		(width 0.1397)
		(layer "In5.Cu")
		(net "PCIE_TX_CAP_N66")
	)
	(segment
		(start 214.547958 -82.596736)
		(end 215.236806 -78.69174)
		(width 0.1397)
		(layer "In5.Cu")
		(net "PCIE_TX_CAP_N66")
	)
	(segment
		(start 217.908378 -63.540894)
		(end 218.120468 -62.337696)
		(width 0.1397)
		(layer "In5.Cu")
		(net "PCIE_TX_CAP_N66")
	)
	(segment
		(start 220.74378 -57.15)
		(end 221.8182 -57.15)
		(width 0.1397)
		(layer "In5.Cu")
		(net "PCIE_TX_CAP_N66")
	)
	(segment
		(start 218.548966 -60.989464)
		(end 218.621864 -60.576714)
		(width 0.1397)
		(layer "In5.Cu")
		(net "PCIE_TX_CAP_N66")
	)
	(segment
		(start 218.759786 -59.793886)
		(end 218.832684 -59.381136)
		(width 0.1397)
		(layer "In5.Cu")
		(net "PCIE_TX_CAP_N66")
	)
	(segment
		(start 218.331288 -61.141864)
		(end 218.548966 -60.989464)
		(width 0.1397)
		(layer "In5.Cu")
		(net "PCIE_TX_CAP_N66")
	)
	(segment
		(start 215.236806 -78.69174)
		(end 215.830658 -75.323446)
		(width 0.1397)
		(layer "In5.Cu")
		(net "PCIE_TX_CAP_N66")
	)
	(segment
		(start 86.665054 -210.22945)
		(end 86.665054 -208.11617)
		(width 0.1397)
		(layer "In5.Cu")
		(net "PCIE_TX_CAP_N66")
	)
	(segment
		(start 217.27414 -67.137026)
		(end 217.559382 -65.5193)
		(width 0.1397)
		(layer "In5.Cu")
		(net "PCIE_TX_CAP_N66")
	)
	(segment
		(start 223.153224 -57.552844)
		(end 223.100138 -57.499758)
		(width 0.1016)
		(layer "In5.Cu")
		(net "PCIE_TX_CAP_N66")
	)
	(segment
		(start 218.120468 -62.337696)
		(end 218.277948 -61.444378)
		(width 0.1397)
		(layer "In5.Cu")
		(net "PCIE_TX_CAP_N66")
	)
	(segment
		(start 217.753438 -64.418972)
		(end 217.908378 -63.540894)
		(width 0.1397)
		(layer "In5.Cu")
		(net "PCIE_TX_CAP_N66")
	)
	(segment
		(start 223.29648 -57.64784)
		(end 223.267524 -57.63387)
		(width 0.1016)
		(layer "In5.Cu")
		(net "PCIE_TX_CAP_N66")
	)
	(segment
		(start 86.665054 -208.11617)
		(end 88.542368 -205.4352)
		(width 0.1397)
		(layer "In5.Cu")
		(net "PCIE_TX_CAP_N66")
	)
	(segment
		(start 221.946978 -57.09666)
		(end 223.325436 -57.09666)
		(width 0.1016)
		(layer "In5.Cu")
		(net "PCIE_TX_CAP_N66")
	)
	(segment
		(start 223.589596 -57.572402)
		(end 223.568768 -57.599834)
		(width 0.1016)
		(layer "In5.Cu")
		(net "PCIE_TX_CAP_N66")
	)
	(segment
		(start 167.005 -150.495)
		(end 214.547958 -82.596736)
		(width 0.1397)
		(layer "In5.Cu")
		(net "PCIE_TX_CAP_N66")
	)
	(segment
		(start 218.832684 -59.381136)
		(end 218.68003 -59.163204)
		(width 0.1397)
		(layer "In5.Cu")
		(net "PCIE_TX_CAP_N66")
	)
	(segment
		(start 218.542108 -59.946286)
		(end 218.759786 -59.793886)
		(width 0.1397)
		(layer "In5.Cu")
		(net "PCIE_TX_CAP_N66")
	)
	(segment
		(start 218.277948 -61.444378)
		(end 218.331288 -61.141864)
		(width 0.1397)
		(layer "In5.Cu")
		(net "PCIE_TX_CAP_N66")
	)
	(arc
		(start 221.8182 -57.15)
		(mid 221.877284 -57.110521)
		(end 221.946978 -57.09666)
		(width 0.1016)
		(layer "In5.Cu")
		(net "PCIE_TX_CAP_N66")
	)
	(arc
		(start 223.568768 -57.599834)
		(mid 223.510958 -57.647545)
		(end 223.437958 -57.664604)
		(width 0.1016)
		(layer "In5.Cu")
		(net "PCIE_TX_CAP_N66")
	)
	(arc
		(start 223.325436 -57.09666)
		(mid 223.401448 -57.11178)
		(end 223.465898 -57.154826)
		(width 0.1016)
		(layer "In5.Cu")
		(net "PCIE_TX_CAP_N66")
	)
	(arc
		(start 86.906354 -210.896454)
		(mid 86.727216 -210.584109)
		(end 86.665054 -210.22945)
		(width 0.1397)
		(layer "In5.Cu")
		(net "PCIE_TX_CAP_N66")
	)
	(arc
		(start 223.599248 -57.316116)
		(mid 223.636519 -57.445861)
		(end 223.589596 -57.572402)
		(width 0.1016)
		(layer "In5.Cu")
		(net "PCIE_TX_CAP_N66")
	)
	(arc
		(start 223.370648 -57.664604)
		(mid 223.332621 -57.660391)
		(end 223.29648 -57.64784)
		(width 0.1016)
		(layer "In5.Cu")
		(net "PCIE_TX_CAP_N66")
	)
	(arc
		(start 223.267524 -57.63387)
		(mid 223.20695 -57.598189)
		(end 223.153224 -57.552844)
		(width 0.1016)
		(layer "In5.Cu")
		(net "PCIE_TX_CAP_N66")
	)
	(arc
		(start 223.465898 -57.154826)
		(mid 223.536389 -57.232316)
		(end 223.599248 -57.316116)
		(width 0.1016)
		(layer "In5.Cu")
		(net "PCIE_TX_CAP_N66")
	)
	(segment
		(start 222.600012 -57.999884)
		(end 222.10014 -58.499756)
		(width 0.136652)
		(layer "F.Cu")
		(net "PCIE_TX_CAP_N65")
	)
	(segment
		(start 89.971626 -211.031074)
		(end 90.1065 -210.896454)
		(width 0.136652)
		(layer "F.Cu")
		(net "PCIE_TX_CAP_N65")
	)
	(segment
		(start 90.2081 -211.975954)
		(end 89.904824 -211.672424)
		(width 0.136652)
		(layer "F.Cu")
		(net "PCIE_TX_CAP_N65")
	)
	(segment
		(start 89.84615 -211.5312)
		(end 89.84615 -211.33435)
		(width 0.136652)
		(layer "F.Cu")
		(net "PCIE_TX_CAP_N65")
	)
	(via
		(at 222.10014 -58.499756)
		(size 0.4572)
		(drill 0.2032)
		(layers "F.Cu" "B.Cu")
		(net "PCIE_TX_CAP_N65")
	)
	(via
		(at 90.1065 -210.896454)
		(size 0.508)
		(drill 0.254)
		(layers "F.Cu" "B.Cu")
		(net "PCIE_TX_CAP_N65")
	)
	(arc
		(start 89.84615 -211.33435)
		(mid 89.878704 -211.17022)
		(end 89.971626 -211.031074)
		(width 0.136652)
		(layer "F.Cu")
		(net "PCIE_TX_CAP_N65")
	)
	(arc
		(start 89.904824 -211.672424)
		(mid 89.861447 -211.607645)
		(end 89.84615 -211.5312)
		(width 0.136652)
		(layer "F.Cu")
		(net "PCIE_TX_CAP_N65")
	)
	(segment
		(start 220.047566 -59.16422)
		(end 220.50756 -58.507376)
		(width 0.1397)
		(layer "In5.Cu")
		(net "PCIE_TX_CAP_N65")
	)
	(segment
		(start 219.87002 -60.171076)
		(end 220.047566 -59.16422)
		(width 0.1397)
		(layer "In5.Cu")
		(net "PCIE_TX_CAP_N65")
	)
	(segment
		(start 219.8116 -61.584586)
		(end 219.6592 -61.366654)
		(width 0.1397)
		(layer "In5.Cu")
		(net "PCIE_TX_CAP_N65")
	)
	(segment
		(start 217.017346 -76.349352)
		(end 217.8685 -71.52259)
		(width 0.1397)
		(layer "In5.Cu")
		(net "PCIE_TX_CAP_N65")
	)
	(segment
		(start 219.732098 -60.953904)
		(end 219.949776 -60.801504)
		(width 0.1397)
		(layer "In5.Cu")
		(net "PCIE_TX_CAP_N65")
	)
	(segment
		(start 218.448128 -68.234052)
		(end 219.310204 -63.345314)
		(width 0.1397)
		(layer "In5.Cu")
		(net "PCIE_TX_CAP_N65")
	)
	(segment
		(start 89.8652 -210.22945)
		(end 89.8652 -207.385158)
		(width 0.1397)
		(layer "In5.Cu")
		(net "PCIE_TX_CAP_N65")
	)
	(segment
		(start 219.465144 -62.467236)
		(end 219.521024 -62.149736)
		(width 0.1397)
		(layer "In5.Cu")
		(net "PCIE_TX_CAP_N65")
	)
	(segment
		(start 219.6592 -61.366654)
		(end 219.732098 -60.953904)
		(width 0.1397)
		(layer "In5.Cu")
		(net "PCIE_TX_CAP_N65")
	)
	(segment
		(start 91.984576 -204.358494)
		(end 167.64 -151.384)
		(width 0.1397)
		(layer "In5.Cu")
		(net "PCIE_TX_CAP_N65")
	)
	(segment
		(start 217.8685 -71.52259)
		(end 218.448128 -68.234052)
		(width 0.1397)
		(layer "In5.Cu")
		(net "PCIE_TX_CAP_N65")
	)
	(segment
		(start 222.153226 -58.552842)
		(end 222.10014 -58.499756)
		(width 0.1016)
		(layer "In5.Cu")
		(net "PCIE_TX_CAP_N65")
	)
	(segment
		(start 219.310204 -63.345314)
		(end 219.465144 -62.467236)
		(width 0.1397)
		(layer "In5.Cu")
		(net "PCIE_TX_CAP_N65")
	)
	(segment
		(start 222.44431 -58.664602)
		(end 222.37065 -58.664602)
		(width 0.1016)
		(layer "In5.Cu")
		(net "PCIE_TX_CAP_N65")
	)
	(segment
		(start 167.64 -151.384)
		(end 215.952832 -82.38617)
		(width 0.1397)
		(layer "In5.Cu")
		(net "PCIE_TX_CAP_N65")
	)
	(segment
		(start 222.601536 -58.530236)
		(end 222.57385 -58.590434)
		(width 0.1016)
		(layer "In5.Cu")
		(net "PCIE_TX_CAP_N65")
	)
	(segment
		(start 220.902022 -58.231278)
		(end 221.2721 -58.166)
		(width 0.1397)
		(layer "In5.Cu")
		(net "PCIE_TX_CAP_N65")
	)
	(segment
		(start 221.2721 -58.166)
		(end 221.6404 -58.166)
		(width 0.1397)
		(layer "In5.Cu")
		(net "PCIE_TX_CAP_N65")
	)
	(segment
		(start 222.296482 -58.647838)
		(end 222.267526 -58.633868)
		(width 0.1016)
		(layer "In5.Cu")
		(net "PCIE_TX_CAP_N65")
	)
	(segment
		(start 216.426542 -79.699612)
		(end 217.017346 -76.349352)
		(width 0.1397)
		(layer "In5.Cu")
		(net "PCIE_TX_CAP_N65")
	)
	(segment
		(start 221.807786 -58.096658)
		(end 222.325438 -58.096658)
		(width 0.1016)
		(layer "In5.Cu")
		(net "PCIE_TX_CAP_N65")
	)
	(segment
		(start 89.8652 -207.385158)
		(end 91.984576 -204.358494)
		(width 0.1397)
		(layer "In5.Cu")
		(net "PCIE_TX_CAP_N65")
	)
	(segment
		(start 220.50756 -58.507376)
		(end 220.902022 -58.231278)
		(width 0.1397)
		(layer "In5.Cu")
		(net "PCIE_TX_CAP_N65")
	)
	(segment
		(start 219.738956 -61.997336)
		(end 219.8116 -61.584586)
		(width 0.1397)
		(layer "In5.Cu")
		(net "PCIE_TX_CAP_N65")
	)
	(segment
		(start 219.949776 -60.801504)
		(end 220.02242 -60.388754)
		(width 0.1397)
		(layer "In5.Cu")
		(net "PCIE_TX_CAP_N65")
	)
	(segment
		(start 215.952832 -82.38617)
		(end 216.426542 -79.699612)
		(width 0.1397)
		(layer "In5.Cu")
		(net "PCIE_TX_CAP_N65")
	)
	(segment
		(start 219.521024 -62.149736)
		(end 219.738956 -61.997336)
		(width 0.1397)
		(layer "In5.Cu")
		(net "PCIE_TX_CAP_N65")
	)
	(segment
		(start 220.02242 -60.388754)
		(end 219.87002 -60.171076)
		(width 0.1397)
		(layer "In5.Cu")
		(net "PCIE_TX_CAP_N65")
	)
	(arc
		(start 90.1065 -210.896454)
		(mid 89.927362 -210.584109)
		(end 89.8652 -210.22945)
		(width 0.1397)
		(layer "In5.Cu")
		(net "PCIE_TX_CAP_N65")
	)
	(arc
		(start 222.610426 -58.34888)
		(mid 222.623461 -58.440408)
		(end 222.601536 -58.530236)
		(width 0.1016)
		(layer "In5.Cu")
		(net "PCIE_TX_CAP_N65")
	)
	(arc
		(start 222.267526 -58.633868)
		(mid 222.206952 -58.598187)
		(end 222.153226 -58.552842)
		(width 0.1016)
		(layer "In5.Cu")
		(net "PCIE_TX_CAP_N65")
	)
	(arc
		(start 221.6404 -58.166)
		(mid 221.717197 -58.114686)
		(end 221.807786 -58.096658)
		(width 0.1016)
		(layer "In5.Cu")
		(net "PCIE_TX_CAP_N65")
	)
	(arc
		(start 222.57385 -58.590434)
		(mid 222.518957 -58.644781)
		(end 222.44431 -58.664602)
		(width 0.1016)
		(layer "In5.Cu")
		(net "PCIE_TX_CAP_N65")
	)
	(arc
		(start 222.4659 -58.154824)
		(mid 222.545223 -58.246594)
		(end 222.610426 -58.34888)
		(width 0.1016)
		(layer "In5.Cu")
		(net "PCIE_TX_CAP_N65")
	)
	(arc
		(start 222.325438 -58.096658)
		(mid 222.40145 -58.111778)
		(end 222.4659 -58.154824)
		(width 0.1016)
		(layer "In5.Cu")
		(net "PCIE_TX_CAP_N65")
	)
	(arc
		(start 222.37065 -58.664602)
		(mid 222.332623 -58.660389)
		(end 222.296482 -58.647838)
		(width 0.1016)
		(layer "In5.Cu")
		(net "PCIE_TX_CAP_N65")
	)
	(segment
		(start 93.407992 -211.975954)
		(end 93.104716 -211.672424)
		(width 0.136652)
		(layer "F.Cu")
		(net "PCIE_TX_CAP_N64")
	)
	(segment
		(start 93.153484 -211.049362)
		(end 93.306392 -210.896454)
		(width 0.136652)
		(layer "F.Cu")
		(net "PCIE_TX_CAP_N64")
	)
	(segment
		(start 93.046042 -211.5312)
		(end 93.046042 -211.308696)
		(width 0.136652)
		(layer "F.Cu")
		(net "PCIE_TX_CAP_N64")
	)
	(segment
		(start 223.60001 -58.999882)
		(end 223.100138 -59.499754)
		(width 0.136652)
		(layer "F.Cu")
		(net "PCIE_TX_CAP_N64")
	)
	(via
		(at 223.100138 -59.499754)
		(size 0.4572)
		(drill 0.2032)
		(layers "F.Cu" "B.Cu")
		(net "PCIE_TX_CAP_N64")
	)
	(via
		(at 93.306392 -210.896454)
		(size 0.508)
		(drill 0.254)
		(layers "F.Cu" "B.Cu")
		(net "PCIE_TX_CAP_N64")
	)
	(arc
		(start 93.046042 -211.308696)
		(mid 93.073961 -211.168337)
		(end 93.153484 -211.049362)
		(width 0.136652)
		(layer "F.Cu")
		(net "PCIE_TX_CAP_N64")
	)
	(arc
		(start 93.104716 -211.672424)
		(mid 93.061339 -211.607645)
		(end 93.046042 -211.5312)
		(width 0.136652)
		(layer "F.Cu")
		(net "PCIE_TX_CAP_N64")
	)
	(segment
		(start 99.452938 -204.015848)
		(end 169.64914 -154.864562)
		(width 0.1397)
		(layer "In5.Cu")
		(net "PCIE_TX_CAP_N64")
	)
	(segment
		(start 223.465898 -59.154822)
		(end 223.550226 -59.23915)
		(width 0.1016)
		(layer "In5.Cu")
		(net "PCIE_TX_CAP_N64")
	)
	(segment
		(start 169.64914 -154.864562)
		(end 216.5223 -87.922862)
		(width 0.1397)
		(layer "In5.Cu")
		(net "PCIE_TX_CAP_N64")
	)
	(segment
		(start 221.853506 -59.386724)
		(end 221.924626 -59.315604)
		(width 0.1016)
		(layer "In5.Cu")
		(net "PCIE_TX_CAP_N64")
	)
	(segment
		(start 93.065092 -207.471772)
		(end 93.955362 -206.581502)
		(width 0.1397)
		(layer "In5.Cu")
		(net "PCIE_TX_CAP_N64")
	)
	(segment
		(start 223.601534 -59.530234)
		(end 223.573848 -59.590432)
		(width 0.1016)
		(layer "In5.Cu")
		(net "PCIE_TX_CAP_N64")
	)
	(segment
		(start 220.61678 -64.703198)
		(end 220.689424 -64.290448)
		(width 0.1397)
		(layer "In5.Cu")
		(net "PCIE_TX_CAP_N64")
	)
	(segment
		(start 217.594942 -81.840324)
		(end 219.596462 -70.48881)
		(width 0.1397)
		(layer "In5.Cu")
		(net "PCIE_TX_CAP_N64")
	)
	(segment
		(start 220.478604 -65.486026)
		(end 220.696536 -65.333626)
		(width 0.1397)
		(layer "In5.Cu")
		(net "PCIE_TX_CAP_N64")
	)
	(segment
		(start 223.444308 -59.6646)
		(end 223.370648 -59.6646)
		(width 0.1016)
		(layer "In5.Cu")
		(net "PCIE_TX_CAP_N64")
	)
	(segment
		(start 221.064328 -62.16523)
		(end 221.453456 -59.95797)
		(width 0.1397)
		(layer "In5.Cu")
		(net "PCIE_TX_CAP_N64")
	)
	(segment
		(start 222.4532 -59.096656)
		(end 223.325436 -59.096656)
		(width 0.1016)
		(layer "In5.Cu")
		(net "PCIE_TX_CAP_N64")
	)
	(segment
		(start 219.596462 -70.48881)
		(end 220.478604 -65.486026)
		(width 0.1397)
		(layer "In5.Cu")
		(net "PCIE_TX_CAP_N64")
	)
	(segment
		(start 223.599248 -59.316112)
		(end 223.610424 -59.348878)
		(width 0.1016)
		(layer "In5.Cu")
		(net "PCIE_TX_CAP_N64")
	)
	(segment
		(start 220.8276 -63.507366)
		(end 220.900244 -63.094616)
		(width 0.1397)
		(layer "In5.Cu")
		(net "PCIE_TX_CAP_N64")
	)
	(segment
		(start 220.76918 -64.920876)
		(end 220.61678 -64.703198)
		(width 0.1397)
		(layer "In5.Cu")
		(net "PCIE_TX_CAP_N64")
	)
	(segment
		(start 220.907356 -64.138048)
		(end 220.98 -63.725298)
		(width 0.1397)
		(layer "In5.Cu")
		(net "PCIE_TX_CAP_N64")
	)
	(segment
		(start 220.900244 -63.094616)
		(end 221.064328 -62.16523)
		(width 0.1397)
		(layer "In5.Cu")
		(net "PCIE_TX_CAP_N64")
	)
	(segment
		(start 216.5223 -87.922862)
		(end 217.594942 -81.840324)
		(width 0.1397)
		(layer "In5.Cu")
		(net "PCIE_TX_CAP_N64")
	)
	(segment
		(start 223.29648 -59.647836)
		(end 223.267524 -59.633866)
		(width 0.1016)
		(layer "In5.Cu")
		(net "PCIE_TX_CAP_N64")
	)
	(segment
		(start 95.893128 -204.643482)
		(end 99.452938 -204.015848)
		(width 0.1397)
		(layer "In5.Cu")
		(net "PCIE_TX_CAP_N64")
	)
	(segment
		(start 93.955362 -206.581502)
		(end 95.893128 -204.643482)
		(width 0.1397)
		(layer "In5.Cu")
		(net "PCIE_TX_CAP_N64")
	)
	(segment
		(start 220.98 -63.725298)
		(end 220.8276 -63.507366)
		(width 0.1397)
		(layer "In5.Cu")
		(net "PCIE_TX_CAP_N64")
	)
	(segment
		(start 93.065092 -210.1088)
		(end 93.065092 -207.471772)
		(width 0.1397)
		(layer "In5.Cu")
		(net "PCIE_TX_CAP_N64")
	)
	(segment
		(start 223.153224 -59.55284)
		(end 223.100138 -59.499754)
		(width 0.1016)
		(layer "In5.Cu")
		(net "PCIE_TX_CAP_N64")
	)
	(segment
		(start 220.696536 -65.333626)
		(end 220.76918 -64.920876)
		(width 0.1397)
		(layer "In5.Cu")
		(net "PCIE_TX_CAP_N64")
	)
	(segment
		(start 221.453456 -59.95797)
		(end 221.853506 -59.386724)
		(width 0.1397)
		(layer "In5.Cu")
		(net "PCIE_TX_CAP_N64")
	)
	(segment
		(start 220.689424 -64.290448)
		(end 220.907356 -64.138048)
		(width 0.1397)
		(layer "In5.Cu")
		(net "PCIE_TX_CAP_N64")
	)
	(arc
		(start 223.610424 -59.348878)
		(mid 223.623459 -59.440406)
		(end 223.601534 -59.530234)
		(width 0.1016)
		(layer "In5.Cu")
		(net "PCIE_TX_CAP_N64")
	)
	(arc
		(start 223.550226 -59.23915)
		(mid 223.576646 -59.276414)
		(end 223.599248 -59.316112)
		(width 0.1016)
		(layer "In5.Cu")
		(net "PCIE_TX_CAP_N64")
	)
	(arc
		(start 221.924626 -59.315604)
		(mid 222.167138 -59.153563)
		(end 222.4532 -59.096656)
		(width 0.1016)
		(layer "In5.Cu")
		(net "PCIE_TX_CAP_N64")
	)
	(arc
		(start 223.267524 -59.633866)
		(mid 223.20695 -59.598185)
		(end 223.153224 -59.55284)
		(width 0.1016)
		(layer "In5.Cu")
		(net "PCIE_TX_CAP_N64")
	)
	(arc
		(start 223.325436 -59.096656)
		(mid 223.401448 -59.111776)
		(end 223.465898 -59.154822)
		(width 0.1016)
		(layer "In5.Cu")
		(net "PCIE_TX_CAP_N64")
	)
	(arc
		(start 223.370648 -59.6646)
		(mid 223.332621 -59.660387)
		(end 223.29648 -59.647836)
		(width 0.1016)
		(layer "In5.Cu")
		(net "PCIE_TX_CAP_N64")
	)
	(arc
		(start 93.306392 -210.896454)
		(mid 93.126765 -210.520694)
		(end 93.065092 -210.1088)
		(width 0.1397)
		(layer "In5.Cu")
		(net "PCIE_TX_CAP_N64")
	)
	(arc
		(start 223.573848 -59.590432)
		(mid 223.518955 -59.644779)
		(end 223.444308 -59.6646)
		(width 0.1016)
		(layer "In5.Cu")
		(net "PCIE_TX_CAP_N64")
	)
	(segment
		(start 98.73996 -211.063078)
		(end 98.906584 -210.896454)
		(width 0.136652)
		(layer "F.Cu")
		(net "PCIE_TX_CAP_N63")
	)
	(segment
		(start 99.008184 -211.975954)
		(end 98.704908 -211.672424)
		(width 0.136652)
		(layer "F.Cu")
		(net "PCIE_TX_CAP_N63")
	)
	(segment
		(start 223.60001 -65.999868)
		(end 223.100138 -66.49974)
		(width 0.136652)
		(layer "F.Cu")
		(net "PCIE_TX_CAP_N63")
	)
	(segment
		(start 98.646234 -211.5312)
		(end 98.646234 -211.289392)
		(width 0.136652)
		(layer "F.Cu")
		(net "PCIE_TX_CAP_N63")
	)
	(via
		(at 223.100138 -66.49974)
		(size 0.4572)
		(drill 0.2032)
		(layers "F.Cu" "B.Cu")
		(net "PCIE_TX_CAP_N63")
	)
	(via
		(at 98.906584 -210.896454)
		(size 0.508)
		(drill 0.254)
		(layers "F.Cu" "B.Cu")
		(net "PCIE_TX_CAP_N63")
	)
	(arc
		(start 98.646234 -211.289392)
		(mid 98.670596 -211.166918)
		(end 98.73996 -211.063078)
		(width 0.136652)
		(layer "F.Cu")
		(net "PCIE_TX_CAP_N63")
	)
	(arc
		(start 98.704908 -211.672424)
		(mid 98.661531 -211.607645)
		(end 98.646234 -211.5312)
		(width 0.136652)
		(layer "F.Cu")
		(net "PCIE_TX_CAP_N63")
	)
	(segment
		(start 222.631254 -66.01968)
		(end 222.63354 -66.017394)
		(width 0.1397)
		(layer "In5.Cu")
		(net "PCIE_TX_CAP_N63")
	)
	(segment
		(start 221.367604 -66.859404)
		(end 221.840552 -66.386456)
		(width 0.1397)
		(layer "In5.Cu")
		(net "PCIE_TX_CAP_N63")
	)
	(segment
		(start 98.665284 -210.22945)
		(end 98.665284 -207.809846)
		(width 0.1397)
		(layer "In5.Cu")
		(net "PCIE_TX_CAP_N63")
	)
	(segment
		(start 217.27541 -89.422986)
		(end 217.832686 -86.26348)
		(width 0.1397)
		(layer "In5.Cu")
		(net "PCIE_TX_CAP_N63")
	)
	(segment
		(start 170.278044 -156.542232)
		(end 217.27541 -89.422986)
		(width 0.1397)
		(layer "In5.Cu")
		(net "PCIE_TX_CAP_N63")
	)
	(segment
		(start 100.210112 -205.603602)
		(end 170.278044 -156.542232)
		(width 0.1397)
		(layer "In5.Cu")
		(net "PCIE_TX_CAP_N63")
	)
	(segment
		(start 223.09455 -66.046096)
		(end 223.125284 -66.076576)
		(width 0.1397)
		(layer "In5.Cu")
		(net "PCIE_TX_CAP_N63")
	)
	(segment
		(start 217.832686 -86.26348)
		(end 221.139258 -67.515994)
		(width 0.1397)
		(layer "In5.Cu")
		(net "PCIE_TX_CAP_N63")
	)
	(segment
		(start 221.991174 -66.27622)
		(end 222.011748 -66.265552)
		(width 0.1397)
		(layer "In5.Cu")
		(net "PCIE_TX_CAP_N63")
	)
	(segment
		(start 221.139258 -67.515994)
		(end 221.139004 -67.515994)
		(width 0.1397)
		(layer "In5.Cu")
		(net "PCIE_TX_CAP_N63")
	)
	(segment
		(start 223.151192 -66.44894)
		(end 223.100138 -66.49974)
		(width 0.1397)
		(layer "In5.Cu")
		(net "PCIE_TX_CAP_N63")
	)
	(segment
		(start 222.799656 -65.94856)
		(end 222.859092 -65.94856)
		(width 0.1397)
		(layer "In5.Cu")
		(net "PCIE_TX_CAP_N63")
	)
	(segment
		(start 98.665284 -207.809846)
		(end 100.210112 -205.603602)
		(width 0.1397)
		(layer "In5.Cu")
		(net "PCIE_TX_CAP_N63")
	)
	(segment
		(start 221.139004 -67.515994)
		(end 221.166944 -67.359276)
		(width 0.1397)
		(layer "In5.Cu")
		(net "PCIE_TX_CAP_N63")
	)
	(arc
		(start 221.840552 -66.386456)
		(mid 221.862283 -66.36572)
		(end 221.885002 -66.34607)
		(width 0.1397)
		(layer "In5.Cu")
		(net "PCIE_TX_CAP_N63")
	)
	(arc
		(start 222.859092 -65.94856)
		(mid 222.986523 -65.973908)
		(end 223.09455 -66.046096)
		(width 0.1397)
		(layer "In5.Cu")
		(net "PCIE_TX_CAP_N63")
	)
	(arc
		(start 222.63354 -66.017394)
		(mid 222.709755 -65.966469)
		(end 222.799656 -65.94856)
		(width 0.1397)
		(layer "In5.Cu")
		(net "PCIE_TX_CAP_N63")
	)
	(arc
		(start 223.2152 -66.294)
		(mid 223.198617 -66.377841)
		(end 223.151192 -66.44894)
		(width 0.1397)
		(layer "In5.Cu")
		(net "PCIE_TX_CAP_N63")
	)
	(arc
		(start 221.885002 -66.34607)
		(mid 221.936267 -66.308378)
		(end 221.991174 -66.27622)
		(width 0.1397)
		(layer "In5.Cu")
		(net "PCIE_TX_CAP_N63")
	)
	(arc
		(start 222.074994 -66.250058)
		(mid 222.376027 -66.190179)
		(end 222.631254 -66.01968)
		(width 0.1397)
		(layer "In5.Cu")
		(net "PCIE_TX_CAP_N63")
	)
	(arc
		(start 222.011748 -66.265552)
		(mid 222.042437 -66.253994)
		(end 222.074994 -66.250058)
		(width 0.1397)
		(layer "In5.Cu")
		(net "PCIE_TX_CAP_N63")
	)
	(arc
		(start 223.125284 -66.076576)
		(mid 223.191855 -66.176346)
		(end 223.2152 -66.294)
		(width 0.1397)
		(layer "In5.Cu")
		(net "PCIE_TX_CAP_N63")
	)
	(arc
		(start 98.906584 -210.896454)
		(mid 98.727446 -210.584109)
		(end 98.665284 -210.22945)
		(width 0.1397)
		(layer "In5.Cu")
		(net "PCIE_TX_CAP_N63")
	)
	(arc
		(start 221.166944 -67.359276)
		(mid 221.241538 -67.09901)
		(end 221.367604 -66.859404)
		(width 0.1397)
		(layer "In5.Cu")
		(net "PCIE_TX_CAP_N63")
	)
	(segment
		(start 101.934518 -211.068412)
		(end 102.106476 -210.896454)
		(width 0.136652)
		(layer "F.Cu")
		(net "PCIE_TX_CAP_N62")
	)
	(segment
		(start 224.600008 -64.99987)
		(end 224.100136 -65.499742)
		(width 0.136652)
		(layer "F.Cu")
		(net "PCIE_TX_CAP_N62")
	)
	(segment
		(start 101.846126 -211.5312)
		(end 101.846126 -211.294218)
		(width 0.136652)
		(layer "F.Cu")
		(net "PCIE_TX_CAP_N62")
	)
	(segment
		(start 102.208076 -211.975954)
		(end 101.9048 -211.672424)
		(width 0.136652)
		(layer "F.Cu")
		(net "PCIE_TX_CAP_N62")
	)
	(via
		(at 102.106476 -210.896454)
		(size 0.508)
		(drill 0.254)
		(layers "F.Cu" "B.Cu")
		(net "PCIE_TX_CAP_N62")
	)
	(via
		(at 224.100136 -65.499742)
		(size 0.4572)
		(drill 0.2032)
		(layers "F.Cu" "B.Cu")
		(net "PCIE_TX_CAP_N62")
	)
	(arc
		(start 101.9048 -211.672424)
		(mid 101.861423 -211.607645)
		(end 101.846126 -211.5312)
		(width 0.136652)
		(layer "F.Cu")
		(net "PCIE_TX_CAP_N62")
	)
	(arc
		(start 101.846126 -211.281772)
		(mid 101.869096 -211.166297)
		(end 101.934518 -211.068412)
		(width 0.136652)
		(layer "F.Cu")
		(net "PCIE_TX_CAP_N62")
	)
	(arc
		(start 101.846126 -211.294218)
		(mid 101.846154 -211.287995)
		(end 101.846126 -211.281772)
		(width 0.136652)
		(layer "F.Cu")
		(net "PCIE_TX_CAP_N62")
	)
	(segment
		(start 101.865176 -209.016092)
		(end 105.700576 -203.538582)
		(width 0.1397)
		(layer "In5.Cu")
		(net "PCIE_TX_CAP_N62")
	)
	(segment
		(start 222.154496 -68.949316)
		(end 222.957136 -67.803268)
		(width 0.1397)
		(layer "In5.Cu")
		(net "PCIE_TX_CAP_N62")
	)
	(segment
		(start 218.437206 -90.032078)
		(end 222.154496 -68.949316)
		(width 0.1397)
		(layer "In5.Cu")
		(net "PCIE_TX_CAP_N62")
	)
	(segment
		(start 224.152968 -65.44691)
		(end 224.100136 -65.499742)
		(width 0.1016)
		(layer "In5.Cu")
		(net "PCIE_TX_CAP_N62")
	)
	(segment
		(start 105.700576 -203.538582)
		(end 170.951398 -157.848808)
		(width 0.1397)
		(layer "In5.Cu")
		(net "PCIE_TX_CAP_N62")
	)
	(segment
		(start 170.951398 -157.848808)
		(end 218.437206 -90.032078)
		(width 0.1397)
		(layer "In5.Cu")
		(net "PCIE_TX_CAP_N62")
	)
	(segment
		(start 223.871282 -64.9986)
		(end 223.967294 -64.9986)
		(width 0.1016)
		(layer "In5.Cu")
		(net "PCIE_TX_CAP_N62")
	)
	(segment
		(start 223.697038 -66.951098)
		(end 223.697038 -65.17386)
		(width 0.1016)
		(layer "In5.Cu")
		(net "PCIE_TX_CAP_N62")
	)
	(segment
		(start 224.064068 -65.038732)
		(end 224.152968 -65.127632)
		(width 0.1016)
		(layer "In5.Cu")
		(net "PCIE_TX_CAP_N62")
	)
	(segment
		(start 222.957136 -67.691)
		(end 223.697038 -66.951098)
		(width 0.1016)
		(layer "In5.Cu")
		(net "PCIE_TX_CAP_N62")
	)
	(segment
		(start 222.957136 -67.803268)
		(end 222.957136 -67.691)
		(width 0.1016)
		(layer "In5.Cu")
		(net "PCIE_TX_CAP_N62")
	)
	(segment
		(start 101.865176 -210.22945)
		(end 101.865176 -209.016092)
		(width 0.1397)
		(layer "In5.Cu")
		(net "PCIE_TX_CAP_N62")
	)
	(arc
		(start 224.152968 -65.127632)
		(mid 224.21922 -65.287308)
		(end 224.152968 -65.44691)
		(width 0.1016)
		(layer "In5.Cu")
		(net "PCIE_TX_CAP_N62")
	)
	(arc
		(start 223.967294 -64.9986)
		(mid 224.019686 -65.009021)
		(end 224.064068 -65.038732)
		(width 0.1016)
		(layer "In5.Cu")
		(net "PCIE_TX_CAP_N62")
	)
	(arc
		(start 102.106476 -210.896454)
		(mid 101.927338 -210.584109)
		(end 101.865176 -210.22945)
		(width 0.1397)
		(layer "In5.Cu")
		(net "PCIE_TX_CAP_N62")
	)
	(arc
		(start 223.7486 -65.0494)
		(mid 223.804887 -65.01179)
		(end 223.871282 -64.9986)
		(width 0.1016)
		(layer "In5.Cu")
		(net "PCIE_TX_CAP_N62")
	)
	(arc
		(start 223.697038 -65.17386)
		(mid 223.710437 -65.106499)
		(end 223.7486 -65.0494)
		(width 0.1016)
		(layer "In5.Cu")
		(net "PCIE_TX_CAP_N62")
	)
	(segment
		(start 105.141014 -211.061808)
		(end 105.306622 -210.896454)
		(width 0.136652)
		(layer "F.Cu")
		(net "PCIE_TX_CAP_N61")
	)
	(segment
		(start 225.600006 -65.999868)
		(end 225.100134 -66.49974)
		(width 0.136652)
		(layer "F.Cu")
		(net "PCIE_TX_CAP_N61")
	)
	(segment
		(start 105.046272 -211.5312)
		(end 105.046272 -211.293456)
		(width 0.136652)
		(layer "F.Cu")
		(net "PCIE_TX_CAP_N61")
	)
	(segment
		(start 105.408222 -211.975954)
		(end 105.104946 -211.672424)
		(width 0.136652)
		(layer "F.Cu")
		(net "PCIE_TX_CAP_N61")
	)
	(via
		(at 225.100134 -66.49974)
		(size 0.4572)
		(drill 0.2032)
		(layers "F.Cu" "B.Cu")
		(net "PCIE_TX_CAP_N61")
	)
	(via
		(at 105.306622 -210.896454)
		(size 0.508)
		(drill 0.254)
		(layers "F.Cu" "B.Cu")
		(net "PCIE_TX_CAP_N61")
	)
	(arc
		(start 105.046272 -211.290916)
		(mid 105.070841 -211.16693)
		(end 105.141014 -211.061808)
		(width 0.136652)
		(layer "F.Cu")
		(net "PCIE_TX_CAP_N61")
	)
	(arc
		(start 105.104946 -211.672424)
		(mid 105.061569 -211.607645)
		(end 105.046272 -211.5312)
		(width 0.136652)
		(layer "F.Cu")
		(net "PCIE_TX_CAP_N61")
	)
	(arc
		(start 105.046272 -211.293456)
		(mid 105.046273 -211.292186)
		(end 105.046272 -211.290916)
		(width 0.136652)
		(layer "F.Cu")
		(net "PCIE_TX_CAP_N61")
	)
	(segment
		(start 105.065322 -210.22945)
		(end 105.065322 -209.07629)
		(width 0.1397)
		(layer "In5.Cu")
		(net "PCIE_TX_CAP_N61")
	)
	(segment
		(start 172.134022 -158.608522)
		(end 221.327726 -88.352884)
		(width 0.1397)
		(layer "In5.Cu")
		(net "PCIE_TX_CAP_N61")
	)
	(segment
		(start 224.759774 -68.882768)
		(end 224.7646 -68.854574)
		(width 0.1397)
		(layer "In5.Cu")
		(net "PCIE_TX_CAP_N61")
	)
	(segment
		(start 108.700062 -203.024994)
		(end 172.134022 -158.608522)
		(width 0.1397)
		(layer "In5.Cu")
		(net "PCIE_TX_CAP_N61")
	)
	(segment
		(start 224.7646 -68.854574)
		(end 224.7646 -66.9798)
		(width 0.1397)
		(layer "In5.Cu")
		(net "PCIE_TX_CAP_N61")
	)
	(segment
		(start 105.268014 -207.926686)
		(end 108.700062 -203.024994)
		(width 0.1397)
		(layer "In5.Cu")
		(net "PCIE_TX_CAP_N61")
	)
	(segment
		(start 224.87128 -65.998598)
		(end 224.967292 -65.998598)
		(width 0.1016)
		(layer "In5.Cu")
		(net "PCIE_TX_CAP_N61")
	)
	(segment
		(start 221.327726 -88.352884)
		(end 224.759774 -68.882768)
		(width 0.1397)
		(layer "In5.Cu")
		(net "PCIE_TX_CAP_N61")
	)
	(segment
		(start 224.7646 -66.9798)
		(end 224.697036 -66.912236)
		(width 0.1016)
		(layer "In5.Cu")
		(net "PCIE_TX_CAP_N61")
	)
	(segment
		(start 225.125534 -66.47434)
		(end 225.100134 -66.49974)
		(width 0.1016)
		(layer "In5.Cu")
		(net "PCIE_TX_CAP_N61")
	)
	(segment
		(start 224.697036 -66.912236)
		(end 224.697036 -66.173858)
		(width 0.1016)
		(layer "In5.Cu")
		(net "PCIE_TX_CAP_N61")
	)
	(segment
		(start 105.065322 -209.07629)
		(end 105.268014 -207.926686)
		(width 0.1397)
		(layer "In5.Cu")
		(net "PCIE_TX_CAP_N61")
	)
	(segment
		(start 225.064066 -66.03873)
		(end 225.071686 -66.04635)
		(width 0.1016)
		(layer "In5.Cu")
		(net "PCIE_TX_CAP_N61")
	)
	(segment
		(start 225.125534 -66.176398)
		(end 225.125534 -66.47434)
		(width 0.1016)
		(layer "In5.Cu")
		(net "PCIE_TX_CAP_N61")
	)
	(arc
		(start 225.071686 -66.04635)
		(mid 225.111554 -66.106017)
		(end 225.125534 -66.176398)
		(width 0.1016)
		(layer "In5.Cu")
		(net "PCIE_TX_CAP_N61")
	)
	(arc
		(start 224.967292 -65.998598)
		(mid 225.019684 -66.009019)
		(end 225.064066 -66.03873)
		(width 0.1016)
		(layer "In5.Cu")
		(net "PCIE_TX_CAP_N61")
	)
	(arc
		(start 224.697036 -66.173858)
		(mid 224.710435 -66.106497)
		(end 224.748598 -66.049398)
		(width 0.1016)
		(layer "In5.Cu")
		(net "PCIE_TX_CAP_N61")
	)
	(arc
		(start 224.748598 -66.049398)
		(mid 224.804885 -66.011788)
		(end 224.87128 -65.998598)
		(width 0.1016)
		(layer "In5.Cu")
		(net "PCIE_TX_CAP_N61")
	)
	(arc
		(start 105.306622 -210.896454)
		(mid 105.127484 -210.584109)
		(end 105.065322 -210.22945)
		(width 0.1397)
		(layer "In5.Cu")
		(net "PCIE_TX_CAP_N61")
	)
	(segment
		(start 108.608114 -211.975954)
		(end 108.304838 -211.672424)
		(width 0.136652)
		(layer "F.Cu")
		(net "PCIE_TX_CAP_N60")
	)
	(segment
		(start 108.246164 -211.5312)
		(end 108.246164 -211.339684)
		(width 0.136652)
		(layer "F.Cu")
		(net "PCIE_TX_CAP_N60")
	)
	(segment
		(start 108.37545 -211.027518)
		(end 108.506514 -210.896454)
		(width 0.136652)
		(layer "F.Cu")
		(net "PCIE_TX_CAP_N60")
	)
	(segment
		(start 226.600004 -64.99987)
		(end 226.100132 -65.499742)
		(width 0.136652)
		(layer "F.Cu")
		(net "PCIE_TX_CAP_N60")
	)
	(via
		(at 108.506514 -210.896454)
		(size 0.508)
		(drill 0.254)
		(layers "F.Cu" "B.Cu")
		(net "PCIE_TX_CAP_N60")
	)
	(via
		(at 226.100132 -65.499742)
		(size 0.4572)
		(drill 0.2032)
		(layers "F.Cu" "B.Cu")
		(net "PCIE_TX_CAP_N60")
	)
	(arc
		(start 108.304838 -211.672424)
		(mid 108.261461 -211.607645)
		(end 108.246164 -211.5312)
		(width 0.136652)
		(layer "F.Cu")
		(net "PCIE_TX_CAP_N60")
	)
	(arc
		(start 108.246164 -211.339684)
		(mid 108.279768 -211.170748)
		(end 108.37545 -211.027518)
		(width 0.136652)
		(layer "F.Cu")
		(net "PCIE_TX_CAP_N60")
	)
	(segment
		(start 225.697034 -65.17386)
		(end 225.697034 -66.93535)
		(width 0.1016)
		(layer "In5.Cu")
		(net "PCIE_TX_CAP_N60")
	)
	(segment
		(start 223.459802 -87.721694)
		(end 172.600112 -160.356804)
		(width 0.1397)
		(layer "In5.Cu")
		(net "PCIE_TX_CAP_N60")
	)
	(segment
		(start 108.265214 -209.331306)
		(end 108.265214 -210.22945)
		(width 0.1397)
		(layer "In5.Cu")
		(net "PCIE_TX_CAP_N60")
	)
	(segment
		(start 226.523042 -72.405494)
		(end 223.459802 -87.721694)
		(width 0.1397)
		(layer "In5.Cu")
		(net "PCIE_TX_CAP_N60")
	)
	(segment
		(start 108.880148 -205.844394)
		(end 108.265214 -209.331306)
		(width 0.1397)
		(layer "In5.Cu")
		(net "PCIE_TX_CAP_N60")
	)
	(segment
		(start 225.697034 -66.93535)
		(end 225.792284 -67.0306)
		(width 0.1016)
		(layer "In5.Cu")
		(net "PCIE_TX_CAP_N60")
	)
	(segment
		(start 110.078266 -204.13345)
		(end 108.880148 -205.844394)
		(width 0.1397)
		(layer "In5.Cu")
		(net "PCIE_TX_CAP_N60")
	)
	(segment
		(start 225.792284 -67.0306)
		(end 225.792284 -68.751704)
		(width 0.1397)
		(layer "In5.Cu")
		(net "PCIE_TX_CAP_N60")
	)
	(segment
		(start 225.792284 -68.751704)
		(end 226.523042 -72.405494)
		(width 0.1397)
		(layer "In5.Cu")
		(net "PCIE_TX_CAP_N60")
	)
	(segment
		(start 172.600112 -160.356804)
		(end 110.078266 -204.13345)
		(width 0.1397)
		(layer "In5.Cu")
		(net "PCIE_TX_CAP_N60")
	)
	(arc
		(start 225.871278 -64.9986)
		(mid 225.804889 -65.011806)
		(end 225.748596 -65.0494)
		(width 0.1016)
		(layer "In5.Cu")
		(net "PCIE_TX_CAP_N60")
	)
	(arc
		(start 226.021646 -65.058544)
		(mid 225.95221 -65.014163)
		(end 225.871278 -64.9986)
		(width 0.1016)
		(layer "In5.Cu")
		(net "PCIE_TX_CAP_N60")
	)
	(arc
		(start 226.0854 -65.151)
		(mid 226.058369 -65.101431)
		(end 226.021646 -65.058544)
		(width 0.1016)
		(layer "In5.Cu")
		(net "PCIE_TX_CAP_N60")
	)
	(arc
		(start 226.100132 -65.499742)
		(mid 226.123852 -65.324053)
		(end 226.0854 -65.151)
		(width 0.1016)
		(layer "In5.Cu")
		(net "PCIE_TX_CAP_N60")
	)
	(arc
		(start 225.748596 -65.0494)
		(mid 225.710441 -65.106503)
		(end 225.697034 -65.17386)
		(width 0.1016)
		(layer "In5.Cu")
		(net "PCIE_TX_CAP_N60")
	)
	(arc
		(start 108.265214 -210.22945)
		(mid 108.327398 -210.584101)
		(end 108.506514 -210.896454)
		(width 0.1397)
		(layer "In5.Cu")
		(net "PCIE_TX_CAP_N60")
	)
	(segment
		(start 302.365664 -34.91992)
		(end 302.47209 -35.026346)
		(width 0.136652)
		(layer "F.Cu")
		(net "PCIE_TX_CAP_N6")
	)
	(segment
		(start 302.49749 -33.984692)
		(end 302.374554 -34.107882)
		(width 0.136652)
		(layer "F.Cu")
		(net "PCIE_TX_CAP_N6")
	)
	(segment
		(start 257.599942 -29.99994)
		(end 258.099814 -29.500068)
		(width 0.136652)
		(layer "F.Cu")
		(net "PCIE_TX_CAP_N6")
	)
	(segment
		(start 302.23079 -34.454592)
		(end 302.23079 -34.594292)
		(width 0.136652)
		(layer "F.Cu")
		(net "PCIE_TX_CAP_N6")
	)
	(via
		(at 258.099814 -29.500068)
		(size 0.4572)
		(drill 0.2032)
		(layers "F.Cu" "B.Cu")
		(net "PCIE_TX_CAP_N6")
	)
	(via
		(at 302.47209 -35.026346)
		(size 0.508)
		(drill 0.254)
		(layers "F.Cu" "B.Cu")
		(net "PCIE_TX_CAP_N6")
	)
	(arc
		(start 302.374554 -34.107882)
		(mid 302.268183 -34.266939)
		(end 302.23079 -34.454592)
		(width 0.136652)
		(layer "F.Cu")
		(net "PCIE_TX_CAP_N6")
	)
	(arc
		(start 302.23079 -34.594292)
		(mid 302.265844 -34.770518)
		(end 302.365664 -34.91992)
		(width 0.136652)
		(layer "F.Cu")
		(net "PCIE_TX_CAP_N6")
	)
	(segment
		(start 302.31207 -36.674552)
		(end 302.867822 -37.468302)
		(width 0.1397)
		(layer "In5.Cu")
		(net "PCIE_TX_CAP_N6")
	)
	(segment
		(start 280.218134 -35.98418)
		(end 278.300688 -33.245806)
		(width 0.1397)
		(layer "In5.Cu")
		(net "PCIE_TX_CAP_N6")
	)
	(segment
		(start 302.811688 -38.56355)
		(end 302.615346 -38.843712)
		(width 0.1397)
		(layer "In5.Cu")
		(net "PCIE_TX_CAP_N6")
	)
	(segment
		(start 302.2092 -35.563302)
		(end 302.2092 -36.086034)
		(width 0.1397)
		(layer "In5.Cu")
		(net "PCIE_TX_CAP_N6")
	)
	(segment
		(start 257.70459 -29.0068)
		(end 257.70459 -29.632402)
		(width 0.1016)
		(layer "In5.Cu")
		(net "PCIE_TX_CAP_N6")
	)
	(segment
		(start 302.867822 -37.468302)
		(end 302.95215 -37.947092)
		(width 0.1397)
		(layer "In5.Cu")
		(net "PCIE_TX_CAP_N6")
	)
	(segment
		(start 258.699 -28.7528)
		(end 258.572 -28.6258)
		(width 0.1016)
		(layer "In5.Cu")
		(net "PCIE_TX_CAP_N6")
	)
	(segment
		(start 265.636248 -28.7528)
		(end 258.793996 -28.7528)
		(width 0.1397)
		(layer "In5.Cu")
		(net "PCIE_TX_CAP_N6")
	)
	(segment
		(start 300.818296 -40.102536)
		(end 296.53611 -40.857932)
		(width 0.1397)
		(layer "In5.Cu")
		(net "PCIE_TX_CAP_N6")
	)
	(segment
		(start 302.95215 -37.947092)
		(end 302.854106 -38.503098)
		(width 0.1397)
		(layer "In5.Cu")
		(net "PCIE_TX_CAP_N6")
	)
	(segment
		(start 296.53611 -40.857932)
		(end 284.031436 -38.654228)
		(width 0.1397)
		(layer "In5.Cu")
		(net "PCIE_TX_CAP_N6")
	)
	(segment
		(start 284.031436 -38.654228)
		(end 280.218134 -35.98418)
		(width 0.1397)
		(layer "In5.Cu")
		(net "PCIE_TX_CAP_N6")
	)
	(segment
		(start 258.092702 -29.8069)
		(end 258.099814 -29.799788)
		(width 0.1016)
		(layer "In5.Cu")
		(net "PCIE_TX_CAP_N6")
	)
	(segment
		(start 278.300688 -33.245806)
		(end 273.987514 -30.225746)
		(width 0.1397)
		(layer "In5.Cu")
		(net "PCIE_TX_CAP_N6")
	)
	(segment
		(start 302.47209 -35.026346)
		(end 302.403002 -35.095434)
		(width 0.1397)
		(layer "In5.Cu")
		(net "PCIE_TX_CAP_N6")
	)
	(segment
		(start 302.615346 -38.843712)
		(end 300.818296 -40.102536)
		(width 0.1397)
		(layer "In5.Cu")
		(net "PCIE_TX_CAP_N6")
	)
	(segment
		(start 273.987514 -30.225746)
		(end 265.636248 -28.7528)
		(width 0.1397)
		(layer "In5.Cu")
		(net "PCIE_TX_CAP_N6")
	)
	(segment
		(start 258.793996 -28.7528)
		(end 258.699 -28.7528)
		(width 0.1016)
		(layer "In5.Cu")
		(net "PCIE_TX_CAP_N6")
	)
	(segment
		(start 302.2092 -36.086034)
		(end 302.31207 -36.674552)
		(width 0.1397)
		(layer "In5.Cu")
		(net "PCIE_TX_CAP_N6")
	)
	(segment
		(start 258.572 -28.6258)
		(end 258.08559 -28.6258)
		(width 0.1016)
		(layer "In5.Cu")
		(net "PCIE_TX_CAP_N6")
	)
	(segment
		(start 302.854106 -38.503098)
		(end 302.811688 -38.563804)
		(width 0.1397)
		(layer "In5.Cu")
		(net "PCIE_TX_CAP_N6")
	)
	(segment
		(start 302.811688 -38.563804)
		(end 302.811688 -38.56355)
		(width 0.1397)
		(layer "In5.Cu")
		(net "PCIE_TX_CAP_N6")
	)
	(arc
		(start 257.862324 -29.85643)
		(mid 257.901855 -29.866862)
		(end 257.942588 -29.8704)
		(width 0.1016)
		(layer "In5.Cu")
		(net "PCIE_TX_CAP_N6")
	)
	(arc
		(start 302.403002 -35.095434)
		(mid 302.259571 -35.310094)
		(end 302.2092 -35.563302)
		(width 0.1397)
		(layer "In5.Cu")
		(net "PCIE_TX_CAP_N6")
	)
	(arc
		(start 258.08559 -28.6258)
		(mid 257.816182 -28.737392)
		(end 257.70459 -29.0068)
		(width 0.1016)
		(layer "In5.Cu")
		(net "PCIE_TX_CAP_N6")
	)
	(arc
		(start 257.70459 -29.632402)
		(mid 257.747976 -29.769403)
		(end 257.862324 -29.85643)
		(width 0.1016)
		(layer "In5.Cu")
		(net "PCIE_TX_CAP_N6")
	)
	(arc
		(start 258.099814 -29.799788)
		(mid 258.161963 -29.649928)
		(end 258.099814 -29.500068)
		(width 0.1016)
		(layer "In5.Cu")
		(net "PCIE_TX_CAP_N6")
	)
	(arc
		(start 257.942588 -29.8704)
		(mid 258.02405 -29.85381)
		(end 258.092702 -29.8069)
		(width 0.1016)
		(layer "In5.Cu")
		(net "PCIE_TX_CAP_N6")
	)
	(segment
		(start 227.600002 -65.999868)
		(end 227.10013 -66.49974)
		(width 0.136652)
		(layer "F.Cu")
		(net "PCIE_TX_CAP_N59")
	)
	(segment
		(start 139.046204 -211.5312)
		(end 139.046204 -211.283804)
		(width 0.136652)
		(layer "F.Cu")
		(net "PCIE_TX_CAP_N59")
	)
	(segment
		(start 139.13612 -211.067142)
		(end 139.306554 -210.896454)
		(width 0.136652)
		(layer "F.Cu")
		(net "PCIE_TX_CAP_N59")
	)
	(segment
		(start 139.408154 -211.975954)
		(end 139.104878 -211.672424)
		(width 0.136652)
		(layer "F.Cu")
		(net "PCIE_TX_CAP_N59")
	)
	(via
		(at 227.10013 -66.49974)
		(size 0.4572)
		(drill 0.2032)
		(layers "F.Cu" "B.Cu")
		(net "PCIE_TX_CAP_N59")
	)
	(via
		(at 139.306554 -210.896454)
		(size 0.508)
		(drill 0.254)
		(layers "F.Cu" "B.Cu")
		(net "PCIE_TX_CAP_N59")
	)
	(arc
		(start 139.104878 -211.672424)
		(mid 139.061501 -211.607645)
		(end 139.046204 -211.5312)
		(width 0.136652)
		(layer "F.Cu")
		(net "PCIE_TX_CAP_N59")
	)
	(arc
		(start 139.046204 -211.283804)
		(mid 139.069624 -211.166535)
		(end 139.13612 -211.067142)
		(width 0.136652)
		(layer "F.Cu")
		(net "PCIE_TX_CAP_N59")
	)
	(segment
		(start 139.065254 -210.313778)
		(end 139.065254 -197.554088)
		(width 0.1397)
		(layer "In5.Cu")
		(net "PCIE_TX_CAP_N59")
	)
	(segment
		(start 226.7712 -68.654168)
		(end 226.7712 -66.9798)
		(width 0.1397)
		(layer "In5.Cu")
		(net "PCIE_TX_CAP_N59")
	)
	(segment
		(start 227.600764 -72.801988)
		(end 226.7712 -68.654168)
		(width 0.1397)
		(layer "In5.Cu")
		(net "PCIE_TX_CAP_N59")
	)
	(segment
		(start 164.613082 -174.580804)
		(end 224.81413 -88.605106)
		(width 0.1397)
		(layer "In5.Cu")
		(net "PCIE_TX_CAP_N59")
	)
	(segment
		(start 224.81413 -88.605106)
		(end 227.600764 -72.801988)
		(width 0.1397)
		(layer "In5.Cu")
		(net "PCIE_TX_CAP_N59")
	)
	(segment
		(start 226.697032 -66.905632)
		(end 226.697032 -66.173858)
		(width 0.1016)
		(layer "In5.Cu")
		(net "PCIE_TX_CAP_N59")
	)
	(segment
		(start 146.05 -187.579)
		(end 164.613082 -174.580804)
		(width 0.1397)
		(layer "In5.Cu")
		(net "PCIE_TX_CAP_N59")
	)
	(segment
		(start 226.7712 -66.9798)
		(end 226.697032 -66.905632)
		(width 0.1016)
		(layer "In5.Cu")
		(net "PCIE_TX_CAP_N59")
	)
	(segment
		(start 227.12553 -66.176398)
		(end 227.12553 -66.47434)
		(width 0.1016)
		(layer "In5.Cu")
		(net "PCIE_TX_CAP_N59")
	)
	(segment
		(start 139.065 -210.313778)
		(end 139.065254 -210.313778)
		(width 0.1397)
		(layer "In5.Cu")
		(net "PCIE_TX_CAP_N59")
	)
	(segment
		(start 139.065254 -197.554088)
		(end 146.05 -187.579)
		(width 0.1397)
		(layer "In5.Cu")
		(net "PCIE_TX_CAP_N59")
	)
	(segment
		(start 226.871276 -65.998598)
		(end 226.967288 -65.998598)
		(width 0.1016)
		(layer "In5.Cu")
		(net "PCIE_TX_CAP_N59")
	)
	(segment
		(start 227.12553 -66.47434)
		(end 227.10013 -66.49974)
		(width 0.1016)
		(layer "In5.Cu")
		(net "PCIE_TX_CAP_N59")
	)
	(segment
		(start 227.064062 -66.03873)
		(end 227.071682 -66.04635)
		(width 0.1016)
		(layer "In5.Cu")
		(net "PCIE_TX_CAP_N59")
	)
	(arc
		(start 226.748594 -66.049398)
		(mid 226.804881 -66.011788)
		(end 226.871276 -65.998598)
		(width 0.1016)
		(layer "In5.Cu")
		(net "PCIE_TX_CAP_N59")
	)
	(arc
		(start 226.967288 -65.998598)
		(mid 227.01968 -66.009019)
		(end 227.064062 -66.03873)
		(width 0.1016)
		(layer "In5.Cu")
		(net "PCIE_TX_CAP_N59")
	)
	(arc
		(start 226.697032 -66.173858)
		(mid 226.710431 -66.106497)
		(end 226.748594 -66.049398)
		(width 0.1016)
		(layer "In5.Cu")
		(net "PCIE_TX_CAP_N59")
	)
	(arc
		(start 227.071682 -66.04635)
		(mid 227.11155 -66.106017)
		(end 227.12553 -66.176398)
		(width 0.1016)
		(layer "In5.Cu")
		(net "PCIE_TX_CAP_N59")
	)
	(arc
		(start 139.306554 -210.896454)
		(mid 139.12779 -210.629149)
		(end 139.065 -210.313778)
		(width 0.1397)
		(layer "In5.Cu")
		(net "PCIE_TX_CAP_N59")
	)
	(segment
		(start 142.608046 -211.975446)
		(end 142.305024 -211.672424)
		(width 0.136652)
		(layer "F.Cu")
		(net "PCIE_TX_CAP_N58")
	)
	(segment
		(start 228.6 -64.99987)
		(end 228.100128 -65.499742)
		(width 0.136652)
		(layer "F.Cu")
		(net "PCIE_TX_CAP_N58")
	)
	(segment
		(start 142.608046 -211.975954)
		(end 142.608046 -211.975446)
		(width 0.136652)
		(layer "F.Cu")
		(net "PCIE_TX_CAP_N58")
	)
	(segment
		(start 142.322042 -211.080858)
		(end 142.5067 -210.896454)
		(width 0.136652)
		(layer "F.Cu")
		(net "PCIE_TX_CAP_N58")
	)
	(segment
		(start 142.24635 -211.5312)
		(end 142.24635 -211.263992)
		(width 0.136652)
		(layer "F.Cu")
		(net "PCIE_TX_CAP_N58")
	)
	(via
		(at 228.100128 -65.499742)
		(size 0.4572)
		(drill 0.2032)
		(layers "F.Cu" "B.Cu")
		(net "PCIE_TX_CAP_N58")
	)
	(via
		(at 142.5067 -210.896454)
		(size 0.508)
		(drill 0.254)
		(layers "F.Cu" "B.Cu")
		(net "PCIE_TX_CAP_N58")
	)
	(arc
		(start 142.24635 -211.263992)
		(mid 142.265969 -211.16489)
		(end 142.322042 -211.080858)
		(width 0.136652)
		(layer "F.Cu")
		(net "PCIE_TX_CAP_N58")
	)
	(arc
		(start 142.305024 -211.672424)
		(mid 142.261647 -211.607645)
		(end 142.24635 -211.5312)
		(width 0.136652)
		(layer "F.Cu")
		(net "PCIE_TX_CAP_N58")
	)
	(segment
		(start 228.06406 -65.038732)
		(end 228.07168 -65.046352)
		(width 0.1016)
		(layer "In5.Cu")
		(net "PCIE_TX_CAP_N58")
	)
	(segment
		(start 228.528372 -72.388476)
		(end 227.7618 -68.555108)
		(width 0.1397)
		(layer "In5.Cu")
		(net "PCIE_TX_CAP_N58")
	)
	(segment
		(start 228.125528 -65.1764)
		(end 228.125528 -65.474342)
		(width 0.1016)
		(layer "In5.Cu")
		(net "PCIE_TX_CAP_N58")
	)
	(segment
		(start 227.69703 -66.976498)
		(end 227.69703 -65.17386)
		(width 0.1016)
		(layer "In5.Cu")
		(net "PCIE_TX_CAP_N58")
	)
	(segment
		(start 142.2654 -195.94068)
		(end 147.32 -188.722)
		(width 0.1397)
		(layer "In5.Cu")
		(net "PCIE_TX_CAP_N58")
	)
	(segment
		(start 164.95522 -176.373536)
		(end 225.534474 -89.857326)
		(width 0.1397)
		(layer "In5.Cu")
		(net "PCIE_TX_CAP_N58")
	)
	(segment
		(start 228.125528 -65.474342)
		(end 228.100128 -65.499742)
		(width 0.1016)
		(layer "In5.Cu")
		(net "PCIE_TX_CAP_N58")
	)
	(segment
		(start 227.871274 -64.9986)
		(end 227.967286 -64.9986)
		(width 0.1016)
		(layer "In5.Cu")
		(net "PCIE_TX_CAP_N58")
	)
	(segment
		(start 227.7618 -67.029076)
		(end 227.718112 -66.985388)
		(width 0.1016)
		(layer "In5.Cu")
		(net "PCIE_TX_CAP_N58")
	)
	(segment
		(start 227.718112 -66.985388)
		(end 227.69703 -66.976498)
		(width 0.1016)
		(layer "In5.Cu")
		(net "PCIE_TX_CAP_N58")
	)
	(segment
		(start 142.5067 -210.896454)
		(end 142.472156 -210.86191)
		(width 0.1397)
		(layer "In5.Cu")
		(net "PCIE_TX_CAP_N58")
	)
	(segment
		(start 225.534474 -89.857326)
		(end 228.528372 -72.878696)
		(width 0.1397)
		(layer "In5.Cu")
		(net "PCIE_TX_CAP_N58")
	)
	(segment
		(start 227.7618 -68.555108)
		(end 227.7618 -67.029076)
		(width 0.1397)
		(layer "In5.Cu")
		(net "PCIE_TX_CAP_N58")
	)
	(segment
		(start 147.32 -188.722)
		(end 164.95522 -176.373536)
		(width 0.1397)
		(layer "In5.Cu")
		(net "PCIE_TX_CAP_N58")
	)
	(segment
		(start 142.2654 -210.3628)
		(end 142.2654 -195.94068)
		(width 0.1397)
		(layer "In5.Cu")
		(net "PCIE_TX_CAP_N58")
	)
	(segment
		(start 228.528372 -72.878696)
		(end 228.528372 -72.388476)
		(width 0.1397)
		(layer "In5.Cu")
		(net "PCIE_TX_CAP_N58")
	)
	(arc
		(start 227.967286 -64.9986)
		(mid 228.019678 -65.009021)
		(end 228.06406 -65.038732)
		(width 0.1016)
		(layer "In5.Cu")
		(net "PCIE_TX_CAP_N58")
	)
	(arc
		(start 227.748592 -65.0494)
		(mid 227.804879 -65.01179)
		(end 227.871274 -64.9986)
		(width 0.1016)
		(layer "In5.Cu")
		(net "PCIE_TX_CAP_N58")
	)
	(arc
		(start 142.472156 -210.86191)
		(mid 142.319147 -210.632916)
		(end 142.2654 -210.3628)
		(width 0.1397)
		(layer "In5.Cu")
		(net "PCIE_TX_CAP_N58")
	)
	(arc
		(start 228.07168 -65.046352)
		(mid 228.111548 -65.106019)
		(end 228.125528 -65.1764)
		(width 0.1016)
		(layer "In5.Cu")
		(net "PCIE_TX_CAP_N58")
	)
	(arc
		(start 227.69703 -65.17386)
		(mid 227.710429 -65.106499)
		(end 227.748592 -65.0494)
		(width 0.1016)
		(layer "In5.Cu")
		(net "PCIE_TX_CAP_N58")
	)
	(segment
		(start 145.808192 -211.975954)
		(end 145.504916 -211.672424)
		(width 0.136652)
		(layer "F.Cu")
		(net "PCIE_TX_CAP_N57")
	)
	(segment
		(start 229.599998 -65.999868)
		(end 229.100126 -66.49974)
		(width 0.136652)
		(layer "F.Cu")
		(net "PCIE_TX_CAP_N57")
	)
	(segment
		(start 145.446242 -211.5312)
		(end 145.446242 -211.308696)
		(width 0.136652)
		(layer "F.Cu")
		(net "PCIE_TX_CAP_N57")
	)
	(segment
		(start 145.553684 -211.049362)
		(end 145.706592 -210.896454)
		(width 0.136652)
		(layer "F.Cu")
		(net "PCIE_TX_CAP_N57")
	)
	(via
		(at 229.100126 -66.49974)
		(size 0.4572)
		(drill 0.2032)
		(layers "F.Cu" "B.Cu")
		(net "PCIE_TX_CAP_N57")
	)
	(via
		(at 145.706592 -210.896454)
		(size 0.508)
		(drill 0.254)
		(layers "F.Cu" "B.Cu")
		(net "PCIE_TX_CAP_N57")
	)
	(arc
		(start 145.504916 -211.672424)
		(mid 145.461539 -211.607645)
		(end 145.446242 -211.5312)
		(width 0.136652)
		(layer "F.Cu")
		(net "PCIE_TX_CAP_N57")
	)
	(arc
		(start 145.446242 -211.308696)
		(mid 145.474161 -211.168337)
		(end 145.553684 -211.049362)
		(width 0.136652)
		(layer "F.Cu")
		(net "PCIE_TX_CAP_N57")
	)
	(segment
		(start 229.542086 -72.405494)
		(end 228.7524 -68.457064)
		(width 0.1397)
		(layer "In5.Cu")
		(net "PCIE_TX_CAP_N57")
	)
	(segment
		(start 145.465292 -210.3882)
		(end 145.465292 -194.581272)
		(width 0.1397)
		(layer "In5.Cu")
		(net "PCIE_TX_CAP_N57")
	)
	(segment
		(start 145.465292 -194.581272)
		(end 148.59 -190.119)
		(width 0.1397)
		(layer "In5.Cu")
		(net "PCIE_TX_CAP_N57")
	)
	(segment
		(start 228.697028 -66.899028)
		(end 228.697028 -66.173858)
		(width 0.1016)
		(layer "In5.Cu")
		(net "PCIE_TX_CAP_N57")
	)
	(segment
		(start 226.14509 -91.670378)
		(end 229.542086 -72.405494)
		(width 0.1397)
		(layer "In5.Cu")
		(net "PCIE_TX_CAP_N57")
	)
	(segment
		(start 229.125526 -66.176398)
		(end 229.125526 -66.47434)
		(width 0.1016)
		(layer "In5.Cu")
		(net "PCIE_TX_CAP_N57")
	)
	(segment
		(start 228.7524 -66.9544)
		(end 228.697028 -66.899028)
		(width 0.1016)
		(layer "In5.Cu")
		(net "PCIE_TX_CAP_N57")
	)
	(segment
		(start 228.871272 -65.998598)
		(end 228.967284 -65.998598)
		(width 0.1016)
		(layer "In5.Cu")
		(net "PCIE_TX_CAP_N57")
	)
	(segment
		(start 145.706592 -210.896454)
		(end 145.654014 -210.843876)
		(width 0.1397)
		(layer "In5.Cu")
		(net "PCIE_TX_CAP_N57")
	)
	(segment
		(start 165.502844 -178.276504)
		(end 226.14509 -91.670378)
		(width 0.1397)
		(layer "In5.Cu")
		(net "PCIE_TX_CAP_N57")
	)
	(segment
		(start 229.064058 -66.03873)
		(end 229.071678 -66.04635)
		(width 0.1016)
		(layer "In5.Cu")
		(net "PCIE_TX_CAP_N57")
	)
	(segment
		(start 148.59 -190.119)
		(end 165.502844 -178.276504)
		(width 0.1397)
		(layer "In5.Cu")
		(net "PCIE_TX_CAP_N57")
	)
	(segment
		(start 229.125526 -66.47434)
		(end 229.100126 -66.49974)
		(width 0.1016)
		(layer "In5.Cu")
		(net "PCIE_TX_CAP_N57")
	)
	(segment
		(start 228.7524 -68.457064)
		(end 228.7524 -66.9544)
		(width 0.1397)
		(layer "In5.Cu")
		(net "PCIE_TX_CAP_N57")
	)
	(arc
		(start 228.697028 -66.173858)
		(mid 228.710427 -66.106497)
		(end 228.74859 -66.049398)
		(width 0.1016)
		(layer "In5.Cu")
		(net "PCIE_TX_CAP_N57")
	)
	(arc
		(start 145.654014 -210.843876)
		(mid 145.514321 -210.63481)
		(end 145.465292 -210.3882)
		(width 0.1397)
		(layer "In5.Cu")
		(net "PCIE_TX_CAP_N57")
	)
	(arc
		(start 228.74859 -66.049398)
		(mid 228.804877 -66.011788)
		(end 228.871272 -65.998598)
		(width 0.1016)
		(layer "In5.Cu")
		(net "PCIE_TX_CAP_N57")
	)
	(arc
		(start 228.967284 -65.998598)
		(mid 229.019676 -66.009019)
		(end 229.064058 -66.03873)
		(width 0.1016)
		(layer "In5.Cu")
		(net "PCIE_TX_CAP_N57")
	)
	(arc
		(start 229.071678 -66.04635)
		(mid 229.111546 -66.106017)
		(end 229.125526 -66.176398)
		(width 0.1016)
		(layer "In5.Cu")
		(net "PCIE_TX_CAP_N57")
	)
	(segment
		(start 149.008084 -211.975954)
		(end 148.704808 -211.672424)
		(width 0.136652)
		(layer "F.Cu")
		(net "PCIE_TX_CAP_N56")
	)
	(segment
		(start 148.646134 -211.5312)
		(end 148.646134 -211.282788)
		(width 0.136652)
		(layer "F.Cu")
		(net "PCIE_TX_CAP_N56")
	)
	(segment
		(start 148.735288 -211.067904)
		(end 148.906484 -210.896454)
		(width 0.136652)
		(layer "F.Cu")
		(net "PCIE_TX_CAP_N56")
	)
	(segment
		(start 230.599996 -64.99987)
		(end 230.100124 -65.499742)
		(width 0.136652)
		(layer "F.Cu")
		(net "PCIE_TX_CAP_N56")
	)
	(via
		(at 230.100124 -65.499742)
		(size 0.4572)
		(drill 0.2032)
		(layers "F.Cu" "B.Cu")
		(net "PCIE_TX_CAP_N56")
	)
	(via
		(at 148.906484 -210.896454)
		(size 0.508)
		(drill 0.254)
		(layers "F.Cu" "B.Cu")
		(net "PCIE_TX_CAP_N56")
	)
	(arc
		(start 148.704808 -211.672424)
		(mid 148.661431 -211.607645)
		(end 148.646134 -211.5312)
		(width 0.136652)
		(layer "F.Cu")
		(net "PCIE_TX_CAP_N56")
	)
	(arc
		(start 148.646134 -211.282788)
		(mid 148.66936 -211.166491)
		(end 148.735288 -211.067904)
		(width 0.136652)
		(layer "F.Cu")
		(net "PCIE_TX_CAP_N56")
	)
	(segment
		(start 148.6662 -194.018916)
		(end 151.13 -190.5)
		(width 0.1397)
		(layer "In5.Cu")
		(net "PCIE_TX_CAP_N56")
	)
	(segment
		(start 151.13 -190.5)
		(end 165.629844 -180.347112)
		(width 0.1397)
		(layer "In5.Cu")
		(net "PCIE_TX_CAP_N56")
	)
	(segment
		(start 227.198682 -92.4179)
		(end 230.657654 -72.801988)
		(width 0.1397)
		(layer "In5.Cu")
		(net "PCIE_TX_CAP_N56")
	)
	(segment
		(start 230.125524 -65.1764)
		(end 230.125524 -65.474342)
		(width 0.1016)
		(layer "In5.Cu")
		(net "PCIE_TX_CAP_N56")
	)
	(segment
		(start 229.7684 -68.355972)
		(end 229.7684 -66.9798)
		(width 0.1397)
		(layer "In5.Cu")
		(net "PCIE_TX_CAP_N56")
	)
	(segment
		(start 165.629844 -180.347112)
		(end 227.198682 -92.4179)
		(width 0.1397)
		(layer "In5.Cu")
		(net "PCIE_TX_CAP_N56")
	)
	(segment
		(start 148.6662 -210.312762)
		(end 148.6662 -194.018916)
		(width 0.1397)
		(layer "In5.Cu")
		(net "PCIE_TX_CAP_N56")
	)
	(segment
		(start 148.665184 -210.313778)
		(end 148.6662 -210.312762)
		(width 0.1397)
		(layer "In5.Cu")
		(net "PCIE_TX_CAP_N56")
	)
	(segment
		(start 229.697026 -66.908426)
		(end 229.697026 -65.17386)
		(width 0.1016)
		(layer "In5.Cu")
		(net "PCIE_TX_CAP_N56")
	)
	(segment
		(start 230.125524 -65.474342)
		(end 230.100124 -65.499742)
		(width 0.1016)
		(layer "In5.Cu")
		(net "PCIE_TX_CAP_N56")
	)
	(segment
		(start 230.064056 -65.038732)
		(end 230.071676 -65.046352)
		(width 0.1016)
		(layer "In5.Cu")
		(net "PCIE_TX_CAP_N56")
	)
	(segment
		(start 229.87127 -64.9986)
		(end 229.967282 -64.9986)
		(width 0.1016)
		(layer "In5.Cu")
		(net "PCIE_TX_CAP_N56")
	)
	(segment
		(start 229.7684 -66.9798)
		(end 229.697026 -66.908426)
		(width 0.1016)
		(layer "In5.Cu")
		(net "PCIE_TX_CAP_N56")
	)
	(segment
		(start 230.657654 -72.801988)
		(end 229.7684 -68.355972)
		(width 0.1397)
		(layer "In5.Cu")
		(net "PCIE_TX_CAP_N56")
	)
	(arc
		(start 229.748588 -65.0494)
		(mid 229.804875 -65.01179)
		(end 229.87127 -64.9986)
		(width 0.1016)
		(layer "In5.Cu")
		(net "PCIE_TX_CAP_N56")
	)
	(arc
		(start 230.071676 -65.046352)
		(mid 230.111544 -65.106019)
		(end 230.125524 -65.1764)
		(width 0.1016)
		(layer "In5.Cu")
		(net "PCIE_TX_CAP_N56")
	)
	(arc
		(start 229.697026 -65.17386)
		(mid 229.710425 -65.106499)
		(end 229.748588 -65.0494)
		(width 0.1016)
		(layer "In5.Cu")
		(net "PCIE_TX_CAP_N56")
	)
	(arc
		(start 148.906484 -210.896454)
		(mid 148.727857 -210.62912)
		(end 148.665184 -210.313778)
		(width 0.1397)
		(layer "In5.Cu")
		(net "PCIE_TX_CAP_N56")
	)
	(arc
		(start 229.967282 -64.9986)
		(mid 230.019674 -65.009021)
		(end 230.064056 -65.038732)
		(width 0.1016)
		(layer "In5.Cu")
		(net "PCIE_TX_CAP_N56")
	)
	(segment
		(start 152.20823 -211.975954)
		(end 151.904954 -211.672424)
		(width 0.136652)
		(layer "F.Cu")
		(net "PCIE_TX_CAP_N55")
	)
	(segment
		(start 151.84628 -211.5312)
		(end 151.84628 -211.276946)
		(width 0.136652)
		(layer "F.Cu")
		(net "PCIE_TX_CAP_N55")
	)
	(segment
		(start 151.931116 -211.071714)
		(end 152.10663 -210.896454)
		(width 0.136652)
		(layer "F.Cu")
		(net "PCIE_TX_CAP_N55")
	)
	(segment
		(start 232.599992 -65.999868)
		(end 232.10012 -66.49974)
		(width 0.136652)
		(layer "F.Cu")
		(net "PCIE_TX_CAP_N55")
	)
	(via
		(at 232.10012 -66.49974)
		(size 0.4572)
		(drill 0.2032)
		(layers "F.Cu" "B.Cu")
		(net "PCIE_TX_CAP_N55")
	)
	(via
		(at 152.10663 -210.896454)
		(size 0.508)
		(drill 0.254)
		(layers "F.Cu" "B.Cu")
		(net "PCIE_TX_CAP_N55")
	)
	(arc
		(start 151.84628 -211.276946)
		(mid 151.868277 -211.165888)
		(end 151.931116 -211.071714)
		(width 0.136652)
		(layer "F.Cu")
		(net "PCIE_TX_CAP_N55")
	)
	(arc
		(start 151.904954 -211.672424)
		(mid 151.861577 -211.607645)
		(end 151.84628 -211.5312)
		(width 0.136652)
		(layer "F.Cu")
		(net "PCIE_TX_CAP_N55")
	)
	(segment
		(start 231.756204 -90.058494)
		(end 232.391204 -93.233494)
		(width 0.1397)
		(layer "In5.Cu")
		(net "PCIE_TX_CAP_N55")
	)
	(segment
		(start 158.029148 -196.863716)
		(end 151.86533 -205.666848)
		(width 0.1397)
		(layer "In5.Cu")
		(net "PCIE_TX_CAP_N55")
	)
	(segment
		(start 231.756204 -83.708494)
		(end 232.391204 -86.883494)
		(width 0.1397)
		(layer "In5.Cu")
		(net "PCIE_TX_CAP_N55")
	)
	(segment
		(start 232.391204 -74.183494)
		(end 231.756204 -77.358494)
		(width 0.1397)
		(layer "In5.Cu")
		(net "PCIE_TX_CAP_N55")
	)
	(segment
		(start 232.10012 -66.49974)
		(end 232.12552 -66.47434)
		(width 0.1016)
		(layer "In5.Cu")
		(net "PCIE_TX_CAP_N55")
	)
	(segment
		(start 151.86533 -205.666848)
		(end 151.86533 -210.313778)
		(width 0.1397)
		(layer "In5.Cu")
		(net "PCIE_TX_CAP_N55")
	)
	(segment
		(start 232.407714 -99.665536)
		(end 158.745428 -195.84035)
		(width 0.1397)
		(layer "In5.Cu")
		(net "PCIE_TX_CAP_N55")
	)
	(segment
		(start 231.756204 -77.358494)
		(end 232.391204 -80.533494)
		(width 0.1397)
		(layer "In5.Cu")
		(net "PCIE_TX_CAP_N55")
	)
	(segment
		(start 231.697022 -66.927222)
		(end 231.7496 -66.9798)
		(width 0.1016)
		(layer "In5.Cu")
		(net "PCIE_TX_CAP_N55")
	)
	(segment
		(start 231.697022 -66.173858)
		(end 231.697022 -66.927222)
		(width 0.1016)
		(layer "In5.Cu")
		(net "PCIE_TX_CAP_N55")
	)
	(segment
		(start 231.967278 -65.998598)
		(end 231.871266 -65.998598)
		(width 0.1016)
		(layer "In5.Cu")
		(net "PCIE_TX_CAP_N55")
	)
	(segment
		(start 231.7496 -66.9798)
		(end 231.7496 -70.975474)
		(width 0.1397)
		(layer "In5.Cu")
		(net "PCIE_TX_CAP_N55")
	)
	(segment
		(start 232.071672 -66.04635)
		(end 232.064052 -66.03873)
		(width 0.1016)
		(layer "In5.Cu")
		(net "PCIE_TX_CAP_N55")
	)
	(segment
		(start 231.7496 -70.975474)
		(end 232.391204 -74.183494)
		(width 0.1397)
		(layer "In5.Cu")
		(net "PCIE_TX_CAP_N55")
	)
	(segment
		(start 158.721552 -195.875148)
		(end 158.029148 -196.863716)
		(width 0.1397)
		(layer "In5.Cu")
		(net "PCIE_TX_CAP_N55")
	)
	(segment
		(start 232.391204 -80.533494)
		(end 231.756204 -83.708494)
		(width 0.1397)
		(layer "In5.Cu")
		(net "PCIE_TX_CAP_N55")
	)
	(segment
		(start 232.12552 -66.47434)
		(end 232.12552 -66.176398)
		(width 0.1016)
		(layer "In5.Cu")
		(net "PCIE_TX_CAP_N55")
	)
	(segment
		(start 158.745428 -195.84035)
		(end 158.721552 -195.875148)
		(width 0.1397)
		(layer "In5.Cu")
		(net "PCIE_TX_CAP_N55")
	)
	(segment
		(start 232.391204 -93.233494)
		(end 231.756204 -96.408494)
		(width 0.1397)
		(layer "In5.Cu")
		(net "PCIE_TX_CAP_N55")
	)
	(segment
		(start 231.756204 -96.408494)
		(end 232.407714 -99.665536)
		(width 0.1397)
		(layer "In5.Cu")
		(net "PCIE_TX_CAP_N55")
	)
	(segment
		(start 232.391204 -86.883494)
		(end 231.756204 -90.058494)
		(width 0.1397)
		(layer "In5.Cu")
		(net "PCIE_TX_CAP_N55")
	)
	(arc
		(start 231.871266 -65.998598)
		(mid 231.804877 -66.011804)
		(end 231.748584 -66.049398)
		(width 0.1016)
		(layer "In5.Cu")
		(net "PCIE_TX_CAP_N55")
	)
	(arc
		(start 231.748584 -66.049398)
		(mid 231.710429 -66.106501)
		(end 231.697022 -66.173858)
		(width 0.1016)
		(layer "In5.Cu")
		(net "PCIE_TX_CAP_N55")
	)
	(arc
		(start 232.064052 -66.03873)
		(mid 232.019652 -66.009063)
		(end 231.967278 -65.998598)
		(width 0.1016)
		(layer "In5.Cu")
		(net "PCIE_TX_CAP_N55")
	)
	(arc
		(start 232.12552 -66.176398)
		(mid 232.111522 -66.106024)
		(end 232.071672 -66.04635)
		(width 0.1016)
		(layer "In5.Cu")
		(net "PCIE_TX_CAP_N55")
	)
	(arc
		(start 151.86533 -210.313778)
		(mid 151.928051 -210.6291)
		(end 152.10663 -210.896454)
		(width 0.1397)
		(layer "In5.Cu")
		(net "PCIE_TX_CAP_N55")
	)
	(segment
		(start 155.408122 -211.975954)
		(end 155.104846 -211.672424)
		(width 0.136652)
		(layer "F.Cu")
		(net "PCIE_TX_CAP_N54")
	)
	(segment
		(start 155.046172 -211.5312)
		(end 155.046172 -211.2518)
		(width 0.136652)
		(layer "F.Cu")
		(net "PCIE_TX_CAP_N54")
	)
	(segment
		(start 233.59999 -64.99987)
		(end 233.100118 -65.499742)
		(width 0.136652)
		(layer "F.Cu")
		(net "PCIE_TX_CAP_N54")
	)
	(segment
		(start 155.113228 -211.089494)
		(end 155.306522 -210.896454)
		(width 0.136652)
		(layer "F.Cu")
		(net "PCIE_TX_CAP_N54")
	)
	(via
		(at 155.306522 -210.896454)
		(size 0.508)
		(drill 0.254)
		(layers "F.Cu" "B.Cu")
		(net "PCIE_TX_CAP_N54")
	)
	(via
		(at 233.100118 -65.499742)
		(size 0.4572)
		(drill 0.2032)
		(layers "F.Cu" "B.Cu")
		(net "PCIE_TX_CAP_N54")
	)
	(arc
		(start 155.104846 -211.672424)
		(mid 155.061469 -211.607645)
		(end 155.046172 -211.5312)
		(width 0.136652)
		(layer "F.Cu")
		(net "PCIE_TX_CAP_N54")
	)
	(arc
		(start 155.046172 -211.2518)
		(mid 155.063548 -211.163973)
		(end 155.113228 -211.089494)
		(width 0.136652)
		(layer "F.Cu")
		(net "PCIE_TX_CAP_N54")
	)
	(segment
		(start 233.125518 -65.1764)
		(end 233.125518 -65.474342)
		(width 0.1016)
		(layer "In5.Cu")
		(net "PCIE_TX_CAP_N54")
	)
	(segment
		(start 167.693594 -192.112138)
		(end 172.662088 -188.6331)
		(width 0.1397)
		(layer "In5.Cu")
		(net "PCIE_TX_CAP_N54")
	)
	(segment
		(start 233.427524 -86.883494)
		(end 232.792524 -83.708494)
		(width 0.1397)
		(layer "In5.Cu")
		(net "PCIE_TX_CAP_N54")
	)
	(segment
		(start 233.427524 -80.533494)
		(end 232.792524 -77.358494)
		(width 0.1397)
		(layer "In5.Cu")
		(net "PCIE_TX_CAP_N54")
	)
	(segment
		(start 155.065222 -204.74051)
		(end 167.693594 -192.112138)
		(width 0.1397)
		(layer "In5.Cu")
		(net "PCIE_TX_CAP_N54")
	)
	(segment
		(start 233.427524 -93.233494)
		(end 232.792524 -90.058494)
		(width 0.1397)
		(layer "In5.Cu")
		(net "PCIE_TX_CAP_N54")
	)
	(segment
		(start 233.06405 -65.038732)
		(end 233.07167 -65.046352)
		(width 0.1016)
		(layer "In5.Cu")
		(net "PCIE_TX_CAP_N54")
	)
	(segment
		(start 232.69702 -66.93662)
		(end 232.69702 -65.17386)
		(width 0.1016)
		(layer "In5.Cu")
		(net "PCIE_TX_CAP_N54")
	)
	(segment
		(start 232.7656 -70.874382)
		(end 232.7656 -67.0052)
		(width 0.1397)
		(layer "In5.Cu")
		(net "PCIE_TX_CAP_N54")
	)
	(segment
		(start 232.871264 -64.9986)
		(end 232.967276 -64.9986)
		(width 0.1016)
		(layer "In5.Cu")
		(net "PCIE_TX_CAP_N54")
	)
	(segment
		(start 232.792524 -96.408494)
		(end 233.427524 -93.233494)
		(width 0.1397)
		(layer "In5.Cu")
		(net "PCIE_TX_CAP_N54")
	)
	(segment
		(start 232.792524 -90.058494)
		(end 233.427524 -86.883494)
		(width 0.1397)
		(layer "In5.Cu")
		(net "PCIE_TX_CAP_N54")
	)
	(segment
		(start 232.792524 -102.758494)
		(end 233.427524 -99.583494)
		(width 0.1397)
		(layer "In5.Cu")
		(net "PCIE_TX_CAP_N54")
	)
	(segment
		(start 232.792524 -83.708494)
		(end 233.427524 -80.533494)
		(width 0.1397)
		(layer "In5.Cu")
		(net "PCIE_TX_CAP_N54")
	)
	(segment
		(start 172.662088 -188.6331)
		(end 232.792524 -102.758494)
		(width 0.1397)
		(layer "In5.Cu")
		(net "PCIE_TX_CAP_N54")
	)
	(segment
		(start 232.7656 -67.0052)
		(end 232.69702 -66.93662)
		(width 0.1016)
		(layer "In5.Cu")
		(net "PCIE_TX_CAP_N54")
	)
	(segment
		(start 233.427524 -74.183494)
		(end 232.7656 -70.874382)
		(width 0.1397)
		(layer "In5.Cu")
		(net "PCIE_TX_CAP_N54")
	)
	(segment
		(start 233.125518 -65.474342)
		(end 233.100118 -65.499742)
		(width 0.1016)
		(layer "In5.Cu")
		(net "PCIE_TX_CAP_N54")
	)
	(segment
		(start 155.065222 -210.313778)
		(end 155.065222 -204.74051)
		(width 0.1397)
		(layer "In5.Cu")
		(net "PCIE_TX_CAP_N54")
	)
	(segment
		(start 232.792524 -77.358494)
		(end 233.427524 -74.183494)
		(width 0.1397)
		(layer "In5.Cu")
		(net "PCIE_TX_CAP_N54")
	)
	(segment
		(start 233.427524 -99.583494)
		(end 232.792524 -96.408494)
		(width 0.1397)
		(layer "In5.Cu")
		(net "PCIE_TX_CAP_N54")
	)
	(arc
		(start 232.69702 -65.17386)
		(mid 232.710419 -65.106499)
		(end 232.748582 -65.0494)
		(width 0.1016)
		(layer "In5.Cu")
		(net "PCIE_TX_CAP_N54")
	)
	(arc
		(start 233.07167 -65.046352)
		(mid 233.111538 -65.106019)
		(end 233.125518 -65.1764)
		(width 0.1016)
		(layer "In5.Cu")
		(net "PCIE_TX_CAP_N54")
	)
	(arc
		(start 232.967276 -64.9986)
		(mid 233.019668 -65.009021)
		(end 233.06405 -65.038732)
		(width 0.1016)
		(layer "In5.Cu")
		(net "PCIE_TX_CAP_N54")
	)
	(arc
		(start 232.748582 -65.0494)
		(mid 232.804869 -65.01179)
		(end 232.871264 -64.9986)
		(width 0.1016)
		(layer "In5.Cu")
		(net "PCIE_TX_CAP_N54")
	)
	(arc
		(start 155.306522 -210.896454)
		(mid 155.127895 -210.62912)
		(end 155.065222 -210.313778)
		(width 0.1397)
		(layer "In5.Cu")
		(net "PCIE_TX_CAP_N54")
	)
	(segment
		(start 158.313374 -211.089494)
		(end 158.506668 -210.896454)
		(width 0.136652)
		(layer "F.Cu")
		(net "PCIE_TX_CAP_N53")
	)
	(segment
		(start 158.608268 -211.975954)
		(end 158.304992 -211.672424)
		(width 0.136652)
		(layer "F.Cu")
		(net "PCIE_TX_CAP_N53")
	)
	(segment
		(start 234.599988 -65.999868)
		(end 234.100116 -66.49974)
		(width 0.136652)
		(layer "F.Cu")
		(net "PCIE_TX_CAP_N53")
	)
	(segment
		(start 158.246318 -211.5312)
		(end 158.246318 -211.2518)
		(width 0.136652)
		(layer "F.Cu")
		(net "PCIE_TX_CAP_N53")
	)
	(via
		(at 234.100116 -66.49974)
		(size 0.4572)
		(drill 0.2032)
		(layers "F.Cu" "B.Cu")
		(net "PCIE_TX_CAP_N53")
	)
	(via
		(at 158.506668 -210.896454)
		(size 0.508)
		(drill 0.254)
		(layers "F.Cu" "B.Cu")
		(net "PCIE_TX_CAP_N53")
	)
	(arc
		(start 158.246318 -211.2518)
		(mid 158.263694 -211.163973)
		(end 158.313374 -211.089494)
		(width 0.136652)
		(layer "F.Cu")
		(net "PCIE_TX_CAP_N53")
	)
	(arc
		(start 158.304992 -211.672424)
		(mid 158.261615 -211.607645)
		(end 158.246318 -211.5312)
		(width 0.136652)
		(layer "F.Cu")
		(net "PCIE_TX_CAP_N53")
	)
	(segment
		(start 234.100116 -66.49974)
		(end 234.125516 -66.47434)
		(width 0.1016)
		(layer "In5.Cu")
		(net "PCIE_TX_CAP_N53")
	)
	(segment
		(start 234.437682 -80.533494)
		(end 233.802682 -83.708494)
		(width 0.1397)
		(layer "In5.Cu")
		(net "PCIE_TX_CAP_N53")
	)
	(segment
		(start 233.802682 -83.708494)
		(end 234.437682 -86.883494)
		(width 0.1397)
		(layer "In5.Cu")
		(net "PCIE_TX_CAP_N53")
	)
	(segment
		(start 233.967274 -65.998598)
		(end 233.871262 -65.998598)
		(width 0.1016)
		(layer "In5.Cu")
		(net "PCIE_TX_CAP_N53")
	)
	(segment
		(start 234.437682 -93.233494)
		(end 233.802682 -96.408494)
		(width 0.1397)
		(layer "In5.Cu")
		(net "PCIE_TX_CAP_N53")
	)
	(segment
		(start 233.528108 -104.130856)
		(end 167.005 -199.136)
		(width 0.1397)
		(layer "In5.Cu")
		(net "PCIE_TX_CAP_N53")
	)
	(segment
		(start 233.7562 -66.9798)
		(end 233.7562 -70.77583)
		(width 0.1397)
		(layer "In5.Cu")
		(net "PCIE_TX_CAP_N53")
	)
	(segment
		(start 234.437682 -74.183494)
		(end 233.802682 -77.358494)
		(width 0.1397)
		(layer "In5.Cu")
		(net "PCIE_TX_CAP_N53")
	)
	(segment
		(start 234.437682 -86.883494)
		(end 233.802682 -90.058494)
		(width 0.1397)
		(layer "In5.Cu")
		(net "PCIE_TX_CAP_N53")
	)
	(segment
		(start 234.071668 -66.04635)
		(end 234.064048 -66.03873)
		(width 0.1016)
		(layer "In5.Cu")
		(net "PCIE_TX_CAP_N53")
	)
	(segment
		(start 233.697018 -66.920618)
		(end 233.7562 -66.9798)
		(width 0.1016)
		(layer "In5.Cu")
		(net "PCIE_TX_CAP_N53")
	)
	(segment
		(start 233.802682 -96.408494)
		(end 234.437682 -99.583494)
		(width 0.1397)
		(layer "In5.Cu")
		(net "PCIE_TX_CAP_N53")
	)
	(segment
		(start 167.005 -199.136)
		(end 161.650934 -202.88504)
		(width 0.1397)
		(layer "In5.Cu")
		(net "PCIE_TX_CAP_N53")
	)
	(segment
		(start 158.265368 -207.71993)
		(end 158.265368 -210.313778)
		(width 0.1397)
		(layer "In5.Cu")
		(net "PCIE_TX_CAP_N53")
	)
	(segment
		(start 161.650934 -202.88504)
		(end 158.265368 -207.71993)
		(width 0.1397)
		(layer "In5.Cu")
		(net "PCIE_TX_CAP_N53")
	)
	(segment
		(start 234.437682 -99.583494)
		(end 233.528108 -104.130856)
		(width 0.1397)
		(layer "In5.Cu")
		(net "PCIE_TX_CAP_N53")
	)
	(segment
		(start 233.7562 -70.77583)
		(end 234.437682 -74.183494)
		(width 0.1397)
		(layer "In5.Cu")
		(net "PCIE_TX_CAP_N53")
	)
	(segment
		(start 234.125516 -66.47434)
		(end 234.125516 -66.176398)
		(width 0.1016)
		(layer "In5.Cu")
		(net "PCIE_TX_CAP_N53")
	)
	(segment
		(start 233.697018 -66.173858)
		(end 233.697018 -66.920618)
		(width 0.1016)
		(layer "In5.Cu")
		(net "PCIE_TX_CAP_N53")
	)
	(segment
		(start 233.802682 -77.358494)
		(end 234.437682 -80.533494)
		(width 0.1397)
		(layer "In5.Cu")
		(net "PCIE_TX_CAP_N53")
	)
	(segment
		(start 233.802682 -90.058494)
		(end 234.437682 -93.233494)
		(width 0.1397)
		(layer "In5.Cu")
		(net "PCIE_TX_CAP_N53")
	)
	(arc
		(start 233.871262 -65.998598)
		(mid 233.804873 -66.011804)
		(end 233.74858 -66.049398)
		(width 0.1016)
		(layer "In5.Cu")
		(net "PCIE_TX_CAP_N53")
	)
	(arc
		(start 234.064048 -66.03873)
		(mid 234.019648 -66.009063)
		(end 233.967274 -65.998598)
		(width 0.1016)
		(layer "In5.Cu")
		(net "PCIE_TX_CAP_N53")
	)
	(arc
		(start 234.125516 -66.176398)
		(mid 234.111518 -66.106024)
		(end 234.071668 -66.04635)
		(width 0.1016)
		(layer "In5.Cu")
		(net "PCIE_TX_CAP_N53")
	)
	(arc
		(start 233.74858 -66.049398)
		(mid 233.710425 -66.106501)
		(end 233.697018 -66.173858)
		(width 0.1016)
		(layer "In5.Cu")
		(net "PCIE_TX_CAP_N53")
	)
	(arc
		(start 158.265368 -210.313778)
		(mid 158.328089 -210.6291)
		(end 158.506668 -210.896454)
		(width 0.1397)
		(layer "In5.Cu")
		(net "PCIE_TX_CAP_N53")
	)
	(segment
		(start 161.5313 -211.071714)
		(end 161.70656 -210.896454)
		(width 0.136652)
		(layer "F.Cu")
		(net "PCIE_TX_CAP_N52")
	)
	(segment
		(start 235.599986 -64.99987)
		(end 235.100114 -65.499742)
		(width 0.136652)
		(layer "F.Cu")
		(net "PCIE_TX_CAP_N52")
	)
	(segment
		(start 161.44621 -211.5312)
		(end 161.44621 -211.2772)
		(width 0.136652)
		(layer "F.Cu")
		(net "PCIE_TX_CAP_N52")
	)
	(segment
		(start 161.80816 -211.975954)
		(end 161.504884 -211.672424)
		(width 0.136652)
		(layer "F.Cu")
		(net "PCIE_TX_CAP_N52")
	)
	(via
		(at 235.100114 -65.499742)
		(size 0.4572)
		(drill 0.2032)
		(layers "F.Cu" "B.Cu")
		(net "PCIE_TX_CAP_N52")
	)
	(via
		(at 161.70656 -210.896454)
		(size 0.508)
		(drill 0.254)
		(layers "F.Cu" "B.Cu")
		(net "PCIE_TX_CAP_N52")
	)
	(arc
		(start 161.44621 -211.2772)
		(mid 161.468329 -211.166001)
		(end 161.5313 -211.071714)
		(width 0.136652)
		(layer "F.Cu")
		(net "PCIE_TX_CAP_N52")
	)
	(arc
		(start 161.504884 -211.672424)
		(mid 161.461507 -211.607645)
		(end 161.44621 -211.5312)
		(width 0.136652)
		(layer "F.Cu")
		(net "PCIE_TX_CAP_N52")
	)
	(segment
		(start 235.448094 -74.183494)
		(end 234.813094 -77.358494)
		(width 0.1397)
		(layer "In5.Cu")
		(net "PCIE_TX_CAP_N52")
	)
	(segment
		(start 234.813094 -96.408494)
		(end 235.448094 -99.583494)
		(width 0.1397)
		(layer "In5.Cu")
		(net "PCIE_TX_CAP_N52")
	)
	(segment
		(start 234.697016 -65.17386)
		(end 234.697016 -66.930016)
		(width 0.1016)
		(layer "In5.Cu")
		(net "PCIE_TX_CAP_N52")
	)
	(segment
		(start 235.448094 -80.533494)
		(end 234.813094 -83.708494)
		(width 0.1397)
		(layer "In5.Cu")
		(net "PCIE_TX_CAP_N52")
	)
	(segment
		(start 234.813094 -90.058494)
		(end 235.448094 -93.233494)
		(width 0.1397)
		(layer "In5.Cu")
		(net "PCIE_TX_CAP_N52")
	)
	(segment
		(start 167.635174 -202.27671)
		(end 161.46526 -208.446624)
		(width 0.1397)
		(layer "In5.Cu")
		(net "PCIE_TX_CAP_N52")
	)
	(segment
		(start 168.656 -201.561954)
		(end 167.635174 -202.27671)
		(width 0.1397)
		(layer "In5.Cu")
		(net "PCIE_TX_CAP_N52")
	)
	(segment
		(start 234.967272 -64.9986)
		(end 234.87126 -64.9986)
		(width 0.1016)
		(layer "In5.Cu")
		(net "PCIE_TX_CAP_N52")
	)
	(segment
		(start 233.622342 -108.780326)
		(end 168.656 -201.561954)
		(width 0.1397)
		(layer "In5.Cu")
		(net "PCIE_TX_CAP_N52")
	)
	(segment
		(start 161.46526 -208.446624)
		(end 161.46526 -210.313778)
		(width 0.1397)
		(layer "In5.Cu")
		(net "PCIE_TX_CAP_N52")
	)
	(segment
		(start 235.448094 -86.883494)
		(end 234.813094 -90.058494)
		(width 0.1397)
		(layer "In5.Cu")
		(net "PCIE_TX_CAP_N52")
	)
	(segment
		(start 235.448094 -93.233494)
		(end 234.813094 -96.408494)
		(width 0.1397)
		(layer "In5.Cu")
		(net "PCIE_TX_CAP_N52")
	)
	(segment
		(start 235.125514 -65.474342)
		(end 235.125514 -65.1764)
		(width 0.1016)
		(layer "In5.Cu")
		(net "PCIE_TX_CAP_N52")
	)
	(segment
		(start 234.813094 -83.708494)
		(end 235.448094 -86.883494)
		(width 0.1397)
		(layer "In5.Cu")
		(net "PCIE_TX_CAP_N52")
	)
	(segment
		(start 234.697016 -66.930016)
		(end 234.7468 -66.9798)
		(width 0.1016)
		(layer "In5.Cu")
		(net "PCIE_TX_CAP_N52")
	)
	(segment
		(start 234.7468 -66.9798)
		(end 234.7468 -70.677278)
		(width 0.1397)
		(layer "In5.Cu")
		(net "PCIE_TX_CAP_N52")
	)
	(segment
		(start 235.100114 -65.499742)
		(end 235.125514 -65.474342)
		(width 0.1016)
		(layer "In5.Cu")
		(net "PCIE_TX_CAP_N52")
	)
	(segment
		(start 234.813094 -77.358494)
		(end 235.448094 -80.533494)
		(width 0.1397)
		(layer "In5.Cu")
		(net "PCIE_TX_CAP_N52")
	)
	(segment
		(start 235.071666 -65.046352)
		(end 235.064046 -65.038732)
		(width 0.1016)
		(layer "In5.Cu")
		(net "PCIE_TX_CAP_N52")
	)
	(segment
		(start 234.7468 -70.677278)
		(end 235.448094 -74.183494)
		(width 0.1397)
		(layer "In5.Cu")
		(net "PCIE_TX_CAP_N52")
	)
	(segment
		(start 235.448094 -99.583494)
		(end 233.622342 -108.780326)
		(width 0.1397)
		(layer "In5.Cu")
		(net "PCIE_TX_CAP_N52")
	)
	(arc
		(start 234.87126 -64.9986)
		(mid 234.804871 -65.011806)
		(end 234.748578 -65.0494)
		(width 0.1016)
		(layer "In5.Cu")
		(net "PCIE_TX_CAP_N52")
	)
	(arc
		(start 161.46526 -210.313778)
		(mid 161.527981 -210.6291)
		(end 161.70656 -210.896454)
		(width 0.1397)
		(layer "In5.Cu")
		(net "PCIE_TX_CAP_N52")
	)
	(arc
		(start 235.064046 -65.038732)
		(mid 235.019646 -65.009065)
		(end 234.967272 -64.9986)
		(width 0.1016)
		(layer "In5.Cu")
		(net "PCIE_TX_CAP_N52")
	)
	(arc
		(start 235.125514 -65.1764)
		(mid 235.111516 -65.106026)
		(end 235.071666 -65.046352)
		(width 0.1016)
		(layer "In5.Cu")
		(net "PCIE_TX_CAP_N52")
	)
	(arc
		(start 234.748578 -65.0494)
		(mid 234.710423 -65.106503)
		(end 234.697016 -65.17386)
		(width 0.1016)
		(layer "In5.Cu")
		(net "PCIE_TX_CAP_N52")
	)
	(segment
		(start 167.046148 -211.5312)
		(end 167.046148 -211.2899)
		(width 0.136652)
		(layer "F.Cu")
		(net "PCIE_TX_CAP_N51")
	)
	(segment
		(start 236.599984 -65.999868)
		(end 236.100112 -66.49974)
		(width 0.136652)
		(layer "F.Cu")
		(net "PCIE_TX_CAP_N51")
	)
	(segment
		(start 167.140382 -211.062824)
		(end 167.306498 -210.896454)
		(width 0.136652)
		(layer "F.Cu")
		(net "PCIE_TX_CAP_N51")
	)
	(segment
		(start 167.408098 -211.975954)
		(end 167.104822 -211.672424)
		(width 0.136652)
		(layer "F.Cu")
		(net "PCIE_TX_CAP_N51")
	)
	(via
		(at 236.100112 -66.49974)
		(size 0.4572)
		(drill 0.2032)
		(layers "F.Cu" "B.Cu")
		(net "PCIE_TX_CAP_N51")
	)
	(via
		(at 167.306498 -210.896454)
		(size 0.508)
		(drill 0.254)
		(layers "F.Cu" "B.Cu")
		(net "PCIE_TX_CAP_N51")
	)
	(arc
		(start 167.104822 -211.672424)
		(mid 167.061445 -211.607645)
		(end 167.046148 -211.5312)
		(width 0.136652)
		(layer "F.Cu")
		(net "PCIE_TX_CAP_N51")
	)
	(arc
		(start 167.046148 -211.2899)
		(mid 167.070689 -211.166994)
		(end 167.140382 -211.062824)
		(width 0.136652)
		(layer "F.Cu")
		(net "PCIE_TX_CAP_N51")
	)
	(segment
		(start 236.064044 -66.03873)
		(end 236.071664 -66.04635)
		(width 0.1016)
		(layer "In5.Cu")
		(net "PCIE_TX_CAP_N51")
	)
	(segment
		(start 235.7374 -70.578726)
		(end 235.7374 -66.9798)
		(width 0.1397)
		(layer "In5.Cu")
		(net "PCIE_TX_CAP_N51")
	)
	(segment
		(start 236.45876 -93.232986)
		(end 235.823506 -90.059002)
		(width 0.1397)
		(layer "In5.Cu")
		(net "PCIE_TX_CAP_N51")
	)
	(segment
		(start 236.125512 -66.47434)
		(end 236.100112 -66.49974)
		(width 0.1016)
		(layer "In5.Cu")
		(net "PCIE_TX_CAP_N51")
	)
	(segment
		(start 167.065198 -209.436716)
		(end 235.421932 -111.813086)
		(width 0.1397)
		(layer "In5.Cu")
		(net "PCIE_TX_CAP_N51")
	)
	(segment
		(start 236.125512 -66.176398)
		(end 236.125512 -66.47434)
		(width 0.1016)
		(layer "In5.Cu")
		(net "PCIE_TX_CAP_N51")
	)
	(segment
		(start 167.065198 -210.313778)
		(end 167.065198 -209.436716)
		(width 0.1397)
		(layer "In5.Cu")
		(net "PCIE_TX_CAP_N51")
	)
	(segment
		(start 235.823506 -90.059002)
		(end 236.45876 -86.882986)
		(width 0.1397)
		(layer "In5.Cu")
		(net "PCIE_TX_CAP_N51")
	)
	(segment
		(start 235.871258 -65.998598)
		(end 235.96727 -65.998598)
		(width 0.1016)
		(layer "In5.Cu")
		(net "PCIE_TX_CAP_N51")
	)
	(segment
		(start 235.421932 -111.813086)
		(end 236.458506 -105.934002)
		(width 0.1397)
		(layer "In5.Cu")
		(net "PCIE_TX_CAP_N51")
	)
	(segment
		(start 236.45749 -99.578414)
		(end 236.441996 -99.497896)
		(width 0.1397)
		(layer "In5.Cu")
		(net "PCIE_TX_CAP_N51")
	)
	(segment
		(start 236.45876 -80.532986)
		(end 235.823506 -77.359002)
		(width 0.1397)
		(layer "In5.Cu")
		(net "PCIE_TX_CAP_N51")
	)
	(segment
		(start 236.457744 -74.186796)
		(end 235.7374 -70.578726)
		(width 0.1397)
		(layer "In5.Cu")
		(net "PCIE_TX_CAP_N51")
	)
	(segment
		(start 236.445806 -99.648264)
		(end 236.45749 -99.578414)
		(width 0.1397)
		(layer "In5.Cu")
		(net "PCIE_TX_CAP_N51")
	)
	(segment
		(start 235.697014 -66.939414)
		(end 235.697014 -66.173858)
		(width 0.1016)
		(layer "In5.Cu")
		(net "PCIE_TX_CAP_N51")
	)
	(segment
		(start 236.458506 -105.934002)
		(end 235.819442 -102.738174)
		(width 0.1397)
		(layer "In5.Cu")
		(net "PCIE_TX_CAP_N51")
	)
	(segment
		(start 235.823506 -96.409002)
		(end 236.45876 -93.232986)
		(width 0.1397)
		(layer "In5.Cu")
		(net "PCIE_TX_CAP_N51")
	)
	(segment
		(start 235.823506 -83.709002)
		(end 236.45876 -80.532986)
		(width 0.1397)
		(layer "In5.Cu")
		(net "PCIE_TX_CAP_N51")
	)
	(segment
		(start 236.45876 -86.882986)
		(end 235.823506 -83.709002)
		(width 0.1397)
		(layer "In5.Cu")
		(net "PCIE_TX_CAP_N51")
	)
	(segment
		(start 235.7374 -66.9798)
		(end 235.697014 -66.939414)
		(width 0.1016)
		(layer "In5.Cu")
		(net "PCIE_TX_CAP_N51")
	)
	(segment
		(start 235.819442 -102.738174)
		(end 236.445806 -99.648264)
		(width 0.1397)
		(layer "In5.Cu")
		(net "PCIE_TX_CAP_N51")
	)
	(segment
		(start 236.441996 -99.497896)
		(end 235.823506 -96.409002)
		(width 0.1397)
		(layer "In5.Cu")
		(net "PCIE_TX_CAP_N51")
	)
	(segment
		(start 235.823506 -77.359002)
		(end 236.457744 -74.186796)
		(width 0.1397)
		(layer "In5.Cu")
		(net "PCIE_TX_CAP_N51")
	)
	(arc
		(start 236.071664 -66.04635)
		(mid 236.111532 -66.106017)
		(end 236.125512 -66.176398)
		(width 0.1016)
		(layer "In5.Cu")
		(net "PCIE_TX_CAP_N51")
	)
	(arc
		(start 235.748576 -66.049398)
		(mid 235.804863 -66.011788)
		(end 235.871258 -65.998598)
		(width 0.1016)
		(layer "In5.Cu")
		(net "PCIE_TX_CAP_N51")
	)
	(arc
		(start 235.96727 -65.998598)
		(mid 236.019662 -66.009019)
		(end 236.064044 -66.03873)
		(width 0.1016)
		(layer "In5.Cu")
		(net "PCIE_TX_CAP_N51")
	)
	(arc
		(start 235.697014 -66.173858)
		(mid 235.710413 -66.106497)
		(end 235.748576 -66.049398)
		(width 0.1016)
		(layer "In5.Cu")
		(net "PCIE_TX_CAP_N51")
	)
	(arc
		(start 167.306498 -210.896454)
		(mid 167.127871 -210.62912)
		(end 167.065198 -210.313778)
		(width 0.1397)
		(layer "In5.Cu")
		(net "PCIE_TX_CAP_N51")
	)
	(segment
		(start 170.336464 -211.066126)
		(end 170.50639 -210.896454)
		(width 0.136652)
		(layer "F.Cu")
		(net "PCIE_TX_CAP_N50")
	)
	(segment
		(start 170.24604 -211.5312)
		(end 170.24604 -211.288884)
		(width 0.136652)
		(layer "F.Cu")
		(net "PCIE_TX_CAP_N50")
	)
	(segment
		(start 237.599982 -64.99987)
		(end 237.10011 -65.499742)
		(width 0.136652)
		(layer "F.Cu")
		(net "PCIE_TX_CAP_N50")
	)
	(segment
		(start 170.60799 -211.975954)
		(end 170.304714 -211.672424)
		(width 0.136652)
		(layer "F.Cu")
		(net "PCIE_TX_CAP_N50")
	)
	(via
		(at 237.10011 -65.499742)
		(size 0.4572)
		(drill 0.2032)
		(layers "F.Cu" "B.Cu")
		(net "PCIE_TX_CAP_N50")
	)
	(via
		(at 170.50639 -210.896454)
		(size 0.508)
		(drill 0.254)
		(layers "F.Cu" "B.Cu")
		(net "PCIE_TX_CAP_N50")
	)
	(arc
		(start 170.304714 -211.672424)
		(mid 170.261337 -211.607645)
		(end 170.24604 -211.5312)
		(width 0.136652)
		(layer "F.Cu")
		(net "PCIE_TX_CAP_N50")
	)
	(arc
		(start 170.24604 -211.28482)
		(mid 170.269487 -211.166472)
		(end 170.336464 -211.066126)
		(width 0.136652)
		(layer "F.Cu")
		(net "PCIE_TX_CAP_N50")
	)
	(arc
		(start 170.24604 -211.288884)
		(mid 170.246043 -211.286852)
		(end 170.24604 -211.28482)
		(width 0.136652)
		(layer "F.Cu")
		(net "PCIE_TX_CAP_N50")
	)
	(segment
		(start 237.494572 -105.933494)
		(end 235.859066 -114.11077)
		(width 0.1397)
		(layer "In5.Cu")
		(net "PCIE_TX_CAP_N50")
	)
	(segment
		(start 236.859572 -96.408494)
		(end 237.494572 -99.583494)
		(width 0.1397)
		(layer "In5.Cu")
		(net "PCIE_TX_CAP_N50")
	)
	(segment
		(start 237.494572 -86.883494)
		(end 236.859572 -90.058494)
		(width 0.1397)
		(layer "In5.Cu")
		(net "PCIE_TX_CAP_N50")
	)
	(segment
		(start 237.494572 -99.583494)
		(end 236.859572 -102.758494)
		(width 0.1397)
		(layer "In5.Cu")
		(net "PCIE_TX_CAP_N50")
	)
	(segment
		(start 235.859066 -114.11077)
		(end 170.26509 -207.789526)
		(width 0.1397)
		(layer "In5.Cu")
		(net "PCIE_TX_CAP_N50")
	)
	(segment
		(start 237.494572 -74.183494)
		(end 236.859572 -77.358494)
		(width 0.1397)
		(layer "In5.Cu")
		(net "PCIE_TX_CAP_N50")
	)
	(segment
		(start 236.697012 -66.948812)
		(end 236.7534 -67.0052)
		(width 0.1016)
		(layer "In5.Cu")
		(net "PCIE_TX_CAP_N50")
	)
	(segment
		(start 236.859572 -83.708494)
		(end 237.494572 -86.883494)
		(width 0.1397)
		(layer "In5.Cu")
		(net "PCIE_TX_CAP_N50")
	)
	(segment
		(start 236.859572 -102.758494)
		(end 237.494572 -105.933494)
		(width 0.1397)
		(layer "In5.Cu")
		(net "PCIE_TX_CAP_N50")
	)
	(segment
		(start 236.859572 -77.358494)
		(end 237.494572 -80.533494)
		(width 0.1397)
		(layer "In5.Cu")
		(net "PCIE_TX_CAP_N50")
	)
	(segment
		(start 170.399964 -210.790028)
		(end 170.50639 -210.896454)
		(width 0.1397)
		(layer "In5.Cu")
		(net "PCIE_TX_CAP_N50")
	)
	(segment
		(start 237.494572 -93.233494)
		(end 236.859572 -96.408494)
		(width 0.1397)
		(layer "In5.Cu")
		(net "PCIE_TX_CAP_N50")
	)
	(segment
		(start 237.071662 -65.046352)
		(end 237.064042 -65.038732)
		(width 0.1016)
		(layer "In5.Cu")
		(net "PCIE_TX_CAP_N50")
	)
	(segment
		(start 237.10011 -65.499742)
		(end 237.12551 -65.474342)
		(width 0.1016)
		(layer "In5.Cu")
		(net "PCIE_TX_CAP_N50")
	)
	(segment
		(start 237.12551 -65.474342)
		(end 237.12551 -65.1764)
		(width 0.1016)
		(layer "In5.Cu")
		(net "PCIE_TX_CAP_N50")
	)
	(segment
		(start 236.7534 -70.477634)
		(end 237.494572 -74.183494)
		(width 0.1397)
		(layer "In5.Cu")
		(net "PCIE_TX_CAP_N50")
	)
	(segment
		(start 236.697012 -65.17386)
		(end 236.697012 -66.948812)
		(width 0.1016)
		(layer "In5.Cu")
		(net "PCIE_TX_CAP_N50")
	)
	(segment
		(start 236.967268 -64.9986)
		(end 236.871256 -64.9986)
		(width 0.1016)
		(layer "In5.Cu")
		(net "PCIE_TX_CAP_N50")
	)
	(segment
		(start 237.494572 -80.533494)
		(end 236.859572 -83.708494)
		(width 0.1397)
		(layer "In5.Cu")
		(net "PCIE_TX_CAP_N50")
	)
	(segment
		(start 236.859572 -90.058494)
		(end 237.494572 -93.233494)
		(width 0.1397)
		(layer "In5.Cu")
		(net "PCIE_TX_CAP_N50")
	)
	(segment
		(start 170.26509 -207.789526)
		(end 170.26509 -210.4644)
		(width 0.1397)
		(layer "In5.Cu")
		(net "PCIE_TX_CAP_N50")
	)
	(segment
		(start 236.7534 -67.0052)
		(end 236.7534 -70.477634)
		(width 0.1397)
		(layer "In5.Cu")
		(net "PCIE_TX_CAP_N50")
	)
	(arc
		(start 170.268138 -210.51901)
		(mid 170.311263 -210.665601)
		(end 170.399964 -210.790028)
		(width 0.1397)
		(layer "In5.Cu")
		(net "PCIE_TX_CAP_N50")
	)
	(arc
		(start 170.26509 -210.4644)
		(mid 170.265797 -210.491751)
		(end 170.268138 -210.51901)
		(width 0.1397)
		(layer "In5.Cu")
		(net "PCIE_TX_CAP_N50")
	)
	(arc
		(start 237.12551 -65.1764)
		(mid 237.111512 -65.106026)
		(end 237.071662 -65.046352)
		(width 0.1016)
		(layer "In5.Cu")
		(net "PCIE_TX_CAP_N50")
	)
	(arc
		(start 236.748574 -65.0494)
		(mid 236.710419 -65.106503)
		(end 236.697012 -65.17386)
		(width 0.1016)
		(layer "In5.Cu")
		(net "PCIE_TX_CAP_N50")
	)
	(arc
		(start 236.871256 -64.9986)
		(mid 236.804867 -65.011806)
		(end 236.748574 -65.0494)
		(width 0.1016)
		(layer "In5.Cu")
		(net "PCIE_TX_CAP_N50")
	)
	(arc
		(start 237.064042 -65.038732)
		(mid 237.019642 -65.009065)
		(end 236.967268 -64.9986)
		(width 0.1016)
		(layer "In5.Cu")
		(net "PCIE_TX_CAP_N50")
	)
	(segment
		(start 300.002194 -34.648648)
		(end 300.002194 -35.757358)
		(width 0.136652)
		(layer "F.Cu")
		(net "PCIE_TX_CAP_N5")
	)
	(segment
		(start 256.599944 -30.999938)
		(end 257.099816 -30.500066)
		(width 0.136652)
		(layer "F.Cu")
		(net "PCIE_TX_CAP_N5")
	)
	(segment
		(start 300.137068 -36.082986)
		(end 300.243494 -36.189412)
		(width 0.136652)
		(layer "F.Cu")
		(net "PCIE_TX_CAP_N5")
	)
	(via
		(at 257.099816 -30.500066)
		(size 0.4572)
		(drill 0.2032)
		(layers "F.Cu" "B.Cu")
		(net "PCIE_TX_CAP_N5")
	)
	(via
		(at 300.243494 -36.189412)
		(size 0.508)
		(drill 0.254)
		(layers "F.Cu" "B.Cu")
		(net "PCIE_TX_CAP_N5")
	)
	(arc
		(start 300.268894 -34.004758)
		(mid 300.071501 -34.300177)
		(end 300.002194 -34.648648)
		(width 0.136652)
		(layer "F.Cu")
		(net "PCIE_TX_CAP_N5")
	)
	(arc
		(start 300.002194 -35.757358)
		(mid 300.037248 -35.933584)
		(end 300.137068 -36.082986)
		(width 0.136652)
		(layer "F.Cu")
		(net "PCIE_TX_CAP_N5")
	)
	(segment
		(start 257.986276 -26.371042)
		(end 257.303524 -26.848816)
		(width 0.1397)
		(layer "In5.Cu")
		(net "PCIE_TX_CAP_N5")
	)
	(segment
		(start 275.4884 -26.8224)
		(end 269.372334 -25.743916)
		(width 0.1397)
		(layer "In5.Cu")
		(net "PCIE_TX_CAP_N5")
	)
	(segment
		(start 278.309578 -29.726128)
		(end 277.034498 -27.905202)
		(width 0.1397)
		(layer "In5.Cu")
		(net "PCIE_TX_CAP_N5")
	)
	(segment
		(start 257.303524 -26.848816)
		(end 257.007868 -27.270964)
		(width 0.1397)
		(layer "In5.Cu")
		(net "PCIE_TX_CAP_N5")
	)
	(segment
		(start 264.671556 -26.572972)
		(end 260.7564 -25.8826)
		(width 0.1397)
		(layer "In5.Cu")
		(net "PCIE_TX_CAP_N5")
	)
	(segment
		(start 256.9464 -27.619198)
		(end 256.9464 -28.32862)
		(width 0.1397)
		(layer "In5.Cu")
		(net "PCIE_TX_CAP_N5")
	)
	(segment
		(start 256.9464 -28.32862)
		(end 256.9464 -28.35402)
		(width 0.1016)
		(layer "In5.Cu")
		(net "PCIE_TX_CAP_N5")
	)
	(segment
		(start 257.099816 -30.854904)
		(end 257.099816 -30.500066)
		(width 0.1016)
		(layer "In5.Cu")
		(net "PCIE_TX_CAP_N5")
	)
	(segment
		(start 269.372334 -25.743916)
		(end 264.671556 -26.572972)
		(width 0.1397)
		(layer "In5.Cu")
		(net "PCIE_TX_CAP_N5")
	)
	(segment
		(start 300.0121 -36.6522)
		(end 300.0121 -36.955984)
		(width 0.1397)
		(layer "In5.Cu")
		(net "PCIE_TX_CAP_N5")
	)
	(segment
		(start 297.492674 -37.572188)
		(end 296.893742 -37.383974)
		(width 0.1397)
		(layer "In5.Cu")
		(net "PCIE_TX_CAP_N5")
	)
	(segment
		(start 284.364938 -37.82568)
		(end 280.957528 -35.440112)
		(width 0.1397)
		(layer "In5.Cu")
		(net "PCIE_TX_CAP_N5")
	)
	(segment
		(start 256.788666 -30.89275)
		(end 256.84226 -30.94609)
		(width 0.1016)
		(layer "In5.Cu")
		(net "PCIE_TX_CAP_N5")
	)
	(segment
		(start 300.243494 -36.189412)
		(end 300.175676 -36.25723)
		(width 0.1397)
		(layer "In5.Cu")
		(net "PCIE_TX_CAP_N5")
	)
	(segment
		(start 300.0121 -36.955984)
		(end 299.610272 -37.357812)
		(width 0.1397)
		(layer "In5.Cu")
		(net "PCIE_TX_CAP_N5")
	)
	(segment
		(start 296.893742 -37.383974)
		(end 295.773094 -37.03193)
		(width 0.1397)
		(layer "In5.Cu")
		(net "PCIE_TX_CAP_N5")
	)
	(segment
		(start 256.8829 -28.41752)
		(end 256.8829 -29.289502)
		(width 0.1016)
		(layer "In5.Cu")
		(net "PCIE_TX_CAP_N5")
	)
	(segment
		(start 256.704592 -29.46781)
		(end 256.704592 -30.6324)
		(width 0.1016)
		(layer "In5.Cu")
		(net "PCIE_TX_CAP_N5")
	)
	(segment
		(start 278.765 -32.3088)
		(end 278.309578 -29.726128)
		(width 0.1397)
		(layer "In5.Cu")
		(net "PCIE_TX_CAP_N5")
	)
	(segment
		(start 287.819338 -38.434518)
		(end 284.364938 -37.82568)
		(width 0.1397)
		(layer "In5.Cu")
		(net "PCIE_TX_CAP_N5")
	)
	(segment
		(start 277.034498 -27.905202)
		(end 275.4884 -26.8224)
		(width 0.1397)
		(layer "In5.Cu")
		(net "PCIE_TX_CAP_N5")
	)
	(segment
		(start 294.778938 -37.20719)
		(end 287.819338 -38.434518)
		(width 0.1397)
		(layer "In5.Cu")
		(net "PCIE_TX_CAP_N5")
	)
	(segment
		(start 280.957528 -35.440112)
		(end 278.765 -32.3088)
		(width 0.1397)
		(layer "In5.Cu")
		(net "PCIE_TX_CAP_N5")
	)
	(segment
		(start 256.9464 -28.35402)
		(end 256.8829 -28.41752)
		(width 0.1016)
		(layer "In5.Cu")
		(net "PCIE_TX_CAP_N5")
	)
	(segment
		(start 257.007868 -27.270964)
		(end 256.9464 -27.619198)
		(width 0.1397)
		(layer "In5.Cu")
		(net "PCIE_TX_CAP_N5")
	)
	(segment
		(start 295.773094 -37.03193)
		(end 294.778938 -37.20719)
		(width 0.1397)
		(layer "In5.Cu")
		(net "PCIE_TX_CAP_N5")
	)
	(segment
		(start 256.8829 -29.289502)
		(end 256.704592 -29.46781)
		(width 0.1016)
		(layer "In5.Cu")
		(net "PCIE_TX_CAP_N5")
	)
	(segment
		(start 256.84226 -30.94609)
		(end 256.892044 -30.995874)
		(width 0.1016)
		(layer "In5.Cu")
		(net "PCIE_TX_CAP_N5")
	)
	(segment
		(start 299.610272 -37.357812)
		(end 298.188634 -37.790882)
		(width 0.1397)
		(layer "In5.Cu")
		(net "PCIE_TX_CAP_N5")
	)
	(segment
		(start 298.188634 -37.790882)
		(end 297.492674 -37.572188)
		(width 0.1397)
		(layer "In5.Cu")
		(net "PCIE_TX_CAP_N5")
	)
	(segment
		(start 260.7564 -25.8826)
		(end 257.986276 -26.371042)
		(width 0.1397)
		(layer "In5.Cu")
		(net "PCIE_TX_CAP_N5")
	)
	(arc
		(start 257.041396 -30.995874)
		(mid 257.084612 -30.931196)
		(end 257.099816 -30.854904)
		(width 0.1016)
		(layer "In5.Cu")
		(net "PCIE_TX_CAP_N5")
	)
	(arc
		(start 256.892044 -30.995874)
		(mid 256.96672 -31.026806)
		(end 257.041396 -30.995874)
		(width 0.1016)
		(layer "In5.Cu")
		(net "PCIE_TX_CAP_N5")
	)
	(arc
		(start 300.175676 -36.25723)
		(mid 300.054593 -36.438444)
		(end 300.0121 -36.6522)
		(width 0.1397)
		(layer "In5.Cu")
		(net "PCIE_TX_CAP_N5")
	)
	(arc
		(start 256.704592 -30.6324)
		(mid 256.726166 -30.769185)
		(end 256.788666 -30.89275)
		(width 0.1016)
		(layer "In5.Cu")
		(net "PCIE_TX_CAP_N5")
	)
	(segment
		(start 173.808136 -211.975954)
		(end 173.50486 -211.672424)
		(width 0.136652)
		(layer "F.Cu")
		(net "PCIE_TX_CAP_N49")
	)
	(segment
		(start 173.538896 -211.064094)
		(end 173.706536 -210.896454)
		(width 0.136652)
		(layer "F.Cu")
		(net "PCIE_TX_CAP_N49")
	)
	(segment
		(start 238.59998 -65.999868)
		(end 238.100108 -66.49974)
		(width 0.136652)
		(layer "F.Cu")
		(net "PCIE_TX_CAP_N49")
	)
	(segment
		(start 173.446186 -211.5312)
		(end 173.446186 -211.287868)
		(width 0.136652)
		(layer "F.Cu")
		(net "PCIE_TX_CAP_N49")
	)
	(via
		(at 238.100108 -66.49974)
		(size 0.4572)
		(drill 0.2032)
		(layers "F.Cu" "B.Cu")
		(net "PCIE_TX_CAP_N49")
	)
	(via
		(at 173.706536 -210.896454)
		(size 0.508)
		(drill 0.254)
		(layers "F.Cu" "B.Cu")
		(net "PCIE_TX_CAP_N49")
	)
	(arc
		(start 173.446186 -211.287868)
		(mid 173.470277 -211.166755)
		(end 173.538896 -211.064094)
		(width 0.136652)
		(layer "F.Cu")
		(net "PCIE_TX_CAP_N49")
	)
	(arc
		(start 173.50486 -211.672424)
		(mid 173.461483 -211.607645)
		(end 173.446186 -211.5312)
		(width 0.136652)
		(layer "F.Cu")
		(net "PCIE_TX_CAP_N49")
	)
	(segment
		(start 237.7694 -70.376542)
		(end 237.7694 -67.0052)
		(width 0.1397)
		(layer "In5.Cu")
		(net "PCIE_TX_CAP_N49")
	)
	(segment
		(start 238.530892 -93.233494)
		(end 237.895892 -90.058494)
		(width 0.1397)
		(layer "In5.Cu")
		(net "PCIE_TX_CAP_N49")
	)
	(segment
		(start 237.895892 -90.058494)
		(end 238.530892 -86.883494)
		(width 0.1397)
		(layer "In5.Cu")
		(net "PCIE_TX_CAP_N49")
	)
	(segment
		(start 238.530892 -99.583494)
		(end 237.895892 -96.408494)
		(width 0.1397)
		(layer "In5.Cu")
		(net "PCIE_TX_CAP_N49")
	)
	(segment
		(start 173.482 -207.902556)
		(end 237.7694 -116.090446)
		(width 0.1397)
		(layer "In5.Cu")
		(net "PCIE_TX_CAP_N49")
	)
	(segment
		(start 237.7694 -67.0052)
		(end 237.69701 -66.93281)
		(width 0.1016)
		(layer "In5.Cu")
		(net "PCIE_TX_CAP_N49")
	)
	(segment
		(start 237.895892 -109.108494)
		(end 238.530892 -105.933494)
		(width 0.1397)
		(layer "In5.Cu")
		(net "PCIE_TX_CAP_N49")
	)
	(segment
		(start 173.482 -210.354418)
		(end 173.482 -207.902556)
		(width 0.1397)
		(layer "In5.Cu")
		(net "PCIE_TX_CAP_N49")
	)
	(segment
		(start 238.530892 -105.933494)
		(end 237.895892 -102.758494)
		(width 0.1397)
		(layer "In5.Cu")
		(net "PCIE_TX_CAP_N49")
	)
	(segment
		(start 237.895892 -96.408494)
		(end 238.530892 -93.233494)
		(width 0.1397)
		(layer "In5.Cu")
		(net "PCIE_TX_CAP_N49")
	)
	(segment
		(start 237.895892 -102.758494)
		(end 238.530892 -99.583494)
		(width 0.1397)
		(layer "In5.Cu")
		(net "PCIE_TX_CAP_N49")
	)
	(segment
		(start 238.125508 -66.47434)
		(end 238.100108 -66.49974)
		(width 0.1016)
		(layer "In5.Cu")
		(net "PCIE_TX_CAP_N49")
	)
	(segment
		(start 238.530892 -74.183494)
		(end 237.7694 -70.376542)
		(width 0.1397)
		(layer "In5.Cu")
		(net "PCIE_TX_CAP_N49")
	)
	(segment
		(start 237.895892 -83.708494)
		(end 238.530892 -80.533494)
		(width 0.1397)
		(layer "In5.Cu")
		(net "PCIE_TX_CAP_N49")
	)
	(segment
		(start 238.530892 -112.283494)
		(end 237.895892 -109.108494)
		(width 0.1397)
		(layer "In5.Cu")
		(net "PCIE_TX_CAP_N49")
	)
	(segment
		(start 238.530892 -86.883494)
		(end 237.895892 -83.708494)
		(width 0.1397)
		(layer "In5.Cu")
		(net "PCIE_TX_CAP_N49")
	)
	(segment
		(start 237.871254 -65.998598)
		(end 237.967266 -65.998598)
		(width 0.1016)
		(layer "In5.Cu")
		(net "PCIE_TX_CAP_N49")
	)
	(segment
		(start 238.06404 -66.03873)
		(end 238.07166 -66.04635)
		(width 0.1016)
		(layer "In5.Cu")
		(net "PCIE_TX_CAP_N49")
	)
	(segment
		(start 238.530892 -80.533494)
		(end 237.895892 -77.358494)
		(width 0.1397)
		(layer "In5.Cu")
		(net "PCIE_TX_CAP_N49")
	)
	(segment
		(start 237.895892 -77.358494)
		(end 238.530892 -74.183494)
		(width 0.1397)
		(layer "In5.Cu")
		(net "PCIE_TX_CAP_N49")
	)
	(segment
		(start 237.7694 -116.090446)
		(end 238.530892 -112.283494)
		(width 0.1397)
		(layer "In5.Cu")
		(net "PCIE_TX_CAP_N49")
	)
	(segment
		(start 238.125508 -66.176398)
		(end 238.125508 -66.47434)
		(width 0.1016)
		(layer "In5.Cu")
		(net "PCIE_TX_CAP_N49")
	)
	(segment
		(start 237.69701 -66.93281)
		(end 237.69701 -66.173858)
		(width 0.1016)
		(layer "In5.Cu")
		(net "PCIE_TX_CAP_N49")
	)
	(arc
		(start 237.69701 -66.173858)
		(mid 237.710409 -66.106497)
		(end 237.748572 -66.049398)
		(width 0.1016)
		(layer "In5.Cu")
		(net "PCIE_TX_CAP_N49")
	)
	(arc
		(start 173.706536 -210.896454)
		(mid 173.540368 -210.647766)
		(end 173.482 -210.354418)
		(width 0.1397)
		(layer "In5.Cu")
		(net "PCIE_TX_CAP_N49")
	)
	(arc
		(start 237.967266 -65.998598)
		(mid 238.019658 -66.009019)
		(end 238.06404 -66.03873)
		(width 0.1016)
		(layer "In5.Cu")
		(net "PCIE_TX_CAP_N49")
	)
	(arc
		(start 237.748572 -66.049398)
		(mid 237.804859 -66.011788)
		(end 237.871254 -65.998598)
		(width 0.1016)
		(layer "In5.Cu")
		(net "PCIE_TX_CAP_N49")
	)
	(arc
		(start 238.07166 -66.04635)
		(mid 238.111528 -66.106017)
		(end 238.125508 -66.176398)
		(width 0.1016)
		(layer "In5.Cu")
		(net "PCIE_TX_CAP_N49")
	)
	(segment
		(start 176.73828 -211.064856)
		(end 176.906428 -210.896454)
		(width 0.136652)
		(layer "F.Cu")
		(net "PCIE_TX_CAP_N48")
	)
	(segment
		(start 176.646078 -211.5312)
		(end 176.646078 -211.287106)
		(width 0.136652)
		(layer "F.Cu")
		(net "PCIE_TX_CAP_N48")
	)
	(segment
		(start 239.599978 -64.99987)
		(end 239.100106 -65.499742)
		(width 0.136652)
		(layer "F.Cu")
		(net "PCIE_TX_CAP_N48")
	)
	(segment
		(start 177.008028 -211.975954)
		(end 176.704752 -211.672424)
		(width 0.136652)
		(layer "F.Cu")
		(net "PCIE_TX_CAP_N48")
	)
	(via
		(at 239.100106 -65.499742)
		(size 0.4572)
		(drill 0.2032)
		(layers "F.Cu" "B.Cu")
		(net "PCIE_TX_CAP_N48")
	)
	(via
		(at 176.906428 -210.896454)
		(size 0.508)
		(drill 0.254)
		(layers "F.Cu" "B.Cu")
		(net "PCIE_TX_CAP_N48")
	)
	(arc
		(start 176.646078 -211.287106)
		(mid 176.670097 -211.166824)
		(end 176.73828 -211.064856)
		(width 0.136652)
		(layer "F.Cu")
		(net "PCIE_TX_CAP_N48")
	)
	(arc
		(start 176.704752 -211.672424)
		(mid 176.661375 -211.607645)
		(end 176.646078 -211.5312)
		(width 0.136652)
		(layer "F.Cu")
		(net "PCIE_TX_CAP_N48")
	)
	(segment
		(start 238.90605 -96.408494)
		(end 239.54105 -99.583494)
		(width 0.1397)
		(layer "In5.Cu")
		(net "PCIE_TX_CAP_N48")
	)
	(segment
		(start 239.54105 -80.533494)
		(end 238.90605 -83.708494)
		(width 0.1397)
		(layer "In5.Cu")
		(net "PCIE_TX_CAP_N48")
	)
	(segment
		(start 239.54105 -93.233494)
		(end 238.90605 -96.408494)
		(width 0.1397)
		(layer "In5.Cu")
		(net "PCIE_TX_CAP_N48")
	)
	(segment
		(start 238.697008 -65.17386)
		(end 238.697008 -66.942208)
		(width 0.1016)
		(layer "In5.Cu")
		(net "PCIE_TX_CAP_N48")
	)
	(segment
		(start 239.54105 -112.283494)
		(end 238.76 -116.189252)
		(width 0.1397)
		(layer "In5.Cu")
		(net "PCIE_TX_CAP_N48")
	)
	(segment
		(start 176.657 -204.88148)
		(end 176.657 -210.4644)
		(width 0.1397)
		(layer "In5.Cu")
		(net "PCIE_TX_CAP_N48")
	)
	(segment
		(start 238.697008 -66.942208)
		(end 238.76 -67.0052)
		(width 0.1016)
		(layer "In5.Cu")
		(net "PCIE_TX_CAP_N48")
	)
	(segment
		(start 238.967264 -64.9986)
		(end 238.871252 -64.9986)
		(width 0.1016)
		(layer "In5.Cu")
		(net "PCIE_TX_CAP_N48")
	)
	(segment
		(start 239.54105 -105.933494)
		(end 238.90605 -109.108494)
		(width 0.1397)
		(layer "In5.Cu")
		(net "PCIE_TX_CAP_N48")
	)
	(segment
		(start 238.90605 -102.758494)
		(end 239.54105 -105.933494)
		(width 0.1397)
		(layer "In5.Cu")
		(net "PCIE_TX_CAP_N48")
	)
	(segment
		(start 238.90605 -109.108494)
		(end 239.54105 -112.283494)
		(width 0.1397)
		(layer "In5.Cu")
		(net "PCIE_TX_CAP_N48")
	)
	(segment
		(start 239.125506 -65.474342)
		(end 239.125506 -65.1764)
		(width 0.1016)
		(layer "In5.Cu")
		(net "PCIE_TX_CAP_N48")
	)
	(segment
		(start 239.54105 -86.883494)
		(end 238.90605 -90.058494)
		(width 0.1397)
		(layer "In5.Cu")
		(net "PCIE_TX_CAP_N48")
	)
	(segment
		(start 239.54105 -74.183494)
		(end 238.90605 -77.358494)
		(width 0.1397)
		(layer "In5.Cu")
		(net "PCIE_TX_CAP_N48")
	)
	(segment
		(start 239.100106 -65.499742)
		(end 239.125506 -65.474342)
		(width 0.1016)
		(layer "In5.Cu")
		(net "PCIE_TX_CAP_N48")
	)
	(segment
		(start 238.76 -116.189252)
		(end 176.657 -204.88148)
		(width 0.1397)
		(layer "In5.Cu")
		(net "PCIE_TX_CAP_N48")
	)
	(segment
		(start 238.90605 -77.358494)
		(end 239.54105 -80.533494)
		(width 0.1397)
		(layer "In5.Cu")
		(net "PCIE_TX_CAP_N48")
	)
	(segment
		(start 239.071658 -65.046352)
		(end 239.064038 -65.038732)
		(width 0.1016)
		(layer "In5.Cu")
		(net "PCIE_TX_CAP_N48")
	)
	(segment
		(start 238.90605 -83.708494)
		(end 239.54105 -86.883494)
		(width 0.1397)
		(layer "In5.Cu")
		(net "PCIE_TX_CAP_N48")
	)
	(segment
		(start 238.76 -67.0052)
		(end 238.76 -70.277736)
		(width 0.1397)
		(layer "In5.Cu")
		(net "PCIE_TX_CAP_N48")
	)
	(segment
		(start 239.54105 -99.583494)
		(end 238.90605 -102.758494)
		(width 0.1397)
		(layer "In5.Cu")
		(net "PCIE_TX_CAP_N48")
	)
	(segment
		(start 238.76 -70.277736)
		(end 239.54105 -74.183494)
		(width 0.1397)
		(layer "In5.Cu")
		(net "PCIE_TX_CAP_N48")
	)
	(segment
		(start 176.786032 -210.776312)
		(end 176.906428 -210.896454)
		(width 0.1397)
		(layer "In5.Cu")
		(net "PCIE_TX_CAP_N48")
	)
	(segment
		(start 238.90605 -90.058494)
		(end 239.54105 -93.233494)
		(width 0.1397)
		(layer "In5.Cu")
		(net "PCIE_TX_CAP_N48")
	)
	(arc
		(start 239.064038 -65.038732)
		(mid 239.019638 -65.009065)
		(end 238.967264 -64.9986)
		(width 0.1016)
		(layer "In5.Cu")
		(net "PCIE_TX_CAP_N48")
	)
	(arc
		(start 176.657 -210.4644)
		(mid 176.690482 -210.633196)
		(end 176.786032 -210.776312)
		(width 0.1397)
		(layer "In5.Cu")
		(net "PCIE_TX_CAP_N48")
	)
	(arc
		(start 239.125506 -65.1764)
		(mid 239.111508 -65.106026)
		(end 239.071658 -65.046352)
		(width 0.1016)
		(layer "In5.Cu")
		(net "PCIE_TX_CAP_N48")
	)
	(arc
		(start 238.74857 -65.0494)
		(mid 238.710415 -65.106503)
		(end 238.697008 -65.17386)
		(width 0.1016)
		(layer "In5.Cu")
		(net "PCIE_TX_CAP_N48")
	)
	(arc
		(start 238.871252 -64.9986)
		(mid 238.804863 -65.011806)
		(end 238.74857 -65.0494)
		(width 0.1016)
		(layer "In5.Cu")
		(net "PCIE_TX_CAP_N48")
	)
	(segment
		(start 241.599974 -64.99987)
		(end 242.099846 -65.499742)
		(width 0.136652)
		(layer "F.Cu")
		(net "PCIE_TX_CAP_N47")
	)
	(segment
		(start 184.646062 -211.5312)
		(end 184.646062 -211.284566)
		(width 0.136652)
		(layer "F.Cu")
		(net "PCIE_TX_CAP_N47")
	)
	(segment
		(start 185.008266 -211.975954)
		(end 184.704736 -211.672424)
		(width 0.136652)
		(layer "F.Cu")
		(net "PCIE_TX_CAP_N47")
	)
	(segment
		(start 184.736486 -211.066634)
		(end 184.906412 -210.896454)
		(width 0.136652)
		(layer "F.Cu")
		(net "PCIE_TX_CAP_N47")
	)
	(via
		(at 184.906412 -210.896454)
		(size 0.508)
		(drill 0.254)
		(layers "F.Cu" "B.Cu")
		(net "PCIE_TX_CAP_N47")
	)
	(via
		(at 242.099846 -65.499742)
		(size 0.4572)
		(drill 0.2032)
		(layers "F.Cu" "B.Cu")
		(net "PCIE_TX_CAP_N47")
	)
	(arc
		(start 184.646062 -211.284566)
		(mid 184.669617 -211.166617)
		(end 184.736486 -211.066634)
		(width 0.136652)
		(layer "F.Cu")
		(net "PCIE_TX_CAP_N47")
	)
	(arc
		(start 184.704736 -211.672424)
		(mid 184.661359 -211.607645)
		(end 184.646062 -211.5312)
		(width 0.136652)
		(layer "F.Cu")
		(net "PCIE_TX_CAP_N47")
	)
	(segment
		(start 241.967004 -64.9986)
		(end 241.870992 -64.9986)
		(width 0.1016)
		(layer "In5.Cu")
		(net "PCIE_TX_CAP_N47")
	)
	(segment
		(start 242.099846 -65.499742)
		(end 242.125246 -65.474342)
		(width 0.1016)
		(layer "In5.Cu")
		(net "PCIE_TX_CAP_N47")
	)
	(segment
		(start 241.962686 -102.758494)
		(end 243.232686 -109.108494)
		(width 0.1397)
		(layer "In5.Cu")
		(net "PCIE_TX_CAP_N47")
	)
	(segment
		(start 184.665112 -205.829662)
		(end 184.665112 -210.313778)
		(width 0.1397)
		(layer "In5.Cu")
		(net "PCIE_TX_CAP_N47")
	)
	(segment
		(start 241.962686 -90.058494)
		(end 243.232686 -96.408494)
		(width 0.1397)
		(layer "In5.Cu")
		(net "PCIE_TX_CAP_N47")
	)
	(segment
		(start 241.7572 -76.330556)
		(end 243.232686 -83.708494)
		(width 0.1397)
		(layer "In5.Cu")
		(net "PCIE_TX_CAP_N47")
	)
	(segment
		(start 243.232686 -109.108494)
		(end 241.7572 -116.486432)
		(width 0.1397)
		(layer "In5.Cu")
		(net "PCIE_TX_CAP_N47")
	)
	(segment
		(start 241.7572 -116.486432)
		(end 186.505342 -195.394326)
		(width 0.1397)
		(layer "In5.Cu")
		(net "PCIE_TX_CAP_N47")
	)
	(segment
		(start 242.071398 -65.046352)
		(end 242.063778 -65.038732)
		(width 0.1016)
		(layer "In5.Cu")
		(net "PCIE_TX_CAP_N47")
	)
	(segment
		(start 186.505342 -195.394326)
		(end 184.665112 -205.829662)
		(width 0.1397)
		(layer "In5.Cu")
		(net "PCIE_TX_CAP_N47")
	)
	(segment
		(start 241.7572 -66.9544)
		(end 241.7572 -76.330556)
		(width 0.1397)
		(layer "In5.Cu")
		(net "PCIE_TX_CAP_N47")
	)
	(segment
		(start 243.232686 -83.708494)
		(end 241.962686 -90.058494)
		(width 0.1397)
		(layer "In5.Cu")
		(net "PCIE_TX_CAP_N47")
	)
	(segment
		(start 241.696748 -65.17386)
		(end 241.696748 -66.893948)
		(width 0.1016)
		(layer "In5.Cu")
		(net "PCIE_TX_CAP_N47")
	)
	(segment
		(start 243.232686 -96.408494)
		(end 241.962686 -102.758494)
		(width 0.1397)
		(layer "In5.Cu")
		(net "PCIE_TX_CAP_N47")
	)
	(segment
		(start 241.696748 -66.893948)
		(end 241.7572 -66.9544)
		(width 0.1016)
		(layer "In5.Cu")
		(net "PCIE_TX_CAP_N47")
	)
	(segment
		(start 242.125246 -65.474342)
		(end 242.125246 -65.1764)
		(width 0.1016)
		(layer "In5.Cu")
		(net "PCIE_TX_CAP_N47")
	)
	(arc
		(start 241.870992 -64.9986)
		(mid 241.804603 -65.011806)
		(end 241.74831 -65.0494)
		(width 0.1016)
		(layer "In5.Cu")
		(net "PCIE_TX_CAP_N47")
	)
	(arc
		(start 184.665112 -210.313778)
		(mid 184.727833 -210.6291)
		(end 184.906412 -210.896454)
		(width 0.1397)
		(layer "In5.Cu")
		(net "PCIE_TX_CAP_N47")
	)
	(arc
		(start 241.74831 -65.0494)
		(mid 241.710155 -65.106503)
		(end 241.696748 -65.17386)
		(width 0.1016)
		(layer "In5.Cu")
		(net "PCIE_TX_CAP_N47")
	)
	(arc
		(start 242.063778 -65.038732)
		(mid 242.019378 -65.009065)
		(end 241.967004 -64.9986)
		(width 0.1016)
		(layer "In5.Cu")
		(net "PCIE_TX_CAP_N47")
	)
	(arc
		(start 242.125246 -65.1764)
		(mid 242.111248 -65.106026)
		(end 242.071398 -65.046352)
		(width 0.1016)
		(layer "In5.Cu")
		(net "PCIE_TX_CAP_N47")
	)
	(segment
		(start 187.936124 -211.067142)
		(end 188.106558 -210.896454)
		(width 0.136652)
		(layer "F.Cu")
		(net "PCIE_TX_CAP_N46")
	)
	(segment
		(start 187.846208 -211.5312)
		(end 187.846208 -211.283804)
		(width 0.136652)
		(layer "F.Cu")
		(net "PCIE_TX_CAP_N46")
	)
	(segment
		(start 242.599972 -65.999868)
		(end 243.099844 -66.49974)
		(width 0.136652)
		(layer "F.Cu")
		(net "PCIE_TX_CAP_N46")
	)
	(segment
		(start 188.208158 -211.975954)
		(end 187.904882 -211.672424)
		(width 0.136652)
		(layer "F.Cu")
		(net "PCIE_TX_CAP_N46")
	)
	(via
		(at 243.099844 -66.49974)
		(size 0.4572)
		(drill 0.2032)
		(layers "F.Cu" "B.Cu")
		(net "PCIE_TX_CAP_N46")
	)
	(via
		(at 188.106558 -210.896454)
		(size 0.508)
		(drill 0.254)
		(layers "F.Cu" "B.Cu")
		(net "PCIE_TX_CAP_N46")
	)
	(arc
		(start 187.846208 -211.283804)
		(mid 187.869628 -211.166535)
		(end 187.936124 -211.067142)
		(width 0.136652)
		(layer "F.Cu")
		(net "PCIE_TX_CAP_N46")
	)
	(arc
		(start 187.904882 -211.672424)
		(mid 187.861505 -211.607645)
		(end 187.846208 -211.5312)
		(width 0.136652)
		(layer "F.Cu")
		(net "PCIE_TX_CAP_N46")
	)
	(segment
		(start 244.243098 -83.708494)
		(end 242.973098 -90.058494)
		(width 0.1397)
		(layer "In5.Cu")
		(net "PCIE_TX_CAP_N46")
	)
	(segment
		(start 190.930784 -190.587122)
		(end 187.865258 -207.97393)
		(width 0.1397)
		(layer "In5.Cu")
		(net "PCIE_TX_CAP_N46")
	)
	(segment
		(start 244.243098 -109.108494)
		(end 242.7478 -116.584984)
		(width 0.1397)
		(layer "In5.Cu")
		(net "PCIE_TX_CAP_N46")
	)
	(segment
		(start 242.973098 -102.758494)
		(end 244.243098 -109.108494)
		(width 0.1397)
		(layer "In5.Cu")
		(net "PCIE_TX_CAP_N46")
	)
	(segment
		(start 242.7478 -116.584984)
		(end 190.930784 -190.587122)
		(width 0.1397)
		(layer "In5.Cu")
		(net "PCIE_TX_CAP_N46")
	)
	(segment
		(start 242.7478 -76.232004)
		(end 244.243098 -83.708494)
		(width 0.1397)
		(layer "In5.Cu")
		(net "PCIE_TX_CAP_N46")
	)
	(segment
		(start 244.243098 -96.408494)
		(end 242.973098 -102.758494)
		(width 0.1397)
		(layer "In5.Cu")
		(net "PCIE_TX_CAP_N46")
	)
	(segment
		(start 187.865258 -207.97393)
		(end 187.865258 -210.313778)
		(width 0.1397)
		(layer "In5.Cu")
		(net "PCIE_TX_CAP_N46")
	)
	(segment
		(start 242.967002 -65.998598)
		(end 242.87099 -65.998598)
		(width 0.1016)
		(layer "In5.Cu")
		(net "PCIE_TX_CAP_N46")
	)
	(segment
		(start 242.7478 -66.929)
		(end 242.7478 -76.232004)
		(width 0.1397)
		(layer "In5.Cu")
		(net "PCIE_TX_CAP_N46")
	)
	(segment
		(start 242.696746 -66.173858)
		(end 242.696746 -66.877946)
		(width 0.1016)
		(layer "In5.Cu")
		(net "PCIE_TX_CAP_N46")
	)
	(segment
		(start 242.696746 -66.877946)
		(end 242.7478 -66.929)
		(width 0.1016)
		(layer "In5.Cu")
		(net "PCIE_TX_CAP_N46")
	)
	(segment
		(start 243.071396 -66.04635)
		(end 243.063776 -66.03873)
		(width 0.1016)
		(layer "In5.Cu")
		(net "PCIE_TX_CAP_N46")
	)
	(segment
		(start 243.099844 -66.49974)
		(end 243.125244 -66.47434)
		(width 0.1016)
		(layer "In5.Cu")
		(net "PCIE_TX_CAP_N46")
	)
	(segment
		(start 243.125244 -66.47434)
		(end 243.125244 -66.176398)
		(width 0.1016)
		(layer "In5.Cu")
		(net "PCIE_TX_CAP_N46")
	)
	(segment
		(start 242.973098 -90.058494)
		(end 244.243098 -96.408494)
		(width 0.1397)
		(layer "In5.Cu")
		(net "PCIE_TX_CAP_N46")
	)
	(arc
		(start 242.87099 -65.998598)
		(mid 242.804601 -66.011804)
		(end 242.748308 -66.049398)
		(width 0.1016)
		(layer "In5.Cu")
		(net "PCIE_TX_CAP_N46")
	)
	(arc
		(start 243.125244 -66.176398)
		(mid 243.111246 -66.106024)
		(end 243.071396 -66.04635)
		(width 0.1016)
		(layer "In5.Cu")
		(net "PCIE_TX_CAP_N46")
	)
	(arc
		(start 187.865258 -210.313778)
		(mid 187.927979 -210.6291)
		(end 188.106558 -210.896454)
		(width 0.1397)
		(layer "In5.Cu")
		(net "PCIE_TX_CAP_N46")
	)
	(arc
		(start 242.748308 -66.049398)
		(mid 242.710153 -66.106501)
		(end 242.696746 -66.173858)
		(width 0.1016)
		(layer "In5.Cu")
		(net "PCIE_TX_CAP_N46")
	)
	(arc
		(start 243.063776 -66.03873)
		(mid 243.019376 -66.009063)
		(end 242.967002 -65.998598)
		(width 0.1016)
		(layer "In5.Cu")
		(net "PCIE_TX_CAP_N46")
	)
	(segment
		(start 191.408304 -211.975954)
		(end 191.104774 -211.672424)
		(width 0.136652)
		(layer "F.Cu")
		(net "PCIE_TX_CAP_N45")
	)
	(segment
		(start 191.142112 -211.060538)
		(end 191.30645 -210.896454)
		(width 0.136652)
		(layer "F.Cu")
		(net "PCIE_TX_CAP_N45")
	)
	(segment
		(start 191.0461 -211.5312)
		(end 191.0461 -211.292694)
		(width 0.136652)
		(layer "F.Cu")
		(net "PCIE_TX_CAP_N45")
	)
	(segment
		(start 243.59997 -64.99987)
		(end 244.099842 -65.499742)
		(width 0.136652)
		(layer "F.Cu")
		(net "PCIE_TX_CAP_N45")
	)
	(via
		(at 244.099842 -65.499742)
		(size 0.4572)
		(drill 0.2032)
		(layers "F.Cu" "B.Cu")
		(net "PCIE_TX_CAP_N45")
	)
	(via
		(at 191.30645 -210.896454)
		(size 0.508)
		(drill 0.254)
		(layers "F.Cu" "B.Cu")
		(net "PCIE_TX_CAP_N45")
	)
	(arc
		(start 191.104774 -211.672424)
		(mid 191.061397 -211.607645)
		(end 191.0461 -211.5312)
		(width 0.136652)
		(layer "F.Cu")
		(net "PCIE_TX_CAP_N45")
	)
	(arc
		(start 191.0461 -211.292694)
		(mid 191.070997 -211.167056)
		(end 191.142112 -211.060538)
		(width 0.136652)
		(layer "F.Cu")
		(net "PCIE_TX_CAP_N45")
	)
	(segment
		(start 245.279418 -83.708494)
		(end 244.009418 -90.058494)
		(width 0.1397)
		(layer "In5.Cu")
		(net "PCIE_TX_CAP_N45")
	)
	(segment
		(start 243.967 -64.9986)
		(end 243.870988 -64.9986)
		(width 0.1016)
		(layer "In5.Cu")
		(net "PCIE_TX_CAP_N45")
	)
	(segment
		(start 244.125242 -65.474342)
		(end 244.125242 -65.1764)
		(width 0.1016)
		(layer "In5.Cu")
		(net "PCIE_TX_CAP_N45")
	)
	(segment
		(start 194.26809 -188.77915)
		(end 191.06515 -206.943198)
		(width 0.1397)
		(layer "In5.Cu")
		(net "PCIE_TX_CAP_N45")
	)
	(segment
		(start 243.696744 -66.938144)
		(end 243.7638 -67.0052)
		(width 0.1016)
		(layer "In5.Cu")
		(net "PCIE_TX_CAP_N45")
	)
	(segment
		(start 244.009418 -90.058494)
		(end 245.279418 -96.408494)
		(width 0.1397)
		(layer "In5.Cu")
		(net "PCIE_TX_CAP_N45")
	)
	(segment
		(start 243.84 -117.983)
		(end 194.26809 -188.77915)
		(width 0.1397)
		(layer "In5.Cu")
		(net "PCIE_TX_CAP_N45")
	)
	(segment
		(start 245.279418 -96.408494)
		(end 244.009418 -102.758494)
		(width 0.1397)
		(layer "In5.Cu")
		(net "PCIE_TX_CAP_N45")
	)
	(segment
		(start 243.696744 -65.17386)
		(end 243.696744 -66.938144)
		(width 0.1016)
		(layer "In5.Cu")
		(net "PCIE_TX_CAP_N45")
	)
	(segment
		(start 244.099842 -65.499742)
		(end 244.125242 -65.474342)
		(width 0.1016)
		(layer "In5.Cu")
		(net "PCIE_TX_CAP_N45")
	)
	(segment
		(start 243.7638 -76.130912)
		(end 245.279418 -83.708494)
		(width 0.1397)
		(layer "In5.Cu")
		(net "PCIE_TX_CAP_N45")
	)
	(segment
		(start 245.345966 -109.441742)
		(end 243.84 -117.983)
		(width 0.1397)
		(layer "In5.Cu")
		(net "PCIE_TX_CAP_N45")
	)
	(segment
		(start 191.06515 -206.943198)
		(end 191.06515 -210.313778)
		(width 0.1397)
		(layer "In5.Cu")
		(net "PCIE_TX_CAP_N45")
	)
	(segment
		(start 244.071394 -65.046352)
		(end 244.063774 -65.038732)
		(width 0.1016)
		(layer "In5.Cu")
		(net "PCIE_TX_CAP_N45")
	)
	(segment
		(start 244.009418 -102.758494)
		(end 245.345966 -109.441742)
		(width 0.1397)
		(layer "In5.Cu")
		(net "PCIE_TX_CAP_N45")
	)
	(segment
		(start 243.7638 -67.0052)
		(end 243.7638 -76.130912)
		(width 0.1397)
		(layer "In5.Cu")
		(net "PCIE_TX_CAP_N45")
	)
	(arc
		(start 244.125242 -65.1764)
		(mid 244.111244 -65.106026)
		(end 244.071394 -65.046352)
		(width 0.1016)
		(layer "In5.Cu")
		(net "PCIE_TX_CAP_N45")
	)
	(arc
		(start 243.870988 -64.9986)
		(mid 243.804599 -65.011806)
		(end 243.748306 -65.0494)
		(width 0.1016)
		(layer "In5.Cu")
		(net "PCIE_TX_CAP_N45")
	)
	(arc
		(start 244.063774 -65.038732)
		(mid 244.019374 -65.009065)
		(end 243.967 -64.9986)
		(width 0.1016)
		(layer "In5.Cu")
		(net "PCIE_TX_CAP_N45")
	)
	(arc
		(start 191.06515 -210.313778)
		(mid 191.127871 -210.6291)
		(end 191.30645 -210.896454)
		(width 0.1397)
		(layer "In5.Cu")
		(net "PCIE_TX_CAP_N45")
	)
	(arc
		(start 243.748306 -65.0494)
		(mid 243.710151 -65.106503)
		(end 243.696744 -65.17386)
		(width 0.1016)
		(layer "In5.Cu")
		(net "PCIE_TX_CAP_N45")
	)
	(segment
		(start 194.608196 -211.975954)
		(end 194.30492 -211.672424)
		(width 0.136652)
		(layer "F.Cu")
		(net "PCIE_TX_CAP_N44")
	)
	(segment
		(start 194.352672 -211.050632)
		(end 194.506596 -210.896454)
		(width 0.136652)
		(layer "F.Cu")
		(net "PCIE_TX_CAP_N44")
	)
	(segment
		(start 194.246246 -211.5312)
		(end 194.246246 -211.307172)
		(width 0.136652)
		(layer "F.Cu")
		(net "PCIE_TX_CAP_N44")
	)
	(segment
		(start 244.599968 -65.999868)
		(end 245.09984 -66.49974)
		(width 0.136652)
		(layer "F.Cu")
		(net "PCIE_TX_CAP_N44")
	)
	(via
		(at 194.506596 -210.896454)
		(size 0.508)
		(drill 0.254)
		(layers "F.Cu" "B.Cu")
		(net "PCIE_TX_CAP_N44")
	)
	(via
		(at 245.09984 -66.49974)
		(size 0.4572)
		(drill 0.2032)
		(layers "F.Cu" "B.Cu")
		(net "PCIE_TX_CAP_N44")
	)
	(arc
		(start 194.30492 -211.672424)
		(mid 194.261543 -211.607645)
		(end 194.246246 -211.5312)
		(width 0.136652)
		(layer "F.Cu")
		(net "PCIE_TX_CAP_N44")
	)
	(arc
		(start 194.246246 -211.307172)
		(mid 194.273958 -211.168325)
		(end 194.352672 -211.050632)
		(width 0.136652)
		(layer "F.Cu")
		(net "PCIE_TX_CAP_N44")
	)
	(segment
		(start 244.696742 -66.896742)
		(end 244.7544 -66.9544)
		(width 0.1016)
		(layer "In5.Cu")
		(net "PCIE_TX_CAP_N44")
	)
	(segment
		(start 245.12524 -66.47434)
		(end 245.12524 -66.176398)
		(width 0.1016)
		(layer "In5.Cu")
		(net "PCIE_TX_CAP_N44")
	)
	(segment
		(start 244.966998 -65.998598)
		(end 244.870986 -65.998598)
		(width 0.1016)
		(layer "In5.Cu")
		(net "PCIE_TX_CAP_N44")
	)
	(segment
		(start 245.09984 -66.49974)
		(end 245.12524 -66.47434)
		(width 0.1016)
		(layer "In5.Cu")
		(net "PCIE_TX_CAP_N44")
	)
	(segment
		(start 245.37035 -118.756176)
		(end 197.36562 -187.312808)
		(width 0.1397)
		(layer "In5.Cu")
		(net "PCIE_TX_CAP_N44")
	)
	(segment
		(start 194.265296 -204.895958)
		(end 194.265296 -210.313778)
		(width 0.1397)
		(layer "In5.Cu")
		(net "PCIE_TX_CAP_N44")
	)
	(segment
		(start 246.70512 -111.186214)
		(end 245.37035 -118.756176)
		(width 0.1397)
		(layer "In5.Cu")
		(net "PCIE_TX_CAP_N44")
	)
	(segment
		(start 245.019576 -102.758494)
		(end 246.70512 -111.186214)
		(width 0.1397)
		(layer "In5.Cu")
		(net "PCIE_TX_CAP_N44")
	)
	(segment
		(start 244.7544 -76.032106)
		(end 246.289576 -83.708494)
		(width 0.1397)
		(layer "In5.Cu")
		(net "PCIE_TX_CAP_N44")
	)
	(segment
		(start 245.071392 -66.04635)
		(end 245.063772 -66.03873)
		(width 0.1016)
		(layer "In5.Cu")
		(net "PCIE_TX_CAP_N44")
	)
	(segment
		(start 244.7544 -66.9544)
		(end 244.7544 -76.032106)
		(width 0.1397)
		(layer "In5.Cu")
		(net "PCIE_TX_CAP_N44")
	)
	(segment
		(start 246.289576 -96.408494)
		(end 245.019576 -102.758494)
		(width 0.1397)
		(layer "In5.Cu")
		(net "PCIE_TX_CAP_N44")
	)
	(segment
		(start 245.019576 -90.058494)
		(end 246.289576 -96.408494)
		(width 0.1397)
		(layer "In5.Cu")
		(net "PCIE_TX_CAP_N44")
	)
	(segment
		(start 244.696742 -66.173858)
		(end 244.696742 -66.896742)
		(width 0.1016)
		(layer "In5.Cu")
		(net "PCIE_TX_CAP_N44")
	)
	(segment
		(start 246.289576 -83.708494)
		(end 245.019576 -90.058494)
		(width 0.1397)
		(layer "In5.Cu")
		(net "PCIE_TX_CAP_N44")
	)
	(segment
		(start 197.36562 -187.312808)
		(end 194.265296 -204.895958)
		(width 0.1397)
		(layer "In5.Cu")
		(net "PCIE_TX_CAP_N44")
	)
	(arc
		(start 245.12524 -66.176398)
		(mid 245.111242 -66.106024)
		(end 245.071392 -66.04635)
		(width 0.1016)
		(layer "In5.Cu")
		(net "PCIE_TX_CAP_N44")
	)
	(arc
		(start 194.265296 -210.313778)
		(mid 194.328017 -210.6291)
		(end 194.506596 -210.896454)
		(width 0.1397)
		(layer "In5.Cu")
		(net "PCIE_TX_CAP_N44")
	)
	(arc
		(start 244.870986 -65.998598)
		(mid 244.804597 -66.011804)
		(end 244.748304 -66.049398)
		(width 0.1016)
		(layer "In5.Cu")
		(net "PCIE_TX_CAP_N44")
	)
	(arc
		(start 244.748304 -66.049398)
		(mid 244.710149 -66.106501)
		(end 244.696742 -66.173858)
		(width 0.1016)
		(layer "In5.Cu")
		(net "PCIE_TX_CAP_N44")
	)
	(arc
		(start 245.063772 -66.03873)
		(mid 245.019372 -66.009063)
		(end 244.966998 -65.998598)
		(width 0.1016)
		(layer "In5.Cu")
		(net "PCIE_TX_CAP_N44")
	)
	(segment
		(start 245.599966 -64.99987)
		(end 246.099838 -65.499742)
		(width 0.136652)
		(layer "F.Cu")
		(net "PCIE_TX_CAP_N43")
	)
	(segment
		(start 197.536562 -211.066634)
		(end 197.706488 -210.896454)
		(width 0.136652)
		(layer "F.Cu")
		(net "PCIE_TX_CAP_N43")
	)
	(segment
		(start 197.808088 -211.975954)
		(end 197.504812 -211.672424)
		(width 0.136652)
		(layer "F.Cu")
		(net "PCIE_TX_CAP_N43")
	)
	(segment
		(start 197.446138 -211.5312)
		(end 197.446138 -211.284566)
		(width 0.136652)
		(layer "F.Cu")
		(net "PCIE_TX_CAP_N43")
	)
	(via
		(at 246.099838 -65.499742)
		(size 0.4572)
		(drill 0.2032)
		(layers "F.Cu" "B.Cu")
		(net "PCIE_TX_CAP_N43")
	)
	(via
		(at 197.706488 -210.896454)
		(size 0.508)
		(drill 0.254)
		(layers "F.Cu" "B.Cu")
		(net "PCIE_TX_CAP_N43")
	)
	(arc
		(start 197.446138 -211.284566)
		(mid 197.469693 -211.166617)
		(end 197.536562 -211.066634)
		(width 0.136652)
		(layer "F.Cu")
		(net "PCIE_TX_CAP_N43")
	)
	(arc
		(start 197.504812 -211.672424)
		(mid 197.461435 -211.607645)
		(end 197.446138 -211.5312)
		(width 0.136652)
		(layer "F.Cu")
		(net "PCIE_TX_CAP_N43")
	)
	(segment
		(start 246.38 -119.507)
		(end 200.953116 -184.383172)
		(width 0.1397)
		(layer "In5.Cu")
		(net "PCIE_TX_CAP_N43")
	)
	(segment
		(start 246.099838 -65.499742)
		(end 246.125238 -65.474342)
		(width 0.1016)
		(layer "In5.Cu")
		(net "PCIE_TX_CAP_N43")
	)
	(segment
		(start 246.029988 -102.758494)
		(end 247.785382 -111.535972)
		(width 0.1397)
		(layer "In5.Cu")
		(net "PCIE_TX_CAP_N43")
	)
	(segment
		(start 246.029988 -90.058494)
		(end 247.299988 -96.408494)
		(width 0.1397)
		(layer "In5.Cu")
		(net "PCIE_TX_CAP_N43")
	)
	(segment
		(start 197.246748 -205.404466)
		(end 197.465188 -206.643732)
		(width 0.1397)
		(layer "In5.Cu")
		(net "PCIE_TX_CAP_N43")
	)
	(segment
		(start 247.785382 -111.535972)
		(end 246.38 -119.507)
		(width 0.1397)
		(layer "In5.Cu")
		(net "PCIE_TX_CAP_N43")
	)
	(segment
		(start 245.966996 -64.9986)
		(end 245.870984 -64.9986)
		(width 0.1016)
		(layer "In5.Cu")
		(net "PCIE_TX_CAP_N43")
	)
	(segment
		(start 245.69674 -66.95694)
		(end 245.745 -67.0052)
		(width 0.1016)
		(layer "In5.Cu")
		(net "PCIE_TX_CAP_N43")
	)
	(segment
		(start 246.125238 -65.474342)
		(end 246.125238 -65.1764)
		(width 0.1016)
		(layer "In5.Cu")
		(net "PCIE_TX_CAP_N43")
	)
	(segment
		(start 200.953116 -184.383172)
		(end 197.246748 -205.404466)
		(width 0.1397)
		(layer "In5.Cu")
		(net "PCIE_TX_CAP_N43")
	)
	(segment
		(start 247.299988 -83.708494)
		(end 246.029988 -90.058494)
		(width 0.1397)
		(layer "In5.Cu")
		(net "PCIE_TX_CAP_N43")
	)
	(segment
		(start 247.299988 -96.408494)
		(end 246.029988 -102.758494)
		(width 0.1397)
		(layer "In5.Cu")
		(net "PCIE_TX_CAP_N43")
	)
	(segment
		(start 245.745 -67.0052)
		(end 245.745 -75.933554)
		(width 0.1397)
		(layer "In5.Cu")
		(net "PCIE_TX_CAP_N43")
	)
	(segment
		(start 245.745 -75.933554)
		(end 247.299988 -83.708494)
		(width 0.1397)
		(layer "In5.Cu")
		(net "PCIE_TX_CAP_N43")
	)
	(segment
		(start 245.69674 -65.17386)
		(end 245.69674 -66.95694)
		(width 0.1016)
		(layer "In5.Cu")
		(net "PCIE_TX_CAP_N43")
	)
	(segment
		(start 197.465188 -206.643732)
		(end 197.465188 -210.313778)
		(width 0.1397)
		(layer "In5.Cu")
		(net "PCIE_TX_CAP_N43")
	)
	(segment
		(start 246.07139 -65.046352)
		(end 246.06377 -65.038732)
		(width 0.1016)
		(layer "In5.Cu")
		(net "PCIE_TX_CAP_N43")
	)
	(arc
		(start 197.465188 -210.313778)
		(mid 197.527909 -210.6291)
		(end 197.706488 -210.896454)
		(width 0.1397)
		(layer "In5.Cu")
		(net "PCIE_TX_CAP_N43")
	)
	(arc
		(start 246.125238 -65.1764)
		(mid 246.11124 -65.106026)
		(end 246.07139 -65.046352)
		(width 0.1016)
		(layer "In5.Cu")
		(net "PCIE_TX_CAP_N43")
	)
	(arc
		(start 245.870984 -64.9986)
		(mid 245.804595 -65.011806)
		(end 245.748302 -65.0494)
		(width 0.1016)
		(layer "In5.Cu")
		(net "PCIE_TX_CAP_N43")
	)
	(arc
		(start 246.06377 -65.038732)
		(mid 246.01937 -65.009065)
		(end 245.966996 -64.9986)
		(width 0.1016)
		(layer "In5.Cu")
		(net "PCIE_TX_CAP_N43")
	)
	(arc
		(start 245.748302 -65.0494)
		(mid 245.710147 -65.106503)
		(end 245.69674 -65.17386)
		(width 0.1016)
		(layer "In5.Cu")
		(net "PCIE_TX_CAP_N43")
	)
	(segment
		(start 200.750678 -211.05241)
		(end 200.90638 -210.896454)
		(width 0.136652)
		(layer "F.Cu")
		(net "PCIE_TX_CAP_N42")
	)
	(segment
		(start 200.64603 -211.5312)
		(end 200.64603 -211.304632)
		(width 0.136652)
		(layer "F.Cu")
		(net "PCIE_TX_CAP_N42")
	)
	(segment
		(start 246.599964 -65.999868)
		(end 247.099836 -66.49974)
		(width 0.136652)
		(layer "F.Cu")
		(net "PCIE_TX_CAP_N42")
	)
	(segment
		(start 201.00798 -211.975954)
		(end 200.704704 -211.672424)
		(width 0.136652)
		(layer "F.Cu")
		(net "PCIE_TX_CAP_N42")
	)
	(via
		(at 247.099836 -66.49974)
		(size 0.4572)
		(drill 0.2032)
		(layers "F.Cu" "B.Cu")
		(net "PCIE_TX_CAP_N42")
	)
	(via
		(at 200.90638 -210.896454)
		(size 0.508)
		(drill 0.254)
		(layers "F.Cu" "B.Cu")
		(net "PCIE_TX_CAP_N42")
	)
	(arc
		(start 200.64603 -211.304632)
		(mid 200.673278 -211.168117)
		(end 200.750678 -211.05241)
		(width 0.136652)
		(layer "F.Cu")
		(net "PCIE_TX_CAP_N42")
	)
	(arc
		(start 200.704704 -211.672424)
		(mid 200.661327 -211.607645)
		(end 200.64603 -211.5312)
		(width 0.136652)
		(layer "F.Cu")
		(net "PCIE_TX_CAP_N42")
	)
	(segment
		(start 246.966994 -65.998598)
		(end 246.870982 -65.998598)
		(width 0.1016)
		(layer "In5.Cu")
		(net "PCIE_TX_CAP_N42")
	)
	(segment
		(start 248.3104 -96.408494)
		(end 247.0404 -102.758494)
		(width 0.1397)
		(layer "In5.Cu")
		(net "PCIE_TX_CAP_N42")
	)
	(segment
		(start 201.93 -202.184)
		(end 200.66508 -209.358484)
		(width 0.1397)
		(layer "In5.Cu")
		(net "PCIE_TX_CAP_N42")
	)
	(segment
		(start 248.3104 -83.708494)
		(end 247.0404 -90.058494)
		(width 0.1397)
		(layer "In5.Cu")
		(net "PCIE_TX_CAP_N42")
	)
	(segment
		(start 247.510808 -120.34139)
		(end 203.852018 -182.692548)
		(width 0.1397)
		(layer "In5.Cu")
		(net "PCIE_TX_CAP_N42")
	)
	(segment
		(start 247.099836 -66.49974)
		(end 247.125236 -66.47434)
		(width 0.1016)
		(layer "In5.Cu")
		(net "PCIE_TX_CAP_N42")
	)
	(segment
		(start 247.0404 -90.058494)
		(end 248.3104 -96.408494)
		(width 0.1397)
		(layer "In5.Cu")
		(net "PCIE_TX_CAP_N42")
	)
	(segment
		(start 247.071388 -66.04635)
		(end 247.063768 -66.03873)
		(width 0.1016)
		(layer "In5.Cu")
		(net "PCIE_TX_CAP_N42")
	)
	(segment
		(start 247.125236 -66.47434)
		(end 247.125236 -66.176398)
		(width 0.1016)
		(layer "In5.Cu")
		(net "PCIE_TX_CAP_N42")
	)
	(segment
		(start 200.66508 -209.358484)
		(end 200.66508 -210.313778)
		(width 0.1397)
		(layer "In5.Cu")
		(net "PCIE_TX_CAP_N42")
	)
	(segment
		(start 203.34859 -185.547254)
		(end 201.17308 -197.8914)
		(width 0.1397)
		(layer "In5.Cu")
		(net "PCIE_TX_CAP_N42")
	)
	(segment
		(start 246.7356 -75.835002)
		(end 248.3104 -83.708494)
		(width 0.1397)
		(layer "In5.Cu")
		(net "PCIE_TX_CAP_N42")
	)
	(segment
		(start 246.7356 -66.9798)
		(end 246.7356 -75.835002)
		(width 0.1397)
		(layer "In5.Cu")
		(net "PCIE_TX_CAP_N42")
	)
	(segment
		(start 247.0404 -102.758494)
		(end 248.938034 -112.247172)
		(width 0.1397)
		(layer "In5.Cu")
		(net "PCIE_TX_CAP_N42")
	)
	(segment
		(start 201.17308 -197.8914)
		(end 201.93 -202.184)
		(width 0.1397)
		(layer "In5.Cu")
		(net "PCIE_TX_CAP_N42")
	)
	(segment
		(start 203.852018 -182.692548)
		(end 203.34859 -185.547254)
		(width 0.1397)
		(layer "In5.Cu")
		(net "PCIE_TX_CAP_N42")
	)
	(segment
		(start 246.696738 -66.940938)
		(end 246.7356 -66.9798)
		(width 0.1016)
		(layer "In5.Cu")
		(net "PCIE_TX_CAP_N42")
	)
	(segment
		(start 248.938034 -112.247172)
		(end 247.510808 -120.34139)
		(width 0.1397)
		(layer "In5.Cu")
		(net "PCIE_TX_CAP_N42")
	)
	(segment
		(start 246.696738 -66.173858)
		(end 246.696738 -66.940938)
		(width 0.1016)
		(layer "In5.Cu")
		(net "PCIE_TX_CAP_N42")
	)
	(arc
		(start 247.063768 -66.03873)
		(mid 247.019368 -66.009063)
		(end 246.966994 -65.998598)
		(width 0.1016)
		(layer "In5.Cu")
		(net "PCIE_TX_CAP_N42")
	)
	(arc
		(start 246.870982 -65.998598)
		(mid 246.804593 -66.011804)
		(end 246.7483 -66.049398)
		(width 0.1016)
		(layer "In5.Cu")
		(net "PCIE_TX_CAP_N42")
	)
	(arc
		(start 247.125236 -66.176398)
		(mid 247.111238 -66.106024)
		(end 247.071388 -66.04635)
		(width 0.1016)
		(layer "In5.Cu")
		(net "PCIE_TX_CAP_N42")
	)
	(arc
		(start 200.66508 -210.313778)
		(mid 200.727801 -210.6291)
		(end 200.90638 -210.896454)
		(width 0.1397)
		(layer "In5.Cu")
		(net "PCIE_TX_CAP_N42")
	)
	(arc
		(start 246.7483 -66.049398)
		(mid 246.710145 -66.106501)
		(end 246.696738 -66.173858)
		(width 0.1016)
		(layer "In5.Cu")
		(net "PCIE_TX_CAP_N42")
	)
	(segment
		(start 204.208126 -211.975954)
		(end 203.90485 -211.672424)
		(width 0.136652)
		(layer "F.Cu")
		(net "PCIE_TX_CAP_N41")
	)
	(segment
		(start 247.599962 -64.99987)
		(end 248.099834 -65.499742)
		(width 0.136652)
		(layer "F.Cu")
		(net "PCIE_TX_CAP_N41")
	)
	(segment
		(start 203.939394 -211.063586)
		(end 204.106526 -210.896454)
		(width 0.136652)
		(layer "F.Cu")
		(net "PCIE_TX_CAP_N41")
	)
	(segment
		(start 203.846176 -211.5312)
		(end 203.846176 -211.28863)
		(width 0.136652)
		(layer "F.Cu")
		(net "PCIE_TX_CAP_N41")
	)
	(via
		(at 204.106526 -210.896454)
		(size 0.508)
		(drill 0.254)
		(layers "F.Cu" "B.Cu")
		(net "PCIE_TX_CAP_N41")
	)
	(via
		(at 248.099834 -65.499742)
		(size 0.4572)
		(drill 0.2032)
		(layers "F.Cu" "B.Cu")
		(net "PCIE_TX_CAP_N41")
	)
	(arc
		(start 203.846176 -211.28863)
		(mid 203.870402 -211.166836)
		(end 203.939394 -211.063586)
		(width 0.136652)
		(layer "F.Cu")
		(net "PCIE_TX_CAP_N41")
	)
	(arc
		(start 203.90485 -211.672424)
		(mid 203.861473 -211.607645)
		(end 203.846176 -211.5312)
		(width 0.136652)
		(layer "F.Cu")
		(net "PCIE_TX_CAP_N41")
	)
	(segment
		(start 203.865226 -207.09255)
		(end 203.865226 -210.313778)
		(width 0.1397)
		(layer "In5.Cu")
		(net "PCIE_TX_CAP_N41")
	)
	(segment
		(start 248.125234 -65.474342)
		(end 248.125234 -65.1764)
		(width 0.1016)
		(layer "In5.Cu")
		(net "PCIE_TX_CAP_N41")
	)
	(segment
		(start 247.7516 -66.9544)
		(end 247.7516 -75.73391)
		(width 0.1397)
		(layer "In5.Cu")
		(net "PCIE_TX_CAP_N41")
	)
	(segment
		(start 248.519188 -121.18848)
		(end 207.007206 -180.474366)
		(width 0.1397)
		(layer "In5.Cu")
		(net "PCIE_TX_CAP_N41")
	)
	(segment
		(start 247.7516 -75.73391)
		(end 249.346466 -83.708494)
		(width 0.1397)
		(layer "In5.Cu")
		(net "PCIE_TX_CAP_N41")
	)
	(segment
		(start 247.966992 -64.9986)
		(end 247.87098 -64.9986)
		(width 0.1016)
		(layer "In5.Cu")
		(net "PCIE_TX_CAP_N41")
	)
	(segment
		(start 247.696736 -65.17386)
		(end 247.696736 -66.899536)
		(width 0.1016)
		(layer "In5.Cu")
		(net "PCIE_TX_CAP_N41")
	)
	(segment
		(start 248.076466 -102.758494)
		(end 250.039124 -112.571276)
		(width 0.1397)
		(layer "In5.Cu")
		(net "PCIE_TX_CAP_N41")
	)
	(segment
		(start 248.099834 -65.499742)
		(end 248.125234 -65.474342)
		(width 0.1016)
		(layer "In5.Cu")
		(net "PCIE_TX_CAP_N41")
	)
	(segment
		(start 250.039124 -112.571276)
		(end 248.519188 -121.18848)
		(width 0.1397)
		(layer "In5.Cu")
		(net "PCIE_TX_CAP_N41")
	)
	(segment
		(start 248.071386 -65.046352)
		(end 248.063766 -65.038732)
		(width 0.1016)
		(layer "In5.Cu")
		(net "PCIE_TX_CAP_N41")
	)
	(segment
		(start 207.007206 -180.474366)
		(end 203.981304 -197.634606)
		(width 0.1397)
		(layer "In5.Cu")
		(net "PCIE_TX_CAP_N41")
	)
	(segment
		(start 203.981304 -197.634606)
		(end 204.75702 -202.03414)
		(width 0.1397)
		(layer "In5.Cu")
		(net "PCIE_TX_CAP_N41")
	)
	(segment
		(start 249.346466 -83.708494)
		(end 248.076466 -90.058494)
		(width 0.1397)
		(layer "In5.Cu")
		(net "PCIE_TX_CAP_N41")
	)
	(segment
		(start 204.75702 -202.03414)
		(end 203.865226 -207.09255)
		(width 0.1397)
		(layer "In5.Cu")
		(net "PCIE_TX_CAP_N41")
	)
	(segment
		(start 249.346466 -96.408494)
		(end 248.076466 -102.758494)
		(width 0.1397)
		(layer "In5.Cu")
		(net "PCIE_TX_CAP_N41")
	)
	(segment
		(start 247.696736 -66.899536)
		(end 247.7516 -66.9544)
		(width 0.1016)
		(layer "In5.Cu")
		(net "PCIE_TX_CAP_N41")
	)
	(segment
		(start 248.076466 -90.058494)
		(end 249.346466 -96.408494)
		(width 0.1397)
		(layer "In5.Cu")
		(net "PCIE_TX_CAP_N41")
	)
	(arc
		(start 247.748298 -65.0494)
		(mid 247.710143 -65.106503)
		(end 247.696736 -65.17386)
		(width 0.1016)
		(layer "In5.Cu")
		(net "PCIE_TX_CAP_N41")
	)
	(arc
		(start 248.125234 -65.1764)
		(mid 248.111236 -65.106026)
		(end 248.071386 -65.046352)
		(width 0.1016)
		(layer "In5.Cu")
		(net "PCIE_TX_CAP_N41")
	)
	(arc
		(start 203.865226 -210.313778)
		(mid 203.927947 -210.6291)
		(end 204.106526 -210.896454)
		(width 0.1397)
		(layer "In5.Cu")
		(net "PCIE_TX_CAP_N41")
	)
	(arc
		(start 247.87098 -64.9986)
		(mid 247.804591 -65.011806)
		(end 247.748298 -65.0494)
		(width 0.1016)
		(layer "In5.Cu")
		(net "PCIE_TX_CAP_N41")
	)
	(arc
		(start 248.063766 -65.038732)
		(mid 248.019366 -65.009065)
		(end 247.966992 -64.9986)
		(width 0.1016)
		(layer "In5.Cu")
		(net "PCIE_TX_CAP_N41")
	)
	(segment
		(start 207.046068 -211.5312)
		(end 207.046068 -211.31657)
		(width 0.136652)
		(layer "F.Cu")
		(net "PCIE_TX_CAP_N40")
	)
	(segment
		(start 248.59996 -65.999868)
		(end 249.099832 -66.49974)
		(width 0.136652)
		(layer "F.Cu")
		(net "PCIE_TX_CAP_N40")
	)
	(segment
		(start 207.408018 -211.975954)
		(end 207.104742 -211.672424)
		(width 0.136652)
		(layer "F.Cu")
		(net "PCIE_TX_CAP_N40")
	)
	(segment
		(start 207.159098 -211.043774)
		(end 207.306418 -210.896454)
		(width 0.136652)
		(layer "F.Cu")
		(net "PCIE_TX_CAP_N40")
	)
	(via
		(at 207.306418 -210.896454)
		(size 0.508)
		(drill 0.254)
		(layers "F.Cu" "B.Cu")
		(net "PCIE_TX_CAP_N40")
	)
	(via
		(at 249.099832 -66.49974)
		(size 0.4572)
		(drill 0.2032)
		(layers "F.Cu" "B.Cu")
		(net "PCIE_TX_CAP_N40")
	)
	(arc
		(start 207.104742 -211.672424)
		(mid 207.061365 -211.607645)
		(end 207.046068 -211.5312)
		(width 0.136652)
		(layer "F.Cu")
		(net "PCIE_TX_CAP_N40")
	)
	(arc
		(start 207.046068 -211.31657)
		(mid 207.075437 -211.168921)
		(end 207.159098 -211.043774)
		(width 0.136652)
		(layer "F.Cu")
		(net "PCIE_TX_CAP_N40")
	)
	(segment
		(start 248.696734 -66.883534)
		(end 248.7422 -66.929)
		(width 0.1016)
		(layer "In5.Cu")
		(net "PCIE_TX_CAP_N40")
	)
	(segment
		(start 206.111094 -197.294246)
		(end 207.645 -205.994)
		(width 0.1397)
		(layer "In5.Cu")
		(net "PCIE_TX_CAP_N40")
	)
	(segment
		(start 207.645 -205.994)
		(end 207.065118 -209.282538)
		(width 0.1397)
		(layer "In5.Cu")
		(net "PCIE_TX_CAP_N40")
	)
	(segment
		(start 248.96699 -65.998598)
		(end 248.870978 -65.998598)
		(width 0.1016)
		(layer "In5.Cu")
		(net "PCIE_TX_CAP_N40")
	)
	(segment
		(start 250.356878 -83.708494)
		(end 249.086878 -90.058494)
		(width 0.1397)
		(layer "In5.Cu")
		(net "PCIE_TX_CAP_N40")
	)
	(segment
		(start 251.107448 -112.861598)
		(end 249.483118 -122.073416)
		(width 0.1397)
		(layer "In5.Cu")
		(net "PCIE_TX_CAP_N40")
	)
	(segment
		(start 207.065118 -209.282538)
		(end 207.065118 -210.313778)
		(width 0.1397)
		(layer "In5.Cu")
		(net "PCIE_TX_CAP_N40")
	)
	(segment
		(start 249.086878 -90.058494)
		(end 250.356878 -96.408494)
		(width 0.1397)
		(layer "In5.Cu")
		(net "PCIE_TX_CAP_N40")
	)
	(segment
		(start 248.7422 -75.635358)
		(end 250.356878 -83.708494)
		(width 0.1397)
		(layer "In5.Cu")
		(net "PCIE_TX_CAP_N40")
	)
	(segment
		(start 249.483118 -122.073416)
		(end 209.240628 -179.54625)
		(width 0.1397)
		(layer "In5.Cu")
		(net "PCIE_TX_CAP_N40")
	)
	(segment
		(start 250.356878 -96.408494)
		(end 249.086878 -102.758494)
		(width 0.1397)
		(layer "In5.Cu")
		(net "PCIE_TX_CAP_N40")
	)
	(segment
		(start 249.086878 -102.758494)
		(end 251.107448 -112.861598)
		(width 0.1397)
		(layer "In5.Cu")
		(net "PCIE_TX_CAP_N40")
	)
	(segment
		(start 248.696734 -66.173858)
		(end 248.696734 -66.883534)
		(width 0.1016)
		(layer "In5.Cu")
		(net "PCIE_TX_CAP_N40")
	)
	(segment
		(start 248.7422 -66.929)
		(end 248.7422 -75.635358)
		(width 0.1397)
		(layer "In5.Cu")
		(net "PCIE_TX_CAP_N40")
	)
	(segment
		(start 249.071384 -66.04635)
		(end 249.063764 -66.03873)
		(width 0.1016)
		(layer "In5.Cu")
		(net "PCIE_TX_CAP_N40")
	)
	(segment
		(start 249.125232 -66.47434)
		(end 249.125232 -66.176398)
		(width 0.1016)
		(layer "In5.Cu")
		(net "PCIE_TX_CAP_N40")
	)
	(segment
		(start 209.240628 -179.54625)
		(end 206.111094 -197.294246)
		(width 0.1397)
		(layer "In5.Cu")
		(net "PCIE_TX_CAP_N40")
	)
	(segment
		(start 249.099832 -66.49974)
		(end 249.125232 -66.47434)
		(width 0.1016)
		(layer "In5.Cu")
		(net "PCIE_TX_CAP_N40")
	)
	(arc
		(start 249.063764 -66.03873)
		(mid 249.019364 -66.009063)
		(end 248.96699 -65.998598)
		(width 0.1016)
		(layer "In5.Cu")
		(net "PCIE_TX_CAP_N40")
	)
	(arc
		(start 248.870978 -65.998598)
		(mid 248.804589 -66.011804)
		(end 248.748296 -66.049398)
		(width 0.1016)
		(layer "In5.Cu")
		(net "PCIE_TX_CAP_N40")
	)
	(arc
		(start 249.125232 -66.176398)
		(mid 249.111234 -66.106024)
		(end 249.071384 -66.04635)
		(width 0.1016)
		(layer "In5.Cu")
		(net "PCIE_TX_CAP_N40")
	)
	(arc
		(start 207.065118 -210.313778)
		(mid 207.127839 -210.6291)
		(end 207.306418 -210.896454)
		(width 0.1397)
		(layer "In5.Cu")
		(net "PCIE_TX_CAP_N40")
	)
	(arc
		(start 248.748296 -66.049398)
		(mid 248.710141 -66.106501)
		(end 248.696734 -66.173858)
		(width 0.1016)
		(layer "In5.Cu")
		(net "PCIE_TX_CAP_N40")
	)
	(segment
		(start 255.599946 -29.99994)
		(end 256.099818 -29.500068)
		(width 0.136652)
		(layer "F.Cu")
		(net "PCIE_TX_CAP_N4")
	)
	(segment
		(start 294.730678 -34.608516)
		(end 294.730678 -34.748216)
		(width 0.136652)
		(layer "F.Cu")
		(net "PCIE_TX_CAP_N4")
	)
	(segment
		(start 294.865552 -35.073844)
		(end 294.971978 -35.18027)
		(width 0.136652)
		(layer "F.Cu")
		(net "PCIE_TX_CAP_N4")
	)
	(segment
		(start 294.997378 -34.138616)
		(end 294.874442 -34.261806)
		(width 0.136652)
		(layer "F.Cu")
		(net "PCIE_TX_CAP_N4")
	)
	(via
		(at 294.971978 -35.18027)
		(size 0.508)
		(drill 0.254)
		(layers "F.Cu" "B.Cu")
		(net "PCIE_TX_CAP_N4")
	)
	(via
		(at 256.099818 -29.500068)
		(size 0.4572)
		(drill 0.2032)
		(layers "F.Cu" "B.Cu")
		(net "PCIE_TX_CAP_N4")
	)
	(arc
		(start 294.874442 -34.261806)
		(mid 294.768071 -34.420863)
		(end 294.730678 -34.608516)
		(width 0.136652)
		(layer "F.Cu")
		(net "PCIE_TX_CAP_N4")
	)
	(arc
		(start 294.730678 -34.748216)
		(mid 294.765732 -34.924442)
		(end 294.865552 -35.073844)
		(width 0.136652)
		(layer "F.Cu")
		(net "PCIE_TX_CAP_N4")
	)
	(segment
		(start 256.643886 -25.802844)
		(end 257.52425 -25.186386)
		(width 0.1397)
		(layer "In5.Cu")
		(net "PCIE_TX_CAP_N4")
	)
	(segment
		(start 255.704594 -28.951428)
		(end 255.871472 -28.78455)
		(width 0.1016)
		(layer "In5.Cu")
		(net "PCIE_TX_CAP_N4")
	)
	(segment
		(start 268.850618 -24.310848)
		(end 276.023324 -25.575768)
		(width 0.1397)
		(layer "In5.Cu")
		(net "PCIE_TX_CAP_N4")
	)
	(segment
		(start 294.852598 -35.299904)
		(end 294.971978 -35.18027)
		(width 0.1397)
		(layer "In5.Cu")
		(net "PCIE_TX_CAP_N4")
	)
	(segment
		(start 255.934972 -27.34691)
		(end 256.06248 -26.633678)
		(width 0.1397)
		(layer "In5.Cu")
		(net "PCIE_TX_CAP_N4")
	)
	(segment
		(start 294.07612 -36.451286)
		(end 294.076628 -36.450778)
		(width 0.1397)
		(layer "In5.Cu")
		(net "PCIE_TX_CAP_N4")
	)
	(segment
		(start 255.871472 -28.29814)
		(end 255.934972 -28.23464)
		(width 0.1016)
		(layer "In5.Cu")
		(net "PCIE_TX_CAP_N4")
	)
	(segment
		(start 277.680166 -26.735786)
		(end 279.520142 -29.363416)
		(width 0.1397)
		(layer "In5.Cu")
		(net "PCIE_TX_CAP_N4")
	)
	(segment
		(start 284.707076 -36.986972)
		(end 287.874456 -37.545264)
		(width 0.1397)
		(layer "In5.Cu")
		(net "PCIE_TX_CAP_N4")
	)
	(segment
		(start 261.36092 -24.509984)
		(end 264.541 -25.146)
		(width 0.1397)
		(layer "In5.Cu")
		(net "PCIE_TX_CAP_N4")
	)
	(segment
		(start 267.716 -24.511)
		(end 268.850618 -24.310848)
		(width 0.1397)
		(layer "In5.Cu")
		(net "PCIE_TX_CAP_N4")
	)
	(segment
		(start 256.099818 -29.500068)
		(end 256.099818 -29.929074)
		(width 0.1016)
		(layer "In5.Cu")
		(net "PCIE_TX_CAP_N4")
	)
	(segment
		(start 276.023324 -25.575768)
		(end 277.680166 -26.735786)
		(width 0.1397)
		(layer "In5.Cu")
		(net "PCIE_TX_CAP_N4")
	)
	(segment
		(start 256.06248 -26.633678)
		(end 256.643886 -25.802844)
		(width 0.1397)
		(layer "In5.Cu")
		(net "PCIE_TX_CAP_N4")
	)
	(segment
		(start 255.934972 -28.23464)
		(end 255.934972 -28.20924)
		(width 0.1016)
		(layer "In5.Cu")
		(net "PCIE_TX_CAP_N4")
	)
	(segment
		(start 264.541 -25.146)
		(end 267.716 -24.511)
		(width 0.1397)
		(layer "In5.Cu")
		(net "PCIE_TX_CAP_N4")
	)
	(segment
		(start 255.905508 -30.009592)
		(end 255.788668 -29.892752)
		(width 0.1016)
		(layer "In5.Cu")
		(net "PCIE_TX_CAP_N4")
	)
	(segment
		(start 280.1112 -32.7152)
		(end 281.558238 -34.781998)
		(width 0.1397)
		(layer "In5.Cu")
		(net "PCIE_TX_CAP_N4")
	)
	(segment
		(start 255.934972 -28.20924)
		(end 255.934972 -27.34691)
		(width 0.1397)
		(layer "In5.Cu")
		(net "PCIE_TX_CAP_N4")
	)
	(segment
		(start 257.52425 -25.186386)
		(end 261.36092 -24.509984)
		(width 0.1397)
		(layer "In5.Cu")
		(net "PCIE_TX_CAP_N4")
	)
	(segment
		(start 287.874456 -37.545264)
		(end 294.07612 -36.451286)
		(width 0.1397)
		(layer "In5.Cu")
		(net "PCIE_TX_CAP_N4")
	)
	(segment
		(start 281.558238 -34.781998)
		(end 284.707076 -36.986972)
		(width 0.1397)
		(layer "In5.Cu")
		(net "PCIE_TX_CAP_N4")
	)
	(segment
		(start 255.871472 -28.78455)
		(end 255.871472 -28.29814)
		(width 0.1016)
		(layer "In5.Cu")
		(net "PCIE_TX_CAP_N4")
	)
	(segment
		(start 255.704594 -29.632402)
		(end 255.704594 -28.951428)
		(width 0.1016)
		(layer "In5.Cu")
		(net "PCIE_TX_CAP_N4")
	)
	(segment
		(start 279.520142 -29.363416)
		(end 280.1112 -32.7152)
		(width 0.1397)
		(layer "In5.Cu")
		(net "PCIE_TX_CAP_N4")
	)
	(arc
		(start 256.099818 -29.929074)
		(mid 256.029572 -30.034204)
		(end 255.905508 -30.009592)
		(width 0.1016)
		(layer "In5.Cu")
		(net "PCIE_TX_CAP_N4")
	)
	(arc
		(start 255.788668 -29.892752)
		(mid 255.726184 -29.769181)
		(end 255.704594 -29.632402)
		(width 0.1016)
		(layer "In5.Cu")
		(net "PCIE_TX_CAP_N4")
	)
	(arc
		(start 294.076628 -36.450778)
		(mid 294.538819 -36.147494)
		(end 294.717978 -35.624516)
		(width 0.1397)
		(layer "In5.Cu")
		(net "PCIE_TX_CAP_N4")
	)
	(arc
		(start 294.717978 -35.624516)
		(mid 294.753018 -35.448829)
		(end 294.852598 -35.299904)
		(width 0.1397)
		(layer "In5.Cu")
		(net "PCIE_TX_CAP_N4")
	)
	(segment
		(start 213.808056 -211.975954)
		(end 213.50478 -211.672424)
		(width 0.136652)
		(layer "F.Cu")
		(net "PCIE_TX_CAP_N39")
	)
	(segment
		(start 213.446106 -211.5312)
		(end 213.446106 -211.301076)
		(width 0.136652)
		(layer "F.Cu")
		(net "PCIE_TX_CAP_N39")
	)
	(segment
		(start 250.599956 -64.99987)
		(end 251.099828 -65.499742)
		(width 0.136652)
		(layer "F.Cu")
		(net "PCIE_TX_CAP_N39")
	)
	(segment
		(start 213.548214 -211.05495)
		(end 213.706456 -210.896454)
		(width 0.136652)
		(layer "F.Cu")
		(net "PCIE_TX_CAP_N39")
	)
	(via
		(at 251.099828 -65.499742)
		(size 0.4572)
		(drill 0.2032)
		(layers "F.Cu" "B.Cu")
		(net "PCIE_TX_CAP_N39")
	)
	(via
		(at 213.706456 -210.896454)
		(size 0.508)
		(drill 0.254)
		(layers "F.Cu" "B.Cu")
		(net "PCIE_TX_CAP_N39")
	)
	(arc
		(start 213.50478 -211.672424)
		(mid 213.461403 -211.607645)
		(end 213.446106 -211.5312)
		(width 0.136652)
		(layer "F.Cu")
		(net "PCIE_TX_CAP_N39")
	)
	(arc
		(start 213.446106 -211.301076)
		(mid 213.472697 -211.167866)
		(end 213.548214 -211.05495)
		(width 0.136652)
		(layer "F.Cu")
		(net "PCIE_TX_CAP_N39")
	)
	(segment
		(start 251.79909 -122.823732)
		(end 210.60791 -181.650894)
		(width 0.1397)
		(layer "In5.Cu")
		(net "PCIE_TX_CAP_N39")
	)
	(segment
		(start 250.966986 -64.9986)
		(end 250.870974 -64.9986)
		(width 0.1016)
		(layer "In5.Cu")
		(net "PCIE_TX_CAP_N39")
	)
	(segment
		(start 251.125228 -65.474342)
		(end 251.125228 -65.1764)
		(width 0.1016)
		(layer "In5.Cu")
		(net "PCIE_TX_CAP_N39")
	)
	(segment
		(start 251.099828 -65.499742)
		(end 251.125228 -65.474342)
		(width 0.1016)
		(layer "In5.Cu")
		(net "PCIE_TX_CAP_N39")
	)
	(segment
		(start 250.7488 -67.055492)
		(end 250.7488 -67.16522)
		(width 0.1016)
		(layer "In5.Cu")
		(net "PCIE_TX_CAP_N39")
	)
	(segment
		(start 255.385062 -101.986334)
		(end 255.385062 -102.485698)
		(width 0.1397)
		(layer "In5.Cu")
		(net "PCIE_TX_CAP_N39")
	)
	(segment
		(start 250.69673 -67.015614)
		(end 250.7488 -67.055492)
		(width 0.1016)
		(layer "In5.Cu")
		(net "PCIE_TX_CAP_N39")
	)
	(segment
		(start 213.465156 -208.811114)
		(end 213.465156 -210.313778)
		(width 0.1397)
		(layer "In5.Cu")
		(net "PCIE_TX_CAP_N39")
	)
	(segment
		(start 208.975706 -190.906654)
		(end 211.684108 -206.267558)
		(width 0.1397)
		(layer "In5.Cu")
		(net "PCIE_TX_CAP_N39")
	)
	(segment
		(start 210.60791 -181.650894)
		(end 208.975706 -190.906654)
		(width 0.1397)
		(layer "In5.Cu")
		(net "PCIE_TX_CAP_N39")
	)
	(segment
		(start 250.7488 -67.16522)
		(end 250.7488 -75.704192)
		(width 0.1397)
		(layer "In5.Cu")
		(net "PCIE_TX_CAP_N39")
	)
	(segment
		(start 251.07138 -65.046352)
		(end 251.06376 -65.038732)
		(width 0.1016)
		(layer "In5.Cu")
		(net "PCIE_TX_CAP_N39")
	)
	(segment
		(start 255.385062 -102.485698)
		(end 251.79909 -122.823732)
		(width 0.1397)
		(layer "In5.Cu")
		(net "PCIE_TX_CAP_N39")
	)
	(segment
		(start 250.69673 -65.17386)
		(end 250.69673 -67.015614)
		(width 0.1016)
		(layer "In5.Cu")
		(net "PCIE_TX_CAP_N39")
	)
	(segment
		(start 250.7488 -75.704192)
		(end 255.385062 -101.986334)
		(width 0.1397)
		(layer "In5.Cu")
		(net "PCIE_TX_CAP_N39")
	)
	(segment
		(start 211.684108 -206.267558)
		(end 213.465156 -208.811114)
		(width 0.1397)
		(layer "In5.Cu")
		(net "PCIE_TX_CAP_N39")
	)
	(arc
		(start 251.125228 -65.1764)
		(mid 251.11123 -65.106026)
		(end 251.07138 -65.046352)
		(width 0.1016)
		(layer "In5.Cu")
		(net "PCIE_TX_CAP_N39")
	)
	(arc
		(start 250.748292 -65.0494)
		(mid 250.710137 -65.106503)
		(end 250.69673 -65.17386)
		(width 0.1016)
		(layer "In5.Cu")
		(net "PCIE_TX_CAP_N39")
	)
	(arc
		(start 250.870974 -64.9986)
		(mid 250.804585 -65.011806)
		(end 250.748292 -65.0494)
		(width 0.1016)
		(layer "In5.Cu")
		(net "PCIE_TX_CAP_N39")
	)
	(arc
		(start 251.06376 -65.038732)
		(mid 251.01936 -65.009065)
		(end 250.966986 -64.9986)
		(width 0.1016)
		(layer "In5.Cu")
		(net "PCIE_TX_CAP_N39")
	)
	(arc
		(start 213.465156 -210.313778)
		(mid 213.527877 -210.6291)
		(end 213.706456 -210.896454)
		(width 0.1397)
		(layer "In5.Cu")
		(net "PCIE_TX_CAP_N39")
	)
	(segment
		(start 216.729056 -211.073492)
		(end 216.906348 -210.896454)
		(width 0.136652)
		(layer "F.Cu")
		(net "PCIE_TX_CAP_N38")
	)
	(segment
		(start 216.645998 -211.5312)
		(end 216.645998 -211.274406)
		(width 0.136652)
		(layer "F.Cu")
		(net "PCIE_TX_CAP_N38")
	)
	(segment
		(start 217.007948 -211.975954)
		(end 216.704672 -211.672424)
		(width 0.136652)
		(layer "F.Cu")
		(net "PCIE_TX_CAP_N38")
	)
	(segment
		(start 251.599954 -65.999868)
		(end 252.099826 -66.49974)
		(width 0.136652)
		(layer "F.Cu")
		(net "PCIE_TX_CAP_N38")
	)
	(via
		(at 252.099826 -66.49974)
		(size 0.4572)
		(drill 0.2032)
		(layers "F.Cu" "B.Cu")
		(net "PCIE_TX_CAP_N38")
	)
	(via
		(at 216.906348 -210.896454)
		(size 0.508)
		(drill 0.254)
		(layers "F.Cu" "B.Cu")
		(net "PCIE_TX_CAP_N38")
	)
	(arc
		(start 216.645998 -211.274406)
		(mid 216.667531 -211.165681)
		(end 216.729056 -211.073492)
		(width 0.136652)
		(layer "F.Cu")
		(net "PCIE_TX_CAP_N38")
	)
	(arc
		(start 216.704672 -211.672424)
		(mid 216.661295 -211.607645)
		(end 216.645998 -211.5312)
		(width 0.136652)
		(layer "F.Cu")
		(net "PCIE_TX_CAP_N38")
	)
	(segment
		(start 251.696728 -66.986404)
		(end 251.696728 -66.173858)
		(width 0.1016)
		(layer "In5.Cu")
		(net "PCIE_TX_CAP_N38")
	)
	(segment
		(start 251.870972 -65.998598)
		(end 251.966984 -65.998598)
		(width 0.1016)
		(layer "In5.Cu")
		(net "PCIE_TX_CAP_N38")
	)
	(segment
		(start 256.72034 -102.321614)
		(end 251.7648 -74.228198)
		(width 0.1397)
		(layer "In5.Cu")
		(net "PCIE_TX_CAP_N38")
	)
	(segment
		(start 252.930914 -124.316998)
		(end 256.72034 -102.824788)
		(width 0.1397)
		(layer "In5.Cu")
		(net "PCIE_TX_CAP_N38")
	)
	(segment
		(start 210.710526 -191.287654)
		(end 212.283548 -182.367174)
		(width 0.1397)
		(layer "In5.Cu")
		(net "PCIE_TX_CAP_N38")
	)
	(segment
		(start 252.125226 -66.176398)
		(end 252.125226 -66.47434)
		(width 0.1016)
		(layer "In5.Cu")
		(net "PCIE_TX_CAP_N38")
	)
	(segment
		(start 252.063758 -66.03873)
		(end 252.071378 -66.04635)
		(width 0.1016)
		(layer "In5.Cu")
		(net "PCIE_TX_CAP_N38")
	)
	(segment
		(start 212.283548 -182.367174)
		(end 252.930914 -124.316998)
		(width 0.1397)
		(layer "In5.Cu")
		(net "PCIE_TX_CAP_N38")
	)
	(segment
		(start 256.72034 -102.824788)
		(end 256.72034 -102.321614)
		(width 0.1397)
		(layer "In5.Cu")
		(net "PCIE_TX_CAP_N38")
	)
	(segment
		(start 252.125226 -66.47434)
		(end 252.099826 -66.49974)
		(width 0.1016)
		(layer "In5.Cu")
		(net "PCIE_TX_CAP_N38")
	)
	(segment
		(start 251.7648 -67.054476)
		(end 251.696728 -66.986404)
		(width 0.1016)
		(layer "In5.Cu")
		(net "PCIE_TX_CAP_N38")
	)
	(segment
		(start 216.665048 -210.313778)
		(end 216.665048 -208.846674)
		(width 0.1397)
		(layer "In5.Cu")
		(net "PCIE_TX_CAP_N38")
	)
	(segment
		(start 216.665048 -208.846674)
		(end 212.844888 -203.391008)
		(width 0.1397)
		(layer "In5.Cu")
		(net "PCIE_TX_CAP_N38")
	)
	(segment
		(start 251.7648 -74.228198)
		(end 251.7648 -67.054476)
		(width 0.1397)
		(layer "In5.Cu")
		(net "PCIE_TX_CAP_N38")
	)
	(segment
		(start 212.844888 -203.391008)
		(end 210.710526 -191.287654)
		(width 0.1397)
		(layer "In5.Cu")
		(net "PCIE_TX_CAP_N38")
	)
	(arc
		(start 216.906348 -210.896454)
		(mid 216.727721 -210.62912)
		(end 216.665048 -210.313778)
		(width 0.1397)
		(layer "In5.Cu")
		(net "PCIE_TX_CAP_N38")
	)
	(arc
		(start 251.696728 -66.173858)
		(mid 251.710127 -66.106497)
		(end 251.74829 -66.049398)
		(width 0.1016)
		(layer "In5.Cu")
		(net "PCIE_TX_CAP_N38")
	)
	(arc
		(start 251.74829 -66.049398)
		(mid 251.804577 -66.011788)
		(end 251.870972 -65.998598)
		(width 0.1016)
		(layer "In5.Cu")
		(net "PCIE_TX_CAP_N38")
	)
	(arc
		(start 252.071378 -66.04635)
		(mid 252.111246 -66.106017)
		(end 252.125226 -66.176398)
		(width 0.1016)
		(layer "In5.Cu")
		(net "PCIE_TX_CAP_N38")
	)
	(arc
		(start 251.966984 -65.998598)
		(mid 252.019376 -66.009019)
		(end 252.063758 -66.03873)
		(width 0.1016)
		(layer "In5.Cu")
		(net "PCIE_TX_CAP_N38")
	)
	(segment
		(start 265.131042 -211.071714)
		(end 265.306556 -210.896454)
		(width 0.136652)
		(layer "F.Cu")
		(net "PCIE_TX_CAP_N37")
	)
	(segment
		(start 265.046206 -211.5312)
		(end 265.046206 -211.276946)
		(width 0.136652)
		(layer "F.Cu")
		(net "PCIE_TX_CAP_N37")
	)
	(segment
		(start 265.408156 -211.975954)
		(end 265.10488 -211.672424)
		(width 0.136652)
		(layer "F.Cu")
		(net "PCIE_TX_CAP_N37")
	)
	(segment
		(start 252.599952 -64.99987)
		(end 253.099824 -65.499742)
		(width 0.136652)
		(layer "F.Cu")
		(net "PCIE_TX_CAP_N37")
	)
	(via
		(at 265.306556 -210.896454)
		(size 0.508)
		(drill 0.254)
		(layers "F.Cu" "B.Cu")
		(net "PCIE_TX_CAP_N37")
	)
	(via
		(at 253.099824 -65.499742)
		(size 0.4572)
		(drill 0.2032)
		(layers "F.Cu" "B.Cu")
		(net "PCIE_TX_CAP_N37")
	)
	(arc
		(start 265.10488 -211.672424)
		(mid 265.061503 -211.607645)
		(end 265.046206 -211.5312)
		(width 0.136652)
		(layer "F.Cu")
		(net "PCIE_TX_CAP_N37")
	)
	(arc
		(start 265.046206 -211.276946)
		(mid 265.068203 -211.165888)
		(end 265.131042 -211.071714)
		(width 0.136652)
		(layer "F.Cu")
		(net "PCIE_TX_CAP_N37")
	)
	(segment
		(start 269.021306 -160.14446)
		(end 263.62406 -190.754254)
		(width 0.1397)
		(layer "In5.Cu")
		(net "PCIE_TX_CAP_N37")
	)
	(segment
		(start 253.098046 -65.073022)
		(end 253.063756 -65.038732)
		(width 0.1016)
		(layer "In5.Cu")
		(net "PCIE_TX_CAP_N37")
	)
	(segment
		(start 266.065 -204.597)
		(end 265.592306 -207.277462)
		(width 0.1397)
		(layer "In5.Cu")
		(net "PCIE_TX_CAP_N37")
	)
	(segment
		(start 252.7554 -66.9544)
		(end 252.7554 -67.89039)
		(width 0.1397)
		(layer "In5.Cu")
		(net "PCIE_TX_CAP_N37")
	)
	(segment
		(start 253.1618 -65.350136)
		(end 253.1618 -65.2272)
		(width 0.1016)
		(layer "In5.Cu")
		(net "PCIE_TX_CAP_N37")
	)
	(segment
		(start 252.7554 -67.89039)
		(end 269.021306 -160.14446)
		(width 0.1397)
		(layer "In5.Cu")
		(net "PCIE_TX_CAP_N37")
	)
	(segment
		(start 265.30681 -207.685386)
		(end 265.0998 -207.981042)
		(width 0.1397)
		(layer "In5.Cu")
		(net "PCIE_TX_CAP_N37")
	)
	(segment
		(start 264.83437 -197.61835)
		(end 266.065 -204.597)
		(width 0.1397)
		(layer "In5.Cu")
		(net "PCIE_TX_CAP_N37")
	)
	(segment
		(start 265.592306 -207.277462)
		(end 265.30681 -207.685386)
		(width 0.1397)
		(layer "In5.Cu")
		(net "PCIE_TX_CAP_N37")
	)
	(segment
		(start 252.696726 -66.895726)
		(end 252.7554 -66.9544)
		(width 0.1016)
		(layer "In5.Cu")
		(net "PCIE_TX_CAP_N37")
	)
	(segment
		(start 265.0998 -207.981042)
		(end 265.0998 -210.397344)
		(width 0.1397)
		(layer "In5.Cu")
		(net "PCIE_TX_CAP_N37")
	)
	(segment
		(start 252.696726 -65.17386)
		(end 252.696726 -66.895726)
		(width 0.1016)
		(layer "In5.Cu")
		(net "PCIE_TX_CAP_N37")
	)
	(segment
		(start 252.966982 -64.9986)
		(end 252.87097 -64.9986)
		(width 0.1016)
		(layer "In5.Cu")
		(net "PCIE_TX_CAP_N37")
	)
	(segment
		(start 263.62406 -190.754254)
		(end 264.83437 -197.61835)
		(width 0.1397)
		(layer "In5.Cu")
		(net "PCIE_TX_CAP_N37")
	)
	(arc
		(start 252.748288 -65.0494)
		(mid 252.710133 -65.106503)
		(end 252.696726 -65.17386)
		(width 0.1016)
		(layer "In5.Cu")
		(net "PCIE_TX_CAP_N37")
	)
	(arc
		(start 252.87097 -64.9986)
		(mid 252.804581 -65.011806)
		(end 252.748288 -65.0494)
		(width 0.1016)
		(layer "In5.Cu")
		(net "PCIE_TX_CAP_N37")
	)
	(arc
		(start 253.1618 -65.2272)
		(mid 253.145226 -65.143787)
		(end 253.098046 -65.073022)
		(width 0.1016)
		(layer "In5.Cu")
		(net "PCIE_TX_CAP_N37")
	)
	(arc
		(start 265.0998 -210.397344)
		(mid 265.153531 -210.667467)
		(end 265.306556 -210.896454)
		(width 0.1397)
		(layer "In5.Cu")
		(net "PCIE_TX_CAP_N37")
	)
	(arc
		(start 253.063756 -65.038732)
		(mid 253.019356 -65.009065)
		(end 252.966982 -64.9986)
		(width 0.1016)
		(layer "In5.Cu")
		(net "PCIE_TX_CAP_N37")
	)
	(arc
		(start 253.099824 -65.499742)
		(mid 253.145688 -65.431102)
		(end 253.1618 -65.350136)
		(width 0.1016)
		(layer "In5.Cu")
		(net "PCIE_TX_CAP_N37")
	)
	(segment
		(start 268.358112 -211.045044)
		(end 268.506448 -210.896454)
		(width 0.136652)
		(layer "F.Cu")
		(net "PCIE_TX_CAP_N36")
	)
	(segment
		(start 268.608048 -211.975954)
		(end 268.304772 -211.672424)
		(width 0.136652)
		(layer "F.Cu")
		(net "PCIE_TX_CAP_N36")
	)
	(segment
		(start 268.246098 -211.5312)
		(end 268.246098 -211.315046)
		(width 0.136652)
		(layer "F.Cu")
		(net "PCIE_TX_CAP_N36")
	)
	(segment
		(start 253.59995 -65.999868)
		(end 254.099822 -66.49974)
		(width 0.136652)
		(layer "F.Cu")
		(net "PCIE_TX_CAP_N36")
	)
	(via
		(at 254.099822 -66.49974)
		(size 0.4572)
		(drill 0.2032)
		(layers "F.Cu" "B.Cu")
		(net "PCIE_TX_CAP_N36")
	)
	(via
		(at 268.506448 -210.896454)
		(size 0.508)
		(drill 0.254)
		(layers "F.Cu" "B.Cu")
		(net "PCIE_TX_CAP_N36")
	)
	(arc
		(start 268.304772 -211.672424)
		(mid 268.261395 -211.607645)
		(end 268.246098 -211.5312)
		(width 0.136652)
		(layer "F.Cu")
		(net "PCIE_TX_CAP_N36")
	)
	(arc
		(start 268.246098 -211.315046)
		(mid 268.27526 -211.168908)
		(end 268.358112 -211.045044)
		(width 0.136652)
		(layer "F.Cu")
		(net "PCIE_TX_CAP_N36")
	)
	(segment
		(start 267.97 -208.28)
		(end 268.265148 -209.954876)
		(width 0.1397)
		(layer "In5.Cu")
		(net "PCIE_TX_CAP_N36")
	)
	(segment
		(start 254.099822 -66.49974)
		(end 254.099822 -66.125852)
		(width 0.1016)
		(layer "In5.Cu")
		(net "PCIE_TX_CAP_N36")
	)
	(segment
		(start 265.366754 -190.613538)
		(end 268.225778 -206.829914)
		(width 0.1397)
		(layer "In5.Cu")
		(net "PCIE_TX_CAP_N36")
	)
	(segment
		(start 270.302228 -162.64001)
		(end 265.366754 -190.613538)
		(width 0.1397)
		(layer "In5.Cu")
		(net "PCIE_TX_CAP_N36")
	)
	(segment
		(start 253.7841 -68.961254)
		(end 270.302228 -162.64001)
		(width 0.1397)
		(layer "In5.Cu")
		(net "PCIE_TX_CAP_N36")
	)
	(segment
		(start 268.265148 -209.954876)
		(end 268.265148 -210.5152)
		(width 0.1397)
		(layer "In5.Cu")
		(net "PCIE_TX_CAP_N36")
	)
	(segment
		(start 253.7841 -66.9163)
		(end 253.7841 -68.961254)
		(width 0.1397)
		(layer "In5.Cu")
		(net "PCIE_TX_CAP_N36")
	)
	(segment
		(start 268.364208 -210.75396)
		(end 268.506448 -210.896454)
		(width 0.1397)
		(layer "In5.Cu")
		(net "PCIE_TX_CAP_N36")
	)
	(segment
		(start 268.225778 -206.829914)
		(end 267.97 -208.28)
		(width 0.1397)
		(layer "In5.Cu")
		(net "PCIE_TX_CAP_N36")
	)
	(segment
		(start 253.696724 -66.173858)
		(end 253.696724 -66.828924)
		(width 0.1016)
		(layer "In5.Cu")
		(net "PCIE_TX_CAP_N36")
	)
	(segment
		(start 253.96698 -65.998598)
		(end 253.870968 -65.998598)
		(width 0.1016)
		(layer "In5.Cu")
		(net "PCIE_TX_CAP_N36")
	)
	(segment
		(start 253.696724 -66.828924)
		(end 253.7841 -66.9163)
		(width 0.1016)
		(layer "In5.Cu")
		(net "PCIE_TX_CAP_N36")
	)
	(arc
		(start 253.748286 -66.049398)
		(mid 253.710131 -66.106501)
		(end 253.696724 -66.173858)
		(width 0.1016)
		(layer "In5.Cu")
		(net "PCIE_TX_CAP_N36")
	)
	(arc
		(start 254.063754 -66.03873)
		(mid 254.019354 -66.009063)
		(end 253.96698 -65.998598)
		(width 0.1016)
		(layer "In5.Cu")
		(net "PCIE_TX_CAP_N36")
	)
	(arc
		(start 254.099822 -66.125852)
		(mid 254.090445 -66.078709)
		(end 254.063754 -66.03873)
		(width 0.1016)
		(layer "In5.Cu")
		(net "PCIE_TX_CAP_N36")
	)
	(arc
		(start 268.265148 -210.5152)
		(mid 268.290946 -210.644424)
		(end 268.364208 -210.75396)
		(width 0.1397)
		(layer "In5.Cu")
		(net "PCIE_TX_CAP_N36")
	)
	(arc
		(start 253.870968 -65.998598)
		(mid 253.804579 -66.011804)
		(end 253.748286 -66.049398)
		(width 0.1016)
		(layer "In5.Cu")
		(net "PCIE_TX_CAP_N36")
	)
	(segment
		(start 271.540732 -211.062316)
		(end 271.706594 -210.896454)
		(width 0.136652)
		(layer "F.Cu")
		(net "PCIE_TX_CAP_N35")
	)
	(segment
		(start 271.808194 -211.975954)
		(end 271.504918 -211.672424)
		(width 0.136652)
		(layer "F.Cu")
		(net "PCIE_TX_CAP_N35")
	)
	(segment
		(start 254.599948 -64.99987)
		(end 255.09982 -65.499742)
		(width 0.136652)
		(layer "F.Cu")
		(net "PCIE_TX_CAP_N35")
	)
	(segment
		(start 271.446244 -211.5312)
		(end 271.446244 -211.290408)
		(width 0.136652)
		(layer "F.Cu")
		(net "PCIE_TX_CAP_N35")
	)
	(via
		(at 271.706594 -210.896454)
		(size 0.508)
		(drill 0.254)
		(layers "F.Cu" "B.Cu")
		(net "PCIE_TX_CAP_N35")
	)
	(via
		(at 255.09982 -65.499742)
		(size 0.4572)
		(drill 0.2032)
		(layers "F.Cu" "B.Cu")
		(net "PCIE_TX_CAP_N35")
	)
	(arc
		(start 271.504918 -211.672424)
		(mid 271.461541 -211.607645)
		(end 271.446244 -211.5312)
		(width 0.136652)
		(layer "F.Cu")
		(net "PCIE_TX_CAP_N35")
	)
	(arc
		(start 271.446244 -211.290408)
		(mid 271.470799 -211.166962)
		(end 271.540732 -211.062316)
		(width 0.136652)
		(layer "F.Cu")
		(net "PCIE_TX_CAP_N35")
	)
	(segment
		(start 269.811754 -199.412098)
		(end 271.492726 -208.948528)
		(width 0.1397)
		(layer "In5.Cu")
		(net "PCIE_TX_CAP_N35")
	)
	(segment
		(start 255.071372 -65.046352)
		(end 255.063752 -65.038732)
		(width 0.1016)
		(layer "In5.Cu")
		(net "PCIE_TX_CAP_N35")
	)
	(segment
		(start 271.492726 -208.948528)
		(end 271.492726 -210.38185)
		(width 0.1397)
		(layer "In5.Cu")
		(net "PCIE_TX_CAP_N35")
	)
	(segment
		(start 254.762 -66.8782)
		(end 254.762 -67.89039)
		(width 0.1397)
		(layer "In5.Cu")
		(net "PCIE_TX_CAP_N35")
	)
	(segment
		(start 255.12522 -65.474342)
		(end 255.12522 -65.1764)
		(width 0.1016)
		(layer "In5.Cu")
		(net "PCIE_TX_CAP_N35")
	)
	(segment
		(start 254.696722 -66.812922)
		(end 254.762 -66.8782)
		(width 0.1016)
		(layer "In5.Cu")
		(net "PCIE_TX_CAP_N35")
	)
	(segment
		(start 254.966978 -64.9986)
		(end 254.870966 -64.9986)
		(width 0.1016)
		(layer "In5.Cu")
		(net "PCIE_TX_CAP_N35")
	)
	(segment
		(start 254.762 -67.89039)
		(end 273.882104 -176.328832)
		(width 0.1397)
		(layer "In5.Cu")
		(net "PCIE_TX_CAP_N35")
	)
	(segment
		(start 254.696722 -65.17386)
		(end 254.696722 -66.812922)
		(width 0.1016)
		(layer "In5.Cu")
		(net "PCIE_TX_CAP_N35")
	)
	(segment
		(start 273.882104 -176.328832)
		(end 269.811754 -199.412098)
		(width 0.1397)
		(layer "In5.Cu")
		(net "PCIE_TX_CAP_N35")
	)
	(segment
		(start 255.09982 -65.499742)
		(end 255.12522 -65.474342)
		(width 0.1016)
		(layer "In5.Cu")
		(net "PCIE_TX_CAP_N35")
	)
	(segment
		(start 271.705324 -210.895184)
		(end 271.706594 -210.896454)
		(width 0.1397)
		(layer "In5.Cu")
		(net "PCIE_TX_CAP_N35")
	)
	(arc
		(start 254.870966 -64.9986)
		(mid 254.804577 -65.011806)
		(end 254.748284 -65.0494)
		(width 0.1016)
		(layer "In5.Cu")
		(net "PCIE_TX_CAP_N35")
	)
	(arc
		(start 255.12522 -65.1764)
		(mid 255.111222 -65.106026)
		(end 255.071372 -65.046352)
		(width 0.1016)
		(layer "In5.Cu")
		(net "PCIE_TX_CAP_N35")
	)
	(arc
		(start 271.492726 -210.38185)
		(mid 271.547984 -210.659652)
		(end 271.705324 -210.895184)
		(width 0.1397)
		(layer "In5.Cu")
		(net "PCIE_TX_CAP_N35")
	)
	(arc
		(start 255.063752 -65.038732)
		(mid 255.019352 -65.009065)
		(end 254.966978 -64.9986)
		(width 0.1016)
		(layer "In5.Cu")
		(net "PCIE_TX_CAP_N35")
	)
	(arc
		(start 254.748284 -65.0494)
		(mid 254.710129 -65.106503)
		(end 254.696722 -65.17386)
		(width 0.1016)
		(layer "In5.Cu")
		(net "PCIE_TX_CAP_N35")
	)
	(segment
		(start 275.008086 -211.975954)
		(end 274.70481 -211.672424)
		(width 0.136652)
		(layer "F.Cu")
		(net "PCIE_TX_CAP_N34")
	)
	(segment
		(start 255.599946 -65.999868)
		(end 256.099818 -66.49974)
		(width 0.136652)
		(layer "F.Cu")
		(net "PCIE_TX_CAP_N34")
	)
	(segment
		(start 274.730972 -211.071714)
		(end 274.906486 -210.896454)
		(width 0.136652)
		(layer "F.Cu")
		(net "PCIE_TX_CAP_N34")
	)
	(segment
		(start 274.646136 -211.5312)
		(end 274.646136 -211.276946)
		(width 0.136652)
		(layer "F.Cu")
		(net "PCIE_TX_CAP_N34")
	)
	(via
		(at 256.099818 -66.49974)
		(size 0.4572)
		(drill 0.2032)
		(layers "F.Cu" "B.Cu")
		(net "PCIE_TX_CAP_N34")
	)
	(via
		(at 274.906486 -210.896454)
		(size 0.508)
		(drill 0.254)
		(layers "F.Cu" "B.Cu")
		(net "PCIE_TX_CAP_N34")
	)
	(arc
		(start 274.70481 -211.672424)
		(mid 274.661433 -211.607645)
		(end 274.646136 -211.5312)
		(width 0.136652)
		(layer "F.Cu")
		(net "PCIE_TX_CAP_N34")
	)
	(arc
		(start 274.646136 -211.276946)
		(mid 274.668133 -211.165888)
		(end 274.730972 -211.071714)
		(width 0.136652)
		(layer "F.Cu")
		(net "PCIE_TX_CAP_N34")
	)
	(segment
		(start 256.099818 -66.49974)
		(end 256.125218 -66.47434)
		(width 0.1016)
		(layer "In5.Cu")
		(net "PCIE_TX_CAP_N34")
	)
	(segment
		(start 255.69672 -66.173858)
		(end 255.69672 -66.87312)
		(width 0.1016)
		(layer "In5.Cu")
		(net "PCIE_TX_CAP_N34")
	)
	(segment
		(start 280.133298 -177.42027)
		(end 279.847548 -178.652932)
		(width 0.1397)
		(layer "In5.Cu")
		(net "PCIE_TX_CAP_N34")
	)
	(segment
		(start 256.125218 -66.47434)
		(end 256.125218 -66.176398)
		(width 0.1016)
		(layer "In5.Cu")
		(net "PCIE_TX_CAP_N34")
	)
	(segment
		(start 255.7526 -66.929)
		(end 255.7526 -68.35013)
		(width 0.1397)
		(layer "In5.Cu")
		(net "PCIE_TX_CAP_N34")
	)
	(segment
		(start 274.665186 -205.123288)
		(end 274.665186 -210.313778)
		(width 0.1397)
		(layer "In5.Cu")
		(net "PCIE_TX_CAP_N34")
	)
	(segment
		(start 256.07137 -66.04635)
		(end 256.06375 -66.03873)
		(width 0.1016)
		(layer "In5.Cu")
		(net "PCIE_TX_CAP_N34")
	)
	(segment
		(start 279.847548 -178.652932)
		(end 274.83181 -204.179424)
		(width 0.1397)
		(layer "In5.Cu")
		(net "PCIE_TX_CAP_N34")
	)
	(segment
		(start 255.959864 -69.52615)
		(end 280.133298 -177.42027)
		(width 0.1397)
		(layer "In5.Cu")
		(net "PCIE_TX_CAP_N34")
	)
	(segment
		(start 255.966976 -65.998598)
		(end 255.870964 -65.998598)
		(width 0.1016)
		(layer "In5.Cu")
		(net "PCIE_TX_CAP_N34")
	)
	(segment
		(start 255.69672 -66.87312)
		(end 255.7526 -66.929)
		(width 0.1016)
		(layer "In5.Cu")
		(net "PCIE_TX_CAP_N34")
	)
	(segment
		(start 274.83181 -204.179424)
		(end 274.665186 -205.123288)
		(width 0.1397)
		(layer "In5.Cu")
		(net "PCIE_TX_CAP_N34")
	)
	(segment
		(start 255.7526 -68.35013)
		(end 255.959864 -69.52615)
		(width 0.1397)
		(layer "In5.Cu")
		(net "PCIE_TX_CAP_N34")
	)
	(arc
		(start 255.748282 -66.049398)
		(mid 255.710127 -66.106501)
		(end 255.69672 -66.173858)
		(width 0.1016)
		(layer "In5.Cu")
		(net "PCIE_TX_CAP_N34")
	)
	(arc
		(start 256.06375 -66.03873)
		(mid 256.01935 -66.009063)
		(end 255.966976 -65.998598)
		(width 0.1016)
		(layer "In5.Cu")
		(net "PCIE_TX_CAP_N34")
	)
	(arc
		(start 255.870964 -65.998598)
		(mid 255.804575 -66.011804)
		(end 255.748282 -66.049398)
		(width 0.1016)
		(layer "In5.Cu")
		(net "PCIE_TX_CAP_N34")
	)
	(arc
		(start 256.125218 -66.176398)
		(mid 256.11122 -66.106024)
		(end 256.07137 -66.04635)
		(width 0.1016)
		(layer "In5.Cu")
		(net "PCIE_TX_CAP_N34")
	)
	(arc
		(start 274.665186 -210.313778)
		(mid 274.727907 -210.6291)
		(end 274.906486 -210.896454)
		(width 0.1397)
		(layer "In5.Cu")
		(net "PCIE_TX_CAP_N34")
	)
	(segment
		(start 277.846028 -211.5312)
		(end 277.846028 -211.276946)
		(width 0.136652)
		(layer "F.Cu")
		(net "PCIE_TX_CAP_N33")
	)
	(segment
		(start 278.207978 -211.975954)
		(end 277.904702 -211.672424)
		(width 0.136652)
		(layer "F.Cu")
		(net "PCIE_TX_CAP_N33")
	)
	(segment
		(start 277.930864 -211.071714)
		(end 278.106378 -210.896454)
		(width 0.136652)
		(layer "F.Cu")
		(net "PCIE_TX_CAP_N33")
	)
	(segment
		(start 256.599944 -64.99987)
		(end 257.099816 -65.499742)
		(width 0.136652)
		(layer "F.Cu")
		(net "PCIE_TX_CAP_N33")
	)
	(via
		(at 257.099816 -65.499742)
		(size 0.4572)
		(drill 0.2032)
		(layers "F.Cu" "B.Cu")
		(net "PCIE_TX_CAP_N33")
	)
	(via
		(at 278.106378 -210.896454)
		(size 0.508)
		(drill 0.254)
		(layers "F.Cu" "B.Cu")
		(net "PCIE_TX_CAP_N33")
	)
	(arc
		(start 277.846028 -211.276946)
		(mid 277.868025 -211.165888)
		(end 277.930864 -211.071714)
		(width 0.136652)
		(layer "F.Cu")
		(net "PCIE_TX_CAP_N33")
	)
	(arc
		(start 277.904702 -211.672424)
		(mid 277.861325 -211.607645)
		(end 277.846028 -211.5312)
		(width 0.136652)
		(layer "F.Cu")
		(net "PCIE_TX_CAP_N33")
	)
	(segment
		(start 257.036316 -69.553328)
		(end 264.243058 -79.845916)
		(width 0.1397)
		(layer "In5.Cu")
		(net "PCIE_TX_CAP_N33")
	)
	(segment
		(start 277.865078 -209.591148)
		(end 277.865078 -210.313778)
		(width 0.1397)
		(layer "In5.Cu")
		(net "PCIE_TX_CAP_N33")
	)
	(segment
		(start 256.696718 -65.17386)
		(end 256.696718 -66.907918)
		(width 0.1016)
		(layer "In5.Cu")
		(net "PCIE_TX_CAP_N33")
	)
	(segment
		(start 278.34844 -206.851504)
		(end 277.865078 -209.591148)
		(width 0.1397)
		(layer "In5.Cu")
		(net "PCIE_TX_CAP_N33")
	)
	(segment
		(start 256.814066 -68.293234)
		(end 256.885186 -68.696586)
		(width 0.1397)
		(layer "In5.Cu")
		(net "PCIE_TX_CAP_N33")
	)
	(segment
		(start 264.243058 -79.845916)
		(end 272.877534 -128.814322)
		(width 0.1397)
		(layer "In5.Cu")
		(net "PCIE_TX_CAP_N33")
	)
	(segment
		(start 272.877534 -128.814322)
		(end 281.509216 -177.767234)
		(width 0.1397)
		(layer "In5.Cu")
		(net "PCIE_TX_CAP_N33")
	)
	(segment
		(start 257.071368 -65.046352)
		(end 257.063748 -65.038732)
		(width 0.1016)
		(layer "In5.Cu")
		(net "PCIE_TX_CAP_N33")
	)
	(segment
		(start 281.509216 -177.767234)
		(end 277.364698 -201.272394)
		(width 0.1397)
		(layer "In5.Cu")
		(net "PCIE_TX_CAP_N33")
	)
	(segment
		(start 257.125216 -65.474342)
		(end 257.125216 -65.1764)
		(width 0.1016)
		(layer "In5.Cu")
		(net "PCIE_TX_CAP_N33")
	)
	(segment
		(start 256.696718 -66.907918)
		(end 256.7432 -66.9544)
		(width 0.1016)
		(layer "In5.Cu")
		(net "PCIE_TX_CAP_N33")
	)
	(segment
		(start 256.885186 -68.696586)
		(end 257.036316 -69.553328)
		(width 0.1397)
		(layer "In5.Cu")
		(net "PCIE_TX_CAP_N33")
	)
	(segment
		(start 256.7432 -67.890136)
		(end 256.814066 -68.293234)
		(width 0.1397)
		(layer "In5.Cu")
		(net "PCIE_TX_CAP_N33")
	)
	(segment
		(start 256.7432 -66.9544)
		(end 256.7432 -67.890136)
		(width 0.1397)
		(layer "In5.Cu")
		(net "PCIE_TX_CAP_N33")
	)
	(segment
		(start 277.364698 -201.272394)
		(end 278.34844 -206.851504)
		(width 0.1397)
		(layer "In5.Cu")
		(net "PCIE_TX_CAP_N33")
	)
	(segment
		(start 257.099816 -65.499742)
		(end 257.125216 -65.474342)
		(width 0.1016)
		(layer "In5.Cu")
		(net "PCIE_TX_CAP_N33")
	)
	(segment
		(start 256.966974 -64.9986)
		(end 256.870962 -64.9986)
		(width 0.1016)
		(layer "In5.Cu")
		(net "PCIE_TX_CAP_N33")
	)
	(arc
		(start 257.063748 -65.038732)
		(mid 257.019348 -65.009065)
		(end 256.966974 -64.9986)
		(width 0.1016)
		(layer "In5.Cu")
		(net "PCIE_TX_CAP_N33")
	)
	(arc
		(start 256.74828 -65.0494)
		(mid 256.710125 -65.106503)
		(end 256.696718 -65.17386)
		(width 0.1016)
		(layer "In5.Cu")
		(net "PCIE_TX_CAP_N33")
	)
	(arc
		(start 256.870962 -64.9986)
		(mid 256.804573 -65.011806)
		(end 256.74828 -65.0494)
		(width 0.1016)
		(layer "In5.Cu")
		(net "PCIE_TX_CAP_N33")
	)
	(arc
		(start 277.865078 -210.313778)
		(mid 277.927799 -210.6291)
		(end 278.106378 -210.896454)
		(width 0.1397)
		(layer "In5.Cu")
		(net "PCIE_TX_CAP_N33")
	)
	(arc
		(start 257.125216 -65.1764)
		(mid 257.111218 -65.106026)
		(end 257.071368 -65.046352)
		(width 0.1016)
		(layer "In5.Cu")
		(net "PCIE_TX_CAP_N33")
	)
	(segment
		(start 281.046174 -211.5312)
		(end 281.046174 -211.276946)
		(width 0.136652)
		(layer "F.Cu")
		(net "PCIE_TX_CAP_N32")
	)
	(segment
		(start 281.13101 -211.071714)
		(end 281.306524 -210.896454)
		(width 0.136652)
		(layer "F.Cu")
		(net "PCIE_TX_CAP_N32")
	)
	(segment
		(start 281.408124 -211.975954)
		(end 281.104848 -211.672424)
		(width 0.136652)
		(layer "F.Cu")
		(net "PCIE_TX_CAP_N32")
	)
	(segment
		(start 257.599942 -65.999868)
		(end 258.099814 -66.49974)
		(width 0.136652)
		(layer "F.Cu")
		(net "PCIE_TX_CAP_N32")
	)
	(via
		(at 258.099814 -66.49974)
		(size 0.4572)
		(drill 0.2032)
		(layers "F.Cu" "B.Cu")
		(net "PCIE_TX_CAP_N32")
	)
	(via
		(at 281.306524 -210.896454)
		(size 0.508)
		(drill 0.254)
		(layers "F.Cu" "B.Cu")
		(net "PCIE_TX_CAP_N32")
	)
	(arc
		(start 281.104848 -211.672424)
		(mid 281.061471 -211.607645)
		(end 281.046174 -211.5312)
		(width 0.136652)
		(layer "F.Cu")
		(net "PCIE_TX_CAP_N32")
	)
	(arc
		(start 281.046174 -211.276946)
		(mid 281.068171 -211.165888)
		(end 281.13101 -211.071714)
		(width 0.136652)
		(layer "F.Cu")
		(net "PCIE_TX_CAP_N32")
	)
	(segment
		(start 257.966972 -65.998598)
		(end 257.87096 -65.998598)
		(width 0.1016)
		(layer "In5.Cu")
		(net "PCIE_TX_CAP_N32")
	)
	(segment
		(start 257.7592 -66.929)
		(end 257.7592 -67.89039)
		(width 0.1397)
		(layer "In5.Cu")
		(net "PCIE_TX_CAP_N32")
	)
	(segment
		(start 258.099814 -66.49974)
		(end 258.125214 -66.47434)
		(width 0.1016)
		(layer "In5.Cu")
		(net "PCIE_TX_CAP_N32")
	)
	(segment
		(start 257.696716 -66.173858)
		(end 257.696716 -66.866516)
		(width 0.1016)
		(layer "In5.Cu")
		(net "PCIE_TX_CAP_N32")
	)
	(segment
		(start 283.041344 -177.268886)
		(end 279.42794 -197.762114)
		(width 0.1397)
		(layer "In5.Cu")
		(net "PCIE_TX_CAP_N32")
	)
	(segment
		(start 281.065224 -210.10245)
		(end 281.065224 -210.313778)
		(width 0.1397)
		(layer "In5.Cu")
		(net "PCIE_TX_CAP_N32")
	)
	(segment
		(start 257.696716 -66.866516)
		(end 257.7592 -66.929)
		(width 0.1016)
		(layer "In5.Cu")
		(net "PCIE_TX_CAP_N32")
	)
	(segment
		(start 258.071366 -66.04635)
		(end 258.063746 -66.03873)
		(width 0.1016)
		(layer "In5.Cu")
		(net "PCIE_TX_CAP_N32")
	)
	(segment
		(start 265.933174 -80.244696)
		(end 283.041344 -177.268886)
		(width 0.1397)
		(layer "In5.Cu")
		(net "PCIE_TX_CAP_N32")
	)
	(segment
		(start 281.334718 -208.574894)
		(end 281.065224 -210.10245)
		(width 0.1397)
		(layer "In5.Cu")
		(net "PCIE_TX_CAP_N32")
	)
	(segment
		(start 258.125214 -66.47434)
		(end 258.125214 -66.176398)
		(width 0.1016)
		(layer "In5.Cu")
		(net "PCIE_TX_CAP_N32")
	)
	(segment
		(start 257.7592 -67.89039)
		(end 257.919474 -68.79971)
		(width 0.1397)
		(layer "In5.Cu")
		(net "PCIE_TX_CAP_N32")
	)
	(segment
		(start 257.919474 -68.79971)
		(end 265.933174 -80.244696)
		(width 0.1397)
		(layer "In5.Cu")
		(net "PCIE_TX_CAP_N32")
	)
	(segment
		(start 279.42794 -197.762114)
		(end 281.334718 -208.574894)
		(width 0.1397)
		(layer "In5.Cu")
		(net "PCIE_TX_CAP_N32")
	)
	(arc
		(start 258.063746 -66.03873)
		(mid 258.019346 -66.009063)
		(end 257.966972 -65.998598)
		(width 0.1016)
		(layer "In5.Cu")
		(net "PCIE_TX_CAP_N32")
	)
	(arc
		(start 258.125214 -66.176398)
		(mid 258.111216 -66.106024)
		(end 258.071366 -66.04635)
		(width 0.1016)
		(layer "In5.Cu")
		(net "PCIE_TX_CAP_N32")
	)
	(arc
		(start 257.748278 -66.049398)
		(mid 257.710123 -66.106501)
		(end 257.696716 -66.173858)
		(width 0.1016)
		(layer "In5.Cu")
		(net "PCIE_TX_CAP_N32")
	)
	(arc
		(start 257.87096 -65.998598)
		(mid 257.804571 -66.011804)
		(end 257.748278 -66.049398)
		(width 0.1016)
		(layer "In5.Cu")
		(net "PCIE_TX_CAP_N32")
	)
	(arc
		(start 281.065224 -210.313778)
		(mid 281.127945 -210.6291)
		(end 281.306524 -210.896454)
		(width 0.1397)
		(layer "In5.Cu")
		(net "PCIE_TX_CAP_N32")
	)
	(segment
		(start 257.599942 -58.999882)
		(end 258.099814 -59.499754)
		(width 0.136652)
		(layer "F.Cu")
		(net "PCIE_TX_CAP_N31")
	)
	(segment
		(start 284.246066 -211.5312)
		(end 284.246066 -211.276946)
		(width 0.136652)
		(layer "F.Cu")
		(net "PCIE_TX_CAP_N31")
	)
	(segment
		(start 284.330902 -211.071714)
		(end 284.506416 -210.896454)
		(width 0.136652)
		(layer "F.Cu")
		(net "PCIE_TX_CAP_N31")
	)
	(segment
		(start 284.608016 -211.975954)
		(end 284.30474 -211.672424)
		(width 0.136652)
		(layer "F.Cu")
		(net "PCIE_TX_CAP_N31")
	)
	(via
		(at 258.099814 -59.499754)
		(size 0.4572)
		(drill 0.2032)
		(layers "F.Cu" "B.Cu")
		(net "PCIE_TX_CAP_N31")
	)
	(via
		(at 284.506416 -210.896454)
		(size 0.508)
		(drill 0.254)
		(layers "F.Cu" "B.Cu")
		(net "PCIE_TX_CAP_N31")
	)
	(arc
		(start 284.30474 -211.672424)
		(mid 284.261363 -211.607645)
		(end 284.246066 -211.5312)
		(width 0.136652)
		(layer "F.Cu")
		(net "PCIE_TX_CAP_N31")
	)
	(arc
		(start 284.246066 -211.276946)
		(mid 284.268063 -211.165888)
		(end 284.330902 -211.071714)
		(width 0.136652)
		(layer "F.Cu")
		(net "PCIE_TX_CAP_N31")
	)
	(segment
		(start 263.531604 -62.422024)
		(end 266.065 -66.04)
		(width 0.1397)
		(layer "In5.Cu")
		(net "PCIE_TX_CAP_N31")
	)
	(segment
		(start 283.531056 -197.94601)
		(end 284.48 -203.327)
		(width 0.1397)
		(layer "In5.Cu")
		(net "PCIE_TX_CAP_N31")
	)
	(segment
		(start 286.427418 -181.520592)
		(end 283.531056 -197.94601)
		(width 0.1397)
		(layer "In5.Cu")
		(net "PCIE_TX_CAP_N31")
	)
	(segment
		(start 257.7846 -59.560714)
		(end 257.762502 -59.582558)
		(width 0.1016)
		(layer "In5.Cu")
		(net "PCIE_TX_CAP_N31")
	)
	(segment
		(start 284.265116 -209.774282)
		(end 284.265116 -210.4644)
		(width 0.1397)
		(layer "In5.Cu")
		(net "PCIE_TX_CAP_N31")
	)
	(segment
		(start 284.48 -203.327)
		(end 283.804106 -207.159606)
		(width 0.1397)
		(layer "In5.Cu")
		(net "PCIE_TX_CAP_N31")
	)
	(segment
		(start 266.065 -66.04)
		(end 286.427418 -181.520592)
		(width 0.1397)
		(layer "In5.Cu")
		(net "PCIE_TX_CAP_N31")
	)
	(segment
		(start 257.722624 -59.666378)
		(end 257.722624 -59.682634)
		(width 0.1016)
		(layer "In5.Cu")
		(net "PCIE_TX_CAP_N31")
	)
	(segment
		(start 283.804106 -207.159606)
		(end 284.265116 -209.774282)
		(width 0.1397)
		(layer "In5.Cu")
		(net "PCIE_TX_CAP_N31")
	)
	(segment
		(start 260.11124 -60.026804)
		(end 263.531604 -62.422024)
		(width 0.1397)
		(layer "In5.Cu")
		(net "PCIE_TX_CAP_N31")
	)
	(segment
		(start 258.070096 -59.888628)
		(end 259.777738 -59.888628)
		(width 0.1016)
		(layer "In5.Cu")
		(net "PCIE_TX_CAP_N31")
	)
	(segment
		(start 258.099814 -59.499754)
		(end 257.931666 -59.499754)
		(width 0.1016)
		(layer "In5.Cu")
		(net "PCIE_TX_CAP_N31")
	)
	(segment
		(start 284.39999 -210.790028)
		(end 284.506416 -210.896454)
		(width 0.1397)
		(layer "In5.Cu")
		(net "PCIE_TX_CAP_N31")
	)
	(arc
		(start 257.722624 -59.682634)
		(mid 257.722615 -59.684412)
		(end 257.722624 -59.68619)
		(width 0.1016)
		(layer "In5.Cu")
		(net "PCIE_TX_CAP_N31")
	)
	(arc
		(start 257.735832 -59.619134)
		(mid 257.728755 -59.636639)
		(end 257.724148 -59.654948)
		(width 0.1016)
		(layer "In5.Cu")
		(net "PCIE_TX_CAP_N31")
	)
	(arc
		(start 257.931666 -59.499754)
		(mid 257.852058 -59.515589)
		(end 257.7846 -59.560714)
		(width 0.1016)
		(layer "In5.Cu")
		(net "PCIE_TX_CAP_N31")
	)
	(arc
		(start 257.74015 -59.611006)
		(mid 257.737931 -59.614782)
		(end 257.735832 -59.618626)
		(width 0.1016)
		(layer "In5.Cu")
		(net "PCIE_TX_CAP_N31")
	)
	(arc
		(start 284.265116 -210.4644)
		(mid 284.30017 -210.640626)
		(end 284.39999 -210.790028)
		(width 0.1397)
		(layer "In5.Cu")
		(net "PCIE_TX_CAP_N31")
	)
	(arc
		(start 257.735832 -59.618626)
		(mid 257.735832 -59.61888)
		(end 257.735832 -59.619134)
		(width 0.1016)
		(layer "In5.Cu")
		(net "PCIE_TX_CAP_N31")
	)
	(arc
		(start 257.722624 -59.68619)
		(mid 257.723609 -59.701502)
		(end 257.725926 -59.71667)
		(width 0.1016)
		(layer "In5.Cu")
		(net "PCIE_TX_CAP_N31")
	)
	(arc
		(start 257.724148 -59.654948)
		(mid 257.723265 -59.660647)
		(end 257.722624 -59.666378)
		(width 0.1016)
		(layer "In5.Cu")
		(net "PCIE_TX_CAP_N31")
	)
	(arc
		(start 257.725926 -59.71667)
		(mid 257.764281 -59.795944)
		(end 257.836416 -59.846464)
		(width 0.1016)
		(layer "In5.Cu")
		(net "PCIE_TX_CAP_N31")
	)
	(arc
		(start 257.762502 -59.582558)
		(mid 257.751139 -59.595243)
		(end 257.74142 -59.609228)
		(width 0.1016)
		(layer "In5.Cu")
		(net "PCIE_TX_CAP_N31")
	)
	(arc
		(start 257.74142 -59.609228)
		(mid 257.740782 -59.610115)
		(end 257.74015 -59.611006)
		(width 0.1016)
		(layer "In5.Cu")
		(net "PCIE_TX_CAP_N31")
	)
	(arc
		(start 259.777738 -59.888628)
		(mid 259.958241 -59.924532)
		(end 260.11124 -60.026804)
		(width 0.1016)
		(layer "In5.Cu")
		(net "PCIE_TX_CAP_N31")
	)
	(arc
		(start 257.836416 -59.846464)
		(mid 257.951369 -59.878007)
		(end 258.070096 -59.888628)
		(width 0.1016)
		(layer "In5.Cu")
		(net "PCIE_TX_CAP_N31")
	)
	(segment
		(start 287.808162 -211.975954)
		(end 287.504886 -211.672424)
		(width 0.136652)
		(layer "F.Cu")
		(net "PCIE_TX_CAP_N30")
	)
	(segment
		(start 287.446212 -211.5312)
		(end 287.446212 -211.299298)
		(width 0.136652)
		(layer "F.Cu")
		(net "PCIE_TX_CAP_N30")
	)
	(segment
		(start 287.539684 -211.063078)
		(end 287.706562 -210.896454)
		(width 0.136652)
		(layer "F.Cu")
		(net "PCIE_TX_CAP_N30")
	)
	(segment
		(start 258.59994 -57.999884)
		(end 259.099812 -58.499756)
		(width 0.136652)
		(layer "F.Cu")
		(net "PCIE_TX_CAP_N30")
	)
	(via
		(at 287.706562 -210.896454)
		(size 0.508)
		(drill 0.254)
		(layers "F.Cu" "B.Cu")
		(net "PCIE_TX_CAP_N30")
	)
	(via
		(at 259.099812 -58.499756)
		(size 0.4572)
		(drill 0.2032)
		(layers "F.Cu" "B.Cu")
		(net "PCIE_TX_CAP_N30")
	)
	(arc
		(start 287.504886 -211.672424)
		(mid 287.461509 -211.607645)
		(end 287.446212 -211.5312)
		(width 0.136652)
		(layer "F.Cu")
		(net "PCIE_TX_CAP_N30")
	)
	(arc
		(start 287.446212 -211.299298)
		(mid 287.446231 -211.294218)
		(end 287.446212 -211.289138)
		(width 0.136652)
		(layer "F.Cu")
		(net "PCIE_TX_CAP_N30")
	)
	(arc
		(start 287.446212 -211.289138)
		(mid 287.470452 -211.166805)
		(end 287.539684 -211.063078)
		(width 0.136652)
		(layer "F.Cu")
		(net "PCIE_TX_CAP_N30")
	)
	(segment
		(start 261.86638 -58.968386)
		(end 262.976106 -59.745626)
		(width 0.1397)
		(layer "In5.Cu")
		(net "PCIE_TX_CAP_N30")
	)
	(segment
		(start 288.571686 -202.176126)
		(end 287.465262 -208.45018)
		(width 0.1397)
		(layer "In5.Cu")
		(net "PCIE_TX_CAP_N30")
	)
	(segment
		(start 264.07364 -60.513976)
		(end 267.64996 -65.621662)
		(width 0.1397)
		(layer "In5.Cu")
		(net "PCIE_TX_CAP_N30")
	)
	(segment
		(start 287.465262 -208.45018)
		(end 287.465262 -210.313778)
		(width 0.1397)
		(layer "In5.Cu")
		(net "PCIE_TX_CAP_N30")
	)
	(segment
		(start 262.976106 -59.745626)
		(end 264.07364 -60.513976)
		(width 0.1397)
		(layer "In5.Cu")
		(net "PCIE_TX_CAP_N30")
	)
	(segment
		(start 259.24002 -59.101482)
		(end 259.491988 -59.101482)
		(width 0.1016)
		(layer "In5.Cu")
		(net "PCIE_TX_CAP_N30")
	)
	(segment
		(start 260.014974 -58.8518)
		(end 261.204456 -58.8518)
		(width 0.1397)
		(layer "In5.Cu")
		(net "PCIE_TX_CAP_N30")
	)
	(segment
		(start 258.99364 -58.983626)
		(end 259.020564 -59.01055)
		(width 0.1016)
		(layer "In5.Cu")
		(net "PCIE_TX_CAP_N30")
	)
	(segment
		(start 287.996122 -181.02961)
		(end 286.419798 -189.970664)
		(width 0.1397)
		(layer "In5.Cu")
		(net "PCIE_TX_CAP_N30")
	)
	(segment
		(start 259.099812 -58.499756)
		(end 259.035296 -58.564526)
		(width 0.1016)
		(layer "In5.Cu")
		(net "PCIE_TX_CAP_N30")
	)
	(segment
		(start 261.204456 -58.8518)
		(end 261.86638 -58.968386)
		(width 0.1397)
		(layer "In5.Cu")
		(net "PCIE_TX_CAP_N30")
	)
	(segment
		(start 277.824438 -123.333256)
		(end 287.996122 -181.02961)
		(width 0.1397)
		(layer "In5.Cu")
		(net "PCIE_TX_CAP_N30")
	)
	(segment
		(start 259.653786 -59.034426)
		(end 259.747258 -58.940954)
		(width 0.1016)
		(layer "In5.Cu")
		(net "PCIE_TX_CAP_N30")
	)
	(segment
		(start 286.419798 -189.970664)
		(end 288.571686 -202.176126)
		(width 0.1397)
		(layer "In5.Cu")
		(net "PCIE_TX_CAP_N30")
	)
	(segment
		(start 267.64996 -65.621662)
		(end 277.824438 -123.333256)
		(width 0.1397)
		(layer "In5.Cu")
		(net "PCIE_TX_CAP_N30")
	)
	(arc
		(start 259.035296 -58.564526)
		(mid 258.955633 -58.683611)
		(end 258.9276 -58.824114)
		(width 0.1016)
		(layer "In5.Cu")
		(net "PCIE_TX_CAP_N30")
	)
	(arc
		(start 259.747258 -58.940954)
		(mid 259.873871 -58.874633)
		(end 260.014974 -58.8518)
		(width 0.1397)
		(layer "In5.Cu")
		(net "PCIE_TX_CAP_N30")
	)
	(arc
		(start 259.491988 -59.101482)
		(mid 259.579567 -59.084062)
		(end 259.653786 -59.034426)
		(width 0.1016)
		(layer "In5.Cu")
		(net "PCIE_TX_CAP_N30")
	)
	(arc
		(start 258.9276 -58.824114)
		(mid 258.944769 -58.910429)
		(end 258.99364 -58.983626)
		(width 0.1016)
		(layer "In5.Cu")
		(net "PCIE_TX_CAP_N30")
	)
	(arc
		(start 259.020564 -59.01055)
		(mid 259.121265 -59.077803)
		(end 259.24002 -59.101482)
		(width 0.1016)
		(layer "In5.Cu")
		(net "PCIE_TX_CAP_N30")
	)
	(arc
		(start 287.465262 -210.313778)
		(mid 287.527983 -210.6291)
		(end 287.706562 -210.896454)
		(width 0.1397)
		(layer "In5.Cu")
		(net "PCIE_TX_CAP_N30")
	)
	(segment
		(start 289.8013 -34.4424)
		(end 289.8013 -34.5821)
		(width 0.136652)
		(layer "F.Cu")
		(net "PCIE_TX_CAP_N3")
	)
	(segment
		(start 290.068 -33.9725)
		(end 289.945064 -34.09569)
		(width 0.136652)
		(layer "F.Cu")
		(net "PCIE_TX_CAP_N3")
	)
	(segment
		(start 289.936174 -34.907728)
		(end 290.0426 -35.014154)
		(width 0.136652)
		(layer "F.Cu")
		(net "PCIE_TX_CAP_N3")
	)
	(segment
		(start 254.599948 -30.999938)
		(end 255.09982 -30.500066)
		(width 0.136652)
		(layer "F.Cu")
		(net "PCIE_TX_CAP_N3")
	)
	(via
		(at 290.0426 -35.014154)
		(size 0.508)
		(drill 0.254)
		(layers "F.Cu" "B.Cu")
		(net "PCIE_TX_CAP_N3")
	)
	(via
		(at 255.09982 -30.500066)
		(size 0.4572)
		(drill 0.2032)
		(layers "F.Cu" "B.Cu")
		(net "PCIE_TX_CAP_N3")
	)
	(arc
		(start 289.8013 -34.5821)
		(mid 289.836354 -34.758326)
		(end 289.936174 -34.907728)
		(width 0.136652)
		(layer "F.Cu")
		(net "PCIE_TX_CAP_N3")
	)
	(arc
		(start 289.945064 -34.09569)
		(mid 289.838693 -34.254747)
		(end 289.8013 -34.4424)
		(width 0.136652)
		(layer "F.Cu")
		(net "PCIE_TX_CAP_N3")
	)
	(segment
		(start 289.92322 -35.133788)
		(end 290.0426 -35.014154)
		(width 0.1397)
		(layer "In5.Cu")
		(net "PCIE_TX_CAP_N3")
	)
	(segment
		(start 288.565082 -36.2712)
		(end 288.871152 -36.2712)
		(width 0.1397)
		(layer "In5.Cu")
		(net "PCIE_TX_CAP_N3")
	)
	(segment
		(start 254.958088 -30.9626)
		(end 254.957326 -30.9626)
		(width 0.1016)
		(layer "In5.Cu")
		(net "PCIE_TX_CAP_N3")
	)
	(segment
		(start 281.053286 -32.206438)
		(end 282.286964 -33.968182)
		(width 0.1397)
		(layer "In5.Cu")
		(net "PCIE_TX_CAP_N3")
	)
	(segment
		(start 257.612388 -23.861522)
		(end 260.52145 -23.243286)
		(width 0.1397)
		(layer "In5.Cu")
		(net "PCIE_TX_CAP_N3")
	)
	(segment
		(start 263.934194 -23.96871)
		(end 272.578068 -22.131528)
		(width 0.1397)
		(layer "In5.Cu")
		(net "PCIE_TX_CAP_N3")
	)
	(segment
		(start 254.842772 -26.774902)
		(end 254.94869 -26.174954)
		(width 0.1397)
		(layer "In5.Cu")
		(net "PCIE_TX_CAP_N3")
	)
	(segment
		(start 289.7886 -35.496754)
		(end 289.7886 -35.4584)
		(width 0.1397)
		(layer "In5.Cu")
		(net "PCIE_TX_CAP_N3")
	)
	(segment
		(start 254.842772 -29.8323)
		(end 254.842772 -26.774902)
		(width 0.1397)
		(layer "In5.Cu")
		(net "PCIE_TX_CAP_N3")
	)
	(segment
		(start 278.50592 -25.454102)
		(end 280.366724 -28.319984)
		(width 0.1397)
		(layer "In5.Cu")
		(net "PCIE_TX_CAP_N3")
	)
	(segment
		(start 254.704596 -30.6324)
		(end 254.704596 -30.228794)
		(width 0.1016)
		(layer "In5.Cu")
		(net "PCIE_TX_CAP_N3")
	)
	(segment
		(start 272.578068 -22.131528)
		(end 273.78406 -22.387814)
		(width 0.1397)
		(layer "In5.Cu")
		(net "PCIE_TX_CAP_N3")
	)
	(segment
		(start 273.78406 -22.387814)
		(end 278.50592 -25.454102)
		(width 0.1397)
		(layer "In5.Cu")
		(net "PCIE_TX_CAP_N3")
	)
	(segment
		(start 255.56464 -25.295098)
		(end 257.612388 -23.861522)
		(width 0.1397)
		(layer "In5.Cu")
		(net "PCIE_TX_CAP_N3")
	)
	(segment
		(start 260.52145 -23.243286)
		(end 263.934194 -23.96871)
		(width 0.1397)
		(layer "In5.Cu")
		(net "PCIE_TX_CAP_N3")
	)
	(segment
		(start 282.286964 -33.968182)
		(end 284.57398 -35.570414)
		(width 0.1397)
		(layer "In5.Cu")
		(net "PCIE_TX_CAP_N3")
	)
	(segment
		(start 254.773684 -30.061916)
		(end 254.842772 -29.992828)
		(width 0.1016)
		(layer "In5.Cu")
		(net "PCIE_TX_CAP_N3")
	)
	(segment
		(start 284.57398 -35.570414)
		(end 288.565082 -36.2712)
		(width 0.1397)
		(layer "In5.Cu")
		(net "PCIE_TX_CAP_N3")
	)
	(segment
		(start 280.366724 -28.319984)
		(end 281.053286 -32.206438)
		(width 0.1397)
		(layer "In5.Cu")
		(net "PCIE_TX_CAP_N3")
	)
	(segment
		(start 254.842772 -29.992828)
		(end 254.842772 -29.8323)
		(width 0.1016)
		(layer "In5.Cu")
		(net "PCIE_TX_CAP_N3")
	)
	(segment
		(start 254.94869 -26.174954)
		(end 255.56464 -25.295098)
		(width 0.1397)
		(layer "In5.Cu")
		(net "PCIE_TX_CAP_N3")
	)
	(arc
		(start 254.957326 -30.9626)
		(mid 254.866054 -30.944445)
		(end 254.78867 -30.89275)
		(width 0.1016)
		(layer "In5.Cu")
		(net "PCIE_TX_CAP_N3")
	)
	(arc
		(start 289.59175 -35.973004)
		(mid 289.737502 -35.754454)
		(end 289.7886 -35.496754)
		(width 0.1397)
		(layer "In5.Cu")
		(net "PCIE_TX_CAP_N3")
	)
	(arc
		(start 254.78867 -30.89275)
		(mid 254.726186 -30.769179)
		(end 254.704596 -30.6324)
		(width 0.1016)
		(layer "In5.Cu")
		(net "PCIE_TX_CAP_N3")
	)
	(arc
		(start 255.09982 -30.500066)
		(mid 255.169355 -30.604133)
		(end 255.1938 -30.726888)
		(width 0.1016)
		(layer "In5.Cu")
		(net "PCIE_TX_CAP_N3")
	)
	(arc
		(start 288.871152 -36.2712)
		(mid 289.261096 -36.193747)
		(end 289.59175 -35.973004)
		(width 0.1397)
		(layer "In5.Cu")
		(net "PCIE_TX_CAP_N3")
	)
	(arc
		(start 254.704596 -30.228794)
		(mid 254.722558 -30.138494)
		(end 254.773684 -30.061916)
		(width 0.1016)
		(layer "In5.Cu")
		(net "PCIE_TX_CAP_N3")
	)
	(arc
		(start 255.1938 -30.726888)
		(mid 255.124762 -30.893562)
		(end 254.958088 -30.9626)
		(width 0.1016)
		(layer "In5.Cu")
		(net "PCIE_TX_CAP_N3")
	)
	(arc
		(start 289.7886 -35.4584)
		(mid 289.82364 -35.282713)
		(end 289.92322 -35.133788)
		(width 0.1397)
		(layer "In5.Cu")
		(net "PCIE_TX_CAP_N3")
	)
	(segment
		(start 290.646104 -211.5312)
		(end 290.646104 -211.3026)
		(width 0.136652)
		(layer "F.Cu")
		(net "PCIE_TX_CAP_N29")
	)
	(segment
		(start 257.599942 -56.999886)
		(end 258.099814 -57.499758)
		(width 0.136652)
		(layer "F.Cu")
		(net "PCIE_TX_CAP_N29")
	)
	(segment
		(start 291.008054 -211.975954)
		(end 290.704778 -211.672424)
		(width 0.136652)
		(layer "F.Cu")
		(net "PCIE_TX_CAP_N29")
	)
	(segment
		(start 290.749228 -211.05368)
		(end 290.906454 -210.896454)
		(width 0.136652)
		(layer "F.Cu")
		(net "PCIE_TX_CAP_N29")
	)
	(via
		(at 258.099814 -57.499758)
		(size 0.4572)
		(drill 0.2032)
		(layers "F.Cu" "B.Cu")
		(net "PCIE_TX_CAP_N29")
	)
	(via
		(at 290.906454 -210.896454)
		(size 0.508)
		(drill 0.254)
		(layers "F.Cu" "B.Cu")
		(net "PCIE_TX_CAP_N29")
	)
	(arc
		(start 290.704778 -211.672424)
		(mid 290.661401 -211.607645)
		(end 290.646104 -211.5312)
		(width 0.136652)
		(layer "F.Cu")
		(net "PCIE_TX_CAP_N29")
	)
	(arc
		(start 290.646104 -211.3026)
		(mid 290.672902 -211.167879)
		(end 290.749228 -211.05368)
		(width 0.136652)
		(layer "F.Cu")
		(net "PCIE_TX_CAP_N29")
	)
	(segment
		(start 265.448288 -59.900058)
		(end 270.05788 -66.482976)
		(width 0.1397)
		(layer "In5.Cu")
		(net "PCIE_TX_CAP_N29")
	)
	(segment
		(start 258.070096 -57.888632)
		(end 259.623306 -57.888632)
		(width 0.1016)
		(layer "In5.Cu")
		(net "PCIE_TX_CAP_N29")
	)
	(segment
		(start 259.7404 -57.840118)
		(end 260.985 -57.840118)
		(width 0.1397)
		(layer "In5.Cu")
		(net "PCIE_TX_CAP_N29")
	)
	(segment
		(start 288.902902 -190.747396)
		(end 291.345112 -204.597)
		(width 0.1397)
		(layer "In5.Cu")
		(net "PCIE_TX_CAP_N29")
	)
	(segment
		(start 260.985 -57.840118)
		(end 263.018524 -58.198766)
		(width 0.1397)
		(layer "In5.Cu")
		(net "PCIE_TX_CAP_N29")
	)
	(segment
		(start 290.436046 -182.05323)
		(end 288.902902 -190.747396)
		(width 0.1397)
		(layer "In5.Cu")
		(net "PCIE_TX_CAP_N29")
	)
	(segment
		(start 290.665154 -208.45272)
		(end 290.665154 -210.313778)
		(width 0.1397)
		(layer "In5.Cu")
		(net "PCIE_TX_CAP_N29")
	)
	(segment
		(start 258.099814 -57.499758)
		(end 257.931666 -57.499758)
		(width 0.1016)
		(layer "In5.Cu")
		(net "PCIE_TX_CAP_N29")
	)
	(segment
		(start 263.018524 -58.198766)
		(end 264.239756 -59.053984)
		(width 0.1397)
		(layer "In5.Cu")
		(net "PCIE_TX_CAP_N29")
	)
	(segment
		(start 291.345112 -204.597)
		(end 290.665154 -208.45272)
		(width 0.1397)
		(layer "In5.Cu")
		(net "PCIE_TX_CAP_N29")
	)
	(segment
		(start 264.239756 -59.053984)
		(end 265.448288 -59.900058)
		(width 0.1397)
		(layer "In5.Cu")
		(net "PCIE_TX_CAP_N29")
	)
	(segment
		(start 270.05788 -66.482976)
		(end 290.436046 -182.05323)
		(width 0.1397)
		(layer "In5.Cu")
		(net "PCIE_TX_CAP_N29")
	)
	(segment
		(start 257.7846 -57.560718)
		(end 257.762502 -57.582562)
		(width 0.1016)
		(layer "In5.Cu")
		(net "PCIE_TX_CAP_N29")
	)
	(segment
		(start 257.722624 -57.666382)
		(end 257.722624 -57.682638)
		(width 0.1016)
		(layer "In5.Cu")
		(net "PCIE_TX_CAP_N29")
	)
	(arc
		(start 257.735832 -57.619138)
		(mid 257.728755 -57.636643)
		(end 257.724148 -57.654952)
		(width 0.1016)
		(layer "In5.Cu")
		(net "PCIE_TX_CAP_N29")
	)
	(arc
		(start 257.724148 -57.654952)
		(mid 257.723265 -57.660651)
		(end 257.722624 -57.666382)
		(width 0.1016)
		(layer "In5.Cu")
		(net "PCIE_TX_CAP_N29")
	)
	(arc
		(start 257.722624 -57.682638)
		(mid 257.722615 -57.684416)
		(end 257.722624 -57.686194)
		(width 0.1016)
		(layer "In5.Cu")
		(net "PCIE_TX_CAP_N29")
	)
	(arc
		(start 257.722624 -57.686194)
		(mid 257.723609 -57.701506)
		(end 257.725926 -57.716674)
		(width 0.1016)
		(layer "In5.Cu")
		(net "PCIE_TX_CAP_N29")
	)
	(arc
		(start 257.725926 -57.716674)
		(mid 257.764281 -57.795948)
		(end 257.836416 -57.846468)
		(width 0.1016)
		(layer "In5.Cu")
		(net "PCIE_TX_CAP_N29")
	)
	(arc
		(start 259.623306 -57.888632)
		(mid 259.686681 -57.876026)
		(end 259.7404 -57.840118)
		(width 0.1016)
		(layer "In5.Cu")
		(net "PCIE_TX_CAP_N29")
	)
	(arc
		(start 257.74142 -57.609232)
		(mid 257.740782 -57.610119)
		(end 257.74015 -57.61101)
		(width 0.1016)
		(layer "In5.Cu")
		(net "PCIE_TX_CAP_N29")
	)
	(arc
		(start 257.762502 -57.582562)
		(mid 257.751139 -57.595247)
		(end 257.74142 -57.609232)
		(width 0.1016)
		(layer "In5.Cu")
		(net "PCIE_TX_CAP_N29")
	)
	(arc
		(start 290.665154 -210.313778)
		(mid 290.727875 -210.6291)
		(end 290.906454 -210.896454)
		(width 0.1397)
		(layer "In5.Cu")
		(net "PCIE_TX_CAP_N29")
	)
	(arc
		(start 257.74015 -57.61101)
		(mid 257.737919 -57.615036)
		(end 257.735832 -57.619138)
		(width 0.1016)
		(layer "In5.Cu")
		(net "PCIE_TX_CAP_N29")
	)
	(arc
		(start 257.836416 -57.846468)
		(mid 257.951374 -57.877991)
		(end 258.070096 -57.888632)
		(width 0.1016)
		(layer "In5.Cu")
		(net "PCIE_TX_CAP_N29")
	)
	(arc
		(start 257.931666 -57.499758)
		(mid 257.852058 -57.515593)
		(end 257.7846 -57.560718)
		(width 0.1016)
		(layer "In5.Cu")
		(net "PCIE_TX_CAP_N29")
	)
	(segment
		(start 258.59994 -55.999888)
		(end 259.099812 -56.49976)
		(width 0.136652)
		(layer "F.Cu")
		(net "PCIE_TX_CAP_N28")
	)
	(segment
		(start 293.957756 -211.045044)
		(end 294.106346 -210.896454)
		(width 0.136652)
		(layer "F.Cu")
		(net "PCIE_TX_CAP_N28")
	)
	(segment
		(start 294.207946 -211.975954)
		(end 293.90467 -211.672424)
		(width 0.136652)
		(layer "F.Cu")
		(net "PCIE_TX_CAP_N28")
	)
	(segment
		(start 293.845996 -211.5312)
		(end 293.845996 -211.314792)
		(width 0.136652)
		(layer "F.Cu")
		(net "PCIE_TX_CAP_N28")
	)
	(via
		(at 259.099812 -56.49976)
		(size 0.4572)
		(drill 0.2032)
		(layers "F.Cu" "B.Cu")
		(net "PCIE_TX_CAP_N28")
	)
	(via
		(at 294.106346 -210.896454)
		(size 0.508)
		(drill 0.254)
		(layers "F.Cu" "B.Cu")
		(net "PCIE_TX_CAP_N28")
	)
	(arc
		(start 293.845996 -211.314792)
		(mid 293.875037 -211.168795)
		(end 293.957756 -211.045044)
		(width 0.136652)
		(layer "F.Cu")
		(net "PCIE_TX_CAP_N28")
	)
	(arc
		(start 293.90467 -211.672424)
		(mid 293.861293 -211.607645)
		(end 293.845996 -211.5312)
		(width 0.136652)
		(layer "F.Cu")
		(net "PCIE_TX_CAP_N28")
	)
	(segment
		(start 294.067484 -208.560924)
		(end 293.8653 -209.70875)
		(width 0.1397)
		(layer "In5.Cu")
		(net "PCIE_TX_CAP_N28")
	)
	(segment
		(start 293.865046 -209.70875)
		(end 293.865046 -210.313778)
		(width 0.1397)
		(layer "In5.Cu")
		(net "PCIE_TX_CAP_N28")
	)
	(segment
		(start 266.269724 -59.252866)
		(end 271.330928 -66.480944)
		(width 0.1397)
		(layer "In5.Cu")
		(net "PCIE_TX_CAP_N28")
	)
	(segment
		(start 259.726684 -57.013602)
		(end 259.890768 -56.849518)
		(width 0.1016)
		(layer "In5.Cu")
		(net "PCIE_TX_CAP_N28")
	)
	(segment
		(start 259.099812 -56.49976)
		(end 259.035296 -56.56453)
		(width 0.1016)
		(layer "In5.Cu")
		(net "PCIE_TX_CAP_N28")
	)
	(segment
		(start 294.284908 -207.3275)
		(end 294.067484 -208.560924)
		(width 0.1397)
		(layer "In5.Cu")
		(net "PCIE_TX_CAP_N28")
	)
	(segment
		(start 271.330928 -66.480944)
		(end 292.923722 -188.940186)
		(width 0.1397)
		(layer "In5.Cu")
		(net "PCIE_TX_CAP_N28")
	)
	(segment
		(start 293.8653 -209.70875)
		(end 293.865046 -209.70875)
		(width 0.1397)
		(layer "In5.Cu")
		(net "PCIE_TX_CAP_N28")
	)
	(segment
		(start 291.983414 -194.273932)
		(end 294.284908 -207.3275)
		(width 0.1397)
		(layer "In5.Cu")
		(net "PCIE_TX_CAP_N28")
	)
	(segment
		(start 263.53643 -57.338976)
		(end 264.9093 -58.300366)
		(width 0.1397)
		(layer "In5.Cu")
		(net "PCIE_TX_CAP_N28")
	)
	(segment
		(start 258.99364 -56.98363)
		(end 259.020564 -57.010554)
		(width 0.1016)
		(layer "In5.Cu")
		(net "PCIE_TX_CAP_N28")
	)
	(segment
		(start 260.760718 -56.849518)
		(end 263.53643 -57.338976)
		(width 0.1397)
		(layer "In5.Cu")
		(net "PCIE_TX_CAP_N28")
	)
	(segment
		(start 259.24002 -57.101486)
		(end 259.514594 -57.101486)
		(width 0.1016)
		(layer "In5.Cu")
		(net "PCIE_TX_CAP_N28")
	)
	(segment
		(start 259.890768 -56.849518)
		(end 260.760718 -56.849518)
		(width 0.1397)
		(layer "In5.Cu")
		(net "PCIE_TX_CAP_N28")
	)
	(segment
		(start 292.923722 -188.940186)
		(end 291.983414 -194.273932)
		(width 0.1397)
		(layer "In5.Cu")
		(net "PCIE_TX_CAP_N28")
	)
	(segment
		(start 264.9093 -58.300366)
		(end 266.269724 -59.252866)
		(width 0.1397)
		(layer "In5.Cu")
		(net "PCIE_TX_CAP_N28")
	)
	(arc
		(start 259.035296 -56.56453)
		(mid 258.955633 -56.683615)
		(end 258.9276 -56.824118)
		(width 0.1016)
		(layer "In5.Cu")
		(net "PCIE_TX_CAP_N28")
	)
	(arc
		(start 259.514594 -57.101486)
		(mid 259.550679 -57.099215)
		(end 259.586222 -57.092596)
		(width 0.1016)
		(layer "In5.Cu")
		(net "PCIE_TX_CAP_N28")
	)
	(arc
		(start 293.865046 -210.313778)
		(mid 293.927767 -210.6291)
		(end 294.106346 -210.896454)
		(width 0.1397)
		(layer "In5.Cu")
		(net "PCIE_TX_CAP_N28")
	)
	(arc
		(start 259.020564 -57.010554)
		(mid 259.121265 -57.077807)
		(end 259.24002 -57.101486)
		(width 0.1016)
		(layer "In5.Cu")
		(net "PCIE_TX_CAP_N28")
	)
	(arc
		(start 259.586222 -57.092596)
		(mid 259.661861 -57.062714)
		(end 259.726684 -57.013602)
		(width 0.1016)
		(layer "In5.Cu")
		(net "PCIE_TX_CAP_N28")
	)
	(arc
		(start 258.9276 -56.824118)
		(mid 258.944769 -56.910433)
		(end 258.99364 -56.98363)
		(width 0.1016)
		(layer "In5.Cu")
		(net "PCIE_TX_CAP_N28")
	)
	(segment
		(start 299.510958 -211.092288)
		(end 299.706538 -210.896454)
		(width 0.136652)
		(layer "F.Cu")
		(net "PCIE_TX_CAP_N27")
	)
	(segment
		(start 299.446188 -211.5312)
		(end 299.446188 -211.2518)
		(width 0.136652)
		(layer "F.Cu")
		(net "PCIE_TX_CAP_N27")
	)
	(segment
		(start 299.808138 -211.975954)
		(end 299.504862 -211.672424)
		(width 0.136652)
		(layer "F.Cu")
		(net "PCIE_TX_CAP_N27")
	)
	(segment
		(start 257.599942 -54.99989)
		(end 258.099814 -55.499762)
		(width 0.136652)
		(layer "F.Cu")
		(net "PCIE_TX_CAP_N27")
	)
	(via
		(at 299.706538 -210.896454)
		(size 0.508)
		(drill 0.254)
		(layers "F.Cu" "B.Cu")
		(net "PCIE_TX_CAP_N27")
	)
	(via
		(at 258.099814 -55.499762)
		(size 0.4572)
		(drill 0.2032)
		(layers "F.Cu" "B.Cu")
		(net "PCIE_TX_CAP_N27")
	)
	(arc
		(start 299.446188 -211.248244)
		(mid 299.463073 -211.16383)
		(end 299.510958 -211.092288)
		(width 0.136652)
		(layer "F.Cu")
		(net "PCIE_TX_CAP_N27")
	)
	(arc
		(start 299.446188 -211.2518)
		(mid 299.446191 -211.250022)
		(end 299.446188 -211.248244)
		(width 0.136652)
		(layer "F.Cu")
		(net "PCIE_TX_CAP_N27")
	)
	(arc
		(start 299.504862 -211.672424)
		(mid 299.461485 -211.607645)
		(end 299.446188 -211.5312)
		(width 0.136652)
		(layer "F.Cu")
		(net "PCIE_TX_CAP_N27")
	)
	(segment
		(start 299.231304 -204.366114)
		(end 300.355 -197.993)
		(width 0.1397)
		(layer "In5.Cu")
		(net "PCIE_TX_CAP_N27")
	)
	(segment
		(start 292.6461 -180.051964)
		(end 272.468594 -65.617852)
		(width 0.1397)
		(layer "In5.Cu")
		(net "PCIE_TX_CAP_N27")
	)
	(segment
		(start 257.722624 -55.682642)
		(end 257.722624 -55.666386)
		(width 0.1016)
		(layer "In5.Cu")
		(net "PCIE_TX_CAP_N27")
	)
	(segment
		(start 257.931666 -55.499762)
		(end 258.099814 -55.499762)
		(width 0.1016)
		(layer "In5.Cu")
		(net "PCIE_TX_CAP_N27")
	)
	(segment
		(start 299.465238 -208.581244)
		(end 299.72 -207.137)
		(width 0.1397)
		(layer "In5.Cu")
		(net "PCIE_TX_CAP_N27")
	)
	(segment
		(start 299.72 -207.137)
		(end 299.231304 -204.366114)
		(width 0.1397)
		(layer "In5.Cu")
		(net "PCIE_TX_CAP_N27")
	)
	(segment
		(start 298.721526 -188.728604)
		(end 292.6461 -180.051964)
		(width 0.1397)
		(layer "In5.Cu")
		(net "PCIE_TX_CAP_N27")
	)
	(segment
		(start 272.468594 -65.617852)
		(end 266.975336 -57.772808)
		(width 0.1397)
		(layer "In5.Cu")
		(net "PCIE_TX_CAP_N27")
	)
	(segment
		(start 257.762502 -55.582566)
		(end 257.7846 -55.560722)
		(width 0.1016)
		(layer "In5.Cu")
		(net "PCIE_TX_CAP_N27")
	)
	(segment
		(start 264.251948 -55.86603)
		(end 262.89 -55.626)
		(width 0.1397)
		(layer "In5.Cu")
		(net "PCIE_TX_CAP_N27")
	)
	(segment
		(start 261.675626 -55.840122)
		(end 259.7404 -55.840122)
		(width 0.1397)
		(layer "In5.Cu")
		(net "PCIE_TX_CAP_N27")
	)
	(segment
		(start 259.623306 -55.888636)
		(end 258.070096 -55.888636)
		(width 0.1016)
		(layer "In5.Cu")
		(net "PCIE_TX_CAP_N27")
	)
	(segment
		(start 299.465238 -210.313778)
		(end 299.465238 -208.581244)
		(width 0.1397)
		(layer "In5.Cu")
		(net "PCIE_TX_CAP_N27")
	)
	(segment
		(start 300.355 -197.993)
		(end 298.721526 -188.728604)
		(width 0.1397)
		(layer "In5.Cu")
		(net "PCIE_TX_CAP_N27")
	)
	(segment
		(start 262.89 -55.626)
		(end 261.675626 -55.840122)
		(width 0.1397)
		(layer "In5.Cu")
		(net "PCIE_TX_CAP_N27")
	)
	(segment
		(start 266.975336 -57.772808)
		(end 264.251948 -55.86603)
		(width 0.1397)
		(layer "In5.Cu")
		(net "PCIE_TX_CAP_N27")
	)
	(arc
		(start 257.724148 -55.654956)
		(mid 257.728785 -55.636657)
		(end 257.735832 -55.619142)
		(width 0.1016)
		(layer "In5.Cu")
		(net "PCIE_TX_CAP_N27")
	)
	(arc
		(start 259.7404 -55.840122)
		(mid 259.686677 -55.876019)
		(end 259.623306 -55.888636)
		(width 0.1016)
		(layer "In5.Cu")
		(net "PCIE_TX_CAP_N27")
	)
	(arc
		(start 257.735832 -55.619142)
		(mid 257.737928 -55.615045)
		(end 257.74015 -55.611014)
		(width 0.1016)
		(layer "In5.Cu")
		(net "PCIE_TX_CAP_N27")
	)
	(arc
		(start 257.722624 -55.666386)
		(mid 257.72327 -55.660656)
		(end 257.724148 -55.654956)
		(width 0.1016)
		(layer "In5.Cu")
		(net "PCIE_TX_CAP_N27")
	)
	(arc
		(start 257.722624 -55.686198)
		(mid 257.722615 -55.68442)
		(end 257.722624 -55.682642)
		(width 0.1016)
		(layer "In5.Cu")
		(net "PCIE_TX_CAP_N27")
	)
	(arc
		(start 257.725926 -55.716678)
		(mid 257.723602 -55.701511)
		(end 257.722624 -55.686198)
		(width 0.1016)
		(layer "In5.Cu")
		(net "PCIE_TX_CAP_N27")
	)
	(arc
		(start 257.7846 -55.560722)
		(mid 257.852074 -55.515637)
		(end 257.931666 -55.499762)
		(width 0.1016)
		(layer "In5.Cu")
		(net "PCIE_TX_CAP_N27")
	)
	(arc
		(start 257.74142 -55.609236)
		(mid 257.751144 -55.595256)
		(end 257.762502 -55.582566)
		(width 0.1016)
		(layer "In5.Cu")
		(net "PCIE_TX_CAP_N27")
	)
	(arc
		(start 257.836416 -55.846472)
		(mid 257.764274 -55.795957)
		(end 257.725926 -55.716678)
		(width 0.1016)
		(layer "In5.Cu")
		(net "PCIE_TX_CAP_N27")
	)
	(arc
		(start 257.74015 -55.611014)
		(mid 257.740782 -55.610123)
		(end 257.74142 -55.609236)
		(width 0.1016)
		(layer "In5.Cu")
		(net "PCIE_TX_CAP_N27")
	)
	(arc
		(start 258.070096 -55.888636)
		(mid 257.951381 -55.877956)
		(end 257.836416 -55.846472)
		(width 0.1016)
		(layer "In5.Cu")
		(net "PCIE_TX_CAP_N27")
	)
	(arc
		(start 299.706538 -210.896454)
		(mid 299.527911 -210.62912)
		(end 299.465238 -210.313778)
		(width 0.1397)
		(layer "In5.Cu")
		(net "PCIE_TX_CAP_N27")
	)
	(segment
		(start 302.64608 -211.5312)
		(end 302.64608 -211.28228)
		(width 0.136652)
		(layer "F.Cu")
		(net "PCIE_TX_CAP_N26")
	)
	(segment
		(start 258.59994 -53.999892)
		(end 259.099812 -54.499764)
		(width 0.136652)
		(layer "F.Cu")
		(net "PCIE_TX_CAP_N26")
	)
	(segment
		(start 303.00803 -211.975954)
		(end 302.704754 -211.672424)
		(width 0.136652)
		(layer "F.Cu")
		(net "PCIE_TX_CAP_N26")
	)
	(segment
		(start 302.734726 -211.067904)
		(end 302.90643 -210.896454)
		(width 0.136652)
		(layer "F.Cu")
		(net "PCIE_TX_CAP_N26")
	)
	(via
		(at 302.90643 -210.896454)
		(size 0.508)
		(drill 0.254)
		(layers "F.Cu" "B.Cu")
		(net "PCIE_TX_CAP_N26")
	)
	(via
		(at 259.099812 -54.499764)
		(size 0.4572)
		(drill 0.2032)
		(layers "F.Cu" "B.Cu")
		(net "PCIE_TX_CAP_N26")
	)
	(arc
		(start 302.64608 -211.28228)
		(mid 302.669063 -211.166265)
		(end 302.734726 -211.067904)
		(width 0.136652)
		(layer "F.Cu")
		(net "PCIE_TX_CAP_N26")
	)
	(arc
		(start 302.704754 -211.672424)
		(mid 302.661377 -211.607645)
		(end 302.64608 -211.5312)
		(width 0.136652)
		(layer "F.Cu")
		(net "PCIE_TX_CAP_N26")
	)
	(segment
		(start 258.99364 -54.983634)
		(end 259.020564 -55.010558)
		(width 0.1016)
		(layer "In5.Cu")
		(net "PCIE_TX_CAP_N26")
	)
	(segment
		(start 302.885602 -208.35366)
		(end 302.66513 -209.603848)
		(width 0.1397)
		(layer "In5.Cu")
		(net "PCIE_TX_CAP_N26")
	)
	(segment
		(start 259.24002 -55.10149)
		(end 259.514594 -55.10149)
		(width 0.1016)
		(layer "In5.Cu")
		(net "PCIE_TX_CAP_N26")
	)
	(segment
		(start 268.431772 -57.361582)
		(end 274.032218 -65.359788)
		(width 0.1397)
		(layer "In5.Cu")
		(net "PCIE_TX_CAP_N26")
	)
	(segment
		(start 302.372776 -205.445106)
		(end 302.885602 -208.35366)
		(width 0.1397)
		(layer "In5.Cu")
		(net "PCIE_TX_CAP_N26")
	)
	(segment
		(start 293.817802 -175.598836)
		(end 293.819072 -175.601376)
		(width 0.1397)
		(layer "In5.Cu")
		(net "PCIE_TX_CAP_N26")
	)
	(segment
		(start 301.763684 -188.865256)
		(end 302.648112 -193.881248)
		(width 0.1397)
		(layer "In5.Cu")
		(net "PCIE_TX_CAP_N26")
	)
	(segment
		(start 293.819072 -175.601376)
		(end 293.827962 -175.621442)
		(width 0.1397)
		(layer "In5.Cu")
		(net "PCIE_TX_CAP_N26")
	)
	(segment
		(start 263.526016 -54.361842)
		(end 264.357104 -54.5084)
		(width 0.1397)
		(layer "In5.Cu")
		(net "PCIE_TX_CAP_N26")
	)
	(segment
		(start 259.099812 -54.499764)
		(end 259.035296 -54.564534)
		(width 0.1016)
		(layer "In5.Cu")
		(net "PCIE_TX_CAP_N26")
	)
	(segment
		(start 302.648112 -193.881248)
		(end 303.53 -198.882)
		(width 0.1397)
		(layer "In5.Cu")
		(net "PCIE_TX_CAP_N26")
	)
	(segment
		(start 264.357104 -54.5084)
		(end 268.431772 -57.361582)
		(width 0.1397)
		(layer "In5.Cu")
		(net "PCIE_TX_CAP_N26")
	)
	(segment
		(start 260.760718 -54.849522)
		(end 263.526016 -54.361842)
		(width 0.1397)
		(layer "In5.Cu")
		(net "PCIE_TX_CAP_N26")
	)
	(segment
		(start 293.827962 -175.621442)
		(end 293.828216 -175.622204)
		(width 0.1397)
		(layer "In5.Cu")
		(net "PCIE_TX_CAP_N26")
	)
	(segment
		(start 295.746678 -180.27142)
		(end 301.763684 -188.865256)
		(width 0.1397)
		(layer "In5.Cu")
		(net "PCIE_TX_CAP_N26")
	)
	(segment
		(start 293.22141 -174.325534)
		(end 293.817802 -175.598836)
		(width 0.1397)
		(layer "In5.Cu")
		(net "PCIE_TX_CAP_N26")
	)
	(segment
		(start 274.032218 -65.359788)
		(end 293.22141 -174.325534)
		(width 0.1397)
		(layer "In5.Cu")
		(net "PCIE_TX_CAP_N26")
	)
	(segment
		(start 293.828216 -175.622204)
		(end 295.746678 -180.27142)
		(width 0.1397)
		(layer "In5.Cu")
		(net "PCIE_TX_CAP_N26")
	)
	(segment
		(start 259.890768 -54.849522)
		(end 260.760718 -54.849522)
		(width 0.1397)
		(layer "In5.Cu")
		(net "PCIE_TX_CAP_N26")
	)
	(segment
		(start 303.53 -198.882)
		(end 302.372776 -205.445106)
		(width 0.1397)
		(layer "In5.Cu")
		(net "PCIE_TX_CAP_N26")
	)
	(segment
		(start 259.726684 -55.013606)
		(end 259.890768 -54.849522)
		(width 0.1016)
		(layer "In5.Cu")
		(net "PCIE_TX_CAP_N26")
	)
	(segment
		(start 302.66513 -209.603848)
		(end 302.66513 -210.313778)
		(width 0.1397)
		(layer "In5.Cu")
		(net "PCIE_TX_CAP_N26")
	)
	(arc
		(start 259.586222 -55.0926)
		(mid 259.661861 -55.062718)
		(end 259.726684 -55.013606)
		(width 0.1016)
		(layer "In5.Cu")
		(net "PCIE_TX_CAP_N26")
	)
	(arc
		(start 258.9276 -54.824122)
		(mid 258.944769 -54.910437)
		(end 258.99364 -54.983634)
		(width 0.1016)
		(layer "In5.Cu")
		(net "PCIE_TX_CAP_N26")
	)
	(arc
		(start 302.66513 -210.313778)
		(mid 302.727851 -210.6291)
		(end 302.90643 -210.896454)
		(width 0.1397)
		(layer "In5.Cu")
		(net "PCIE_TX_CAP_N26")
	)
	(arc
		(start 259.035296 -54.564534)
		(mid 258.955633 -54.683619)
		(end 258.9276 -54.824122)
		(width 0.1016)
		(layer "In5.Cu")
		(net "PCIE_TX_CAP_N26")
	)
	(arc
		(start 259.514594 -55.10149)
		(mid 259.550679 -55.099219)
		(end 259.586222 -55.0926)
		(width 0.1016)
		(layer "In5.Cu")
		(net "PCIE_TX_CAP_N26")
	)
	(arc
		(start 259.020564 -55.010558)
		(mid 259.121265 -55.077811)
		(end 259.24002 -55.10149)
		(width 0.1016)
		(layer "In5.Cu")
		(net "PCIE_TX_CAP_N26")
	)
	(segment
		(start 310.646318 -211.5312)
		(end 310.646318 -211.281518)
		(width 0.136652)
		(layer "F.Cu")
		(net "PCIE_TX_CAP_N25")
	)
	(segment
		(start 311.008014 -211.975446)
		(end 310.704992 -211.672424)
		(width 0.136652)
		(layer "F.Cu")
		(net "PCIE_TX_CAP_N25")
	)
	(segment
		(start 310.734456 -211.068666)
		(end 310.906668 -210.896454)
		(width 0.136652)
		(layer "F.Cu")
		(net "PCIE_TX_CAP_N25")
	)
	(segment
		(start 257.599942 -52.999894)
		(end 258.099814 -53.499766)
		(width 0.136652)
		(layer "F.Cu")
		(net "PCIE_TX_CAP_N25")
	)
	(segment
		(start 311.008014 -211.975954)
		(end 311.008014 -211.975446)
		(width 0.136652)
		(layer "F.Cu")
		(net "PCIE_TX_CAP_N25")
	)
	(via
		(at 258.099814 -53.499766)
		(size 0.4572)
		(drill 0.2032)
		(layers "F.Cu" "B.Cu")
		(net "PCIE_TX_CAP_N25")
	)
	(via
		(at 310.906668 -210.896454)
		(size 0.508)
		(drill 0.254)
		(layers "F.Cu" "B.Cu")
		(net "PCIE_TX_CAP_N25")
	)
	(arc
		(start 310.646318 -211.281518)
		(mid 310.669229 -211.166334)
		(end 310.734456 -211.068666)
		(width 0.136652)
		(layer "F.Cu")
		(net "PCIE_TX_CAP_N25")
	)
	(arc
		(start 310.704992 -211.672424)
		(mid 310.661615 -211.607645)
		(end 310.646318 -211.5312)
		(width 0.136652)
		(layer "F.Cu")
		(net "PCIE_TX_CAP_N25")
	)
	(segment
		(start 269.360396 -56.851042)
		(end 275.995638 -66.327274)
		(width 0.1397)
		(layer "In5.Cu")
		(net "PCIE_TX_CAP_N25")
	)
	(segment
		(start 264.865358 -53.703474)
		(end 269.360396 -56.851042)
		(width 0.1397)
		(layer "In5.Cu")
		(net "PCIE_TX_CAP_N25")
	)
	(segment
		(start 258.099814 -53.499766)
		(end 257.931666 -53.499766)
		(width 0.1016)
		(layer "In5.Cu")
		(net "PCIE_TX_CAP_N25")
	)
	(segment
		(start 310.881776 -208.835244)
		(end 310.665876 -210.061048)
		(width 0.1397)
		(layer "In5.Cu")
		(net "PCIE_TX_CAP_N25")
	)
	(segment
		(start 258.070096 -53.88864)
		(end 259.623306 -53.88864)
		(width 0.1016)
		(layer "In5.Cu")
		(net "PCIE_TX_CAP_N25")
	)
	(segment
		(start 275.995638 -66.327274)
		(end 294.30726 -170.175936)
		(width 0.1397)
		(layer "In5.Cu")
		(net "PCIE_TX_CAP_N25")
	)
	(segment
		(start 310.515 -206.756)
		(end 310.881776 -208.835244)
		(width 0.1397)
		(layer "In5.Cu")
		(net "PCIE_TX_CAP_N25")
	)
	(segment
		(start 310.665368 -210.061556)
		(end 310.665368 -210.313778)
		(width 0.1397)
		(layer "In5.Cu")
		(net "PCIE_TX_CAP_N25")
	)
	(segment
		(start 294.30726 -170.175936)
		(end 308.99608 -191.156844)
		(width 0.1397)
		(layer "In5.Cu")
		(net "PCIE_TX_CAP_N25")
	)
	(segment
		(start 308.99608 -191.156844)
		(end 311.13095 -203.263754)
		(width 0.1397)
		(layer "In5.Cu")
		(net "PCIE_TX_CAP_N25")
	)
	(segment
		(start 261.408672 -53.840126)
		(end 263.525 -53.467)
		(width 0.1397)
		(layer "In5.Cu")
		(net "PCIE_TX_CAP_N25")
	)
	(segment
		(start 310.665876 -210.061048)
		(end 310.665368 -210.061556)
		(width 0.1397)
		(layer "In5.Cu")
		(net "PCIE_TX_CAP_N25")
	)
	(segment
		(start 311.13095 -203.263754)
		(end 310.515 -206.756)
		(width 0.1397)
		(layer "In5.Cu")
		(net "PCIE_TX_CAP_N25")
	)
	(segment
		(start 263.525 -53.467)
		(end 264.865358 -53.703474)
		(width 0.1397)
		(layer "In5.Cu")
		(net "PCIE_TX_CAP_N25")
	)
	(segment
		(start 259.7404 -53.840126)
		(end 261.408672 -53.840126)
		(width 0.1397)
		(layer "In5.Cu")
		(net "PCIE_TX_CAP_N25")
	)
	(segment
		(start 257.7846 -53.560726)
		(end 257.762502 -53.58257)
		(width 0.1016)
		(layer "In5.Cu")
		(net "PCIE_TX_CAP_N25")
	)
	(segment
		(start 257.722624 -53.66639)
		(end 257.722624 -53.682646)
		(width 0.1016)
		(layer "In5.Cu")
		(net "PCIE_TX_CAP_N25")
	)
	(arc
		(start 257.74142 -53.60924)
		(mid 257.740782 -53.610127)
		(end 257.74015 -53.611018)
		(width 0.1016)
		(layer "In5.Cu")
		(net "PCIE_TX_CAP_N25")
	)
	(arc
		(start 257.836416 -53.846476)
		(mid 257.951374 -53.877999)
		(end 258.070096 -53.88864)
		(width 0.1016)
		(layer "In5.Cu")
		(net "PCIE_TX_CAP_N25")
	)
	(arc
		(start 257.722624 -53.686202)
		(mid 257.723609 -53.701514)
		(end 257.725926 -53.716682)
		(width 0.1016)
		(layer "In5.Cu")
		(net "PCIE_TX_CAP_N25")
	)
	(arc
		(start 310.665368 -210.313778)
		(mid 310.728089 -210.6291)
		(end 310.906668 -210.896454)
		(width 0.1397)
		(layer "In5.Cu")
		(net "PCIE_TX_CAP_N25")
	)
	(arc
		(start 257.931666 -53.499766)
		(mid 257.852058 -53.515601)
		(end 257.7846 -53.560726)
		(width 0.1016)
		(layer "In5.Cu")
		(net "PCIE_TX_CAP_N25")
	)
	(arc
		(start 257.762502 -53.58257)
		(mid 257.751139 -53.595255)
		(end 257.74142 -53.60924)
		(width 0.1016)
		(layer "In5.Cu")
		(net "PCIE_TX_CAP_N25")
	)
	(arc
		(start 257.722624 -53.682646)
		(mid 257.722615 -53.684424)
		(end 257.722624 -53.686202)
		(width 0.1016)
		(layer "In5.Cu")
		(net "PCIE_TX_CAP_N25")
	)
	(arc
		(start 257.724148 -53.65496)
		(mid 257.723265 -53.660659)
		(end 257.722624 -53.66639)
		(width 0.1016)
		(layer "In5.Cu")
		(net "PCIE_TX_CAP_N25")
	)
	(arc
		(start 257.735832 -53.619146)
		(mid 257.728755 -53.636651)
		(end 257.724148 -53.65496)
		(width 0.1016)
		(layer "In5.Cu")
		(net "PCIE_TX_CAP_N25")
	)
	(arc
		(start 257.74015 -53.611018)
		(mid 257.737919 -53.615044)
		(end 257.735832 -53.619146)
		(width 0.1016)
		(layer "In5.Cu")
		(net "PCIE_TX_CAP_N25")
	)
	(arc
		(start 257.725926 -53.716682)
		(mid 257.764281 -53.795956)
		(end 257.836416 -53.846476)
		(width 0.1016)
		(layer "In5.Cu")
		(net "PCIE_TX_CAP_N25")
	)
	(arc
		(start 259.623306 -53.88864)
		(mid 259.686681 -53.876034)
		(end 259.7404 -53.840126)
		(width 0.1016)
		(layer "In5.Cu")
		(net "PCIE_TX_CAP_N25")
	)
	(segment
		(start 258.59994 -51.999896)
		(end 259.099812 -52.499768)
		(width 0.136652)
		(layer "F.Cu")
		(net "PCIE_TX_CAP_N24")
	)
	(segment
		(start 313.939174 -211.063586)
		(end 314.10656 -210.896454)
		(width 0.136652)
		(layer "F.Cu")
		(net "PCIE_TX_CAP_N24")
	)
	(segment
		(start 314.20816 -211.975954)
		(end 313.904884 -211.672424)
		(width 0.136652)
		(layer "F.Cu")
		(net "PCIE_TX_CAP_N24")
	)
	(segment
		(start 313.84621 -211.5312)
		(end 313.84621 -211.288376)
		(width 0.136652)
		(layer "F.Cu")
		(net "PCIE_TX_CAP_N24")
	)
	(via
		(at 259.099812 -52.499768)
		(size 0.4572)
		(drill 0.2032)
		(layers "F.Cu" "B.Cu")
		(net "PCIE_TX_CAP_N24")
	)
	(via
		(at 314.10656 -210.896454)
		(size 0.508)
		(drill 0.254)
		(layers "F.Cu" "B.Cu")
		(net "PCIE_TX_CAP_N24")
	)
	(arc
		(start 313.904884 -211.672424)
		(mid 313.861507 -211.607645)
		(end 313.84621 -211.5312)
		(width 0.136652)
		(layer "F.Cu")
		(net "PCIE_TX_CAP_N24")
	)
	(arc
		(start 313.84621 -211.288376)
		(mid 313.870315 -211.166723)
		(end 313.939174 -211.063586)
		(width 0.136652)
		(layer "F.Cu")
		(net "PCIE_TX_CAP_N24")
	)
	(segment
		(start 313.390534 -206.883)
		(end 313.86526 -209.57667)
		(width 0.1397)
		(layer "In5.Cu")
		(net "PCIE_TX_CAP_N24")
	)
	(segment
		(start 258.99364 -52.983638)
		(end 259.020564 -53.010562)
		(width 0.1016)
		(layer "In5.Cu")
		(net "PCIE_TX_CAP_N24")
	)
	(segment
		(start 311.992518 -191.289178)
		(end 314.066428 -203.050394)
		(width 0.1397)
		(layer "In5.Cu")
		(net "PCIE_TX_CAP_N24")
	)
	(segment
		(start 268.180312 -54.43347)
		(end 270.641572 -56.156606)
		(width 0.1397)
		(layer "In5.Cu")
		(net "PCIE_TX_CAP_N24")
	)
	(segment
		(start 263.654032 -52.33924)
		(end 265.706606 -52.70119)
		(width 0.1397)
		(layer "In5.Cu")
		(net "PCIE_TX_CAP_N24")
	)
	(segment
		(start 259.099812 -52.499768)
		(end 259.035296 -52.564538)
		(width 0.1016)
		(layer "In5.Cu")
		(net "PCIE_TX_CAP_N24")
	)
	(segment
		(start 259.24002 -53.101494)
		(end 259.514594 -53.101494)
		(width 0.1016)
		(layer "In5.Cu")
		(net "PCIE_TX_CAP_N24")
	)
	(segment
		(start 277.719282 -66.264282)
		(end 295.649142 -167.94988)
		(width 0.1397)
		(layer "In5.Cu")
		(net "PCIE_TX_CAP_N24")
	)
	(segment
		(start 270.641572 -56.156606)
		(end 277.719282 -66.264282)
		(width 0.1397)
		(layer "In5.Cu")
		(net "PCIE_TX_CAP_N24")
	)
	(segment
		(start 259.726684 -53.01361)
		(end 259.890768 -52.849526)
		(width 0.1016)
		(layer "In5.Cu")
		(net "PCIE_TX_CAP_N24")
	)
	(segment
		(start 314.066428 -203.050394)
		(end 313.390534 -206.883)
		(width 0.1397)
		(layer "In5.Cu")
		(net "PCIE_TX_CAP_N24")
	)
	(segment
		(start 295.649142 -167.94988)
		(end 311.992518 -191.289178)
		(width 0.1397)
		(layer "In5.Cu")
		(net "PCIE_TX_CAP_N24")
	)
	(segment
		(start 313.86526 -209.57667)
		(end 313.86526 -210.313778)
		(width 0.1397)
		(layer "In5.Cu")
		(net "PCIE_TX_CAP_N24")
	)
	(segment
		(start 260.760718 -52.849526)
		(end 263.654032 -52.33924)
		(width 0.1397)
		(layer "In5.Cu")
		(net "PCIE_TX_CAP_N24")
	)
	(segment
		(start 265.706606 -52.70119)
		(end 268.180312 -54.43347)
		(width 0.1397)
		(layer "In5.Cu")
		(net "PCIE_TX_CAP_N24")
	)
	(segment
		(start 259.890768 -52.849526)
		(end 260.760718 -52.849526)
		(width 0.1397)
		(layer "In5.Cu")
		(net "PCIE_TX_CAP_N24")
	)
	(arc
		(start 259.059934 -53.043836)
		(mid 259.145488 -53.086685)
		(end 259.24002 -53.101494)
		(width 0.1016)
		(layer "In5.Cu")
		(net "PCIE_TX_CAP_N24")
	)
	(arc
		(start 259.586222 -53.092604)
		(mid 259.661861 -53.062722)
		(end 259.726684 -53.01361)
		(width 0.1016)
		(layer "In5.Cu")
		(net "PCIE_TX_CAP_N24")
	)
	(arc
		(start 258.9276 -52.824126)
		(mid 258.944769 -52.910441)
		(end 258.99364 -52.983638)
		(width 0.1016)
		(layer "In5.Cu")
		(net "PCIE_TX_CAP_N24")
	)
	(arc
		(start 259.020564 -53.010562)
		(mid 259.039556 -53.028019)
		(end 259.059934 -53.043836)
		(width 0.1016)
		(layer "In5.Cu")
		(net "PCIE_TX_CAP_N24")
	)
	(arc
		(start 259.514594 -53.101494)
		(mid 259.550679 -53.099223)
		(end 259.586222 -53.092604)
		(width 0.1016)
		(layer "In5.Cu")
		(net "PCIE_TX_CAP_N24")
	)
	(arc
		(start 313.86526 -210.313778)
		(mid 313.927981 -210.6291)
		(end 314.10656 -210.896454)
		(width 0.1397)
		(layer "In5.Cu")
		(net "PCIE_TX_CAP_N24")
	)
	(arc
		(start 259.035296 -52.564538)
		(mid 258.955633 -52.683623)
		(end 258.9276 -52.824126)
		(width 0.1016)
		(layer "In5.Cu")
		(net "PCIE_TX_CAP_N24")
	)
	(segment
		(start 317.408052 -211.975954)
		(end 317.408052 -211.975446)
		(width 0.136652)
		(layer "F.Cu")
		(net "PCIE_TX_CAP_N23")
	)
	(segment
		(start 317.408052 -211.975446)
		(end 317.10503 -211.672424)
		(width 0.136652)
		(layer "F.Cu")
		(net "PCIE_TX_CAP_N23")
	)
	(segment
		(start 257.599942 -49.9999)
		(end 258.099814 -50.499772)
		(width 0.136652)
		(layer "F.Cu")
		(net "PCIE_TX_CAP_N23")
	)
	(segment
		(start 317.15202 -211.05114)
		(end 317.306706 -210.896454)
		(width 0.136652)
		(layer "F.Cu")
		(net "PCIE_TX_CAP_N23")
	)
	(segment
		(start 317.046356 -211.5312)
		(end 317.046356 -211.306156)
		(width 0.136652)
		(layer "F.Cu")
		(net "PCIE_TX_CAP_N23")
	)
	(via
		(at 317.306706 -210.896454)
		(size 0.508)
		(drill 0.254)
		(layers "F.Cu" "B.Cu")
		(net "PCIE_TX_CAP_N23")
	)
	(via
		(at 258.099814 -50.499772)
		(size 0.4572)
		(drill 0.2032)
		(layers "F.Cu" "B.Cu")
		(net "PCIE_TX_CAP_N23")
	)
	(arc
		(start 317.10503 -211.672424)
		(mid 317.061653 -211.607645)
		(end 317.046356 -211.5312)
		(width 0.136652)
		(layer "F.Cu")
		(net "PCIE_TX_CAP_N23")
	)
	(arc
		(start 317.046356 -211.306156)
		(mid 317.073811 -211.16813)
		(end 317.15202 -211.05114)
		(width 0.136652)
		(layer "F.Cu")
		(net "PCIE_TX_CAP_N23")
	)
	(segment
		(start 264.860532 -50.402998)
		(end 264.840466 -50.389028)
		(width 0.1397)
		(layer "In5.Cu")
		(net "PCIE_TX_CAP_N23")
	)
	(segment
		(start 257.931666 -50.499772)
		(end 258.099814 -50.499772)
		(width 0.1016)
		(layer "In5.Cu")
		(net "PCIE_TX_CAP_N23")
	)
	(segment
		(start 279.630632 -66.640456)
		(end 271.575276 -55.136542)
		(width 0.1397)
		(layer "In5.Cu")
		(net "PCIE_TX_CAP_N23")
	)
	(segment
		(start 257.722624 -50.682652)
		(end 257.722624 -50.666396)
		(width 0.1016)
		(layer "In5.Cu")
		(net "PCIE_TX_CAP_N23")
	)
	(segment
		(start 265.503152 -50.853086)
		(end 264.884408 -50.419762)
		(width 0.1397)
		(layer "In5.Cu")
		(net "PCIE_TX_CAP_N23")
	)
	(segment
		(start 261.060438 -50.840132)
		(end 259.7404 -50.840132)
		(width 0.1397)
		(layer "In5.Cu")
		(net "PCIE_TX_CAP_N23")
	)
	(segment
		(start 317.065406 -210.002374)
		(end 317.227458 -209.082386)
		(width 0.1397)
		(layer "In5.Cu")
		(net "PCIE_TX_CAP_N23")
	)
	(segment
		(start 264.884408 -50.419762)
		(end 264.860532 -50.402998)
		(width 0.1397)
		(layer "In5.Cu")
		(net "PCIE_TX_CAP_N23")
	)
	(segment
		(start 317.065152 -210.313778)
		(end 317.065406 -210.313778)
		(width 0.1397)
		(layer "In5.Cu")
		(net "PCIE_TX_CAP_N23")
	)
	(segment
		(start 317.227458 -209.082386)
		(end 316.945264 -207.481932)
		(width 0.1397)
		(layer "In5.Cu")
		(net "PCIE_TX_CAP_N23")
	)
	(segment
		(start 317.853568 -201.150728)
		(end 316.632336 -194.224148)
		(width 0.1397)
		(layer "In5.Cu")
		(net "PCIE_TX_CAP_N23")
	)
	(segment
		(start 257.762502 -50.582576)
		(end 257.7846 -50.560732)
		(width 0.1016)
		(layer "In5.Cu")
		(net "PCIE_TX_CAP_N23")
	)
	(segment
		(start 316.841378 -206.891382)
		(end 317.853568 -201.150728)
		(width 0.1397)
		(layer "In5.Cu")
		(net "PCIE_TX_CAP_N23")
	)
	(segment
		(start 317.065406 -210.313778)
		(end 317.065406 -210.002374)
		(width 0.1397)
		(layer "In5.Cu")
		(net "PCIE_TX_CAP_N23")
	)
	(segment
		(start 297.24477 -166.5351)
		(end 279.630632 -66.640456)
		(width 0.1397)
		(layer "In5.Cu")
		(net "PCIE_TX_CAP_N23")
	)
	(segment
		(start 316.632336 -194.224148)
		(end 297.24477 -166.5351)
		(width 0.1397)
		(layer "In5.Cu")
		(net "PCIE_TX_CAP_N23")
	)
	(segment
		(start 264.840466 -50.389028)
		(end 261.060438 -50.840132)
		(width 0.1397)
		(layer "In5.Cu")
		(net "PCIE_TX_CAP_N23")
	)
	(segment
		(start 259.623306 -50.888646)
		(end 258.070096 -50.888646)
		(width 0.1016)
		(layer "In5.Cu")
		(net "PCIE_TX_CAP_N23")
	)
	(segment
		(start 271.575276 -55.136542)
		(end 265.503152 -50.853086)
		(width 0.1397)
		(layer "In5.Cu")
		(net "PCIE_TX_CAP_N23")
	)
	(segment
		(start 316.945264 -207.481932)
		(end 316.841378 -206.891382)
		(width 0.1397)
		(layer "In5.Cu")
		(net "PCIE_TX_CAP_N23")
	)
	(arc
		(start 257.74142 -50.609246)
		(mid 257.751144 -50.595266)
		(end 257.762502 -50.582576)
		(width 0.1016)
		(layer "In5.Cu")
		(net "PCIE_TX_CAP_N23")
	)
	(arc
		(start 258.070096 -50.888646)
		(mid 257.951381 -50.877966)
		(end 257.836416 -50.846482)
		(width 0.1016)
		(layer "In5.Cu")
		(net "PCIE_TX_CAP_N23")
	)
	(arc
		(start 257.722624 -50.666396)
		(mid 257.72327 -50.660666)
		(end 257.724148 -50.654966)
		(width 0.1016)
		(layer "In5.Cu")
		(net "PCIE_TX_CAP_N23")
	)
	(arc
		(start 257.735832 -50.619152)
		(mid 257.737928 -50.615055)
		(end 257.74015 -50.611024)
		(width 0.1016)
		(layer "In5.Cu")
		(net "PCIE_TX_CAP_N23")
	)
	(arc
		(start 257.836416 -50.846482)
		(mid 257.764274 -50.795967)
		(end 257.725926 -50.716688)
		(width 0.1016)
		(layer "In5.Cu")
		(net "PCIE_TX_CAP_N23")
	)
	(arc
		(start 257.725926 -50.716688)
		(mid 257.723602 -50.701521)
		(end 257.722624 -50.686208)
		(width 0.1016)
		(layer "In5.Cu")
		(net "PCIE_TX_CAP_N23")
	)
	(arc
		(start 317.306706 -210.896454)
		(mid 317.127942 -210.629149)
		(end 317.065152 -210.313778)
		(width 0.1397)
		(layer "In5.Cu")
		(net "PCIE_TX_CAP_N23")
	)
	(arc
		(start 257.74015 -50.611024)
		(mid 257.740782 -50.610133)
		(end 257.74142 -50.609246)
		(width 0.1016)
		(layer "In5.Cu")
		(net "PCIE_TX_CAP_N23")
	)
	(arc
		(start 259.7404 -50.840132)
		(mid 259.686677 -50.876029)
		(end 259.623306 -50.888646)
		(width 0.1016)
		(layer "In5.Cu")
		(net "PCIE_TX_CAP_N23")
	)
	(arc
		(start 257.722624 -50.686208)
		(mid 257.722615 -50.68443)
		(end 257.722624 -50.682652)
		(width 0.1016)
		(layer "In5.Cu")
		(net "PCIE_TX_CAP_N23")
	)
	(arc
		(start 257.7846 -50.560732)
		(mid 257.852074 -50.515647)
		(end 257.931666 -50.499772)
		(width 0.1016)
		(layer "In5.Cu")
		(net "PCIE_TX_CAP_N23")
	)
	(arc
		(start 257.724148 -50.654966)
		(mid 257.728785 -50.636667)
		(end 257.735832 -50.619152)
		(width 0.1016)
		(layer "In5.Cu")
		(net "PCIE_TX_CAP_N23")
	)
	(segment
		(start 320.246248 -211.5312)
		(end 320.246248 -211.314538)
		(width 0.136652)
		(layer "F.Cu")
		(net "PCIE_TX_CAP_N22")
	)
	(segment
		(start 320.357754 -211.045298)
		(end 320.506598 -210.896454)
		(width 0.136652)
		(layer "F.Cu")
		(net "PCIE_TX_CAP_N22")
	)
	(segment
		(start 258.59994 -48.999902)
		(end 259.099812 -49.499774)
		(width 0.136652)
		(layer "F.Cu")
		(net "PCIE_TX_CAP_N22")
	)
	(segment
		(start 320.608198 -211.975954)
		(end 320.304922 -211.672424)
		(width 0.136652)
		(layer "F.Cu")
		(net "PCIE_TX_CAP_N22")
	)
	(via
		(at 259.099812 -49.499774)
		(size 0.4572)
		(drill 0.2032)
		(layers "F.Cu" "B.Cu")
		(net "PCIE_TX_CAP_N22")
	)
	(via
		(at 320.506598 -210.896454)
		(size 0.508)
		(drill 0.254)
		(layers "F.Cu" "B.Cu")
		(net "PCIE_TX_CAP_N22")
	)
	(arc
		(start 320.246248 -211.314538)
		(mid 320.275231 -211.168833)
		(end 320.357754 -211.045298)
		(width 0.136652)
		(layer "F.Cu")
		(net "PCIE_TX_CAP_N22")
	)
	(arc
		(start 320.304922 -211.672424)
		(mid 320.261545 -211.607645)
		(end 320.246248 -211.5312)
		(width 0.136652)
		(layer "F.Cu")
		(net "PCIE_TX_CAP_N22")
	)
	(segment
		(start 260.611874 -49.849532)
		(end 264.194544 -49.217834)
		(width 0.1397)
		(layer "In5.Cu")
		(net "PCIE_TX_CAP_N22")
	)
	(segment
		(start 322.07708 -201.27976)
		(end 321.930522 -202.110594)
		(width 0.1397)
		(layer "In5.Cu")
		(net "PCIE_TX_CAP_N22")
	)
	(segment
		(start 259.099812 -49.499774)
		(end 259.035296 -49.564544)
		(width 0.1016)
		(layer "In5.Cu")
		(net "PCIE_TX_CAP_N22")
	)
	(segment
		(start 321.857116 -202.526392)
		(end 321.677792 -203.543154)
		(width 0.1397)
		(layer "In5.Cu")
		(net "PCIE_TX_CAP_N22")
	)
	(segment
		(start 265.72845 -49.488344)
		(end 269.121382 -51.86426)
		(width 0.1397)
		(layer "In5.Cu")
		(net "PCIE_TX_CAP_N22")
	)
	(segment
		(start 320.265298 -209.86623)
		(end 320.265298 -210.313778)
		(width 0.1397)
		(layer "In5.Cu")
		(net "PCIE_TX_CAP_N22")
	)
	(segment
		(start 259.726684 -50.013616)
		(end 259.890768 -49.849532)
		(width 0.1016)
		(layer "In5.Cu")
		(net "PCIE_TX_CAP_N22")
	)
	(segment
		(start 259.890768 -49.849532)
		(end 260.611874 -49.849532)
		(width 0.1397)
		(layer "In5.Cu")
		(net "PCIE_TX_CAP_N22")
	)
	(segment
		(start 259.24002 -50.1015)
		(end 259.514594 -50.1015)
		(width 0.1016)
		(layer "In5.Cu")
		(net "PCIE_TX_CAP_N22")
	)
	(segment
		(start 322.306696 -199.976232)
		(end 322.07708 -201.27976)
		(width 0.1397)
		(layer "In5.Cu")
		(net "PCIE_TX_CAP_N22")
	)
	(segment
		(start 258.99364 -49.983644)
		(end 259.020564 -50.010568)
		(width 0.1016)
		(layer "In5.Cu")
		(net "PCIE_TX_CAP_N22")
	)
	(segment
		(start 319.92316 -207.926686)
		(end 320.265298 -209.86623)
		(width 0.1397)
		(layer "In5.Cu")
		(net "PCIE_TX_CAP_N22")
	)
	(segment
		(start 320.886836 -191.92367)
		(end 322.306696 -199.976232)
		(width 0.1397)
		(layer "In5.Cu")
		(net "PCIE_TX_CAP_N22")
	)
	(segment
		(start 321.476878 -204.682598)
		(end 320.164714 -206.555594)
		(width 0.1397)
		(layer "In5.Cu")
		(net "PCIE_TX_CAP_N22")
	)
	(segment
		(start 321.677792 -203.543154)
		(end 321.476878 -204.682598)
		(width 0.1397)
		(layer "In5.Cu")
		(net "PCIE_TX_CAP_N22")
	)
	(segment
		(start 269.121382 -51.86426)
		(end 272.502122 -54.231286)
		(width 0.1397)
		(layer "In5.Cu")
		(net "PCIE_TX_CAP_N22")
	)
	(segment
		(start 276.924008 -60.546742)
		(end 281.355038 -66.874644)
		(width 0.1397)
		(layer "In5.Cu")
		(net "PCIE_TX_CAP_N22")
	)
	(segment
		(start 264.194544 -49.217834)
		(end 265.72845 -49.488344)
		(width 0.1397)
		(layer "In5.Cu")
		(net "PCIE_TX_CAP_N22")
	)
	(segment
		(start 281.355038 -66.874644)
		(end 297.520614 -158.552896)
		(width 0.1397)
		(layer "In5.Cu")
		(net "PCIE_TX_CAP_N22")
	)
	(segment
		(start 321.930522 -202.110594)
		(end 321.857116 -202.526392)
		(width 0.1397)
		(layer "In5.Cu")
		(net "PCIE_TX_CAP_N22")
	)
	(segment
		(start 297.520614 -158.552896)
		(end 320.886836 -191.92367)
		(width 0.1397)
		(layer "In5.Cu")
		(net "PCIE_TX_CAP_N22")
	)
	(segment
		(start 320.164714 -206.555594)
		(end 319.92316 -207.926686)
		(width 0.1397)
		(layer "In5.Cu")
		(net "PCIE_TX_CAP_N22")
	)
	(segment
		(start 272.502122 -54.231286)
		(end 276.924008 -60.546742)
		(width 0.1397)
		(layer "In5.Cu")
		(net "PCIE_TX_CAP_N22")
	)
	(arc
		(start 259.514594 -50.1015)
		(mid 259.550679 -50.099229)
		(end 259.586222 -50.09261)
		(width 0.1016)
		(layer "In5.Cu")
		(net "PCIE_TX_CAP_N22")
	)
	(arc
		(start 259.035296 -49.564544)
		(mid 258.955633 -49.683629)
		(end 258.9276 -49.824132)
		(width 0.1016)
		(layer "In5.Cu")
		(net "PCIE_TX_CAP_N22")
	)
	(arc
		(start 259.586222 -50.09261)
		(mid 259.661861 -50.062728)
		(end 259.726684 -50.013616)
		(width 0.1016)
		(layer "In5.Cu")
		(net "PCIE_TX_CAP_N22")
	)
	(arc
		(start 259.059934 -50.043842)
		(mid 259.145488 -50.086691)
		(end 259.24002 -50.1015)
		(width 0.1016)
		(layer "In5.Cu")
		(net "PCIE_TX_CAP_N22")
	)
	(arc
		(start 320.265298 -210.313778)
		(mid 320.328019 -210.6291)
		(end 320.506598 -210.896454)
		(width 0.1397)
		(layer "In5.Cu")
		(net "PCIE_TX_CAP_N22")
	)
	(arc
		(start 258.9276 -49.824132)
		(mid 258.944769 -49.910447)
		(end 258.99364 -49.983644)
		(width 0.1016)
		(layer "In5.Cu")
		(net "PCIE_TX_CAP_N22")
	)
	(arc
		(start 259.020564 -50.010568)
		(mid 259.039556 -50.028025)
		(end 259.059934 -50.043842)
		(width 0.1016)
		(layer "In5.Cu")
		(net "PCIE_TX_CAP_N22")
	)
	(segment
		(start 257.599942 -47.999904)
		(end 258.099814 -48.499776)
		(width 0.136652)
		(layer "F.Cu")
		(net "PCIE_TX_CAP_N21")
	)
	(segment
		(start 323.539104 -211.063586)
		(end 323.70649 -210.896454)
		(width 0.136652)
		(layer "F.Cu")
		(net "PCIE_TX_CAP_N21")
	)
	(segment
		(start 323.44614 -211.5312)
		(end 323.44614 -211.288376)
		(width 0.136652)
		(layer "F.Cu")
		(net "PCIE_TX_CAP_N21")
	)
	(segment
		(start 323.80809 -211.975954)
		(end 323.504814 -211.672424)
		(width 0.136652)
		(layer "F.Cu")
		(net "PCIE_TX_CAP_N21")
	)
	(via
		(at 323.70649 -210.896454)
		(size 0.508)
		(drill 0.254)
		(layers "F.Cu" "B.Cu")
		(net "PCIE_TX_CAP_N21")
	)
	(via
		(at 258.099814 -48.499776)
		(size 0.4572)
		(drill 0.2032)
		(layers "F.Cu" "B.Cu")
		(net "PCIE_TX_CAP_N21")
	)
	(arc
		(start 323.504814 -211.672424)
		(mid 323.461437 -211.607645)
		(end 323.44614 -211.5312)
		(width 0.136652)
		(layer "F.Cu")
		(net "PCIE_TX_CAP_N21")
	)
	(arc
		(start 323.44614 -211.288376)
		(mid 323.470245 -211.166723)
		(end 323.539104 -211.063586)
		(width 0.136652)
		(layer "F.Cu")
		(net "PCIE_TX_CAP_N21")
	)
	(segment
		(start 323.46519 -209.698844)
		(end 322.946268 -206.756)
		(width 0.1397)
		(layer "In5.Cu")
		(net "PCIE_TX_CAP_N21")
	)
	(segment
		(start 323.957188 -201.022966)
		(end 321.945 -189.611)
		(width 0.1397)
		(layer "In5.Cu")
		(net "PCIE_TX_CAP_N21")
	)
	(segment
		(start 321.945 -189.611)
		(end 298.088558 -155.540456)
		(width 0.1397)
		(layer "In5.Cu")
		(net "PCIE_TX_CAP_N21")
	)
	(segment
		(start 260.219444 -48.840136)
		(end 259.7404 -48.840136)
		(width 0.1397)
		(layer "In5.Cu")
		(net "PCIE_TX_CAP_N21")
	)
	(segment
		(start 273.038062 -53.269388)
		(end 266.065 -48.387)
		(width 0.1397)
		(layer "In5.Cu")
		(net "PCIE_TX_CAP_N21")
	)
	(segment
		(start 257.931666 -48.499776)
		(end 258.099814 -48.499776)
		(width 0.1016)
		(layer "In5.Cu")
		(net "PCIE_TX_CAP_N21")
	)
	(segment
		(start 322.946268 -206.756)
		(end 323.957188 -201.022966)
		(width 0.1397)
		(layer "In5.Cu")
		(net "PCIE_TX_CAP_N21")
	)
	(segment
		(start 257.762502 -48.58258)
		(end 257.7846 -48.560736)
		(width 0.1016)
		(layer "In5.Cu")
		(net "PCIE_TX_CAP_N21")
	)
	(segment
		(start 259.623306 -48.88865)
		(end 258.070096 -48.88865)
		(width 0.1016)
		(layer "In5.Cu")
		(net "PCIE_TX_CAP_N21")
	)
	(segment
		(start 298.088558 -155.540456)
		(end 282.415996 -66.6623)
		(width 0.1397)
		(layer "In5.Cu")
		(net "PCIE_TX_CAP_N21")
	)
	(segment
		(start 257.722624 -48.682656)
		(end 257.722624 -48.6664)
		(width 0.1016)
		(layer "In5.Cu")
		(net "PCIE_TX_CAP_N21")
	)
	(segment
		(start 323.46519 -210.313778)
		(end 323.46519 -209.698844)
		(width 0.1397)
		(layer "In5.Cu")
		(net "PCIE_TX_CAP_N21")
	)
	(segment
		(start 266.065 -48.387)
		(end 264.4267 -48.098202)
		(width 0.1397)
		(layer "In5.Cu")
		(net "PCIE_TX_CAP_N21")
	)
	(segment
		(start 282.415996 -66.6623)
		(end 273.038062 -53.269388)
		(width 0.1397)
		(layer "In5.Cu")
		(net "PCIE_TX_CAP_N21")
	)
	(segment
		(start 264.4267 -48.098202)
		(end 260.219444 -48.840136)
		(width 0.1397)
		(layer "In5.Cu")
		(net "PCIE_TX_CAP_N21")
	)
	(arc
		(start 258.070096 -48.88865)
		(mid 257.951381 -48.87797)
		(end 257.836416 -48.846486)
		(width 0.1016)
		(layer "In5.Cu")
		(net "PCIE_TX_CAP_N21")
	)
	(arc
		(start 257.724148 -48.65497)
		(mid 257.728785 -48.636671)
		(end 257.735832 -48.619156)
		(width 0.1016)
		(layer "In5.Cu")
		(net "PCIE_TX_CAP_N21")
	)
	(arc
		(start 323.70649 -210.896454)
		(mid 323.527863 -210.62912)
		(end 323.46519 -210.313778)
		(width 0.1397)
		(layer "In5.Cu")
		(net "PCIE_TX_CAP_N21")
	)
	(arc
		(start 257.7846 -48.560736)
		(mid 257.852074 -48.515651)
		(end 257.931666 -48.499776)
		(width 0.1016)
		(layer "In5.Cu")
		(net "PCIE_TX_CAP_N21")
	)
	(arc
		(start 257.722624 -48.6664)
		(mid 257.72327 -48.66067)
		(end 257.724148 -48.65497)
		(width 0.1016)
		(layer "In5.Cu")
		(net "PCIE_TX_CAP_N21")
	)
	(arc
		(start 257.74015 -48.611028)
		(mid 257.740782 -48.610137)
		(end 257.74142 -48.60925)
		(width 0.1016)
		(layer "In5.Cu")
		(net "PCIE_TX_CAP_N21")
	)
	(arc
		(start 257.735832 -48.619156)
		(mid 257.737928 -48.615059)
		(end 257.74015 -48.611028)
		(width 0.1016)
		(layer "In5.Cu")
		(net "PCIE_TX_CAP_N21")
	)
	(arc
		(start 257.836416 -48.846486)
		(mid 257.764274 -48.795971)
		(end 257.725926 -48.716692)
		(width 0.1016)
		(layer "In5.Cu")
		(net "PCIE_TX_CAP_N21")
	)
	(arc
		(start 257.722624 -48.686212)
		(mid 257.722615 -48.684434)
		(end 257.722624 -48.682656)
		(width 0.1016)
		(layer "In5.Cu")
		(net "PCIE_TX_CAP_N21")
	)
	(arc
		(start 257.725926 -48.716692)
		(mid 257.723602 -48.701525)
		(end 257.722624 -48.686212)
		(width 0.1016)
		(layer "In5.Cu")
		(net "PCIE_TX_CAP_N21")
	)
	(arc
		(start 257.74142 -48.60925)
		(mid 257.751144 -48.59527)
		(end 257.762502 -48.58258)
		(width 0.1016)
		(layer "In5.Cu")
		(net "PCIE_TX_CAP_N21")
	)
	(arc
		(start 259.7404 -48.840136)
		(mid 259.686677 -48.876033)
		(end 259.623306 -48.88865)
		(width 0.1016)
		(layer "In5.Cu")
		(net "PCIE_TX_CAP_N21")
	)
	(segment
		(start 326.646032 -211.5312)
		(end 326.646032 -211.276946)
		(width 0.136652)
		(layer "F.Cu")
		(net "PCIE_TX_CAP_N20")
	)
	(segment
		(start 258.59994 -46.999906)
		(end 259.099812 -46.500034)
		(width 0.136652)
		(layer "F.Cu")
		(net "PCIE_TX_CAP_N20")
	)
	(segment
		(start 326.721724 -211.080858)
		(end 326.906382 -210.896454)
		(width 0.136652)
		(layer "F.Cu")
		(net "PCIE_TX_CAP_N20")
	)
	(segment
		(start 327.007982 -211.975954)
		(end 326.704706 -211.672424)
		(width 0.136652)
		(layer "F.Cu")
		(net "PCIE_TX_CAP_N20")
	)
	(via
		(at 326.906382 -210.896454)
		(size 0.508)
		(drill 0.254)
		(layers "F.Cu" "B.Cu")
		(net "PCIE_TX_CAP_N20")
	)
	(via
		(at 259.099812 -46.500034)
		(size 0.4572)
		(drill 0.2032)
		(layers "F.Cu" "B.Cu")
		(net "PCIE_TX_CAP_N20")
	)
	(arc
		(start 326.646032 -211.276946)
		(mid 326.646064 -211.270469)
		(end 326.646032 -211.263992)
		(width 0.136652)
		(layer "F.Cu")
		(net "PCIE_TX_CAP_N20")
	)
	(arc
		(start 326.704706 -211.672424)
		(mid 326.661329 -211.607645)
		(end 326.646032 -211.5312)
		(width 0.136652)
		(layer "F.Cu")
		(net "PCIE_TX_CAP_N20")
	)
	(arc
		(start 326.646032 -211.263992)
		(mid 326.665651 -211.16489)
		(end 326.721724 -211.080858)
		(width 0.136652)
		(layer "F.Cu")
		(net "PCIE_TX_CAP_N20")
	)
	(segment
		(start 258.827778 -47.118778)
		(end 258.953 -47.244)
		(width 0.1397)
		(layer "In5.Cu")
		(net "PCIE_TX_CAP_N20")
	)
	(segment
		(start 324.538848 -189.608714)
		(end 326.39889 -200.158096)
		(width 0.1397)
		(layer "In5.Cu")
		(net "PCIE_TX_CAP_N20")
	)
	(segment
		(start 327.025 -203.708)
		(end 326.326754 -207.66786)
		(width 0.1397)
		(layer "In5.Cu")
		(net "PCIE_TX_CAP_N20")
	)
	(segment
		(start 263.51103 -46.644814)
		(end 266.771628 -47.219362)
		(width 0.1397)
		(layer "In5.Cu")
		(net "PCIE_TX_CAP_N20")
	)
	(segment
		(start 327.01484 -203.65085)
		(end 327.015094 -203.65085)
		(width 0.1397)
		(layer "In5.Cu")
		(net "PCIE_TX_CAP_N20")
	)
	(segment
		(start 301.343822 -156.48305)
		(end 324.538848 -189.608714)
		(width 0.1397)
		(layer "In5.Cu")
		(net "PCIE_TX_CAP_N20")
	)
	(segment
		(start 326.326754 -207.66786)
		(end 326.665082 -209.58683)
		(width 0.1397)
		(layer "In5.Cu")
		(net "PCIE_TX_CAP_N20")
	)
	(segment
		(start 259.099812 -46.500034)
		(end 258.858766 -46.74108)
		(width 0.1397)
		(layer "In5.Cu")
		(net "PCIE_TX_CAP_N20")
	)
	(segment
		(start 274.48764 -52.602892)
		(end 282.645104 -64.25311)
		(width 0.1397)
		(layer "In5.Cu")
		(net "PCIE_TX_CAP_N20")
	)
	(segment
		(start 282.645104 -64.25311)
		(end 286.853376 -74.369168)
		(width 0.1397)
		(layer "In5.Cu")
		(net "PCIE_TX_CAP_N20")
	)
	(segment
		(start 286.853376 -74.369168)
		(end 301.343822 -156.48305)
		(width 0.1397)
		(layer "In5.Cu")
		(net "PCIE_TX_CAP_N20")
	)
	(segment
		(start 326.665082 -209.58683)
		(end 326.665082 -210.313778)
		(width 0.1397)
		(layer "In5.Cu")
		(net "PCIE_TX_CAP_N20")
	)
	(segment
		(start 259.234686 -47.370238)
		(end 263.34847 -46.644814)
		(width 0.1397)
		(layer "In5.Cu")
		(net "PCIE_TX_CAP_N20")
	)
	(segment
		(start 326.39889 -200.158096)
		(end 327.01484 -203.65085)
		(width 0.1397)
		(layer "In5.Cu")
		(net "PCIE_TX_CAP_N20")
	)
	(segment
		(start 327.015094 -203.65085)
		(end 327.025 -203.708)
		(width 0.1397)
		(layer "In5.Cu")
		(net "PCIE_TX_CAP_N20")
	)
	(segment
		(start 266.959588 -47.297086)
		(end 274.372324 -52.487576)
		(width 0.1397)
		(layer "In5.Cu")
		(net "PCIE_TX_CAP_N20")
	)
	(arc
		(start 258.953 -47.244)
		(mid 259.082223 -47.333055)
		(end 259.234686 -47.370238)
		(width 0.1397)
		(layer "In5.Cu")
		(net "PCIE_TX_CAP_N20")
	)
	(arc
		(start 274.372324 -52.487576)
		(mid 274.435024 -52.540192)
		(end 274.48764 -52.602892)
		(width 0.1397)
		(layer "In5.Cu")
		(net "PCIE_TX_CAP_N20")
	)
	(arc
		(start 263.34847 -46.644814)
		(mid 263.42975 -46.637734)
		(end 263.51103 -46.644814)
		(width 0.1397)
		(layer "In5.Cu")
		(net "PCIE_TX_CAP_N20")
	)
	(arc
		(start 258.858766 -46.74108)
		(mid 258.789387 -46.844914)
		(end 258.76504 -46.967394)
		(width 0.1397)
		(layer "In5.Cu")
		(net "PCIE_TX_CAP_N20")
	)
	(arc
		(start 258.76504 -46.967394)
		(mid 258.781339 -47.049335)
		(end 258.827778 -47.118778)
		(width 0.1397)
		(layer "In5.Cu")
		(net "PCIE_TX_CAP_N20")
	)
	(arc
		(start 326.665082 -210.313778)
		(mid 326.727803 -210.6291)
		(end 326.906382 -210.896454)
		(width 0.1397)
		(layer "In5.Cu")
		(net "PCIE_TX_CAP_N20")
	)
	(arc
		(start 266.771628 -47.219362)
		(mid 266.869868 -47.247925)
		(end 266.959588 -47.297086)
		(width 0.1397)
		(layer "In5.Cu")
		(net "PCIE_TX_CAP_N20")
	)
	(segment
		(start 285.369 -33.5788)
		(end 285.635446 -33.5788)
		(width 0.136652)
		(layer "F.Cu")
		(net "PCIE_TX_CAP_N2")
	)
	(segment
		(start 284.988254 -33.864296)
		(end 285.20644 -33.64611)
		(width 0.136652)
		(layer "F.Cu")
		(net "PCIE_TX_CAP_N2")
	)
	(segment
		(start 253.59995 -29.99994)
		(end 254.099822 -29.500068)
		(width 0.136652)
		(layer "F.Cu")
		(net "PCIE_TX_CAP_N2")
	)
	(segment
		(start 285.85287 -33.668716)
		(end 286.0421 -33.8582)
		(width 0.136652)
		(layer "F.Cu")
		(net "PCIE_TX_CAP_N2")
	)
	(via
		(at 284.988254 -33.864296)
		(size 0.508)
		(drill 0.254)
		(layers "F.Cu" "B.Cu")
		(net "PCIE_TX_CAP_N2")
	)
	(via
		(at 254.099822 -29.500068)
		(size 0.4572)
		(drill 0.2032)
		(layers "F.Cu" "B.Cu")
		(net "PCIE_TX_CAP_N2")
	)
	(arc
		(start 285.635446 -33.5788)
		(mid 285.753114 -33.602112)
		(end 285.85287 -33.668716)
		(width 0.136652)
		(layer "F.Cu")
		(net "PCIE_TX_CAP_N2")
	)
	(arc
		(start 285.20644 -33.64611)
		(mid 285.281023 -33.596275)
		(end 285.369 -33.5788)
		(width 0.136652)
		(layer "F.Cu")
		(net "PCIE_TX_CAP_N2")
	)
	(segment
		(start 254.73533 -24.657558)
		(end 257.264408 -22.886924)
		(width 0.1397)
		(layer "In5.Cu")
		(net "PCIE_TX_CAP_N2")
	)
	(segment
		(start 282.081732 -27.96286)
		(end 282.5369 -30.543754)
		(width 0.1397)
		(layer "In5.Cu")
		(net "PCIE_TX_CAP_N2")
	)
	(segment
		(start 253.619 -26.25217)
		(end 254.73533 -24.657558)
		(width 0.1397)
		(layer "In5.Cu")
		(net "PCIE_TX_CAP_N2")
	)
	(segment
		(start 282.5369 -30.543754)
		(end 282.392628 -30.749748)
		(width 0.1397)
		(layer "In5.Cu")
		(net "PCIE_TX_CAP_N2")
	)
	(segment
		(start 282.392628 -30.749748)
		(end 282.465272 -31.162498)
		(width 0.1397)
		(layer "In5.Cu")
		(net "PCIE_TX_CAP_N2")
	)
	(segment
		(start 283.115258 -33.014412)
		(end 283.993336 -33.6296)
		(width 0.1397)
		(layer "In5.Cu")
		(net "PCIE_TX_CAP_N2")
	)
	(segment
		(start 257.264408 -22.886924)
		(end 260.39318 -22.222206)
		(width 0.1397)
		(layer "In5.Cu")
		(net "PCIE_TX_CAP_N2")
	)
	(segment
		(start 253.619 -29.0322)
		(end 253.619 -26.25217)
		(width 0.1397)
		(layer "In5.Cu")
		(net "PCIE_TX_CAP_N2")
	)
	(segment
		(start 282.671266 -31.30677)
		(end 282.924504 -32.742124)
		(width 0.1397)
		(layer "In5.Cu")
		(net "PCIE_TX_CAP_N2")
	)
	(segment
		(start 260.39318 -22.222206)
		(end 263.650476 -22.91461)
		(width 0.1397)
		(layer "In5.Cu")
		(net "PCIE_TX_CAP_N2")
	)
	(segment
		(start 254.2794 -29.679646)
		(end 254.2794 -29.94914)
		(width 0.1016)
		(layer "In5.Cu")
		(net "PCIE_TX_CAP_N2")
	)
	(segment
		(start 279.847548 -24.771604)
		(end 282.081732 -27.96286)
		(width 0.1397)
		(layer "In5.Cu")
		(net "PCIE_TX_CAP_N2")
	)
	(segment
		(start 282.465272 -31.162498)
		(end 282.671266 -31.30677)
		(width 0.1397)
		(layer "In5.Cu")
		(net "PCIE_TX_CAP_N2")
	)
	(segment
		(start 253.5555 -29.1211)
		(end 253.619 -29.0576)
		(width 0.1016)
		(layer "In5.Cu")
		(net "PCIE_TX_CAP_N2")
	)
	(segment
		(start 283.993336 -33.6296)
		(end 284.498796 -33.6296)
		(width 0.1397)
		(layer "In5.Cu")
		(net "PCIE_TX_CAP_N2")
	)
	(segment
		(start 274.942554 -21.585682)
		(end 279.847548 -24.771604)
		(width 0.1397)
		(layer "In5.Cu")
		(net "PCIE_TX_CAP_N2")
	)
	(segment
		(start 254.156972 -30.071568)
		(end 254.034798 -30.071568)
		(width 0.1016)
		(layer "In5.Cu")
		(net "PCIE_TX_CAP_N2")
	)
	(segment
		(start 253.90602 -30.018228)
		(end 253.905512 -30.018228)
		(width 0.1016)
		(layer "In5.Cu")
		(net "PCIE_TX_CAP_N2")
	)
	(segment
		(start 253.619 -29.0576)
		(end 253.619 -29.0322)
		(width 0.1016)
		(layer "In5.Cu")
		(net "PCIE_TX_CAP_N2")
	)
	(segment
		(start 282.924504 -32.742124)
		(end 283.115258 -33.014412)
		(width 0.1397)
		(layer "In5.Cu")
		(net "PCIE_TX_CAP_N2")
	)
	(segment
		(start 253.905512 -30.018228)
		(end 253.762256 -29.874972)
		(width 0.1016)
		(layer "In5.Cu")
		(net "PCIE_TX_CAP_N2")
	)
	(segment
		(start 253.5555 -29.3624)
		(end 253.5555 -29.1211)
		(width 0.1016)
		(layer "In5.Cu")
		(net "PCIE_TX_CAP_N2")
	)
	(segment
		(start 272.422874 -21.049996)
		(end 274.942554 -21.585682)
		(width 0.1397)
		(layer "In5.Cu")
		(net "PCIE_TX_CAP_N2")
	)
	(segment
		(start 263.650476 -22.91461)
		(end 272.422874 -21.049996)
		(width 0.1397)
		(layer "In5.Cu")
		(net "PCIE_TX_CAP_N2")
	)
	(segment
		(start 284.933644 -33.809686)
		(end 284.988254 -33.864296)
		(width 0.1397)
		(layer "In5.Cu")
		(net "PCIE_TX_CAP_N2")
	)
	(arc
		(start 284.498796 -33.6296)
		(mid 284.734121 -33.676409)
		(end 284.933644 -33.809686)
		(width 0.1397)
		(layer "In5.Cu")
		(net "PCIE_TX_CAP_N2")
	)
	(arc
		(start 254.2794 -29.94914)
		(mid 254.243542 -30.03571)
		(end 254.156972 -30.071568)
		(width 0.1016)
		(layer "In5.Cu")
		(net "PCIE_TX_CAP_N2")
	)
	(arc
		(start 254.099822 -29.500068)
		(mid 254.226803 -29.552665)
		(end 254.2794 -29.679646)
		(width 0.1016)
		(layer "In5.Cu")
		(net "PCIE_TX_CAP_N2")
	)
	(arc
		(start 253.762256 -29.874972)
		(mid 253.609114 -29.638756)
		(end 253.5555 -29.3624)
		(width 0.1016)
		(layer "In5.Cu")
		(net "PCIE_TX_CAP_N2")
	)
	(arc
		(start 254.034798 -30.071568)
		(mid 253.965104 -30.057705)
		(end 253.90602 -30.018228)
		(width 0.1016)
		(layer "In5.Cu")
		(net "PCIE_TX_CAP_N2")
	)
	(segment
		(start 333.40802 -211.975446)
		(end 333.104998 -211.672424)
		(width 0.136652)
		(layer "F.Cu")
		(net "PCIE_TX_CAP_N19")
	)
	(segment
		(start 333.40802 -211.975954)
		(end 333.40802 -211.975446)
		(width 0.136652)
		(layer "F.Cu")
		(net "PCIE_TX_CAP_N19")
	)
	(segment
		(start 333.158338 -211.045044)
		(end 333.306674 -210.896454)
		(width 0.136652)
		(layer "F.Cu")
		(net "PCIE_TX_CAP_N19")
	)
	(segment
		(start 333.046324 -211.5312)
		(end 333.046324 -211.315046)
		(width 0.136652)
		(layer "F.Cu")
		(net "PCIE_TX_CAP_N19")
	)
	(segment
		(start 257.599942 -45.999908)
		(end 258.099814 -45.500036)
		(width 0.136652)
		(layer "F.Cu")
		(net "PCIE_TX_CAP_N19")
	)
	(via
		(at 258.099814 -45.500036)
		(size 0.4572)
		(drill 0.2032)
		(layers "F.Cu" "B.Cu")
		(net "PCIE_TX_CAP_N19")
	)
	(via
		(at 333.306674 -210.896454)
		(size 0.508)
		(drill 0.254)
		(layers "F.Cu" "B.Cu")
		(net "PCIE_TX_CAP_N19")
	)
	(arc
		(start 333.046324 -211.315046)
		(mid 333.075486 -211.168908)
		(end 333.158338 -211.045044)
		(width 0.136652)
		(layer "F.Cu")
		(net "PCIE_TX_CAP_N19")
	)
	(arc
		(start 333.104998 -211.672424)
		(mid 333.061621 -211.607645)
		(end 333.046324 -211.5312)
		(width 0.136652)
		(layer "F.Cu")
		(net "PCIE_TX_CAP_N19")
	)
	(segment
		(start 303.916842 -158.207964)
		(end 303.916842 -158.208218)
		(width 0.1397)
		(layer "In5.Cu")
		(net "PCIE_TX_CAP_N19")
	)
	(segment
		(start 258.070096 -45.88891)
		(end 259.623306 -45.88891)
		(width 0.1016)
		(layer "In5.Cu")
		(net "PCIE_TX_CAP_N19")
	)
	(segment
		(start 263.554464 -45.252386)
		(end 266.785852 -45.822108)
		(width 0.1397)
		(layer "In5.Cu")
		(net "PCIE_TX_CAP_N19")
	)
	(segment
		(start 257.7846 -45.560996)
		(end 257.762502 -45.58284)
		(width 0.1016)
		(layer "In5.Cu")
		(net "PCIE_TX_CAP_N19")
	)
	(segment
		(start 333.065374 -199.836786)
		(end 333.105506 -199.962516)
		(width 0.1397)
		(layer "In5.Cu")
		(net "PCIE_TX_CAP_N19")
	)
	(segment
		(start 258.099814 -45.500036)
		(end 257.931666 -45.500036)
		(width 0.1016)
		(layer "In5.Cu")
		(net "PCIE_TX_CAP_N19")
	)
	(segment
		(start 297.03776 -118.987824)
		(end 303.916842 -158.207964)
		(width 0.1397)
		(layer "In5.Cu")
		(net "PCIE_TX_CAP_N19")
	)
	(segment
		(start 333.005684 -199.75195)
		(end 333.005938 -199.75195)
		(width 0.1397)
		(layer "In5.Cu")
		(net "PCIE_TX_CAP_N19")
	)
	(segment
		(start 333.302102 -208.038954)
		(end 333.065374 -209.381598)
		(width 0.1397)
		(layer "In5.Cu")
		(net "PCIE_TX_CAP_N19")
	)
	(segment
		(start 333.421228 -200.987152)
		(end 332.74 -204.851)
		(width 0.1397)
		(layer "In5.Cu")
		(net "PCIE_TX_CAP_N19")
	)
	(segment
		(start 275.524976 -51.941476)
		(end 283.059378 -62.702186)
		(width 0.1397)
		(layer "In5.Cu")
		(net "PCIE_TX_CAP_N19")
	)
	(segment
		(start 332.74 -204.851)
		(end 333.302102 -208.038954)
		(width 0.1397)
		(layer "In5.Cu")
		(net "PCIE_TX_CAP_N19")
	)
	(segment
		(start 283.059378 -62.702186)
		(end 290.158678 -79.767938)
		(width 0.1397)
		(layer "In5.Cu")
		(net "PCIE_TX_CAP_N19")
	)
	(segment
		(start 260.218682 -45.840396)
		(end 263.554464 -45.252386)
		(width 0.1397)
		(layer "In5.Cu")
		(net "PCIE_TX_CAP_N19")
	)
	(segment
		(start 333.065374 -209.381598)
		(end 333.065374 -210.313778)
		(width 0.1397)
		(layer "In5.Cu")
		(net "PCIE_TX_CAP_N19")
	)
	(segment
		(start 333.005938 -199.75195)
		(end 333.065374 -199.836786)
		(width 0.1397)
		(layer "In5.Cu")
		(net "PCIE_TX_CAP_N19")
	)
	(segment
		(start 290.158678 -79.767938)
		(end 297.03776 -118.987824)
		(width 0.1397)
		(layer "In5.Cu")
		(net "PCIE_TX_CAP_N19")
	)
	(segment
		(start 333.099918 -199.972676)
		(end 333.421228 -200.987152)
		(width 0.1397)
		(layer "In5.Cu")
		(net "PCIE_TX_CAP_N19")
	)
	(segment
		(start 259.7404 -45.840396)
		(end 260.218682 -45.840396)
		(width 0.1397)
		(layer "In5.Cu")
		(net "PCIE_TX_CAP_N19")
	)
	(segment
		(start 333.105506 -199.962516)
		(end 333.099918 -199.972676)
		(width 0.1397)
		(layer "In5.Cu")
		(net "PCIE_TX_CAP_N19")
	)
	(segment
		(start 257.722624 -45.66666)
		(end 257.722624 -45.682916)
		(width 0.1016)
		(layer "In5.Cu")
		(net "PCIE_TX_CAP_N19")
	)
	(segment
		(start 266.785852 -45.822108)
		(end 275.524976 -51.941476)
		(width 0.1397)
		(layer "In5.Cu")
		(net "PCIE_TX_CAP_N19")
	)
	(segment
		(start 303.916842 -158.208218)
		(end 333.005684 -199.75195)
		(width 0.1397)
		(layer "In5.Cu")
		(net "PCIE_TX_CAP_N19")
	)
	(arc
		(start 257.722624 -45.686472)
		(mid 257.723609 -45.701784)
		(end 257.725926 -45.716952)
		(width 0.1016)
		(layer "In5.Cu")
		(net "PCIE_TX_CAP_N19")
	)
	(arc
		(start 333.065374 -210.313778)
		(mid 333.128095 -210.6291)
		(end 333.306674 -210.896454)
		(width 0.1397)
		(layer "In5.Cu")
		(net "PCIE_TX_CAP_N19")
	)
	(arc
		(start 257.74142 -45.60951)
		(mid 257.740782 -45.610397)
		(end 257.74015 -45.611288)
		(width 0.1016)
		(layer "In5.Cu")
		(net "PCIE_TX_CAP_N19")
	)
	(arc
		(start 259.623306 -45.88891)
		(mid 259.686681 -45.876304)
		(end 259.7404 -45.840396)
		(width 0.1016)
		(layer "In5.Cu")
		(net "PCIE_TX_CAP_N19")
	)
	(arc
		(start 257.735832 -45.619416)
		(mid 257.728755 -45.636921)
		(end 257.724148 -45.65523)
		(width 0.1016)
		(layer "In5.Cu")
		(net "PCIE_TX_CAP_N19")
	)
	(arc
		(start 257.724148 -45.65523)
		(mid 257.723265 -45.660929)
		(end 257.722624 -45.66666)
		(width 0.1016)
		(layer "In5.Cu")
		(net "PCIE_TX_CAP_N19")
	)
	(arc
		(start 257.931666 -45.500036)
		(mid 257.852058 -45.515871)
		(end 257.7846 -45.560996)
		(width 0.1016)
		(layer "In5.Cu")
		(net "PCIE_TX_CAP_N19")
	)
	(arc
		(start 257.725926 -45.716952)
		(mid 257.764281 -45.796226)
		(end 257.836416 -45.846746)
		(width 0.1016)
		(layer "In5.Cu")
		(net "PCIE_TX_CAP_N19")
	)
	(arc
		(start 257.722624 -45.682916)
		(mid 257.722615 -45.684694)
		(end 257.722624 -45.686472)
		(width 0.1016)
		(layer "In5.Cu")
		(net "PCIE_TX_CAP_N19")
	)
	(arc
		(start 257.836416 -45.846746)
		(mid 257.951374 -45.878269)
		(end 258.070096 -45.88891)
		(width 0.1016)
		(layer "In5.Cu")
		(net "PCIE_TX_CAP_N19")
	)
	(arc
		(start 257.762502 -45.58284)
		(mid 257.751139 -45.595525)
		(end 257.74142 -45.60951)
		(width 0.1016)
		(layer "In5.Cu")
		(net "PCIE_TX_CAP_N19")
	)
	(arc
		(start 257.74015 -45.611288)
		(mid 257.737919 -45.615314)
		(end 257.735832 -45.619416)
		(width 0.1016)
		(layer "In5.Cu")
		(net "PCIE_TX_CAP_N19")
	)
	(segment
		(start 258.59994 -44.99991)
		(end 259.099812 -44.500038)
		(width 0.136652)
		(layer "F.Cu")
		(net "PCIE_TX_CAP_N18")
	)
	(segment
		(start 336.246216 -211.5312)
		(end 336.246216 -211.2518)
		(width 0.136652)
		(layer "F.Cu")
		(net "PCIE_TX_CAP_N18")
	)
	(segment
		(start 336.312002 -211.091018)
		(end 336.506566 -210.896454)
		(width 0.136652)
		(layer "F.Cu")
		(net "PCIE_TX_CAP_N18")
	)
	(segment
		(start 336.608166 -211.975954)
		(end 336.30489 -211.672424)
		(width 0.136652)
		(layer "F.Cu")
		(net "PCIE_TX_CAP_N18")
	)
	(via
		(at 259.099812 -44.500038)
		(size 0.4572)
		(drill 0.2032)
		(layers "F.Cu" "B.Cu")
		(net "PCIE_TX_CAP_N18")
	)
	(via
		(at 336.506566 -210.896454)
		(size 0.508)
		(drill 0.254)
		(layers "F.Cu" "B.Cu")
		(net "PCIE_TX_CAP_N18")
	)
	(arc
		(start 336.246216 -211.249768)
		(mid 336.263308 -211.163842)
		(end 336.312002 -211.091018)
		(width 0.136652)
		(layer "F.Cu")
		(net "PCIE_TX_CAP_N18")
	)
	(arc
		(start 336.30489 -211.672424)
		(mid 336.261513 -211.607645)
		(end 336.246216 -211.5312)
		(width 0.136652)
		(layer "F.Cu")
		(net "PCIE_TX_CAP_N18")
	)
	(arc
		(start 336.246216 -211.2518)
		(mid 336.246217 -211.250784)
		(end 336.246216 -211.249768)
		(width 0.136652)
		(layer "F.Cu")
		(net "PCIE_TX_CAP_N18")
	)
	(segment
		(start 336.26044 -203.971144)
		(end 336.26044 -203.97089)
		(width 0.1397)
		(layer "In5.Cu")
		(net "PCIE_TX_CAP_N18")
	)
	(segment
		(start 336.26044 -203.97089)
		(end 336.265266 -203.998322)
		(width 0.1397)
		(layer "In5.Cu")
		(net "PCIE_TX_CAP_N18")
	)
	(segment
		(start 263.57072 -44.32808)
		(end 268.010132 -45.110908)
		(width 0.1397)
		(layer "In5.Cu")
		(net "PCIE_TX_CAP_N18")
	)
	(segment
		(start 336.046826 -202.759818)
		(end 336.26044 -203.971144)
		(width 0.1397)
		(layer "In5.Cu")
		(net "PCIE_TX_CAP_N18")
	)
	(segment
		(start 336.265266 -203.998322)
		(end 336.265266 -210.313778)
		(width 0.1397)
		(layer "In5.Cu")
		(net "PCIE_TX_CAP_N18")
	)
	(segment
		(start 259.24002 -45.101764)
		(end 259.514594 -45.101764)
		(width 0.1016)
		(layer "In5.Cu")
		(net "PCIE_TX_CAP_N18")
	)
	(segment
		(start 259.099812 -44.500038)
		(end 259.035296 -44.564808)
		(width 0.1016)
		(layer "In5.Cu")
		(net "PCIE_TX_CAP_N18")
	)
	(segment
		(start 271.896078 -47.83201)
		(end 275.769324 -50.543968)
		(width 0.1397)
		(layer "In5.Cu")
		(net "PCIE_TX_CAP_N18")
	)
	(segment
		(start 283.337254 -61.352684)
		(end 291.715952 -81.493868)
		(width 0.1397)
		(layer "In5.Cu")
		(net "PCIE_TX_CAP_N18")
	)
	(segment
		(start 259.726684 -45.01388)
		(end 259.890768 -44.849796)
		(width 0.1016)
		(layer "In5.Cu")
		(net "PCIE_TX_CAP_N18")
	)
	(segment
		(start 260.611874 -44.849796)
		(end 263.57072 -44.32808)
		(width 0.1397)
		(layer "In5.Cu")
		(net "PCIE_TX_CAP_N18")
	)
	(segment
		(start 268.010132 -45.110908)
		(end 271.896078 -47.83201)
		(width 0.1397)
		(layer "In5.Cu")
		(net "PCIE_TX_CAP_N18")
	)
	(segment
		(start 258.99364 -44.983908)
		(end 259.020564 -45.010832)
		(width 0.1016)
		(layer "In5.Cu")
		(net "PCIE_TX_CAP_N18")
	)
	(segment
		(start 259.890768 -44.849796)
		(end 260.611874 -44.849796)
		(width 0.1397)
		(layer "In5.Cu")
		(net "PCIE_TX_CAP_N18")
	)
	(segment
		(start 305.058064 -157.542992)
		(end 335.820512 -201.476356)
		(width 0.1397)
		(layer "In5.Cu")
		(net "PCIE_TX_CAP_N18")
	)
	(segment
		(start 335.820512 -201.476356)
		(end 336.046826 -202.759818)
		(width 0.1397)
		(layer "In5.Cu")
		(net "PCIE_TX_CAP_N18")
	)
	(segment
		(start 275.769324 -50.543968)
		(end 283.337254 -61.352684)
		(width 0.1397)
		(layer "In5.Cu")
		(net "PCIE_TX_CAP_N18")
	)
	(segment
		(start 291.715952 -81.493868)
		(end 305.058064 -157.542992)
		(width 0.1397)
		(layer "In5.Cu")
		(net "PCIE_TX_CAP_N18")
	)
	(arc
		(start 259.514594 -45.101764)
		(mid 259.550679 -45.099493)
		(end 259.586222 -45.092874)
		(width 0.1016)
		(layer "In5.Cu")
		(net "PCIE_TX_CAP_N18")
	)
	(arc
		(start 259.586222 -45.092874)
		(mid 259.661861 -45.062992)
		(end 259.726684 -45.01388)
		(width 0.1016)
		(layer "In5.Cu")
		(net "PCIE_TX_CAP_N18")
	)
	(arc
		(start 259.059934 -45.044106)
		(mid 259.14548 -45.08699)
		(end 259.24002 -45.101764)
		(width 0.1016)
		(layer "In5.Cu")
		(net "PCIE_TX_CAP_N18")
	)
	(arc
		(start 259.035296 -44.564808)
		(mid 258.955633 -44.683893)
		(end 258.9276 -44.824396)
		(width 0.1016)
		(layer "In5.Cu")
		(net "PCIE_TX_CAP_N18")
	)
	(arc
		(start 259.020564 -45.010832)
		(mid 259.039557 -45.028288)
		(end 259.059934 -45.044106)
		(width 0.1016)
		(layer "In5.Cu")
		(net "PCIE_TX_CAP_N18")
	)
	(arc
		(start 258.9276 -44.824396)
		(mid 258.944769 -44.910711)
		(end 258.99364 -44.983908)
		(width 0.1016)
		(layer "In5.Cu")
		(net "PCIE_TX_CAP_N18")
	)
	(arc
		(start 336.265266 -210.313778)
		(mid 336.327987 -210.6291)
		(end 336.506566 -210.896454)
		(width 0.1397)
		(layer "In5.Cu")
		(net "PCIE_TX_CAP_N18")
	)
	(segment
		(start 339.575394 -211.027518)
		(end 339.706458 -210.896454)
		(width 0.136652)
		(layer "F.Cu")
		(net "PCIE_TX_CAP_N17")
	)
	(segment
		(start 339.808058 -211.975954)
		(end 339.504782 -211.672424)
		(width 0.136652)
		(layer "F.Cu")
		(net "PCIE_TX_CAP_N17")
	)
	(segment
		(start 339.446108 -211.5312)
		(end 339.446108 -211.339684)
		(width 0.136652)
		(layer "F.Cu")
		(net "PCIE_TX_CAP_N17")
	)
	(segment
		(start 257.599942 -43.999912)
		(end 258.099814 -43.50004)
		(width 0.136652)
		(layer "F.Cu")
		(net "PCIE_TX_CAP_N17")
	)
	(via
		(at 339.706458 -210.896454)
		(size 0.508)
		(drill 0.254)
		(layers "F.Cu" "B.Cu")
		(net "PCIE_TX_CAP_N17")
	)
	(via
		(at 258.099814 -43.50004)
		(size 0.4572)
		(drill 0.2032)
		(layers "F.Cu" "B.Cu")
		(net "PCIE_TX_CAP_N17")
	)
	(arc
		(start 339.446108 -211.339684)
		(mid 339.479712 -211.170748)
		(end 339.575394 -211.027518)
		(width 0.136652)
		(layer "F.Cu")
		(net "PCIE_TX_CAP_N17")
	)
	(arc
		(start 339.504782 -211.672424)
		(mid 339.461405 -211.607645)
		(end 339.446108 -211.5312)
		(width 0.136652)
		(layer "F.Cu")
		(net "PCIE_TX_CAP_N17")
	)
	(segment
		(start 259.715 -43.8404)
		(end 260.219444 -43.8404)
		(width 0.1397)
		(layer "In5.Cu")
		(net "PCIE_TX_CAP_N17")
	)
	(segment
		(start 339.465158 -205.114906)
		(end 339.465158 -210.313778)
		(width 0.1397)
		(layer "In5.Cu")
		(net "PCIE_TX_CAP_N17")
	)
	(segment
		(start 263.595612 -43.24477)
		(end 268.01826 -44.02455)
		(width 0.1397)
		(layer "In5.Cu")
		(net "PCIE_TX_CAP_N17")
	)
	(segment
		(start 276.221952 -49.769014)
		(end 283.947616 -60.80252)
		(width 0.1397)
		(layer "In5.Cu")
		(net "PCIE_TX_CAP_N17")
	)
	(segment
		(start 292.758622 -81.982564)
		(end 306.0573 -157.403546)
		(width 0.1397)
		(layer "In5.Cu")
		(net "PCIE_TX_CAP_N17")
	)
	(segment
		(start 283.947616 -60.80252)
		(end 292.758622 -81.982564)
		(width 0.1397)
		(layer "In5.Cu")
		(net "PCIE_TX_CAP_N17")
	)
	(segment
		(start 260.219444 -43.8404)
		(end 263.595612 -43.24477)
		(width 0.1397)
		(layer "In5.Cu")
		(net "PCIE_TX_CAP_N17")
	)
	(segment
		(start 272.126456 -46.901354)
		(end 276.221952 -49.769014)
		(width 0.1397)
		(layer "In5.Cu")
		(net "PCIE_TX_CAP_N17")
	)
	(segment
		(start 257.722624 -43.666664)
		(end 257.722624 -43.68292)
		(width 0.1016)
		(layer "In5.Cu")
		(net "PCIE_TX_CAP_N17")
	)
	(segment
		(start 268.01826 -44.02455)
		(end 272.126456 -46.901354)
		(width 0.1397)
		(layer "In5.Cu")
		(net "PCIE_TX_CAP_N17")
	)
	(segment
		(start 258.2164 -43.8912)
		(end 259.592318 -43.8912)
		(width 0.1016)
		(layer "In5.Cu")
		(net "PCIE_TX_CAP_N17")
	)
	(segment
		(start 258.070096 -43.888914)
		(end 258.140454 -43.888914)
		(width 0.1016)
		(layer "In5.Cu")
		(net "PCIE_TX_CAP_N17")
	)
	(segment
		(start 258.140454 -43.888914)
		(end 258.152646 -43.889168)
		(width 0.1016)
		(layer "In5.Cu")
		(net "PCIE_TX_CAP_N17")
	)
	(segment
		(start 306.0573 -157.403546)
		(end 339.465158 -205.114906)
		(width 0.1397)
		(layer "In5.Cu")
		(net "PCIE_TX_CAP_N17")
	)
	(segment
		(start 257.7846 -43.561)
		(end 257.762502 -43.582844)
		(width 0.1016)
		(layer "In5.Cu")
		(net "PCIE_TX_CAP_N17")
	)
	(segment
		(start 258.099814 -43.50004)
		(end 257.931666 -43.50004)
		(width 0.1016)
		(layer "In5.Cu")
		(net "PCIE_TX_CAP_N17")
	)
	(arc
		(start 257.931666 -43.50004)
		(mid 257.852058 -43.515875)
		(end 257.7846 -43.561)
		(width 0.1016)
		(layer "In5.Cu")
		(net "PCIE_TX_CAP_N17")
	)
	(arc
		(start 257.722624 -43.68292)
		(mid 257.722615 -43.684698)
		(end 257.722624 -43.686476)
		(width 0.1016)
		(layer "In5.Cu")
		(net "PCIE_TX_CAP_N17")
	)
	(arc
		(start 339.465158 -210.313778)
		(mid 339.527879 -210.6291)
		(end 339.706458 -210.896454)
		(width 0.1397)
		(layer "In5.Cu")
		(net "PCIE_TX_CAP_N17")
	)
	(arc
		(start 257.735832 -43.61942)
		(mid 257.728755 -43.636925)
		(end 257.724148 -43.655234)
		(width 0.1016)
		(layer "In5.Cu")
		(net "PCIE_TX_CAP_N17")
	)
	(arc
		(start 259.592318 -43.8912)
		(mid 259.658707 -43.877994)
		(end 259.715 -43.8404)
		(width 0.1016)
		(layer "In5.Cu")
		(net "PCIE_TX_CAP_N17")
	)
	(arc
		(start 258.152646 -43.889168)
		(mid 258.184508 -43.890664)
		(end 258.2164 -43.8912)
		(width 0.1016)
		(layer "In5.Cu")
		(net "PCIE_TX_CAP_N17")
	)
	(arc
		(start 257.74142 -43.609514)
		(mid 257.740782 -43.610401)
		(end 257.74015 -43.611292)
		(width 0.1016)
		(layer "In5.Cu")
		(net "PCIE_TX_CAP_N17")
	)
	(arc
		(start 257.725926 -43.716956)
		(mid 257.764281 -43.79623)
		(end 257.836416 -43.84675)
		(width 0.1016)
		(layer "In5.Cu")
		(net "PCIE_TX_CAP_N17")
	)
	(arc
		(start 257.836416 -43.84675)
		(mid 257.951374 -43.878273)
		(end 258.070096 -43.888914)
		(width 0.1016)
		(layer "In5.Cu")
		(net "PCIE_TX_CAP_N17")
	)
	(arc
		(start 257.722624 -43.686476)
		(mid 257.723609 -43.701788)
		(end 257.725926 -43.716956)
		(width 0.1016)
		(layer "In5.Cu")
		(net "PCIE_TX_CAP_N17")
	)
	(arc
		(start 257.724148 -43.655234)
		(mid 257.723265 -43.660933)
		(end 257.722624 -43.666664)
		(width 0.1016)
		(layer "In5.Cu")
		(net "PCIE_TX_CAP_N17")
	)
	(arc
		(start 257.74015 -43.611292)
		(mid 257.737919 -43.615318)
		(end 257.735832 -43.61942)
		(width 0.1016)
		(layer "In5.Cu")
		(net "PCIE_TX_CAP_N17")
	)
	(arc
		(start 257.762502 -43.582844)
		(mid 257.751139 -43.595529)
		(end 257.74142 -43.609514)
		(width 0.1016)
		(layer "In5.Cu")
		(net "PCIE_TX_CAP_N17")
	)
	(segment
		(start 258.59994 -42.999914)
		(end 259.099812 -42.500042)
		(width 0.136652)
		(layer "F.Cu")
		(net "PCIE_TX_CAP_N16")
	)
	(segment
		(start 342.73109 -211.071714)
		(end 342.90635 -210.896454)
		(width 0.136652)
		(layer "F.Cu")
		(net "PCIE_TX_CAP_N16")
	)
	(segment
		(start 342.646 -211.469732)
		(end 342.646 -211.2772)
		(width 0.136652)
		(layer "F.Cu")
		(net "PCIE_TX_CAP_N16")
	)
	(segment
		(start 343.00795 -211.975954)
		(end 342.748108 -211.715858)
		(width 0.136652)
		(layer "F.Cu")
		(net "PCIE_TX_CAP_N16")
	)
	(via
		(at 259.099812 -42.500042)
		(size 0.4572)
		(drill 0.2032)
		(layers "F.Cu" "B.Cu")
		(net "PCIE_TX_CAP_N16")
	)
	(via
		(at 342.90635 -210.896454)
		(size 0.508)
		(drill 0.254)
		(layers "F.Cu" "B.Cu")
		(net "PCIE_TX_CAP_N16")
	)
	(arc
		(start 342.646 -211.2772)
		(mid 342.668119 -211.166001)
		(end 342.73109 -211.071714)
		(width 0.136652)
		(layer "F.Cu")
		(net "PCIE_TX_CAP_N16")
	)
	(arc
		(start 342.748108 -211.715858)
		(mid 342.672572 -211.602949)
		(end 342.646 -211.469732)
		(width 0.136652)
		(layer "F.Cu")
		(net "PCIE_TX_CAP_N16")
	)
	(segment
		(start 342.90635 -210.896454)
		(end 342.78189 -210.772248)
		(width 0.1397)
		(layer "In5.Cu")
		(net "PCIE_TX_CAP_N16")
	)
	(segment
		(start 259.020564 -43.010836)
		(end 258.99364 -42.983912)
		(width 0.1016)
		(layer "In5.Cu")
		(net "PCIE_TX_CAP_N16")
	)
	(segment
		(start 293.88435 -82.671158)
		(end 284.466284 -60.031884)
		(width 0.1397)
		(layer "In5.Cu")
		(net "PCIE_TX_CAP_N16")
	)
	(segment
		(start 284.466284 -60.031884)
		(end 276.573234 -48.75911)
		(width 0.1397)
		(layer "In5.Cu")
		(net "PCIE_TX_CAP_N16")
	)
	(segment
		(start 276.573234 -48.75911)
		(end 272.59534 -45.974)
		(width 0.1397)
		(layer "In5.Cu")
		(net "PCIE_TX_CAP_N16")
	)
	(segment
		(start 307.015134 -157.117034)
		(end 293.88435 -82.671158)
		(width 0.1397)
		(layer "In5.Cu")
		(net "PCIE_TX_CAP_N16")
	)
	(segment
		(start 259.890768 -42.8498)
		(end 259.726684 -43.013884)
		(width 0.1016)
		(layer "In5.Cu")
		(net "PCIE_TX_CAP_N16")
	)
	(segment
		(start 342.66505 -210.4898)
		(end 342.66505 -208.030826)
		(width 0.1397)
		(layer "In5.Cu")
		(net "PCIE_TX_CAP_N16")
	)
	(segment
		(start 259.035296 -42.564812)
		(end 259.099812 -42.500042)
		(width 0.1016)
		(layer "In5.Cu")
		(net "PCIE_TX_CAP_N16")
	)
	(segment
		(start 272.59534 -45.974)
		(end 268.605 -43.18)
		(width 0.1397)
		(layer "In5.Cu")
		(net "PCIE_TX_CAP_N16")
	)
	(segment
		(start 342.66505 -208.030826)
		(end 307.015134 -157.117034)
		(width 0.1397)
		(layer "In5.Cu")
		(net "PCIE_TX_CAP_N16")
	)
	(segment
		(start 263.671812 -42.31005)
		(end 260.611874 -42.8498)
		(width 0.1397)
		(layer "In5.Cu")
		(net "PCIE_TX_CAP_N16")
	)
	(segment
		(start 259.514594 -43.101768)
		(end 259.24002 -43.101768)
		(width 0.1016)
		(layer "In5.Cu")
		(net "PCIE_TX_CAP_N16")
	)
	(segment
		(start 260.611874 -42.8498)
		(end 259.890768 -42.8498)
		(width 0.1397)
		(layer "In5.Cu")
		(net "PCIE_TX_CAP_N16")
	)
	(segment
		(start 268.605 -43.18)
		(end 263.671812 -42.31005)
		(width 0.1397)
		(layer "In5.Cu")
		(net "PCIE_TX_CAP_N16")
	)
	(arc
		(start 259.059934 -43.04411)
		(mid 259.039558 -43.02829)
		(end 259.020564 -43.010836)
		(width 0.1016)
		(layer "In5.Cu")
		(net "PCIE_TX_CAP_N16")
	)
	(arc
		(start 342.78189 -210.772248)
		(mid 342.695385 -210.642645)
		(end 342.66505 -210.4898)
		(width 0.1397)
		(layer "In5.Cu")
		(net "PCIE_TX_CAP_N16")
	)
	(arc
		(start 259.24002 -43.101768)
		(mid 259.222339 -43.101249)
		(end 259.204714 -43.099736)
		(width 0.1016)
		(layer "In5.Cu")
		(net "PCIE_TX_CAP_N16")
	)
	(arc
		(start 258.9276 -42.8244)
		(mid 258.955641 -42.6839)
		(end 259.035296 -42.564812)
		(width 0.1016)
		(layer "In5.Cu")
		(net "PCIE_TX_CAP_N16")
	)
	(arc
		(start 258.99364 -42.983912)
		(mid 258.94474 -42.910727)
		(end 258.9276 -42.8244)
		(width 0.1016)
		(layer "In5.Cu")
		(net "PCIE_TX_CAP_N16")
	)
	(arc
		(start 259.586222 -43.092878)
		(mid 259.550676 -43.099473)
		(end 259.514594 -43.101768)
		(width 0.1016)
		(layer "In5.Cu")
		(net "PCIE_TX_CAP_N16")
	)
	(arc
		(start 259.726684 -43.013884)
		(mid 259.661855 -43.062985)
		(end 259.586222 -43.092878)
		(width 0.1016)
		(layer "In5.Cu")
		(net "PCIE_TX_CAP_N16")
	)
	(arc
		(start 259.204714 -43.099736)
		(mid 259.128783 -43.081132)
		(end 259.059934 -43.04411)
		(width 0.1016)
		(layer "In5.Cu")
		(net "PCIE_TX_CAP_N16")
	)
	(segment
		(start 257.599942 -40.999918)
		(end 258.099814 -40.500046)
		(width 0.136652)
		(layer "F.Cu")
		(net "PCIE_TX_CAP_N15")
	)
	(segment
		(start 329.081892 -34.812986)
		(end 329.188318 -34.919412)
		(width 0.136652)
		(layer "F.Cu")
		(net "PCIE_TX_CAP_N15")
	)
	(segment
		(start 329.213718 -33.877758)
		(end 329.090782 -34.000948)
		(width 0.136652)
		(layer "F.Cu")
		(net "PCIE_TX_CAP_N15")
	)
	(segment
		(start 328.947018 -34.347658)
		(end 328.947018 -34.487358)
		(width 0.136652)
		(layer "F.Cu")
		(net "PCIE_TX_CAP_N15")
	)
	(via
		(at 258.099814 -40.500046)
		(size 0.4572)
		(drill 0.2032)
		(layers "F.Cu" "B.Cu")
		(net "PCIE_TX_CAP_N15")
	)
	(via
		(at 329.188318 -34.919412)
		(size 0.508)
		(drill 0.254)
		(layers "F.Cu" "B.Cu")
		(net "PCIE_TX_CAP_N15")
	)
	(arc
		(start 329.090782 -34.000948)
		(mid 328.984411 -34.160005)
		(end 328.947018 -34.347658)
		(width 0.136652)
		(layer "F.Cu")
		(net "PCIE_TX_CAP_N15")
	)
	(arc
		(start 328.947018 -34.487358)
		(mid 328.982072 -34.663584)
		(end 329.081892 -34.812986)
		(width 0.136652)
		(layer "F.Cu")
		(net "PCIE_TX_CAP_N15")
	)
	(segment
		(start 311.827164 -46.584362)
		(end 308.523386 -48.897794)
		(width 0.1397)
		(layer "In5.Cu")
		(net "PCIE_TX_CAP_N15")
	)
	(segment
		(start 329.188318 -34.919412)
		(end 329.148694 -34.959036)
		(width 0.1397)
		(layer "In5.Cu")
		(net "PCIE_TX_CAP_N15")
	)
	(segment
		(start 266.86129 -40.080692)
		(end 263.2964 -40.709342)
		(width 0.1397)
		(layer "In5.Cu")
		(net "PCIE_TX_CAP_N15")
	)
	(segment
		(start 300.884336 -50.425604)
		(end 297.709336 -49.790604)
		(width 0.1397)
		(layer "In5.Cu")
		(net "PCIE_TX_CAP_N15")
	)
	(segment
		(start 258.4704 -40.104822)
		(end 258.053332 -40.104822)
		(width 0.1016)
		(layer "In5.Cu")
		(net "PCIE_TX_CAP_N15")
	)
	(segment
		(start 271.25422 -41.732454)
		(end 269.579852 -40.55999)
		(width 0.1397)
		(layer "In5.Cu")
		(net "PCIE_TX_CAP_N15")
	)
	(segment
		(start 327.162414 -38.14953)
		(end 322.842636 -41.174162)
		(width 0.1397)
		(layer "In5.Cu")
		(net "PCIE_TX_CAP_N15")
	)
	(segment
		(start 288.44367 -50.373788)
		(end 280.007568 -48.886364)
		(width 0.1397)
		(layer "In5.Cu")
		(net "PCIE_TX_CAP_N15")
	)
	(segment
		(start 313.256168 -44.543726)
		(end 311.827164 -46.584362)
		(width 0.1397)
		(layer "In5.Cu")
		(net "PCIE_TX_CAP_N15")
	)
	(segment
		(start 272.661888 -43.743118)
		(end 271.25422 -41.732454)
		(width 0.1397)
		(layer "In5.Cu")
		(net "PCIE_TX_CAP_N15")
	)
	(segment
		(start 259.217668 -40.709342)
		(end 258.713986 -40.20566)
		(width 0.1016)
		(layer "In5.Cu")
		(net "PCIE_TX_CAP_N15")
	)
	(segment
		(start 294.534336 -50.425604)
		(end 291.359336 -49.790604)
		(width 0.1397)
		(layer "In5.Cu")
		(net "PCIE_TX_CAP_N15")
	)
	(segment
		(start 328.967846 -35.395662)
		(end 328.967846 -36.344098)
		(width 0.1397)
		(layer "In5.Cu")
		(net "PCIE_TX_CAP_N15")
	)
	(segment
		(start 291.359336 -49.790604)
		(end 288.44367 -50.373788)
		(width 0.1397)
		(layer "In5.Cu")
		(net "PCIE_TX_CAP_N15")
	)
	(segment
		(start 280.007568 -48.886364)
		(end 272.661888 -43.743118)
		(width 0.1397)
		(layer "In5.Cu")
		(net "PCIE_TX_CAP_N15")
	)
	(segment
		(start 308.523386 -48.897794)
		(end 300.884336 -50.425604)
		(width 0.1397)
		(layer "In5.Cu")
		(net "PCIE_TX_CAP_N15")
	)
	(segment
		(start 316.461902 -42.299128)
		(end 313.256168 -44.543726)
		(width 0.1397)
		(layer "In5.Cu")
		(net "PCIE_TX_CAP_N15")
	)
	(segment
		(start 259.5372 -40.709342)
		(end 259.217668 -40.709342)
		(width 0.1016)
		(layer "In5.Cu")
		(net "PCIE_TX_CAP_N15")
	)
	(segment
		(start 269.579852 -40.55999)
		(end 266.86129 -40.080692)
		(width 0.1397)
		(layer "In5.Cu")
		(net "PCIE_TX_CAP_N15")
	)
	(segment
		(start 322.842636 -41.174162)
		(end 316.461902 -42.299128)
		(width 0.1397)
		(layer "In5.Cu")
		(net "PCIE_TX_CAP_N15")
	)
	(segment
		(start 328.967846 -36.344098)
		(end 327.162414 -38.14953)
		(width 0.1397)
		(layer "In5.Cu")
		(net "PCIE_TX_CAP_N15")
	)
	(segment
		(start 297.709336 -49.790604)
		(end 294.534336 -50.425604)
		(width 0.1397)
		(layer "In5.Cu")
		(net "PCIE_TX_CAP_N15")
	)
	(segment
		(start 263.2964 -40.709342)
		(end 259.5372 -40.709342)
		(width 0.1397)
		(layer "In5.Cu")
		(net "PCIE_TX_CAP_N15")
	)
	(arc
		(start 329.148694 -34.959036)
		(mid 329.014841 -35.159362)
		(end 328.967846 -35.395662)
		(width 0.1397)
		(layer "In5.Cu")
		(net "PCIE_TX_CAP_N15")
	)
	(arc
		(start 257.876802 -40.302434)
		(mid 257.943617 -40.451672)
		(end 258.099814 -40.500046)
		(width 0.1016)
		(layer "In5.Cu")
		(net "PCIE_TX_CAP_N15")
	)
	(arc
		(start 258.713986 -40.20566)
		(mid 258.602228 -40.130986)
		(end 258.4704 -40.104822)
		(width 0.1016)
		(layer "In5.Cu")
		(net "PCIE_TX_CAP_N15")
	)
	(arc
		(start 258.053332 -40.104822)
		(mid 257.920888 -40.164126)
		(end 257.876802 -40.302434)
		(width 0.1016)
		(layer "In5.Cu")
		(net "PCIE_TX_CAP_N15")
	)
	(segment
		(start 326.675496 -35.855148)
		(end 326.781922 -35.961574)
		(width 0.136652)
		(layer "F.Cu")
		(net "PCIE_TX_CAP_N14")
	)
	(segment
		(start 326.540622 -34.54781)
		(end 326.540622 -35.52952)
		(width 0.136652)
		(layer "F.Cu")
		(net "PCIE_TX_CAP_N14")
	)
	(segment
		(start 258.59994 -39.99992)
		(end 259.099812 -39.500048)
		(width 0.136652)
		(layer "F.Cu")
		(net "PCIE_TX_CAP_N14")
	)
	(via
		(at 326.781922 -35.961574)
		(size 0.508)
		(drill 0.254)
		(layers "F.Cu" "B.Cu")
		(net "PCIE_TX_CAP_N14")
	)
	(via
		(at 259.099812 -39.500048)
		(size 0.4572)
		(drill 0.2032)
		(layers "F.Cu" "B.Cu")
		(net "PCIE_TX_CAP_N14")
	)
	(arc
		(start 326.540622 -35.52952)
		(mid 326.575676 -35.705746)
		(end 326.675496 -35.855148)
		(width 0.136652)
		(layer "F.Cu")
		(net "PCIE_TX_CAP_N14")
	)
	(arc
		(start 326.807322 -33.90392)
		(mid 326.609929 -34.199339)
		(end 326.540622 -34.54781)
		(width 0.136652)
		(layer "F.Cu")
		(net "PCIE_TX_CAP_N14")
	)
	(segment
		(start 267.093954 -38.940994)
		(end 270.1036 -39.4716)
		(width 0.1397)
		(layer "In5.Cu")
		(net "PCIE_TX_CAP_N14")
	)
	(segment
		(start 280.401014 -47.777654)
		(end 289.019234 -49.297336)
		(width 0.1397)
		(layer "In5.Cu")
		(net "PCIE_TX_CAP_N14")
	)
	(segment
		(start 315.378846 -41.682162)
		(end 322.178172 -40.483282)
		(width 0.1397)
		(layer "In5.Cu")
		(net "PCIE_TX_CAP_N14")
	)
	(segment
		(start 310.6928 -46.0248)
		(end 312.15076 -43.942508)
		(width 0.1397)
		(layer "In5.Cu")
		(net "PCIE_TX_CAP_N14")
	)
	(segment
		(start 326.714104 -36.029646)
		(end 326.781922 -35.961574)
		(width 0.1397)
		(layer "In5.Cu")
		(net "PCIE_TX_CAP_N14")
	)
	(segment
		(start 259.258308 -38.949122)
		(end 259.843778 -39.534592)
		(width 0.1397)
		(layer "In5.Cu")
		(net "PCIE_TX_CAP_N14")
	)
	(segment
		(start 259.003292 -38.885622)
		(end 259.1054 -38.885622)
		(width 0.1397)
		(layer "In5.Cu")
		(net "PCIE_TX_CAP_N14")
	)
	(segment
		(start 301.475394 -49.346104)
		(end 307.738272 -48.09363)
		(width 0.1397)
		(layer "In5.Cu")
		(net "PCIE_TX_CAP_N14")
	)
	(segment
		(start 298.300394 -48.711104)
		(end 301.475394 -49.346104)
		(width 0.1397)
		(layer "In5.Cu")
		(net "PCIE_TX_CAP_N14")
	)
	(segment
		(start 322.366132 -40.405558)
		(end 325.815452 -37.989256)
		(width 0.1397)
		(layer "In5.Cu")
		(net "PCIE_TX_CAP_N14")
	)
	(segment
		(start 263.7282 -39.534592)
		(end 267.093954 -38.940994)
		(width 0.1397)
		(layer "In5.Cu")
		(net "PCIE_TX_CAP_N14")
	)
	(segment
		(start 307.738272 -48.09363)
		(end 310.6928 -46.0248)
		(width 0.1397)
		(layer "In5.Cu")
		(net "PCIE_TX_CAP_N14")
	)
	(segment
		(start 258.865624 -39.40302)
		(end 258.862576 -39.399972)
		(width 0.1397)
		(layer "In5.Cu")
		(net "PCIE_TX_CAP_N14")
	)
	(segment
		(start 295.125394 -49.346104)
		(end 298.300394 -48.711104)
		(width 0.1397)
		(layer "In5.Cu")
		(net "PCIE_TX_CAP_N14")
	)
	(segment
		(start 326.513952 -36.914074)
		(end 326.513952 -36.5125)
		(width 0.1397)
		(layer "In5.Cu")
		(net "PCIE_TX_CAP_N14")
	)
	(segment
		(start 270.1036 -39.4716)
		(end 272.188178 -40.931338)
		(width 0.1397)
		(layer "In5.Cu")
		(net "PCIE_TX_CAP_N14")
	)
	(segment
		(start 289.019234 -49.297336)
		(end 291.950394 -48.711104)
		(width 0.1397)
		(layer "In5.Cu")
		(net "PCIE_TX_CAP_N14")
	)
	(segment
		(start 272.188178 -40.931338)
		(end 273.693636 -43.081448)
		(width 0.1397)
		(layer "In5.Cu")
		(net "PCIE_TX_CAP_N14")
	)
	(segment
		(start 259.843778 -39.534592)
		(end 263.7282 -39.534592)
		(width 0.1397)
		(layer "In5.Cu")
		(net "PCIE_TX_CAP_N14")
	)
	(segment
		(start 291.950394 -48.711104)
		(end 295.125394 -49.346104)
		(width 0.1397)
		(layer "In5.Cu")
		(net "PCIE_TX_CAP_N14")
	)
	(segment
		(start 325.815452 -37.989256)
		(end 326.513952 -36.914074)
		(width 0.1397)
		(layer "In5.Cu")
		(net "PCIE_TX_CAP_N14")
	)
	(segment
		(start 312.15076 -43.942508)
		(end 315.378846 -41.682162)
		(width 0.1397)
		(layer "In5.Cu")
		(net "PCIE_TX_CAP_N14")
	)
	(segment
		(start 258.764786 -39.163752)
		(end 258.764786 -39.124128)
		(width 0.1397)
		(layer "In5.Cu")
		(net "PCIE_TX_CAP_N14")
	)
	(segment
		(start 273.693636 -43.081448)
		(end 280.401014 -47.777654)
		(width 0.1397)
		(layer "In5.Cu")
		(net "PCIE_TX_CAP_N14")
	)
	(arc
		(start 258.834636 -38.955472)
		(mid 258.880504 -38.919646)
		(end 258.933696 -38.896036)
		(width 0.1397)
		(layer "In5.Cu")
		(net "PCIE_TX_CAP_N14")
	)
	(arc
		(start 258.764786 -39.124128)
		(mid 258.782941 -39.032856)
		(end 258.834636 -38.955472)
		(width 0.1397)
		(layer "In5.Cu")
		(net "PCIE_TX_CAP_N14")
	)
	(arc
		(start 259.1054 -38.885622)
		(mid 259.188162 -38.902178)
		(end 259.258308 -38.949122)
		(width 0.1397)
		(layer "In5.Cu")
		(net "PCIE_TX_CAP_N14")
	)
	(arc
		(start 326.513952 -36.5125)
		(mid 326.566026 -36.251179)
		(end 326.714104 -36.029646)
		(width 0.1397)
		(layer "In5.Cu")
		(net "PCIE_TX_CAP_N14")
	)
	(arc
		(start 322.178172 -40.483282)
		(mid 322.276404 -40.454706)
		(end 322.366132 -40.405558)
		(width 0.1397)
		(layer "In5.Cu")
		(net "PCIE_TX_CAP_N14")
	)
	(arc
		(start 258.933696 -38.896036)
		(mid 258.968109 -38.888264)
		(end 259.003292 -38.885622)
		(width 0.1397)
		(layer "In5.Cu")
		(net "PCIE_TX_CAP_N14")
	)
	(arc
		(start 258.862576 -39.399972)
		(mid 258.790213 -39.291579)
		(end 258.764786 -39.163752)
		(width 0.1397)
		(layer "In5.Cu")
		(net "PCIE_TX_CAP_N14")
	)
	(arc
		(start 259.099812 -39.500048)
		(mid 258.973061 -39.474836)
		(end 258.865624 -39.40302)
		(width 0.1397)
		(layer "In5.Cu")
		(net "PCIE_TX_CAP_N14")
	)
	(segment
		(start 324.18401 -34.397188)
		(end 324.18401 -34.536888)
		(width 0.136652)
		(layer "F.Cu")
		(net "PCIE_TX_CAP_N13")
	)
	(segment
		(start 257.599942 -38.999922)
		(end 258.099814 -38.50005)
		(width 0.136652)
		(layer "F.Cu")
		(net "PCIE_TX_CAP_N13")
	)
	(segment
		(start 324.318884 -34.862516)
		(end 324.42531 -34.968942)
		(width 0.136652)
		(layer "F.Cu")
		(net "PCIE_TX_CAP_N13")
	)
	(via
		(at 324.42531 -34.968942)
		(size 0.508)
		(drill 0.254)
		(layers "F.Cu" "B.Cu")
		(net "PCIE_TX_CAP_N13")
	)
	(via
		(at 258.099814 -38.50005)
		(size 0.4572)
		(drill 0.2032)
		(layers "F.Cu" "B.Cu")
		(net "PCIE_TX_CAP_N13")
	)
	(arc
		(start 324.18401 -34.536888)
		(mid 324.219064 -34.713114)
		(end 324.318884 -34.862516)
		(width 0.136652)
		(layer "F.Cu")
		(net "PCIE_TX_CAP_N13")
	)
	(arc
		(start 324.45071 -33.927288)
		(mid 324.255353 -34.12704)
		(end 324.18401 -34.397188)
		(width 0.136652)
		(layer "F.Cu")
		(net "PCIE_TX_CAP_N13")
	)
	(segment
		(start 311.607708 -42.817288)
		(end 309.9308 -45.212)
		(width 0.1397)
		(layer "In5.Cu")
		(net "PCIE_TX_CAP_N13")
	)
	(segment
		(start 324.169532 -35.464242)
		(end 324.169532 -36.02101)
		(width 0.1397)
		(layer "In5.Cu")
		(net "PCIE_TX_CAP_N13")
	)
	(segment
		(start 280.990294 -46.654974)
		(end 274.268692 -41.9481)
		(width 0.1397)
		(layer "In5.Cu")
		(net "PCIE_TX_CAP_N13")
	)
	(segment
		(start 301.990252 -48.190404)
		(end 298.815252 -47.555404)
		(width 0.1397)
		(layer "In5.Cu")
		(net "PCIE_TX_CAP_N13")
	)
	(segment
		(start 295.030652 -48.312324)
		(end 291.855652 -47.677324)
		(width 0.1397)
		(layer "In5.Cu")
		(net "PCIE_TX_CAP_N13")
	)
	(segment
		(start 298.815252 -47.555404)
		(end 295.030652 -48.312324)
		(width 0.1397)
		(layer "In5.Cu")
		(net "PCIE_TX_CAP_N13")
	)
	(segment
		(start 307.151532 -47.158148)
		(end 301.990252 -48.190404)
		(width 0.1397)
		(layer "In5.Cu")
		(net "PCIE_TX_CAP_N13")
	)
	(segment
		(start 259.503164 -38.104826)
		(end 258.058158 -38.104826)
		(width 0.1016)
		(layer "In5.Cu")
		(net "PCIE_TX_CAP_N13")
	)
	(segment
		(start 257.876802 -38.286182)
		(end 257.876802 -38.302438)
		(width 0.1016)
		(layer "In5.Cu")
		(net "PCIE_TX_CAP_N13")
	)
	(segment
		(start 320.922904 -39.267638)
		(end 319.58026 -40.139874)
		(width 0.1397)
		(layer "In5.Cu")
		(net "PCIE_TX_CAP_N13")
	)
	(segment
		(start 324.42531 -34.968942)
		(end 324.33895 -35.055302)
		(width 0.1397)
		(layer "In5.Cu")
		(net "PCIE_TX_CAP_N13")
	)
	(segment
		(start 289.481514 -48.15205)
		(end 280.990294 -46.654974)
		(width 0.1397)
		(layer "In5.Cu")
		(net "PCIE_TX_CAP_N13")
	)
	(segment
		(start 270.4973 -38.381686)
		(end 267.0556 -37.775134)
		(width 0.1397)
		(layer "In5.Cu")
		(net "PCIE_TX_CAP_N13")
	)
	(segment
		(start 274.268692 -41.9481)
		(end 272.996914 -40.131746)
		(width 0.1397)
		(layer "In5.Cu")
		(net "PCIE_TX_CAP_N13")
	)
	(segment
		(start 319.58026 -40.139874)
		(end 314.035186 -41.117774)
		(width 0.1397)
		(layer "In5.Cu")
		(net "PCIE_TX_CAP_N13")
	)
	(segment
		(start 272.996914 -40.131746)
		(end 270.4973 -38.381686)
		(width 0.1397)
		(layer "In5.Cu")
		(net "PCIE_TX_CAP_N13")
	)
	(segment
		(start 291.855652 -47.677324)
		(end 289.481514 -48.15205)
		(width 0.1397)
		(layer "In5.Cu")
		(net "PCIE_TX_CAP_N13")
	)
	(segment
		(start 259.73532 -38.231826)
		(end 259.682742 -38.179248)
		(width 0.1016)
		(layer "In5.Cu")
		(net "PCIE_TX_CAP_N13")
	)
	(segment
		(start 264.464038 -38.231826)
		(end 259.73532 -38.231826)
		(width 0.1397)
		(layer "In5.Cu")
		(net "PCIE_TX_CAP_N13")
	)
	(segment
		(start 267.0556 -37.775134)
		(end 264.464038 -38.231826)
		(width 0.1397)
		(layer "In5.Cu")
		(net "PCIE_TX_CAP_N13")
	)
	(segment
		(start 314.035186 -41.117774)
		(end 311.607708 -42.817288)
		(width 0.1397)
		(layer "In5.Cu")
		(net "PCIE_TX_CAP_N13")
	)
	(segment
		(start 324.169532 -36.02101)
		(end 320.922904 -39.267638)
		(width 0.1397)
		(layer "In5.Cu")
		(net "PCIE_TX_CAP_N13")
	)
	(segment
		(start 309.9308 -45.212)
		(end 307.151532 -47.158148)
		(width 0.1397)
		(layer "In5.Cu")
		(net "PCIE_TX_CAP_N13")
	)
	(arc
		(start 259.682742 -38.179248)
		(mid 259.600365 -38.124142)
		(end 259.503164 -38.104826)
		(width 0.1016)
		(layer "In5.Cu")
		(net "PCIE_TX_CAP_N13")
	)
	(arc
		(start 257.876802 -38.302438)
		(mid 257.943617 -38.451676)
		(end 258.099814 -38.50005)
		(width 0.1016)
		(layer "In5.Cu")
		(net "PCIE_TX_CAP_N13")
	)
	(arc
		(start 258.058158 -38.104826)
		(mid 257.92992 -38.157944)
		(end 257.876802 -38.286182)
		(width 0.1016)
		(layer "In5.Cu")
		(net "PCIE_TX_CAP_N13")
	)
	(arc
		(start 324.33895 -35.055302)
		(mid 324.213584 -35.242925)
		(end 324.169532 -35.464242)
		(width 0.1397)
		(layer "In5.Cu")
		(net "PCIE_TX_CAP_N13")
	)
	(segment
		(start 320.42735 -36.919154)
		(end 320.533776 -37.02558)
		(width 0.136652)
		(layer "F.Cu")
		(net "PCIE_TX_CAP_N12")
	)
	(segment
		(start 320.292476 -34.595816)
		(end 320.292476 -36.593526)
		(width 0.136652)
		(layer "F.Cu")
		(net "PCIE_TX_CAP_N12")
	)
	(segment
		(start 258.59994 -37.999924)
		(end 259.099812 -37.500052)
		(width 0.136652)
		(layer "F.Cu")
		(net "PCIE_TX_CAP_N12")
	)
	(via
		(at 259.099812 -37.500052)
		(size 0.4572)
		(drill 0.2032)
		(layers "F.Cu" "B.Cu")
		(net "PCIE_TX_CAP_N12")
	)
	(via
		(at 320.533776 -37.02558)
		(size 0.508)
		(drill 0.254)
		(layers "F.Cu" "B.Cu")
		(net "PCIE_TX_CAP_N12")
	)
	(arc
		(start 320.292476 -36.593526)
		(mid 320.32753 -36.769752)
		(end 320.42735 -36.919154)
		(width 0.136652)
		(layer "F.Cu")
		(net "PCIE_TX_CAP_N12")
	)
	(arc
		(start 320.559176 -33.951926)
		(mid 320.361783 -34.247345)
		(end 320.292476 -34.595816)
		(width 0.136652)
		(layer "F.Cu")
		(net "PCIE_TX_CAP_N12")
	)
	(segment
		(start 291.939218 -46.668944)
		(end 295.114218 -47.303944)
		(width 0.1397)
		(layer "In5.Cu")
		(net "PCIE_TX_CAP_N12")
	)
	(segment
		(start 320.282062 -37.820346)
		(end 320.282062 -37.427154)
		(width 0.1397)
		(layer "In5.Cu")
		(net "PCIE_TX_CAP_N12")
	)
	(segment
		(start 317.708026 -39.646352)
		(end 319.841372 -38.261036)
		(width 0.1397)
		(layer "In5.Cu")
		(net "PCIE_TX_CAP_N12")
	)
	(segment
		(start 319.841372 -38.261036)
		(end 320.282062 -37.820346)
		(width 0.1397)
		(layer "In5.Cu")
		(net "PCIE_TX_CAP_N12")
	)
	(segment
		(start 258.764786 -37.163756)
		(end 258.764786 -37.124132)
		(width 0.1397)
		(layer "In5.Cu")
		(net "PCIE_TX_CAP_N12")
	)
	(segment
		(start 313.518804 -40.386)
		(end 317.708026 -39.646352)
		(width 0.1397)
		(layer "In5.Cu")
		(net "PCIE_TX_CAP_N12")
	)
	(segment
		(start 306.701444 -46.256448)
		(end 309.245 -44.4754)
		(width 0.1397)
		(layer "In5.Cu")
		(net "PCIE_TX_CAP_N12")
	)
	(segment
		(start 271.054576 -37.457126)
		(end 273.877024 -39.433246)
		(width 0.1397)
		(layer "In5.Cu")
		(net "PCIE_TX_CAP_N12")
	)
	(segment
		(start 302.55591 -47.085504)
		(end 306.701444 -46.256448)
		(width 0.1397)
		(layer "In5.Cu")
		(net "PCIE_TX_CAP_N12")
	)
	(segment
		(start 264.26287 -37.3126)
		(end 267.250418 -36.786312)
		(width 0.1397)
		(layer "In5.Cu")
		(net "PCIE_TX_CAP_N12")
	)
	(segment
		(start 259.48132 -36.98748)
		(end 259.493766 -37.00018)
		(width 0.1397)
		(layer "In5.Cu")
		(net "PCIE_TX_CAP_N12")
	)
	(segment
		(start 259.003292 -36.885626)
		(end 259.235956 -36.885626)
		(width 0.1397)
		(layer "In5.Cu")
		(net "PCIE_TX_CAP_N12")
	)
	(segment
		(start 273.877024 -39.433246)
		(end 274.909534 -40.907462)
		(width 0.1397)
		(layer "In5.Cu")
		(net "PCIE_TX_CAP_N12")
	)
	(segment
		(start 281.547062 -45.555154)
		(end 290.02863 -47.05096)
		(width 0.1397)
		(layer "In5.Cu")
		(net "PCIE_TX_CAP_N12")
	)
	(segment
		(start 260.2484 -37.3126)
		(end 264.26287 -37.3126)
		(width 0.1397)
		(layer "In5.Cu")
		(net "PCIE_TX_CAP_N12")
	)
	(segment
		(start 290.02863 -47.05096)
		(end 291.939218 -46.668944)
		(width 0.1397)
		(layer "In5.Cu")
		(net "PCIE_TX_CAP_N12")
	)
	(segment
		(start 274.909534 -40.907462)
		(end 281.547062 -45.555154)
		(width 0.1397)
		(layer "In5.Cu")
		(net "PCIE_TX_CAP_N12")
	)
	(segment
		(start 309.245 -44.4754)
		(end 310.75376 -42.320972)
		(width 0.1397)
		(layer "In5.Cu")
		(net "PCIE_TX_CAP_N12")
	)
	(segment
		(start 267.250418 -36.786312)
		(end 271.054576 -37.457126)
		(width 0.1397)
		(layer "In5.Cu")
		(net "PCIE_TX_CAP_N12")
	)
	(segment
		(start 299.38091 -46.450504)
		(end 302.55591 -47.085504)
		(width 0.1397)
		(layer "In5.Cu")
		(net "PCIE_TX_CAP_N12")
	)
	(segment
		(start 310.75376 -42.320972)
		(end 313.518804 -40.386)
		(width 0.1397)
		(layer "In5.Cu")
		(net "PCIE_TX_CAP_N12")
	)
	(segment
		(start 295.114218 -47.303944)
		(end 299.38091 -46.450504)
		(width 0.1397)
		(layer "In5.Cu")
		(net "PCIE_TX_CAP_N12")
	)
	(segment
		(start 258.865624 -37.403024)
		(end 258.862576 -37.399976)
		(width 0.1397)
		(layer "In5.Cu")
		(net "PCIE_TX_CAP_N12")
	)
	(arc
		(start 259.099812 -37.500052)
		(mid 258.973061 -37.47484)
		(end 258.865624 -37.403024)
		(width 0.1397)
		(layer "In5.Cu")
		(net "PCIE_TX_CAP_N12")
	)
	(arc
		(start 258.933696 -36.89604)
		(mid 258.968109 -36.888268)
		(end 259.003292 -36.885626)
		(width 0.1397)
		(layer "In5.Cu")
		(net "PCIE_TX_CAP_N12")
	)
	(arc
		(start 258.834636 -36.955476)
		(mid 258.880504 -36.91965)
		(end 258.933696 -36.89604)
		(width 0.1397)
		(layer "In5.Cu")
		(net "PCIE_TX_CAP_N12")
	)
	(arc
		(start 258.862576 -37.399976)
		(mid 258.790213 -37.291583)
		(end 258.764786 -37.163756)
		(width 0.1397)
		(layer "In5.Cu")
		(net "PCIE_TX_CAP_N12")
	)
	(arc
		(start 320.282062 -37.427154)
		(mid 320.350184 -37.190169)
		(end 320.533776 -37.02558)
		(width 0.1397)
		(layer "In5.Cu")
		(net "PCIE_TX_CAP_N12")
	)
	(arc
		(start 259.235956 -36.885626)
		(mid 259.368763 -36.912154)
		(end 259.48132 -36.98748)
		(width 0.1397)
		(layer "In5.Cu")
		(net "PCIE_TX_CAP_N12")
	)
	(arc
		(start 258.764786 -37.124132)
		(mid 258.782941 -37.03286)
		(end 258.834636 -36.955476)
		(width 0.1397)
		(layer "In5.Cu")
		(net "PCIE_TX_CAP_N12")
	)
	(arc
		(start 259.493766 -37.00018)
		(mid 259.84001 -37.23144)
		(end 260.2484 -37.3126)
		(width 0.1397)
		(layer "In5.Cu")
		(net "PCIE_TX_CAP_N12")
	)
	(segment
		(start 315.722 -33.9725)
		(end 315.599064 -34.09569)
		(width 0.136652)
		(layer "F.Cu")
		(net "PCIE_TX_CAP_N11")
	)
	(segment
		(start 315.590174 -34.907728)
		(end 315.6966 -35.014154)
		(width 0.136652)
		(layer "F.Cu")
		(net "PCIE_TX_CAP_N11")
	)
	(segment
		(start 315.4553 -34.4424)
		(end 315.4553 -34.5821)
		(width 0.136652)
		(layer "F.Cu")
		(net "PCIE_TX_CAP_N11")
	)
	(segment
		(start 257.599942 -36.999926)
		(end 258.099814 -36.500054)
		(width 0.136652)
		(layer "F.Cu")
		(net "PCIE_TX_CAP_N11")
	)
	(via
		(at 258.099814 -36.500054)
		(size 0.4572)
		(drill 0.2032)
		(layers "F.Cu" "B.Cu")
		(net "PCIE_TX_CAP_N11")
	)
	(via
		(at 315.6966 -35.014154)
		(size 0.508)
		(drill 0.254)
		(layers "F.Cu" "B.Cu")
		(net "PCIE_TX_CAP_N11")
	)
	(arc
		(start 315.599064 -34.09569)
		(mid 315.492693 -34.254747)
		(end 315.4553 -34.4424)
		(width 0.136652)
		(layer "F.Cu")
		(net "PCIE_TX_CAP_N11")
	)
	(arc
		(start 315.4553 -34.5821)
		(mid 315.490354 -34.758326)
		(end 315.590174 -34.907728)
		(width 0.136652)
		(layer "F.Cu")
		(net "PCIE_TX_CAP_N11")
	)
	(segment
		(start 267.526262 -35.654488)
		(end 264.211562 -36.238688)
		(width 0.1397)
		(layer "In5.Cu")
		(net "PCIE_TX_CAP_N11")
	)
	(segment
		(start 310.220614 -41.319196)
		(end 308.6481 -43.564556)
		(width 0.1397)
		(layer "In5.Cu")
		(net "PCIE_TX_CAP_N11")
	)
	(segment
		(start 264.211562 -36.238688)
		(end 259.8674 -36.238688)
		(width 0.1397)
		(layer "In5.Cu")
		(net "PCIE_TX_CAP_N11")
	)
	(segment
		(start 275.823426 -39.985442)
		(end 274.610322 -38.252908)
		(width 0.1397)
		(layer "In5.Cu")
		(net "PCIE_TX_CAP_N11")
	)
	(segment
		(start 300.09465 -45.303948)
		(end 295.316148 -46.25975)
		(width 0.1397)
		(layer "In5.Cu")
		(net "PCIE_TX_CAP_N11")
	)
	(segment
		(start 315.315092 -36.867338)
		(end 314.099956 -38.60292)
		(width 0.1397)
		(layer "In5.Cu")
		(net "PCIE_TX_CAP_N11")
	)
	(segment
		(start 315.4553 -36.072064)
		(end 315.315092 -36.867338)
		(width 0.1397)
		(layer "In5.Cu")
		(net "PCIE_TX_CAP_N11")
	)
	(segment
		(start 259.8674 -36.238688)
		(end 259.67436 -36.238688)
		(width 0.1016)
		(layer "In5.Cu")
		(net "PCIE_TX_CAP_N11")
	)
	(segment
		(start 314.099956 -38.60292)
		(end 310.220614 -41.319196)
		(width 0.1397)
		(layer "In5.Cu")
		(net "PCIE_TX_CAP_N11")
	)
	(segment
		(start 272.034 -36.449)
		(end 267.526262 -35.654488)
		(width 0.1397)
		(layer "In5.Cu")
		(net "PCIE_TX_CAP_N11")
	)
	(segment
		(start 315.4553 -35.489642)
		(end 315.4553 -36.072064)
		(width 0.1397)
		(layer "In5.Cu")
		(net "PCIE_TX_CAP_N11")
	)
	(segment
		(start 290.332668 -45.891704)
		(end 281.829764 -44.191174)
		(width 0.1397)
		(layer "In5.Cu")
		(net "PCIE_TX_CAP_N11")
	)
	(segment
		(start 257.876802 -36.274756)
		(end 257.876802 -36.302442)
		(width 0.1016)
		(layer "In5.Cu")
		(net "PCIE_TX_CAP_N11")
	)
	(segment
		(start 315.6966 -35.014154)
		(end 315.620908 -35.089846)
		(width 0.1397)
		(layer "In5.Cu")
		(net "PCIE_TX_CAP_N11")
	)
	(segment
		(start 306.240688 -45.2501)
		(end 303.032668 -45.891704)
		(width 0.1397)
		(layer "In5.Cu")
		(net "PCIE_TX_CAP_N11")
	)
	(segment
		(start 259.67436 -36.238688)
		(end 259.607304 -36.171632)
		(width 0.1016)
		(layer "In5.Cu")
		(net "PCIE_TX_CAP_N11")
	)
	(segment
		(start 295.316148 -46.25975)
		(end 291.904166 -45.577506)
		(width 0.1397)
		(layer "In5.Cu")
		(net "PCIE_TX_CAP_N11")
	)
	(segment
		(start 259.44576 -36.10483)
		(end 258.046728 -36.10483)
		(width 0.1016)
		(layer "In5.Cu")
		(net "PCIE_TX_CAP_N11")
	)
	(segment
		(start 274.610322 -38.252908)
		(end 272.034 -36.449)
		(width 0.1397)
		(layer "In5.Cu")
		(net "PCIE_TX_CAP_N11")
	)
	(segment
		(start 281.829764 -44.191174)
		(end 275.823426 -39.985442)
		(width 0.1397)
		(layer "In5.Cu")
		(net "PCIE_TX_CAP_N11")
	)
	(segment
		(start 303.032668 -45.891704)
		(end 300.09465 -45.303948)
		(width 0.1397)
		(layer "In5.Cu")
		(net "PCIE_TX_CAP_N11")
	)
	(segment
		(start 308.6481 -43.564556)
		(end 306.240688 -45.2501)
		(width 0.1397)
		(layer "In5.Cu")
		(net "PCIE_TX_CAP_N11")
	)
	(segment
		(start 291.904166 -45.577506)
		(end 290.332668 -45.891704)
		(width 0.1397)
		(layer "In5.Cu")
		(net "PCIE_TX_CAP_N11")
	)
	(arc
		(start 257.926586 -36.154614)
		(mid 257.889755 -36.209736)
		(end 257.876802 -36.274756)
		(width 0.1016)
		(layer "In5.Cu")
		(net "PCIE_TX_CAP_N11")
	)
	(arc
		(start 258.046728 -36.10483)
		(mid 257.9817 -36.117765)
		(end 257.926586 -36.154614)
		(width 0.1016)
		(layer "In5.Cu")
		(net "PCIE_TX_CAP_N11")
	)
	(arc
		(start 259.607304 -36.171632)
		(mid 259.533159 -36.122216)
		(end 259.44576 -36.10483)
		(width 0.1016)
		(layer "In5.Cu")
		(net "PCIE_TX_CAP_N11")
	)
	(arc
		(start 315.620908 -35.089846)
		(mid 315.498345 -35.273274)
		(end 315.4553 -35.489642)
		(width 0.1397)
		(layer "In5.Cu")
		(net "PCIE_TX_CAP_N11")
	)
	(arc
		(start 257.876802 -36.302442)
		(mid 257.943617 -36.45168)
		(end 258.099814 -36.500054)
		(width 0.1016)
		(layer "In5.Cu")
		(net "PCIE_TX_CAP_N11")
	)
	(segment
		(start 313.38266 -36.079176)
		(end 313.489086 -36.185602)
		(width 0.136652)
		(layer "F.Cu")
		(net "PCIE_TX_CAP_N10")
	)
	(segment
		(start 258.59994 -35.999928)
		(end 259.099812 -35.500056)
		(width 0.136652)
		(layer "F.Cu")
		(net "PCIE_TX_CAP_N10")
	)
	(segment
		(start 313.247786 -34.644838)
		(end 313.247786 -35.753548)
		(width 0.136652)
		(layer "F.Cu")
		(net "PCIE_TX_CAP_N10")
	)
	(via
		(at 259.099812 -35.500056)
		(size 0.4572)
		(drill 0.2032)
		(layers "F.Cu" "B.Cu")
		(net "PCIE_TX_CAP_N10")
	)
	(via
		(at 313.489086 -36.185602)
		(size 0.508)
		(drill 0.254)
		(layers "F.Cu" "B.Cu")
		(net "PCIE_TX_CAP_N10")
	)
	(arc
		(start 313.247786 -35.753548)
		(mid 313.28284 -35.929774)
		(end 313.38266 -36.079176)
		(width 0.136652)
		(layer "F.Cu")
		(net "PCIE_TX_CAP_N10")
	)
	(arc
		(start 313.514486 -34.000948)
		(mid 313.317093 -34.296367)
		(end 313.247786 -34.644838)
		(width 0.136652)
		(layer "F.Cu")
		(net "PCIE_TX_CAP_N10")
	)
	(segment
		(start 267.80363 -34.436812)
		(end 262.78332 -35.239706)
		(width 0.1397)
		(layer "In5.Cu")
		(net "PCIE_TX_CAP_N10")
	)
	(segment
		(start 290.720526 -44.609004)
		(end 281.511502 -42.767504)
		(width 0.1397)
		(layer "In5.Cu")
		(net "PCIE_TX_CAP_N10")
	)
	(segment
		(start 295.620186 -45.22978)
		(end 291.618416 -44.429426)
		(width 0.1397)
		(layer "In5.Cu")
		(net "PCIE_TX_CAP_N10")
	)
	(segment
		(start 276.833838 -39.492428)
		(end 276.80031 -39.444676)
		(width 0.1397)
		(layer "In5.Cu")
		(net "PCIE_TX_CAP_N10")
	)
	(segment
		(start 301.157386 -44.12234)
		(end 295.620186 -45.22978)
		(width 0.1397)
		(layer "In5.Cu")
		(net "PCIE_TX_CAP_N10")
	)
	(segment
		(start 276.04339 -38.363144)
		(end 275.68144 -37.846254)
		(width 0.1397)
		(layer "In5.Cu")
		(net "PCIE_TX_CAP_N10")
	)
	(segment
		(start 309.141622 -41.053004)
		(end 308.05374 -42.606722)
		(width 0.1397)
		(layer "In5.Cu")
		(net "PCIE_TX_CAP_N10")
	)
	(segment
		(start 303.050702 -44.456096)
		(end 301.157386 -44.12234)
		(width 0.1397)
		(layer "In5.Cu")
		(net "PCIE_TX_CAP_N10")
	)
	(segment
		(start 260.119622 -35.239706)
		(end 259.984748 -35.104832)
		(width 0.1016)
		(layer "In5.Cu")
		(net "PCIE_TX_CAP_N10")
	)
	(segment
		(start 281.511502 -42.767504)
		(end 276.833838 -39.492428)
		(width 0.1397)
		(layer "In5.Cu")
		(net "PCIE_TX_CAP_N10")
	)
	(segment
		(start 259.061204 -35.104832)
		(end 258.998466 -35.13201)
		(width 0.1016)
		(layer "In5.Cu")
		(net "PCIE_TX_CAP_N10")
	)
	(segment
		(start 276.80031 -39.444676)
		(end 276.800564 -39.444676)
		(width 0.1397)
		(layer "In5.Cu")
		(net "PCIE_TX_CAP_N10")
	)
	(segment
		(start 275.68144 -37.846254)
		(end 275.31949 -37.329618)
		(width 0.1397)
		(layer "In5.Cu")
		(net "PCIE_TX_CAP_N10")
	)
	(segment
		(start 313.22264 -36.987988)
		(end 311.564782 -39.356538)
		(width 0.1397)
		(layer "In5.Cu")
		(net "PCIE_TX_CAP_N10")
	)
	(segment
		(start 291.618416 -44.429426)
		(end 290.720526 -44.609004)
		(width 0.1397)
		(layer "In5.Cu")
		(net "PCIE_TX_CAP_N10")
	)
	(segment
		(start 313.489086 -36.185602)
		(end 313.35472 -36.320222)
		(width 0.1397)
		(layer "In5.Cu")
		(net "PCIE_TX_CAP_N10")
	)
	(segment
		(start 308.05374 -42.606722)
		(end 306.207414 -43.899582)
		(width 0.1397)
		(layer "In5.Cu")
		(net "PCIE_TX_CAP_N10")
	)
	(segment
		(start 276.800564 -39.444676)
		(end 276.04339 -38.363144)
		(width 0.1397)
		(layer "In5.Cu")
		(net "PCIE_TX_CAP_N10")
	)
	(segment
		(start 259.984748 -35.104832)
		(end 259.061204 -35.104832)
		(width 0.1016)
		(layer "In5.Cu")
		(net "PCIE_TX_CAP_N10")
	)
	(segment
		(start 258.9022 -35.300158)
		(end 258.9022 -35.302444)
		(width 0.1016)
		(layer "In5.Cu")
		(net "PCIE_TX_CAP_N10")
	)
	(segment
		(start 262.78332 -35.239706)
		(end 260.274562 -35.239706)
		(width 0.1397)
		(layer "In5.Cu")
		(net "PCIE_TX_CAP_N10")
	)
	(segment
		(start 313.22264 -36.638738)
		(end 313.22264 -36.987988)
		(width 0.1397)
		(layer "In5.Cu")
		(net "PCIE_TX_CAP_N10")
	)
	(segment
		(start 311.564782 -39.356538)
		(end 309.141622 -41.053004)
		(width 0.1397)
		(layer "In5.Cu")
		(net "PCIE_TX_CAP_N10")
	)
	(segment
		(start 272.327624 -35.234626)
		(end 267.80363 -34.436812)
		(width 0.1397)
		(layer "In5.Cu")
		(net "PCIE_TX_CAP_N10")
	)
	(segment
		(start 275.31949 -37.329618)
		(end 272.327624 -35.234626)
		(width 0.1397)
		(layer "In5.Cu")
		(net "PCIE_TX_CAP_N10")
	)
	(segment
		(start 306.207414 -43.899582)
		(end 303.050702 -44.456096)
		(width 0.1397)
		(layer "In5.Cu")
		(net "PCIE_TX_CAP_N10")
	)
	(segment
		(start 260.274562 -35.239706)
		(end 260.119622 -35.239706)
		(width 0.1016)
		(layer "In5.Cu")
		(net "PCIE_TX_CAP_N10")
	)
	(arc
		(start 258.9022 -35.302444)
		(mid 258.960079 -35.442177)
		(end 259.099812 -35.500056)
		(width 0.1016)
		(layer "In5.Cu")
		(net "PCIE_TX_CAP_N10")
	)
	(arc
		(start 313.35472 -36.320222)
		(mid 313.256967 -36.46633)
		(end 313.22264 -36.638738)
		(width 0.1397)
		(layer "In5.Cu")
		(net "PCIE_TX_CAP_N10")
	)
	(arc
		(start 258.998466 -35.13201)
		(mid 258.927999 -35.203291)
		(end 258.9022 -35.300158)
		(width 0.1016)
		(layer "In5.Cu")
		(net "PCIE_TX_CAP_N10")
	)
	(segment
		(start 252.599952 -30.999938)
		(end 253.099824 -30.500066)
		(width 0.136652)
		(layer "F.Cu")
		(net "PCIE_TX_CAP_N1")
	)
	(segment
		(start 272.5166 -15.0876)
		(end 273.1262 -15.0876)
		(width 0.136652)
		(layer "F.Cu")
		(net "PCIE_TX_CAP_N1")
	)
	(via
		(at 253.099824 -30.500066)
		(size 0.4572)
		(drill 0.2032)
		(layers "F.Cu" "B.Cu")
		(net "PCIE_TX_CAP_N1")
	)
	(via
		(at 272.06829 -15.33525)
		(size 0.508)
		(drill 0.254)
		(layers "F.Cu" "B.Cu")
		(net "PCIE_TX_CAP_N1")
	)
	(arc
		(start 272.06829 -15.33525)
		(mid 272.260516 -15.153624)
		(end 272.5166 -15.0876)
		(width 0.136652)
		(layer "F.Cu")
		(net "PCIE_TX_CAP_N1")
	)
	(arc
		(start 273.1262 -15.0876)
		(mid 273.357361 -15.165347)
		(end 273.4945 -15.367)
		(width 0.136652)
		(layer "F.Cu")
		(net "PCIE_TX_CAP_N1")
	)
	(segment
		(start 252.6157 -28.893262)
		(end 252.6157 -28.20924)
		(width 0.1016)
		(layer "In5.Cu")
		(net "PCIE_TX_CAP_N1")
	)
	(segment
		(start 263.731248 -20.592034)
		(end 263.868154 -20.381214)
		(width 0.1397)
		(layer "In5.Cu")
		(net "PCIE_TX_CAP_N1")
	)
	(segment
		(start 252.6792 -28.14574)
		(end 252.6792 -28.12034)
		(width 0.1016)
		(layer "In5.Cu")
		(net "PCIE_TX_CAP_N1")
	)
	(segment
		(start 252.6792 -25.639522)
		(end 254.411734 -23.164292)
		(width 0.1397)
		(layer "In5.Cu")
		(net "PCIE_TX_CAP_N1")
	)
	(segment
		(start 264.27811 -20.294092)
		(end 268.02715 -21.09089)
		(width 0.1397)
		(layer "In5.Cu")
		(net "PCIE_TX_CAP_N1")
	)
	(segment
		(start 271.165066 -18.269712)
		(end 270.694912 -16.059404)
		(width 0.1397)
		(layer "In5.Cu")
		(net "PCIE_TX_CAP_N1")
	)
	(segment
		(start 263.110472 -20.54225)
		(end 263.321292 -20.679156)
		(width 0.1397)
		(layer "In5.Cu")
		(net "PCIE_TX_CAP_N1")
	)
	(segment
		(start 255.998472 -22.053296)
		(end 260.775196 -21.038566)
		(width 0.1397)
		(layer "In5.Cu")
		(net "PCIE_TX_CAP_N1")
	)
	(segment
		(start 260.986016 -21.175472)
		(end 261.395972 -21.08835)
		(width 0.1397)
		(layer "In5.Cu")
		(net "PCIE_TX_CAP_N1")
	)
	(segment
		(start 270.694912 -16.059404)
		(end 270.836136 -15.395194)
		(width 0.1397)
		(layer "In5.Cu")
		(net "PCIE_TX_CAP_N1")
	)
	(segment
		(start 252.6792 -28.12034)
		(end 252.6792 -25.639522)
		(width 0.1397)
		(layer "In5.Cu")
		(net "PCIE_TX_CAP_N1")
	)
	(segment
		(start 252.702314 -28.979876)
		(end 252.6157 -28.893262)
		(width 0.1016)
		(layer "In5.Cu")
		(net "PCIE_TX_CAP_N1")
	)
	(segment
		(start 271.350232 -15.070074)
		(end 271.789398 -15.070074)
		(width 0.1397)
		(layer "In5.Cu")
		(net "PCIE_TX_CAP_N1")
	)
	(segment
		(start 252.702314 -30.632146)
		(end 252.702314 -28.979876)
		(width 0.1016)
		(layer "In5.Cu")
		(net "PCIE_TX_CAP_N1")
	)
	(segment
		(start 270.917162 -19.435826)
		(end 271.165066 -18.269712)
		(width 0.1397)
		(layer "In5.Cu")
		(net "PCIE_TX_CAP_N1")
	)
	(segment
		(start 270.511778 -20.059904)
		(end 270.917162 -19.435826)
		(width 0.1397)
		(layer "In5.Cu")
		(net "PCIE_TX_CAP_N1")
	)
	(segment
		(start 253.099824 -30.500066)
		(end 253.168912 -30.602174)
		(width 0.1016)
		(layer "In5.Cu")
		(net "PCIE_TX_CAP_N1")
	)
	(segment
		(start 270.907256 -15.336774)
		(end 271.350232 -15.070074)
		(width 0.1397)
		(layer "In5.Cu")
		(net "PCIE_TX_CAP_N1")
	)
	(segment
		(start 253.105158 -30.93212)
		(end 253.104904 -30.932374)
		(width 0.1016)
		(layer "In5.Cu")
		(net "PCIE_TX_CAP_N1")
	)
	(segment
		(start 262.153654 -20.927314)
		(end 262.56361 -20.840192)
		(width 0.1397)
		(layer "In5.Cu")
		(net "PCIE_TX_CAP_N1")
	)
	(segment
		(start 252.6157 -28.20924)
		(end 252.6792 -28.14574)
		(width 0.1016)
		(layer "In5.Cu")
		(net "PCIE_TX_CAP_N1")
	)
	(segment
		(start 254.411734 -23.164292)
		(end 255.998472 -22.053296)
		(width 0.1397)
		(layer "In5.Cu")
		(net "PCIE_TX_CAP_N1")
	)
	(segment
		(start 263.321292 -20.679156)
		(end 263.731248 -20.592034)
		(width 0.1397)
		(layer "In5.Cu")
		(net "PCIE_TX_CAP_N1")
	)
	(segment
		(start 262.700516 -20.629372)
		(end 263.110472 -20.54225)
		(width 0.1397)
		(layer "In5.Cu")
		(net "PCIE_TX_CAP_N1")
	)
	(segment
		(start 268.02715 -21.09089)
		(end 269.361158 -20.807172)
		(width 0.1397)
		(layer "In5.Cu")
		(net "PCIE_TX_CAP_N1")
	)
	(segment
		(start 261.395972 -21.08835)
		(end 261.532878 -20.87753)
		(width 0.1397)
		(layer "In5.Cu")
		(net "PCIE_TX_CAP_N1")
	)
	(segment
		(start 261.942834 -20.790408)
		(end 262.153654 -20.927314)
		(width 0.1397)
		(layer "In5.Cu")
		(net "PCIE_TX_CAP_N1")
	)
	(segment
		(start 260.775196 -21.038566)
		(end 260.986016 -21.175472)
		(width 0.1397)
		(layer "In5.Cu")
		(net "PCIE_TX_CAP_N1")
	)
	(segment
		(start 261.532878 -20.87753)
		(end 261.942834 -20.790408)
		(width 0.1397)
		(layer "In5.Cu")
		(net "PCIE_TX_CAP_N1")
	)
	(segment
		(start 263.868154 -20.381214)
		(end 264.27811 -20.294092)
		(width 0.1397)
		(layer "In5.Cu")
		(net "PCIE_TX_CAP_N1")
	)
	(segment
		(start 262.56361 -20.840192)
		(end 262.700516 -20.629372)
		(width 0.1397)
		(layer "In5.Cu")
		(net "PCIE_TX_CAP_N1")
	)
	(segment
		(start 269.361158 -20.807172)
		(end 270.511778 -20.059904)
		(width 0.1397)
		(layer "In5.Cu")
		(net "PCIE_TX_CAP_N1")
	)
	(arc
		(start 252.774704 -30.868366)
		(mid 252.720822 -30.755677)
		(end 252.702314 -30.632146)
		(width 0.1016)
		(layer "In5.Cu")
		(net "PCIE_TX_CAP_N1")
	)
	(arc
		(start 253.104904 -30.932374)
		(mid 252.972533 -30.992416)
		(end 252.833378 -30.950408)
		(width 0.1016)
		(layer "In5.Cu")
		(net "PCIE_TX_CAP_N1")
	)
	(arc
		(start 271.789398 -15.070074)
		(mid 271.981783 -15.146957)
		(end 272.06829 -15.33525)
		(width 0.1397)
		(layer "In5.Cu")
		(net "PCIE_TX_CAP_N1")
	)
	(arc
		(start 270.836136 -15.395194)
		(mid 270.869507 -15.363317)
		(end 270.907256 -15.336774)
		(width 0.1397)
		(layer "In5.Cu")
		(net "PCIE_TX_CAP_N1")
	)
	(arc
		(start 253.168912 -30.602174)
		(mid 253.205328 -30.780357)
		(end 253.105158 -30.93212)
		(width 0.1016)
		(layer "In5.Cu")
		(net "PCIE_TX_CAP_N1")
	)
	(arc
		(start 252.833378 -30.950408)
		(mid 252.803511 -30.909766)
		(end 252.774704 -30.868366)
		(width 0.1016)
		(layer "In5.Cu")
		(net "PCIE_TX_CAP_N1")
	)
	(segment
		(start 269.0876 -14.08938)
		(end 268.890496 -14.08938)
		(width 0.136652)
		(layer "F.Cu")
		(net "PCIE_TX_CAP_N0")
	)
	(segment
		(start 252.099826 -29.500068)
		(end 252.099826 -29.398468)
		(width 0.136652)
		(layer "F.Cu")
		(net "PCIE_TX_CAP_N0")
	)
	(segment
		(start 251.599954 -29.99994)
		(end 252.099826 -29.500068)
		(width 0.136652)
		(layer "F.Cu")
		(net "PCIE_TX_CAP_N0")
	)
	(segment
		(start 268.606778 -13.972032)
		(end 268.478 -13.843)
		(width 0.136652)
		(layer "F.Cu")
		(net "PCIE_TX_CAP_N0")
	)
	(segment
		(start 272.95856 -12.921996)
		(end 271.90573 -12.921996)
		(width 0.136652)
		(layer "F.Cu")
		(net "PCIE_TX_CAP_N0")
	)
	(via
		(at 252.099826 -29.398468)
		(size 0.4572)
		(drill 0.2032)
		(layers "F.Cu" "B.Cu")
		(net "PCIE_TX_CAP_N0")
	)
	(via
		(at 268.478 -13.843)
		(size 0.508)
		(drill 0.254)
		(layers "F.Cu" "B.Cu")
		(net "PCIE_TX_CAP_N0")
	)
	(arc
		(start 268.890496 -14.08938)
		(mid 268.736961 -14.058934)
		(end 268.606778 -13.972032)
		(width 0.136652)
		(layer "F.Cu")
		(net "PCIE_TX_CAP_N0")
	)
	(arc
		(start 270.023082 -13.701776)
		(mid 269.593893 -13.988614)
		(end 269.0876 -14.08938)
		(width 0.136652)
		(layer "F.Cu")
		(net "PCIE_TX_CAP_N0")
	)
	(arc
		(start 273.4945 -12.7)
		(mid 273.253515 -12.862159)
		(end 272.969228 -12.921742)
		(width 0.136652)
		(layer "F.Cu")
		(net "PCIE_TX_CAP_N0")
	)
	(arc
		(start 271.90573 -12.921996)
		(mid 270.886849 -13.124646)
		(end 270.023082 -13.701776)
		(width 0.136652)
		(layer "F.Cu")
		(net "PCIE_TX_CAP_N0")
	)
	(arc
		(start 272.969228 -12.921742)
		(mid 272.963894 -12.921888)
		(end 272.95856 -12.921996)
		(width 0.136652)
		(layer "F.Cu")
		(net "PCIE_TX_CAP_N0")
	)
	(segment
		(start 252.08738 -22.751796)
		(end 251.757942 -24.620982)
		(width 0.1397)
		(layer "In5.Cu")
		(net "PCIE_TX_CAP_N0")
	)
	(segment
		(start 251.757942 -24.620982)
		(end 251.757942 -28.389834)
		(width 0.1397)
		(layer "In5.Cu")
		(net "PCIE_TX_CAP_N0")
	)
	(segment
		(start 269.222728 -14.031214)
		(end 269.551404 -14.284198)
		(width 0.1397)
		(layer "In5.Cu")
		(net "PCIE_TX_CAP_N0")
	)
	(segment
		(start 258.994148 -18.698972)
		(end 256.65049 -20.22094)
		(width 0.1397)
		(layer "In5.Cu")
		(net "PCIE_TX_CAP_N0")
	)
	(segment
		(start 269.651988 -14.99108)
		(end 268.945106 -16.080994)
		(width 0.1397)
		(layer "In5.Cu")
		(net "PCIE_TX_CAP_N0")
	)
	(segment
		(start 251.757942 -28.389834)
		(end 251.697236 -28.45054)
		(width 0.1016)
		(layer "In5.Cu")
		(net "PCIE_TX_CAP_N0")
	)
	(segment
		(start 251.697236 -28.45054)
		(end 251.697236 -29.64815)
		(width 0.1016)
		(layer "In5.Cu")
		(net "PCIE_TX_CAP_N0")
	)
	(segment
		(start 268.821662 -14.031214)
		(end 269.222728 -14.031214)
		(width 0.1397)
		(layer "In5.Cu")
		(net "PCIE_TX_CAP_N0")
	)
	(segment
		(start 267.793724 -16.82877)
		(end 258.994148 -18.698972)
		(width 0.1397)
		(layer "In5.Cu")
		(net "PCIE_TX_CAP_N0")
	)
	(segment
		(start 268.945106 -16.080994)
		(end 267.793724 -16.82877)
		(width 0.1397)
		(layer "In5.Cu")
		(net "PCIE_TX_CAP_N0")
	)
	(segment
		(start 269.551404 -14.284198)
		(end 269.651988 -14.99108)
		(width 0.1397)
		(layer "In5.Cu")
		(net "PCIE_TX_CAP_N0")
	)
	(segment
		(start 256.65049 -20.22094)
		(end 252.08738 -22.751796)
		(width 0.1397)
		(layer "In5.Cu")
		(net "PCIE_TX_CAP_N0")
	)
	(arc
		(start 268.478 -13.843)
		(mid 268.625756 -13.981057)
		(end 268.821662 -14.031214)
		(width 0.1397)
		(layer "In5.Cu")
		(net "PCIE_TX_CAP_N0")
	)
	(arc
		(start 251.849382 -29.800296)
		(mid 252.086083 -29.668895)
		(end 252.099826 -29.398468)
		(width 0.1016)
		(layer "In5.Cu")
		(net "PCIE_TX_CAP_N0")
	)
	(arc
		(start 251.697236 -29.64815)
		(mid 251.741799 -29.755733)
		(end 251.849382 -29.800296)
		(width 0.1016)
		(layer "In5.Cu")
		(net "PCIE_TX_CAP_N0")
	)
	(segment
		(start 238.59998 -30.999938)
		(end 238.100108 -30.500066)
		(width 0.136652)
		(layer "F.Cu")
		(net "PCIE_RX_P95")
	)
	(via
		(at 238.100108 -30.500066)
		(size 0.4572)
		(drill 0.2032)
		(layers "F.Cu" "B.Cu")
		(net "PCIE_RX_P95")
	)
	(segment
		(start 212.29066 -22.737572)
		(end 214.108538 -20.919694)
		(width 0.1397)
		(layer "In2.Cu")
		(net "PCIE_RX_P95")
	)
	(segment
		(start 206.657448 -23.679658)
		(end 207.094582 -23.586694)
		(width 0.1397)
		(layer "In2.Cu")
		(net "PCIE_RX_P95")
	)
	(segment
		(start 237.73257 -28.279598)
		(end 237.73257 -28.304998)
		(width 0.1016)
		(layer "In2.Cu")
		(net "PCIE_RX_P95")
	)
	(segment
		(start 238.100108 -30.20314)
		(end 238.100108 -30.500066)
		(width 0.1016)
		(layer "In2.Cu")
		(net "PCIE_RX_P95")
	)
	(segment
		(start 201.974958 -22.684232)
		(end 206.657448 -23.679658)
		(width 0.1397)
		(layer "In2.Cu")
		(net "PCIE_RX_P95")
	)
	(segment
		(start 232.061004 -19.611086)
		(end 232.793032 -20.123658)
		(width 0.1397)
		(layer "In2.Cu")
		(net "PCIE_RX_P95")
	)
	(segment
		(start 223.408748 -18.0848)
		(end 232.061004 -19.611086)
		(width 0.1397)
		(layer "In2.Cu")
		(net "PCIE_RX_P95")
	)
	(segment
		(start 171.315888 -13.678154)
		(end 171.723304 -14.08557)
		(width 0.1397)
		(layer "In2.Cu")
		(net "PCIE_RX_P95")
	)
	(segment
		(start 170.676062 -13.829538)
		(end 170.850306 -13.655294)
		(width 0.1397)
		(layer "In2.Cu")
		(net "PCIE_RX_P95")
	)
	(segment
		(start 217.625168 -20.056602)
		(end 219.443046 -18.784062)
		(width 0.1397)
		(layer "In2.Cu")
		(net "PCIE_RX_P95")
	)
	(segment
		(start 198.204836 -23.11146)
		(end 199.084946 -23.298404)
		(width 0.1397)
		(layer "In2.Cu")
		(net "PCIE_RX_P95")
	)
	(segment
		(start 209.481166 -24.093932)
		(end 210.332574 -23.912322)
		(width 0.1397)
		(layer "In2.Cu")
		(net "PCIE_RX_P95")
	)
	(segment
		(start 237.861094 -30.10154)
		(end 237.998508 -30.10154)
		(width 0.1016)
		(layer "In2.Cu")
		(net "PCIE_RX_P95")
	)
	(segment
		(start 214.62365 -20.58543)
		(end 217.625168 -20.056602)
		(width 0.1397)
		(layer "In2.Cu")
		(net "PCIE_RX_P95")
	)
	(segment
		(start 199.084946 -23.298404)
		(end 201.974958 -22.684232)
		(width 0.1397)
		(layer "In2.Cu")
		(net "PCIE_RX_P95")
	)
	(segment
		(start 187.897262 -15.893288)
		(end 198.204836 -23.11146)
		(width 0.1397)
		(layer "In2.Cu")
		(net "PCIE_RX_P95")
	)
	(segment
		(start 214.108538 -20.919694)
		(end 214.62365 -20.58543)
		(width 0.1397)
		(layer "In2.Cu")
		(net "PCIE_RX_P95")
	)
	(segment
		(start 237.505748 -29.214064)
		(end 237.505748 -29.746194)
		(width 0.1016)
		(layer "In2.Cu")
		(net "PCIE_RX_P95")
	)
	(segment
		(start 181.757828 -14.81074)
		(end 187.897262 -15.893288)
		(width 0.1397)
		(layer "In2.Cu")
		(net "PCIE_RX_P95")
	)
	(segment
		(start 207.094582 -23.586694)
		(end 209.481166 -24.093932)
		(width 0.1397)
		(layer "In2.Cu")
		(net "PCIE_RX_P95")
	)
	(segment
		(start 237.73257 -26.173684)
		(end 237.73257 -28.279598)
		(width 0.1397)
		(layer "In2.Cu")
		(net "PCIE_RX_P95")
	)
	(segment
		(start 219.443046 -18.784062)
		(end 223.408748 -18.0848)
		(width 0.1397)
		(layer "In2.Cu")
		(net "PCIE_RX_P95")
	)
	(segment
		(start 171.315634 -13.677646)
		(end 171.315888 -13.678154)
		(width 0.1397)
		(layer "In2.Cu")
		(net "PCIE_RX_P95")
	)
	(segment
		(start 233.524552 -20.635976)
		(end 236.633766 -25.07488)
		(width 0.1397)
		(layer "In2.Cu")
		(net "PCIE_RX_P95")
	)
	(segment
		(start 210.332574 -23.912322)
		(end 212.29066 -22.737572)
		(width 0.1397)
		(layer "In2.Cu")
		(net "PCIE_RX_P95")
	)
	(segment
		(start 176.746408 -15.693644)
		(end 181.757828 -14.81074)
		(width 0.1397)
		(layer "In2.Cu")
		(net "PCIE_RX_P95")
	)
	(segment
		(start 236.633766 -25.07488)
		(end 237.73257 -26.173684)
		(width 0.1397)
		(layer "In2.Cu")
		(net "PCIE_RX_P95")
	)
	(segment
		(start 237.79607 -28.368498)
		(end 237.79607 -28.923742)
		(width 0.1016)
		(layer "In2.Cu")
		(net "PCIE_RX_P95")
	)
	(segment
		(start 237.73257 -28.304998)
		(end 237.79607 -28.368498)
		(width 0.1016)
		(layer "In2.Cu")
		(net "PCIE_RX_P95")
	)
	(segment
		(start 232.793032 -20.123912)
		(end 233.524552 -20.635976)
		(width 0.1397)
		(layer "In2.Cu")
		(net "PCIE_RX_P95")
	)
	(segment
		(start 237.505748 -29.746194)
		(end 237.861094 -30.10154)
		(width 0.1016)
		(layer "In2.Cu")
		(net "PCIE_RX_P95")
	)
	(segment
		(start 232.793032 -20.123658)
		(end 232.793032 -20.123912)
		(width 0.1397)
		(layer "In2.Cu")
		(net "PCIE_RX_P95")
	)
	(segment
		(start 171.293282 -13.655294)
		(end 171.315634 -13.677646)
		(width 0.1397)
		(layer "In2.Cu")
		(net "PCIE_RX_P95")
	)
	(segment
		(start 237.79607 -28.923742)
		(end 237.505748 -29.214064)
		(width 0.1016)
		(layer "In2.Cu")
		(net "PCIE_RX_P95")
	)
	(segment
		(start 171.723304 -14.08557)
		(end 176.746408 -15.693644)
		(width 0.1397)
		(layer "In2.Cu")
		(net "PCIE_RX_P95")
	)
	(arc
		(start 237.998508 -30.10154)
		(mid 238.07035 -30.131298)
		(end 238.100108 -30.20314)
		(width 0.1016)
		(layer "In2.Cu")
		(net "PCIE_RX_P95")
	)
	(arc
		(start 170.634406 -13.930122)
		(mid 170.645233 -13.875689)
		(end 170.676062 -13.829538)
		(width 0.1397)
		(layer "In2.Cu")
		(net "PCIE_RX_P95")
	)
	(arc
		(start 170.850306 -13.655294)
		(mid 171.071794 -13.563625)
		(end 171.293282 -13.655294)
		(width 0.1397)
		(layer "In2.Cu")
		(net "PCIE_RX_P95")
	)
	(segment
		(start 237.599982 -31.999936)
		(end 237.10011 -31.500064)
		(width 0.136652)
		(layer "F.Cu")
		(net "PCIE_RX_P94")
	)
	(via
		(at 237.10011 -31.500064)
		(size 0.4572)
		(drill 0.2032)
		(layers "F.Cu" "B.Cu")
		(net "PCIE_RX_P94")
	)
	(segment
		(start 235.54182 -27.943302)
		(end 235.54182 -27.950668)
		(width 0.1397)
		(layer "In2.Cu")
		(net "PCIE_RX_P94")
	)
	(segment
		(start 236.101636 -28.510484)
		(end 236.119416 -28.528264)
		(width 0.1016)
		(layer "In2.Cu")
		(net "PCIE_RX_P94")
	)
	(segment
		(start 216.474802 -23.496016)
		(end 220.328236 -20.798028)
		(width 0.1397)
		(layer "In2.Cu")
		(net "PCIE_RX_P94")
	)
	(segment
		(start 174.943516 -18.633694)
		(end 180.902864 -17.368012)
		(width 0.1397)
		(layer "In2.Cu")
		(net "PCIE_RX_P94")
	)
	(segment
		(start 235.54182 -27.950668)
		(end 236.101636 -28.510484)
		(width 0.1397)
		(layer "In2.Cu")
		(net "PCIE_RX_P94")
	)
	(segment
		(start 203.22794 -27.651202)
		(end 205.680056 -27.129994)
		(width 0.1397)
		(layer "In2.Cu")
		(net "PCIE_RX_P94")
	)
	(segment
		(start 228.97592 -21.157692)
		(end 229.337616 -21.41093)
		(width 0.1397)
		(layer "In2.Cu")
		(net "PCIE_RX_P94")
	)
	(segment
		(start 236.119416 -28.528264)
		(end 236.209332 -28.528264)
		(width 0.1016)
		(layer "In2.Cu")
		(net "PCIE_RX_P94")
	)
	(segment
		(start 171.77512 -17.96034)
		(end 171.777152 -17.960848)
		(width 0.1397)
		(layer "In2.Cu")
		(net "PCIE_RX_P94")
	)
	(segment
		(start 237.047024 -31.154624)
		(end 237.070392 -31.177992)
		(width 0.1016)
		(layer "In2.Cu")
		(net "PCIE_RX_P94")
	)
	(segment
		(start 236.4994 -28.818332)
		(end 236.4994 -30.8356)
		(width 0.1016)
		(layer "In2.Cu")
		(net "PCIE_RX_P94")
	)
	(segment
		(start 233.228642 -24.641048)
		(end 235.54182 -27.943302)
		(width 0.1397)
		(layer "In2.Cu")
		(net "PCIE_RX_P94")
	)
	(segment
		(start 236.765338 -31.101538)
		(end 236.918754 -31.101538)
		(width 0.1016)
		(layer "In2.Cu")
		(net "PCIE_RX_P94")
	)
	(segment
		(start 196.324728 -26.183336)
		(end 203.22794 -27.651202)
		(width 0.1397)
		(layer "In2.Cu")
		(net "PCIE_RX_P94")
	)
	(segment
		(start 180.902864 -17.368012)
		(end 184.688226 -18.034508)
		(width 0.1397)
		(layer "In2.Cu")
		(net "PCIE_RX_P94")
	)
	(segment
		(start 171.777152 -17.960848)
		(end 171.777406 -17.960848)
		(width 0.1397)
		(layer "In2.Cu")
		(net "PCIE_RX_P94")
	)
	(segment
		(start 229.337616 -21.41093)
		(end 230.912416 -22.98573)
		(width 0.1397)
		(layer "In2.Cu")
		(net "PCIE_RX_P94")
	)
	(segment
		(start 237.10011 -31.249874)
		(end 237.10011 -31.500064)
		(width 0.1016)
		(layer "In2.Cu")
		(net "PCIE_RX_P94")
	)
	(segment
		(start 230.912416 -22.98573)
		(end 230.957374 -23.049992)
		(width 0.1397)
		(layer "In2.Cu")
		(net "PCIE_RX_P94")
	)
	(segment
		(start 171.777406 -17.960848)
		(end 174.943516 -18.633694)
		(width 0.1397)
		(layer "In2.Cu")
		(net "PCIE_RX_P94")
	)
	(segment
		(start 213.962488 -23.938992)
		(end 216.474802 -23.496016)
		(width 0.1397)
		(layer "In2.Cu")
		(net "PCIE_RX_P94")
	)
	(segment
		(start 208.032858 -27.54376)
		(end 209.077052 -27.359356)
		(width 0.1397)
		(layer "In2.Cu")
		(net "PCIE_RX_P94")
	)
	(segment
		(start 223.422972 -20.17903)
		(end 228.97592 -21.157692)
		(width 0.1397)
		(layer "In2.Cu")
		(net "PCIE_RX_P94")
	)
	(segment
		(start 236.209332 -28.528264)
		(end 236.4994 -28.818332)
		(width 0.1016)
		(layer "In2.Cu")
		(net "PCIE_RX_P94")
	)
	(segment
		(start 205.680056 -27.129994)
		(end 208.032858 -27.54376)
		(width 0.1397)
		(layer "In2.Cu")
		(net "PCIE_RX_P94")
	)
	(segment
		(start 220.328236 -20.798028)
		(end 223.422972 -20.17903)
		(width 0.1397)
		(layer "In2.Cu")
		(net "PCIE_RX_P94")
	)
	(segment
		(start 209.077052 -27.359356)
		(end 213.962488 -23.938992)
		(width 0.1397)
		(layer "In2.Cu")
		(net "PCIE_RX_P94")
	)
	(segment
		(start 230.957374 -23.049992)
		(end 233.228642 -24.641048)
		(width 0.1397)
		(layer "In2.Cu")
		(net "PCIE_RX_P94")
	)
	(segment
		(start 184.688226 -18.034508)
		(end 196.324728 -26.183336)
		(width 0.1397)
		(layer "In2.Cu")
		(net "PCIE_RX_P94")
	)
	(arc
		(start 237.070392 -31.177992)
		(mid 237.092375 -31.210986)
		(end 237.10011 -31.249874)
		(width 0.1016)
		(layer "In2.Cu")
		(net "PCIE_RX_P94")
	)
	(arc
		(start 236.918754 -31.101538)
		(mid 236.98817 -31.115328)
		(end 237.047024 -31.154624)
		(width 0.1016)
		(layer "In2.Cu")
		(net "PCIE_RX_P94")
	)
	(arc
		(start 171.363132 -17.628362)
		(mid 171.41592 -17.698787)
		(end 171.472098 -17.766538)
		(width 0.1397)
		(layer "In2.Cu")
		(net "PCIE_RX_P94")
	)
	(arc
		(start 171.75353 -17.953482)
		(mid 171.764294 -17.957009)
		(end 171.77512 -17.96034)
		(width 0.1397)
		(layer "In2.Cu")
		(net "PCIE_RX_P94")
	)
	(arc
		(start 170.634406 -17.729962)
		(mid 170.94171 -17.429094)
		(end 171.339002 -17.593564)
		(width 0.1397)
		(layer "In2.Cu")
		(net "PCIE_RX_P94")
	)
	(arc
		(start 171.472098 -17.766538)
		(mid 171.600171 -17.879046)
		(end 171.75353 -17.953482)
		(width 0.1397)
		(layer "In2.Cu")
		(net "PCIE_RX_P94")
	)
	(arc
		(start 171.339002 -17.593564)
		(mid 171.350963 -17.611035)
		(end 171.363132 -17.628362)
		(width 0.1397)
		(layer "In2.Cu")
		(net "PCIE_RX_P94")
	)
	(arc
		(start 236.4994 -30.8356)
		(mid 236.577291 -31.023647)
		(end 236.765338 -31.101538)
		(width 0.1016)
		(layer "In2.Cu")
		(net "PCIE_RX_P94")
	)
	(segment
		(start 236.599984 -30.999938)
		(end 236.100112 -30.500066)
		(width 0.136652)
		(layer "F.Cu")
		(net "PCIE_RX_P93")
	)
	(via
		(at 236.100112 -30.500066)
		(size 0.4572)
		(drill 0.2032)
		(layers "F.Cu" "B.Cu")
		(net "PCIE_RX_P93")
	)
	(segment
		(start 173.112176 -20.307046)
		(end 173.184566 -20.319746)
		(width 0.1397)
		(layer "In2.Cu")
		(net "PCIE_RX_P93")
	)
	(segment
		(start 230.980234 -24.273256)
		(end 231.632506 -25.202896)
		(width 0.1397)
		(layer "In2.Cu")
		(net "PCIE_RX_P93")
	)
	(segment
		(start 231.632252 -25.20315)
		(end 232.306876 -25.675336)
		(width 0.1397)
		(layer "In2.Cu")
		(net "PCIE_RX_P93")
	)
	(segment
		(start 220.376496 -23.796244)
		(end 220.37802 -23.79472)
		(width 0.1397)
		(layer "In2.Cu")
		(net "PCIE_RX_P93")
	)
	(segment
		(start 209.298032 -28.29433)
		(end 214.158068 -24.891746)
		(width 0.1397)
		(layer "In2.Cu")
		(net "PCIE_RX_P93")
	)
	(segment
		(start 229.32644 -23.114508)
		(end 230.980488 -24.273256)
		(width 0.1397)
		(layer "In2.Cu")
		(net "PCIE_RX_P93")
	)
	(segment
		(start 188.54547 -25.19172)
		(end 191.27343 -27.102308)
		(width 0.1397)
		(layer "In2.Cu")
		(net "PCIE_RX_P93")
	)
	(segment
		(start 198.792338 -27.816302)
		(end 204.78369 -29.089858)
		(width 0.1397)
		(layer "In2.Cu")
		(net "PCIE_RX_P93")
	)
	(segment
		(start 169.208958 -17.63776)
		(end 169.503852 -17.966182)
		(width 0.1397)
		(layer "In2.Cu")
		(net "PCIE_RX_P93")
	)
	(segment
		(start 173.184566 -20.319746)
		(end 173.716442 -20.432776)
		(width 0.1397)
		(layer "In2.Cu")
		(net "PCIE_RX_P93")
	)
	(segment
		(start 191.27343 -27.102308)
		(end 197.057518 -28.122372)
		(width 0.1397)
		(layer "In2.Cu")
		(net "PCIE_RX_P93")
	)
	(segment
		(start 227.60559 -22.553422)
		(end 229.32644 -23.114508)
		(width 0.1397)
		(layer "In2.Cu")
		(net "PCIE_RX_P93")
	)
	(segment
		(start 204.78369 -29.089858)
		(end 209.298032 -28.29433)
		(width 0.1397)
		(layer "In2.Cu")
		(net "PCIE_RX_P93")
	)
	(segment
		(start 232.60177 -26.09469)
		(end 234.46359 -27.95651)
		(width 0.1397)
		(layer "In2.Cu")
		(net "PCIE_RX_P93")
	)
	(segment
		(start 168.80459 -17.24152)
		(end 168.87698 -17.280382)
		(width 0.1397)
		(layer "In2.Cu")
		(net "PCIE_RX_P93")
	)
	(segment
		(start 220.37802 -23.79472)
		(end 225.859086 -22.698456)
		(width 0.1397)
		(layer "In2.Cu")
		(net "PCIE_RX_P93")
	)
	(segment
		(start 234.80395 -28.396184)
		(end 234.80395 -29.58973)
		(width 0.1016)
		(layer "In2.Cu")
		(net "PCIE_RX_P93")
	)
	(segment
		(start 170.497246 -19.197574)
		(end 171.936156 -19.483324)
		(width 0.1397)
		(layer "In2.Cu")
		(net "PCIE_RX_P93")
	)
	(segment
		(start 234.481624 -27.974544)
		(end 234.571286 -27.974544)
		(width 0.1016)
		(layer "In2.Cu")
		(net "PCIE_RX_P93")
	)
	(segment
		(start 184.674764 -19.231102)
		(end 188.54547 -25.19172)
		(width 0.1397)
		(layer "In2.Cu")
		(net "PCIE_RX_P93")
	)
	(segment
		(start 231.632506 -25.202896)
		(end 231.632252 -25.20315)
		(width 0.1397)
		(layer "In2.Cu")
		(net "PCIE_RX_P93")
	)
	(segment
		(start 168.384474 -17.729962)
		(end 168.602406 -17.323054)
		(width 0.1397)
		(layer "In2.Cu")
		(net "PCIE_RX_P93")
	)
	(segment
		(start 169.503852 -17.966182)
		(end 169.841672 -18.726404)
		(width 0.1397)
		(layer "In2.Cu")
		(net "PCIE_RX_P93")
	)
	(segment
		(start 214.158068 -24.891746)
		(end 220.3704 -23.796244)
		(width 0.1397)
		(layer "In2.Cu")
		(net "PCIE_RX_P93")
	)
	(segment
		(start 184.401968 -19.054064)
		(end 184.674764 -19.231102)
		(width 0.1397)
		(layer "In2.Cu")
		(net "PCIE_RX_P93")
	)
	(segment
		(start 230.980488 -24.273256)
		(end 230.980234 -24.273256)
		(width 0.1397)
		(layer "In2.Cu")
		(net "PCIE_RX_P93")
	)
	(segment
		(start 232.314496 -25.680416)
		(end 232.60177 -26.09469)
		(width 0.1397)
		(layer "In2.Cu")
		(net "PCIE_RX_P93")
	)
	(segment
		(start 234.571286 -27.974544)
		(end 234.670092 -28.07335)
		(width 0.1016)
		(layer "In2.Cu")
		(net "PCIE_RX_P93")
	)
	(segment
		(start 225.859086 -22.698456)
		(end 226.7458 -22.876002)
		(width 0.1397)
		(layer "In2.Cu")
		(net "PCIE_RX_P93")
	)
	(segment
		(start 234.46359 -27.95651)
		(end 234.481624 -27.974544)
		(width 0.1016)
		(layer "In2.Cu")
		(net "PCIE_RX_P93")
	)
	(segment
		(start 182.302658 -18.607786)
		(end 184.401968 -19.054064)
		(width 0.1397)
		(layer "In2.Cu")
		(net "PCIE_RX_P93")
	)
	(segment
		(start 197.057518 -28.122372)
		(end 198.792338 -27.816302)
		(width 0.1397)
		(layer "In2.Cu")
		(net "PCIE_RX_P93")
	)
	(segment
		(start 235.33227 -30.11805)
		(end 235.964476 -30.11805)
		(width 0.1016)
		(layer "In2.Cu")
		(net "PCIE_RX_P93")
	)
	(segment
		(start 169.841672 -18.726404)
		(end 170.497246 -19.197574)
		(width 0.1397)
		(layer "In2.Cu")
		(net "PCIE_RX_P93")
	)
	(segment
		(start 173.716442 -20.432776)
		(end 182.302658 -18.607786)
		(width 0.1397)
		(layer "In2.Cu")
		(net "PCIE_RX_P93")
	)
	(segment
		(start 220.3704 -23.796244)
		(end 220.376496 -23.796244)
		(width 0.1397)
		(layer "In2.Cu")
		(net "PCIE_RX_P93")
	)
	(segment
		(start 226.7458 -22.876002)
		(end 227.60559 -22.553422)
		(width 0.1397)
		(layer "In2.Cu")
		(net "PCIE_RX_P93")
	)
	(segment
		(start 168.87698 -17.280382)
		(end 168.87698 -17.280636)
		(width 0.1397)
		(layer "In2.Cu")
		(net "PCIE_RX_P93")
	)
	(segment
		(start 236.100112 -30.253686)
		(end 236.100112 -30.500066)
		(width 0.1016)
		(layer "In2.Cu")
		(net "PCIE_RX_P93")
	)
	(segment
		(start 171.936156 -19.483324)
		(end 173.112176 -20.307046)
		(width 0.1397)
		(layer "In2.Cu")
		(net "PCIE_RX_P93")
	)
	(segment
		(start 168.913556 -17.30883)
		(end 169.208958 -17.63776)
		(width 0.1397)
		(layer "In2.Cu")
		(net "PCIE_RX_P93")
	)
	(segment
		(start 232.306876 -25.675336)
		(end 232.314496 -25.680416)
		(width 0.1397)
		(layer "In2.Cu")
		(net "PCIE_RX_P93")
	)
	(arc
		(start 168.87698 -17.280636)
		(mid 168.896481 -17.293157)
		(end 168.913556 -17.30883)
		(width 0.1397)
		(layer "In2.Cu")
		(net "PCIE_RX_P93")
	)
	(arc
		(start 235.964476 -30.11805)
		(mid 236.060385 -30.157777)
		(end 236.100112 -30.253686)
		(width 0.1016)
		(layer "In2.Cu")
		(net "PCIE_RX_P93")
	)
	(arc
		(start 234.80395 -29.58973)
		(mid 234.958691 -29.963309)
		(end 235.33227 -30.11805)
		(width 0.1016)
		(layer "In2.Cu")
		(net "PCIE_RX_P93")
	)
	(arc
		(start 168.602406 -17.323054)
		(mid 168.688712 -17.245644)
		(end 168.80459 -17.24152)
		(width 0.1397)
		(layer "In2.Cu")
		(net "PCIE_RX_P93")
	)
	(arc
		(start 234.670092 -28.07335)
		(mid 234.769198 -28.221438)
		(end 234.80395 -28.396184)
		(width 0.1016)
		(layer "In2.Cu")
		(net "PCIE_RX_P93")
	)
	(segment
		(start 235.599986 -31.999936)
		(end 235.100114 -31.500064)
		(width 0.136652)
		(layer "F.Cu")
		(net "PCIE_RX_P92")
	)
	(via
		(at 235.100114 -31.500064)
		(size 0.4572)
		(drill 0.2032)
		(layers "F.Cu" "B.Cu")
		(net "PCIE_RX_P92")
	)
	(segment
		(start 236.665008 -26.514552)
		(end 237.01502 -27.05354)
		(width 0.1397)
		(layer "In2.Cu")
		(net "PCIE_RX_P92")
	)
	(segment
		(start 214.214964 -22.80666)
		(end 216.62898 -22.380956)
		(width 0.1397)
		(layer "In2.Cu")
		(net "PCIE_RX_P92")
	)
	(segment
		(start 195.388484 -24.048212)
		(end 195.45427 -24.062182)
		(width 0.1397)
		(layer "In2.Cu")
		(net "PCIE_RX_P92")
	)
	(segment
		(start 223.65462 -19.13509)
		(end 231.077008 -20.715732)
		(width 0.1397)
		(layer "In2.Cu")
		(net "PCIE_RX_P92")
	)
	(segment
		(start 169.040048 -13.616686)
		(end 169.041064 -13.61821)
		(width 0.1397)
		(layer "In2.Cu")
		(net "PCIE_RX_P92")
	)
	(segment
		(start 169.85996 -14.681708)
		(end 169.86123 -14.68247)
		(width 0.1397)
		(layer "In2.Cu")
		(net "PCIE_RX_P92")
	)
	(segment
		(start 195.454524 -24.062182)
		(end 195.454524 -24.062436)
		(width 0.1397)
		(layer "In2.Cu")
		(net "PCIE_RX_P92")
	)
	(segment
		(start 168.24579 -13.476224)
		(end 168.232328 -13.449046)
		(width 0.1397)
		(layer "In2.Cu")
		(net "PCIE_RX_P92")
	)
	(segment
		(start 211.413852 -24.6253)
		(end 214.214964 -22.80666)
		(width 0.1397)
		(layer "In2.Cu")
		(net "PCIE_RX_P92")
	)
	(segment
		(start 237.01502 -28.44927)
		(end 237.01502 -28.47467)
		(width 0.1016)
		(layer "In2.Cu")
		(net "PCIE_RX_P92")
	)
	(segment
		(start 237.07852 -28.53817)
		(end 237.07852 -29.915866)
		(width 0.1016)
		(layer "In2.Cu")
		(net "PCIE_RX_P92")
	)
	(segment
		(start 177.23739 -16.847058)
		(end 181.148736 -16.015208)
		(width 0.1397)
		(layer "In2.Cu")
		(net "PCIE_RX_P92")
	)
	(segment
		(start 232.632758 -21.842476)
		(end 232.726992 -22.284436)
		(width 0.1397)
		(layer "In2.Cu")
		(net "PCIE_RX_P92")
	)
	(segment
		(start 237.087156 -31.9024)
		(end 234.921552 -31.9024)
		(width 0.1016)
		(layer "In2.Cu")
		(net "PCIE_RX_P92")
	)
	(segment
		(start 234.8484 -31.110936)
		(end 234.882436 -31.104332)
		(width 0.1016)
		(layer "In2.Cu")
		(net "PCIE_RX_P92")
	)
	(segment
		(start 206.474822 -26.402538)
		(end 207.640936 -26.650696)
		(width 0.1397)
		(layer "In2.Cu")
		(net "PCIE_RX_P92")
	)
	(segment
		(start 184.852564 -16.667988)
		(end 195.388484 -24.048212)
		(width 0.1397)
		(layer "In2.Cu")
		(net "PCIE_RX_P92")
	)
	(segment
		(start 232.726992 -22.284436)
		(end 234.604814 -25.175972)
		(width 0.1397)
		(layer "In2.Cu")
		(net "PCIE_RX_P92")
	)
	(segment
		(start 237.500414 -30.33776)
		(end 237.500414 -31.489142)
		(width 0.1016)
		(layer "In2.Cu")
		(net "PCIE_RX_P92")
	)
	(segment
		(start 207.640936 -26.650696)
		(end 208.217262 -26.528268)
		(width 0.1397)
		(layer "In2.Cu")
		(net "PCIE_RX_P92")
	)
	(segment
		(start 220.30817 -19.804634)
		(end 223.65462 -19.13509)
		(width 0.1397)
		(layer "In2.Cu")
		(net "PCIE_RX_P92")
	)
	(segment
		(start 201.754486 -24.357838)
		(end 205.690724 -25.194514)
		(width 0.1397)
		(layer "In2.Cu")
		(net "PCIE_RX_P92")
	)
	(segment
		(start 234.724194 -31.230316)
		(end 234.739434 -31.196788)
		(width 0.1016)
		(layer "In2.Cu")
		(net "PCIE_RX_P92")
	)
	(segment
		(start 169.797984 -14.646148)
		(end 169.85996 -14.681708)
		(width 0.1397)
		(layer "In2.Cu")
		(net "PCIE_RX_P92")
	)
	(segment
		(start 199.300846 -24.8793)
		(end 201.754486 -24.357838)
		(width 0.1397)
		(layer "In2.Cu")
		(net "PCIE_RX_P92")
	)
	(segment
		(start 168.789604 -13.170154)
		(end 168.955466 -13.501624)
		(width 0.1397)
		(layer "In2.Cu")
		(net "PCIE_RX_P92")
	)
	(segment
		(start 232.502202 -21.641054)
		(end 232.632758 -21.842476)
		(width 0.1397)
		(layer "In2.Cu")
		(net "PCIE_RX_P92")
	)
	(segment
		(start 168.384474 -13.930122)
		(end 168.268142 -13.532612)
		(width 0.1397)
		(layer "In2.Cu")
		(net "PCIE_RX_P92")
	)
	(segment
		(start 231.077008 -20.715732)
		(end 232.502202 -21.641054)
		(width 0.1397)
		(layer "In2.Cu")
		(net "PCIE_RX_P92")
	)
	(segment
		(start 169.86123 -14.68247)
		(end 170.75531 -15.195804)
		(width 0.1397)
		(layer "In2.Cu")
		(net "PCIE_RX_P92")
	)
	(segment
		(start 181.148736 -16.015208)
		(end 184.852564 -16.667988)
		(width 0.1397)
		(layer "In2.Cu")
		(net "PCIE_RX_P92")
	)
	(segment
		(start 216.62898 -22.380956)
		(end 220.30817 -19.804634)
		(width 0.1397)
		(layer "In2.Cu")
		(net "PCIE_RX_P92")
	)
	(segment
		(start 237.07852 -29.915866)
		(end 237.500414 -30.33776)
		(width 0.1016)
		(layer "In2.Cu")
		(net "PCIE_RX_P92")
	)
	(segment
		(start 169.027856 -13.600176)
		(end 169.040048 -13.616686)
		(width 0.1397)
		(layer "In2.Cu")
		(net "PCIE_RX_P92")
	)
	(segment
		(start 237.01502 -27.05354)
		(end 237.01502 -28.44927)
		(width 0.1397)
		(layer "In2.Cu")
		(net "PCIE_RX_P92")
	)
	(segment
		(start 237.01502 -28.47467)
		(end 237.07852 -28.53817)
		(width 0.1016)
		(layer "In2.Cu")
		(net "PCIE_RX_P92")
	)
	(segment
		(start 208.217262 -26.528268)
		(end 208.612994 -26.444194)
		(width 0.1397)
		(layer "In2.Cu")
		(net "PCIE_RX_P92")
	)
	(segment
		(start 168.955466 -13.501624)
		(end 169.027856 -13.600176)
		(width 0.1397)
		(layer "In2.Cu")
		(net "PCIE_RX_P92")
	)
	(segment
		(start 234.707176 -31.688024)
		(end 234.707176 -31.308294)
		(width 0.1016)
		(layer "In2.Cu")
		(net "PCIE_RX_P92")
	)
	(segment
		(start 235.100114 -31.203138)
		(end 235.100114 -31.500064)
		(width 0.1016)
		(layer "In2.Cu")
		(net "PCIE_RX_P92")
	)
	(segment
		(start 173.719744 -16.098266)
		(end 177.23739 -16.847058)
		(width 0.1397)
		(layer "In2.Cu")
		(net "PCIE_RX_P92")
	)
	(segment
		(start 169.79773 -14.646402)
		(end 169.797984 -14.646148)
		(width 0.1397)
		(layer "In2.Cu")
		(net "PCIE_RX_P92")
	)
	(segment
		(start 234.604814 -25.175972)
		(end 236.665008 -26.514552)
		(width 0.1397)
		(layer "In2.Cu")
		(net "PCIE_RX_P92")
	)
	(segment
		(start 234.911646 -31.101538)
		(end 234.998514 -31.101538)
		(width 0.1016)
		(layer "In2.Cu")
		(net "PCIE_RX_P92")
	)
	(segment
		(start 168.369742 -13.027914)
		(end 168.369996 -13.02766)
		(width 0.1397)
		(layer "In2.Cu")
		(net "PCIE_RX_P92")
	)
	(segment
		(start 205.690724 -25.194514)
		(end 206.474822 -26.402538)
		(width 0.1397)
		(layer "In2.Cu")
		(net "PCIE_RX_P92")
	)
	(segment
		(start 208.612994 -26.444194)
		(end 211.413852 -24.6253)
		(width 0.1397)
		(layer "In2.Cu")
		(net "PCIE_RX_P92")
	)
	(segment
		(start 195.45427 -24.062182)
		(end 195.454524 -24.062182)
		(width 0.1397)
		(layer "In2.Cu")
		(net "PCIE_RX_P92")
	)
	(segment
		(start 195.454524 -24.062436)
		(end 199.300846 -24.8793)
		(width 0.1397)
		(layer "In2.Cu")
		(net "PCIE_RX_P92")
	)
	(segment
		(start 169.04081 -13.61821)
		(end 169.79773 -14.646402)
		(width 0.1397)
		(layer "In2.Cu")
		(net "PCIE_RX_P92")
	)
	(segment
		(start 170.75531 -15.195804)
		(end 173.719744 -16.098266)
		(width 0.1397)
		(layer "In2.Cu")
		(net "PCIE_RX_P92")
	)
	(segment
		(start 169.041064 -13.61821)
		(end 169.04081 -13.61821)
		(width 0.1397)
		(layer "In2.Cu")
		(net "PCIE_RX_P92")
	)
	(arc
		(start 168.369996 -13.02766)
		(mid 168.60957 -13.011227)
		(end 168.789604 -13.170154)
		(width 0.1397)
		(layer "In2.Cu")
		(net "PCIE_RX_P92")
	)
	(arc
		(start 234.739434 -31.196788)
		(mid 234.783525 -31.140674)
		(end 234.8484 -31.110936)
		(width 0.1016)
		(layer "In2.Cu")
		(net "PCIE_RX_P92")
	)
	(arc
		(start 168.232328 -13.449046)
		(mid 168.213908 -13.210076)
		(end 168.369742 -13.027914)
		(width 0.1397)
		(layer "In2.Cu")
		(net "PCIE_RX_P92")
	)
	(arc
		(start 234.707176 -31.308294)
		(mid 234.711479 -31.268387)
		(end 234.724194 -31.230316)
		(width 0.1016)
		(layer "In2.Cu")
		(net "PCIE_RX_P92")
	)
	(arc
		(start 237.500414 -31.489142)
		(mid 237.379374 -31.78136)
		(end 237.087156 -31.9024)
		(width 0.1016)
		(layer "In2.Cu")
		(net "PCIE_RX_P92")
	)
	(arc
		(start 234.998514 -31.101538)
		(mid 235.070356 -31.131296)
		(end 235.100114 -31.203138)
		(width 0.1016)
		(layer "In2.Cu")
		(net "PCIE_RX_P92")
	)
	(arc
		(start 234.921552 -31.9024)
		(mid 234.769965 -31.839611)
		(end 234.707176 -31.688024)
		(width 0.1016)
		(layer "In2.Cu")
		(net "PCIE_RX_P92")
	)
	(arc
		(start 234.882436 -31.104332)
		(mid 234.896974 -31.102232)
		(end 234.911646 -31.101538)
		(width 0.1016)
		(layer "In2.Cu")
		(net "PCIE_RX_P92")
	)
	(arc
		(start 168.268142 -13.532612)
		(mid 168.258228 -13.503918)
		(end 168.24579 -13.476224)
		(width 0.1397)
		(layer "In2.Cu")
		(net "PCIE_RX_P92")
	)
	(segment
		(start 234.599988 -30.999938)
		(end 234.100116 -30.500066)
		(width 0.136652)
		(layer "F.Cu")
		(net "PCIE_RX_P91")
	)
	(via
		(at 234.100116 -30.500066)
		(size 0.4572)
		(drill 0.2032)
		(layers "F.Cu" "B.Cu")
		(net "PCIE_RX_P91")
	)
	(segment
		(start 214.624412 -25.877774)
		(end 209.906616 -29.180536)
		(width 0.1397)
		(layer "In2.Cu")
		(net "PCIE_RX_P91")
	)
	(segment
		(start 233.748072 -28.436316)
		(end 233.658664 -28.43657)
		(width 0.1016)
		(layer "In2.Cu")
		(net "PCIE_RX_P91")
	)
	(segment
		(start 209.906616 -29.180536)
		(end 204.587602 -30.11805)
		(width 0.1397)
		(layer "In2.Cu")
		(net "PCIE_RX_P91")
	)
	(segment
		(start 192.548002 -29.91612)
		(end 186.193176 -28.795472)
		(width 0.1397)
		(layer "In2.Cu")
		(net "PCIE_RX_P91")
	)
	(segment
		(start 182.521098 -27.901646)
		(end 181.436772 -28.132278)
		(width 0.1397)
		(layer "In2.Cu")
		(net "PCIE_RX_P91")
	)
	(segment
		(start 185.722768 -28.466288)
		(end 182.521098 -27.901646)
		(width 0.1397)
		(layer "In2.Cu")
		(net "PCIE_RX_P91")
	)
	(segment
		(start 163.198302 -15.923006)
		(end 160.772094 -14.224)
		(width 0.1397)
		(layer "In2.Cu")
		(net "PCIE_RX_P91")
	)
	(segment
		(start 204.587602 -30.11805)
		(end 197.994524 -28.955746)
		(width 0.1397)
		(layer "In2.Cu")
		(net "PCIE_RX_P91")
	)
	(segment
		(start 233.66984 -29.04998)
		(end 233.893614 -28.826206)
		(width 0.1016)
		(layer "In2.Cu")
		(net "PCIE_RX_P91")
	)
	(segment
		(start 169.27449 -22.545802)
		(end 166.723822 -22.966426)
		(width 0.1397)
		(layer "In2.Cu")
		(net "PCIE_RX_P91")
	)
	(segment
		(start 225.944176 -23.799292)
		(end 222.45955 -24.496268)
		(width 0.1397)
		(layer "In2.Cu")
		(net "PCIE_RX_P91")
	)
	(segment
		(start 233.764074 -30.004512)
		(end 233.638344 -29.878782)
		(width 0.1016)
		(layer "In2.Cu")
		(net "PCIE_RX_P91")
	)
	(segment
		(start 234.100116 -30.500066)
		(end 234.100116 -30.20314)
		(width 0.1016)
		(layer "In2.Cu")
		(net "PCIE_RX_P91")
	)
	(segment
		(start 227.100892 -24.030686)
		(end 225.944176 -23.799292)
		(width 0.1397)
		(layer "In2.Cu")
		(net "PCIE_RX_P91")
	)
	(segment
		(start 197.994524 -28.955746)
		(end 192.548002 -29.91612)
		(width 0.1397)
		(layer "In2.Cu")
		(net "PCIE_RX_P91")
	)
	(segment
		(start 231.580436 -26.358342)
		(end 228.201474 -23.992078)
		(width 0.1397)
		(layer "In2.Cu")
		(net "PCIE_RX_P91")
	)
	(segment
		(start 222.45955 -24.496268)
		(end 214.624412 -25.877774)
		(width 0.1397)
		(layer "In2.Cu")
		(net "PCIE_RX_P91")
	)
	(segment
		(start 166.723822 -22.966426)
		(end 165.910514 -22.82317)
		(width 0.1397)
		(layer "In2.Cu")
		(net "PCIE_RX_P91")
	)
	(segment
		(start 181.436772 -28.132278)
		(end 179.24653 -27.666696)
		(width 0.1397)
		(layer "In2.Cu")
		(net "PCIE_RX_P91")
	)
	(segment
		(start 228.201474 -23.992078)
		(end 227.650802 -23.821898)
		(width 0.1397)
		(layer "In2.Cu")
		(net "PCIE_RX_P91")
	)
	(segment
		(start 165.144196 -22.083776)
		(end 164.347144 -17.5641)
		(width 0.1397)
		(layer "In2.Cu")
		(net "PCIE_RX_P91")
	)
	(segment
		(start 227.650802 -23.821898)
		(end 227.100892 -24.030686)
		(width 0.1397)
		(layer "In2.Cu")
		(net "PCIE_RX_P91")
	)
	(segment
		(start 186.193176 -28.795472)
		(end 185.722768 -28.466288)
		(width 0.1397)
		(layer "In2.Cu")
		(net "PCIE_RX_P91")
	)
	(segment
		(start 233.640884 -28.41879)
		(end 231.580436 -26.358342)
		(width 0.1397)
		(layer "In2.Cu")
		(net "PCIE_RX_P91")
	)
	(segment
		(start 165.422834 -22.481794)
		(end 165.144196 -22.083776)
		(width 0.1397)
		(layer "In2.Cu")
		(net "PCIE_RX_P91")
	)
	(segment
		(start 164.347144 -17.5641)
		(end 163.198302 -15.923006)
		(width 0.1397)
		(layer "In2.Cu")
		(net "PCIE_RX_P91")
	)
	(segment
		(start 233.658664 -28.43657)
		(end 233.640884 -28.41879)
		(width 0.1016)
		(layer "In2.Cu")
		(net "PCIE_RX_P91")
	)
	(segment
		(start 233.505756 -29.558488)
		(end 233.505756 -29.446474)
		(width 0.1016)
		(layer "In2.Cu")
		(net "PCIE_RX_P91")
	)
	(segment
		(start 233.919268 -28.607512)
		(end 233.748072 -28.436316)
		(width 0.1016)
		(layer "In2.Cu")
		(net "PCIE_RX_P91")
	)
	(segment
		(start 160.772094 -14.224)
		(end 160.163256 -13.615162)
		(width 0.1397)
		(layer "In2.Cu")
		(net "PCIE_RX_P91")
	)
	(segment
		(start 165.910514 -22.82317)
		(end 165.422834 -22.481794)
		(width 0.1397)
		(layer "In2.Cu")
		(net "PCIE_RX_P91")
	)
	(segment
		(start 172.652436 -23.141432)
		(end 169.27449 -22.545802)
		(width 0.1397)
		(layer "In2.Cu")
		(net "PCIE_RX_P91")
	)
	(segment
		(start 179.24653 -27.666696)
		(end 172.652436 -23.141432)
		(width 0.1397)
		(layer "In2.Cu")
		(net "PCIE_RX_P91")
	)
	(arc
		(start 233.998516 -30.10154)
		(mid 233.871614 -30.076391)
		(end 233.764074 -30.004512)
		(width 0.1016)
		(layer "In2.Cu")
		(net "PCIE_RX_P91")
	)
	(arc
		(start 233.893614 -28.826206)
		(mid 233.93225 -28.719878)
		(end 233.919268 -28.607512)
		(width 0.1016)
		(layer "In2.Cu")
		(net "PCIE_RX_P91")
	)
	(arc
		(start 233.505756 -29.446474)
		(mid 233.548329 -29.231882)
		(end 233.66984 -29.04998)
		(width 0.1016)
		(layer "In2.Cu")
		(net "PCIE_RX_P91")
	)
	(arc
		(start 160.163256 -13.615162)
		(mid 159.776244 -13.566871)
		(end 159.634428 -13.930122)
		(width 0.1397)
		(layer "In2.Cu")
		(net "PCIE_RX_P91")
	)
	(arc
		(start 233.638344 -29.878782)
		(mid 233.540237 -29.731815)
		(end 233.505756 -29.558488)
		(width 0.1016)
		(layer "In2.Cu")
		(net "PCIE_RX_P91")
	)
	(arc
		(start 234.100116 -30.20314)
		(mid 234.070358 -30.131298)
		(end 233.998516 -30.10154)
		(width 0.1016)
		(layer "In2.Cu")
		(net "PCIE_RX_P91")
	)
	(segment
		(start 233.59999 -31.999936)
		(end 233.100118 -31.500064)
		(width 0.136652)
		(layer "F.Cu")
		(net "PCIE_RX_P90")
	)
	(via
		(at 233.100118 -31.500064)
		(size 0.4572)
		(drill 0.2032)
		(layers "F.Cu" "B.Cu")
		(net "PCIE_RX_P90")
	)
	(segment
		(start 163.573206 -25.294082)
		(end 165.28161 -27.734006)
		(width 0.1397)
		(layer "In2.Cu")
		(net "PCIE_RX_P90")
	)
	(segment
		(start 233.100118 -31.249874)
		(end 233.100118 -31.500064)
		(width 0.1016)
		(layer "In2.Cu")
		(net "PCIE_RX_P90")
	)
	(segment
		(start 162.614864 -19.853402)
		(end 163.573206 -25.294082)
		(width 0.1397)
		(layer "In2.Cu")
		(net "PCIE_RX_P90")
	)
	(segment
		(start 160.344104 -17.582896)
		(end 162.614864 -19.853402)
		(width 0.1397)
		(layer "In2.Cu")
		(net "PCIE_RX_P90")
	)
	(segment
		(start 182.866792 -31.899098)
		(end 183.577992 -32.050482)
		(width 0.1397)
		(layer "In2.Cu")
		(net "PCIE_RX_P90")
	)
	(segment
		(start 221.877636 -26.806652)
		(end 225.758502 -27.490928)
		(width 0.1397)
		(layer "In2.Cu")
		(net "PCIE_RX_P90")
	)
	(segment
		(start 232.836974 -31.101538)
		(end 232.918762 -31.101538)
		(width 0.1016)
		(layer "In2.Cu")
		(net "PCIE_RX_P90")
	)
	(segment
		(start 231.8385 -28.764992)
		(end 231.839008 -28.765246)
		(width 0.1397)
		(layer "In2.Cu")
		(net "PCIE_RX_P90")
	)
	(segment
		(start 187.882784 -31.13532)
		(end 192.304162 -32.07512)
		(width 0.1397)
		(layer "In2.Cu")
		(net "PCIE_RX_P90")
	)
	(segment
		(start 231.8385 -28.764738)
		(end 231.8385 -28.764992)
		(width 0.1397)
		(layer "In2.Cu")
		(net "PCIE_RX_P90")
	)
	(segment
		(start 204.025754 -31.811468)
		(end 211.230464 -30.54096)
		(width 0.1397)
		(layer "In2.Cu")
		(net "PCIE_RX_P90")
	)
	(segment
		(start 230.453692 -27.845258)
		(end 231.718358 -28.687522)
		(width 0.1397)
		(layer "In2.Cu")
		(net "PCIE_RX_P90")
	)
	(segment
		(start 227.1014 -27.2542)
		(end 230.453692 -27.845258)
		(width 0.1397)
		(layer "In2.Cu")
		(net "PCIE_RX_P90")
	)
	(segment
		(start 183.577992 -32.050482)
		(end 187.882784 -31.13532)
		(width 0.1397)
		(layer "In2.Cu")
		(net "PCIE_RX_P90")
	)
	(segment
		(start 231.952038 -28.758134)
		(end 232.273348 -28.96362)
		(width 0.1016)
		(layer "In2.Cu")
		(net "PCIE_RX_P90")
	)
	(segment
		(start 211.230464 -30.54096)
		(end 214.750142 -28.076398)
		(width 0.1397)
		(layer "In2.Cu")
		(net "PCIE_RX_P90")
	)
	(segment
		(start 232.273348 -28.96362)
		(end 232.499408 -29.314902)
		(width 0.1016)
		(layer "In2.Cu")
		(net "PCIE_RX_P90")
	)
	(segment
		(start 231.860344 -28.778708)
		(end 231.952038 -28.758134)
		(width 0.1016)
		(layer "In2.Cu")
		(net "PCIE_RX_P90")
	)
	(segment
		(start 165.28161 -27.734006)
		(end 169.698924 -30.82671)
		(width 0.1397)
		(layer "In2.Cu")
		(net "PCIE_RX_P90")
	)
	(segment
		(start 231.718358 -28.687522)
		(end 231.8385 -28.764738)
		(width 0.1397)
		(layer "In2.Cu")
		(net "PCIE_RX_P90")
	)
	(segment
		(start 198.88073 -30.903926)
		(end 204.025754 -31.811468)
		(width 0.1397)
		(layer "In2.Cu")
		(net "PCIE_RX_P90")
	)
	(segment
		(start 192.304162 -32.07512)
		(end 198.88073 -30.903926)
		(width 0.1397)
		(layer "In2.Cu")
		(net "PCIE_RX_P90")
	)
	(segment
		(start 231.839008 -28.765246)
		(end 231.860344 -28.778708)
		(width 0.1016)
		(layer "In2.Cu")
		(net "PCIE_RX_P90")
	)
	(segment
		(start 233.047032 -31.154624)
		(end 233.0704 -31.177992)
		(width 0.1016)
		(layer "In2.Cu")
		(net "PCIE_RX_P90")
	)
	(segment
		(start 232.499408 -29.314902)
		(end 232.499408 -30.763972)
		(width 0.1016)
		(layer "In2.Cu")
		(net "PCIE_RX_P90")
	)
	(segment
		(start 214.750142 -28.076398)
		(end 221.877636 -26.806652)
		(width 0.1397)
		(layer "In2.Cu")
		(net "PCIE_RX_P90")
	)
	(segment
		(start 179.324 -32.523938)
		(end 182.866792 -31.899098)
		(width 0.1397)
		(layer "In2.Cu")
		(net "PCIE_RX_P90")
	)
	(segment
		(start 169.698924 -30.82671)
		(end 179.324 -32.523938)
		(width 0.1397)
		(layer "In2.Cu")
		(net "PCIE_RX_P90")
	)
	(segment
		(start 225.758502 -27.490928)
		(end 227.1014 -27.2542)
		(width 0.1397)
		(layer "In2.Cu")
		(net "PCIE_RX_P90")
	)
	(arc
		(start 233.0704 -31.177992)
		(mid 233.092383 -31.210986)
		(end 233.100118 -31.249874)
		(width 0.1016)
		(layer "In2.Cu")
		(net "PCIE_RX_P90")
	)
	(arc
		(start 159.634428 -17.729962)
		(mid 159.90142 -17.420316)
		(end 160.295082 -17.53108)
		(width 0.1397)
		(layer "In2.Cu")
		(net "PCIE_RX_P90")
	)
	(arc
		(start 160.295082 -17.53108)
		(mid 160.319225 -17.557336)
		(end 160.344104 -17.582896)
		(width 0.1397)
		(layer "In2.Cu")
		(net "PCIE_RX_P90")
	)
	(arc
		(start 232.918762 -31.101538)
		(mid 232.988178 -31.115328)
		(end 233.047032 -31.154624)
		(width 0.1016)
		(layer "In2.Cu")
		(net "PCIE_RX_P90")
	)
	(arc
		(start 232.499408 -30.763972)
		(mid 232.598279 -31.002667)
		(end 232.836974 -31.101538)
		(width 0.1016)
		(layer "In2.Cu")
		(net "PCIE_RX_P90")
	)
	(segment
		(start 253.59995 -34.99993)
		(end 254.099822 -34.500058)
		(width 0.136652)
		(layer "F.Cu")
		(net "PCIE_RX_P9")
	)
	(via
		(at 254.099822 -34.500058)
		(size 0.4572)
		(drill 0.2032)
		(layers "F.Cu" "B.Cu")
		(net "PCIE_RX_P9")
	)
	(segment
		(start 306.1208 -21.910294)
		(end 306.1208 -18.379694)
		(width 0.1397)
		(layer "In2.Cu")
		(net "PCIE_RX_P9")
	)
	(segment
		(start 257.87604 -32.893762)
		(end 259.719318 -32.893762)
		(width 0.1016)
		(layer "In2.Cu")
		(net "PCIE_RX_P9")
	)
	(segment
		(start 266.03452 -33.44926)
		(end 278.735028 -31.209488)
		(width 0.1397)
		(layer "In2.Cu")
		(net "PCIE_RX_P9")
	)
	(segment
		(start 309.712868 -18.202402)
		(end 309.737506 -18.22704)
		(width 0.1397)
		(layer "In2.Cu")
		(net "PCIE_RX_P9")
	)
	(segment
		(start 257.496818 -33.693862)
		(end 257.496818 -33.272984)
		(width 0.1016)
		(layer "In2.Cu")
		(net "PCIE_RX_P9")
	)
	(segment
		(start 279.564592 -30.628844)
		(end 280.15819 -30.213046)
		(width 0.1397)
		(layer "In2.Cu")
		(net "PCIE_RX_P9")
	)
	(segment
		(start 280.15819 -30.213046)
		(end 284.367986 -29.471112)
		(width 0.1397)
		(layer "In2.Cu")
		(net "PCIE_RX_P9")
	)
	(segment
		(start 305.018694 -24.9047)
		(end 305.353466 -23.006304)
		(width 0.1397)
		(layer "In2.Cu")
		(net "PCIE_RX_P9")
	)
	(segment
		(start 309.4482 -17.7292)
		(end 309.45963 -17.740376)
		(width 0.1397)
		(layer "In2.Cu")
		(net "PCIE_RX_P9")
	)
	(segment
		(start 295.485566 -30.032706)
		(end 296.146982 -29.570172)
		(width 0.1397)
		(layer "In2.Cu")
		(net "PCIE_RX_P9")
	)
	(segment
		(start 305.13528 -27.855926)
		(end 305.336956 -26.710386)
		(width 0.1397)
		(layer "In2.Cu")
		(net "PCIE_RX_P9")
	)
	(segment
		(start 302.210216 -29.528262)
		(end 302.53813 -29.470604)
		(width 0.1397)
		(layer "In2.Cu")
		(net "PCIE_RX_P9")
	)
	(segment
		(start 303.919636 -29.227272)
		(end 304.302922 -28.959302)
		(width 0.1397)
		(layer "In2.Cu")
		(net "PCIE_RX_P9")
	)
	(segment
		(start 289.517836 -29.649166)
		(end 294.03548 -30.445202)
		(width 0.1397)
		(layer "In2.Cu")
		(net "PCIE_RX_P9")
	)
	(segment
		(start 304.302922 -28.959302)
		(end 304.723546 -28.54325)
		(width 0.1397)
		(layer "In2.Cu")
		(net "PCIE_RX_P9")
	)
	(segment
		(start 308.492906 -16.773906)
		(end 309.4482 -17.7292)
		(width 0.1397)
		(layer "In2.Cu")
		(net "PCIE_RX_P9")
	)
	(segment
		(start 307.726588 -16.773906)
		(end 308.492906 -16.773906)
		(width 0.1397)
		(layer "In2.Cu")
		(net "PCIE_RX_P9")
	)
	(segment
		(start 301.188882 -29.708602)
		(end 302.210216 -29.528262)
		(width 0.1397)
		(layer "In2.Cu")
		(net "PCIE_RX_P9")
	)
	(segment
		(start 284.367986 -29.471112)
		(end 287.412938 -30.008322)
		(width 0.1397)
		(layer "In2.Cu")
		(net "PCIE_RX_P9")
	)
	(segment
		(start 298.27474 -29.195014)
		(end 301.188882 -29.708602)
		(width 0.1397)
		(layer "In2.Cu")
		(net "PCIE_RX_P9")
	)
	(segment
		(start 259.785104 -32.840676)
		(end 262.991854 -32.840676)
		(width 0.1397)
		(layer "In2.Cu")
		(net "PCIE_RX_P9")
	)
	(segment
		(start 262.991854 -32.840676)
		(end 266.03452 -33.44926)
		(width 0.1397)
		(layer "In2.Cu")
		(net "PCIE_RX_P9")
	)
	(segment
		(start 305.336956 -26.710386)
		(end 305.018694 -24.9047)
		(width 0.1397)
		(layer "In2.Cu")
		(net "PCIE_RX_P9")
	)
	(segment
		(start 305.353466 -23.006304)
		(end 306.1208 -21.910294)
		(width 0.1397)
		(layer "In2.Cu")
		(net "PCIE_RX_P9")
	)
	(segment
		(start 278.735028 -31.209488)
		(end 279.149556 -30.91942)
		(width 0.1397)
		(layer "In2.Cu")
		(net "PCIE_RX_P9")
	)
	(segment
		(start 279.149556 -30.91942)
		(end 279.540208 -30.645862)
		(width 0.1397)
		(layer "In2.Cu")
		(net "PCIE_RX_P9")
	)
	(segment
		(start 294.03548 -30.445202)
		(end 295.186354 -30.242256)
		(width 0.1397)
		(layer "In2.Cu")
		(net "PCIE_RX_P9")
	)
	(segment
		(start 305.111912 -27.989022)
		(end 305.13528 -27.855926)
		(width 0.1397)
		(layer "In2.Cu")
		(net "PCIE_RX_P9")
	)
	(segment
		(start 310.108092 -18.44294)
		(end 310.584088 -18.44294)
		(width 0.1397)
		(layer "In2.Cu")
		(net "PCIE_RX_P9")
	)
	(segment
		(start 309.73776 -18.22704)
		(end 309.814468 -18.303748)
		(width 0.1397)
		(layer "In2.Cu")
		(net "PCIE_RX_P9")
	)
	(segment
		(start 306.1208 -18.379694)
		(end 307.726588 -16.773906)
		(width 0.1397)
		(layer "In2.Cu")
		(net "PCIE_RX_P9")
	)
	(segment
		(start 309.634128 -18.057114)
		(end 309.646574 -18.095214)
		(width 0.1397)
		(layer "In2.Cu")
		(net "PCIE_RX_P9")
	)
	(segment
		(start 309.737506 -18.22704)
		(end 309.73776 -18.22704)
		(width 0.1397)
		(layer "In2.Cu")
		(net "PCIE_RX_P9")
	)
	(segment
		(start 309.814468 -18.303748)
		(end 309.843932 -18.33372)
		(width 0.1397)
		(layer "In2.Cu")
		(net "PCIE_RX_P9")
	)
	(segment
		(start 302.53813 -29.470604)
		(end 303.22901 -29.348938)
		(width 0.1397)
		(layer "In2.Cu")
		(net "PCIE_RX_P9")
	)
	(segment
		(start 303.22901 -29.348938)
		(end 303.919636 -29.227272)
		(width 0.1397)
		(layer "In2.Cu")
		(net "PCIE_RX_P9")
	)
	(segment
		(start 259.719318 -32.893762)
		(end 259.772404 -32.840676)
		(width 0.1016)
		(layer "In2.Cu")
		(net "PCIE_RX_P9")
	)
	(segment
		(start 309.611268 -17.987264)
		(end 309.634128 -18.057114)
		(width 0.1397)
		(layer "In2.Cu")
		(net "PCIE_RX_P9")
	)
	(segment
		(start 259.772404 -32.840676)
		(end 259.785104 -32.840676)
		(width 0.1016)
		(layer "In2.Cu")
		(net "PCIE_RX_P9")
	)
	(segment
		(start 279.540208 -30.645862)
		(end 279.564592 -30.628844)
		(width 0.1397)
		(layer "In2.Cu")
		(net "PCIE_RX_P9")
	)
	(segment
		(start 304.723546 -28.54325)
		(end 305.111912 -27.989022)
		(width 0.1397)
		(layer "In2.Cu")
		(net "PCIE_RX_P9")
	)
	(segment
		(start 295.186354 -30.242256)
		(end 295.485566 -30.032706)
		(width 0.1397)
		(layer "In2.Cu")
		(net "PCIE_RX_P9")
	)
	(segment
		(start 287.412938 -30.008322)
		(end 289.517836 -29.649166)
		(width 0.1397)
		(layer "In2.Cu")
		(net "PCIE_RX_P9")
	)
	(segment
		(start 254.981202 -33.899602)
		(end 257.291078 -33.899602)
		(width 0.1016)
		(layer "In2.Cu")
		(net "PCIE_RX_P9")
	)
	(segment
		(start 296.146982 -29.570172)
		(end 298.27474 -29.195014)
		(width 0.1397)
		(layer "In2.Cu")
		(net "PCIE_RX_P9")
	)
	(arc
		(start 311.105042 -17.671796)
		(mid 311.085159 -17.551077)
		(end 311.03697 -17.438624)
		(width 0.1397)
		(layer "In2.Cu")
		(net "PCIE_RX_P9")
	)
	(arc
		(start 309.701438 -18.190464)
		(mid 309.707063 -18.19652)
		(end 309.712868 -18.202402)
		(width 0.1397)
		(layer "In2.Cu")
		(net "PCIE_RX_P9")
	)
	(arc
		(start 310.928004 -17.30756)
		(mid 310.483765 -17.296985)
		(end 310.384444 -17.729962)
		(width 0.1397)
		(layer "In2.Cu")
		(net "PCIE_RX_P9")
	)
	(arc
		(start 311.030874 -18.13433)
		(mid 311.091369 -17.906815)
		(end 311.105042 -17.671796)
		(width 0.1397)
		(layer "In2.Cu")
		(net "PCIE_RX_P9")
	)
	(arc
		(start 254.099822 -34.500058)
		(mid 254.447975 -34.064012)
		(end 254.981202 -33.899602)
		(width 0.1016)
		(layer "In2.Cu")
		(net "PCIE_RX_P9")
	)
	(arc
		(start 257.496818 -33.272984)
		(mid 257.60789 -33.004834)
		(end 257.87604 -32.893762)
		(width 0.1016)
		(layer "In2.Cu")
		(net "PCIE_RX_P9")
	)
	(arc
		(start 309.843932 -18.33372)
		(mid 309.893449 -18.375114)
		(end 309.949342 -18.40738)
		(width 0.1397)
		(layer "In2.Cu")
		(net "PCIE_RX_P9")
	)
	(arc
		(start 309.949342 -18.40738)
		(mid 310.02676 -18.433888)
		(end 310.108092 -18.44294)
		(width 0.1397)
		(layer "In2.Cu")
		(net "PCIE_RX_P9")
	)
	(arc
		(start 310.584088 -18.44294)
		(mid 310.855602 -18.358292)
		(end 311.030874 -18.13433)
		(width 0.1397)
		(layer "In2.Cu")
		(net "PCIE_RX_P9")
	)
	(arc
		(start 309.646574 -18.095214)
		(mid 309.66907 -18.145682)
		(end 309.701438 -18.190464)
		(width 0.1397)
		(layer "In2.Cu")
		(net "PCIE_RX_P9")
	)
	(arc
		(start 257.291078 -33.899602)
		(mid 257.436558 -33.839342)
		(end 257.496818 -33.693862)
		(width 0.1016)
		(layer "In2.Cu")
		(net "PCIE_RX_P9")
	)
	(arc
		(start 311.03697 -17.438624)
		(mid 310.988025 -17.368488)
		(end 310.928004 -17.30756)
		(width 0.1397)
		(layer "In2.Cu")
		(net "PCIE_RX_P9")
	)
	(arc
		(start 309.45963 -17.740376)
		(mid 309.549973 -17.854898)
		(end 309.611268 -17.987264)
		(width 0.1397)
		(layer "In2.Cu")
		(net "PCIE_RX_P9")
	)
	(segment
		(start 232.599992 -30.999938)
		(end 232.10012 -30.500066)
		(width 0.136652)
		(layer "F.Cu")
		(net "PCIE_RX_P89")
	)
	(via
		(at 232.10012 -30.500066)
		(size 0.4572)
		(drill 0.2032)
		(layers "F.Cu" "B.Cu")
		(net "PCIE_RX_P89")
	)
	(segment
		(start 179.31003 -33.509966)
		(end 182.61457 -32.849312)
		(width 0.1397)
		(layer "In2.Cu")
		(net "PCIE_RX_P89")
	)
	(segment
		(start 161.693352 -24.518366)
		(end 162.21964 -26.64206)
		(width 0.1397)
		(layer "In2.Cu")
		(net "PCIE_RX_P89")
	)
	(segment
		(start 214.51824 -29.244036)
		(end 222.190564 -27.847798)
		(width 0.1397)
		(layer "In2.Cu")
		(net "PCIE_RX_P89")
	)
	(segment
		(start 162.155886 -22.182074)
		(end 161.693352 -24.518366)
		(width 0.1397)
		(layer "In2.Cu")
		(net "PCIE_RX_P89")
	)
	(segment
		(start 176.03724 -32.90951)
		(end 177.03292 -33.108392)
		(width 0.1397)
		(layer "In2.Cu")
		(net "PCIE_RX_P89")
	)
	(segment
		(start 227.253292 -28.143454)
		(end 230.045006 -28.635452)
		(width 0.1397)
		(layer "In2.Cu")
		(net "PCIE_RX_P89")
	)
	(segment
		(start 230.57866 -28.835604)
		(end 230.803958 -29.060902)
		(width 0.1016)
		(layer "In2.Cu")
		(net "PCIE_RX_P89")
	)
	(segment
		(start 158.023052 -17.530572)
		(end 158.448248 -17.955768)
		(width 0.1397)
		(layer "In2.Cu")
		(net "PCIE_RX_P89")
	)
	(segment
		(start 201.811382 -33.09366)
		(end 211.446872 -31.394654)
		(width 0.1397)
		(layer "In2.Cu")
		(net "PCIE_RX_P89")
	)
	(segment
		(start 230.045006 -28.635452)
		(end 230.269034 -28.752038)
		(width 0.1397)
		(layer "In2.Cu")
		(net "PCIE_RX_P89")
	)
	(segment
		(start 162.60953 -27.198574)
		(end 169.427398 -31.744158)
		(width 0.1397)
		(layer "In2.Cu")
		(net "PCIE_RX_P89")
	)
	(segment
		(start 159.51073 -19.147282)
		(end 160.913826 -19.433286)
		(width 0.1397)
		(layer "In2.Cu")
		(net "PCIE_RX_P89")
	)
	(segment
		(start 161.85388 -20.59178)
		(end 161.853626 -20.59178)
		(width 0.1397)
		(layer "In2.Cu")
		(net "PCIE_RX_P89")
	)
	(segment
		(start 193.65849 -33.305496)
		(end 198.232268 -32.33293)
		(width 0.1397)
		(layer "In2.Cu")
		(net "PCIE_RX_P89")
	)
	(segment
		(start 161.853626 -20.59178)
		(end 162.155886 -22.182074)
		(width 0.1397)
		(layer "In2.Cu")
		(net "PCIE_RX_P89")
	)
	(segment
		(start 232.10012 -30.20314)
		(end 232.10012 -30.500066)
		(width 0.1016)
		(layer "In2.Cu")
		(net "PCIE_RX_P89")
	)
	(segment
		(start 198.232268 -32.33293)
		(end 201.811382 -33.09366)
		(width 0.1397)
		(layer "In2.Cu")
		(net "PCIE_RX_P89")
	)
	(segment
		(start 230.803958 -29.060902)
		(end 230.803958 -29.363924)
		(width 0.1016)
		(layer "In2.Cu")
		(net "PCIE_RX_P89")
	)
	(segment
		(start 187.809886 -32.061912)
		(end 193.65849 -33.305496)
		(width 0.1397)
		(layer "In2.Cu")
		(net "PCIE_RX_P89")
	)
	(segment
		(start 183.378856 -33.00349)
		(end 187.809886 -32.061912)
		(width 0.1397)
		(layer "In2.Cu")
		(net "PCIE_RX_P89")
	)
	(segment
		(start 161.41573 -19.85137)
		(end 161.458148 -19.923252)
		(width 0.1397)
		(layer "In2.Cu")
		(net "PCIE_RX_P89")
	)
	(segment
		(start 160.913826 -19.433286)
		(end 161.41573 -19.85137)
		(width 0.1397)
		(layer "In2.Cu")
		(net "PCIE_RX_P89")
	)
	(segment
		(start 158.9532 -18.7452)
		(end 159.51073 -19.147282)
		(width 0.1397)
		(layer "In2.Cu")
		(net "PCIE_RX_P89")
	)
	(segment
		(start 158.448248 -17.955768)
		(end 158.9532 -18.7452)
		(width 0.1397)
		(layer "In2.Cu")
		(net "PCIE_RX_P89")
	)
	(segment
		(start 230.269034 -28.752038)
		(end 230.29164 -28.763976)
		(width 0.1016)
		(layer "In2.Cu")
		(net "PCIE_RX_P89")
	)
	(segment
		(start 231.57434 -30.10154)
		(end 231.99852 -30.10154)
		(width 0.1016)
		(layer "In2.Cu")
		(net "PCIE_RX_P89")
	)
	(segment
		(start 169.427398 -31.744158)
		(end 176.03724 -32.90951)
		(width 0.1397)
		(layer "In2.Cu")
		(net "PCIE_RX_P89")
	)
	(segment
		(start 182.61457 -32.849312)
		(end 183.378856 -33.00349)
		(width 0.1397)
		(layer "In2.Cu")
		(net "PCIE_RX_P89")
	)
	(segment
		(start 230.384604 -28.734258)
		(end 230.57866 -28.835604)
		(width 0.1016)
		(layer "In2.Cu")
		(net "PCIE_RX_P89")
	)
	(segment
		(start 161.458148 -19.923252)
		(end 161.488628 -19.974814)
		(width 0.1397)
		(layer "In2.Cu")
		(net "PCIE_RX_P89")
	)
	(segment
		(start 161.535872 -20.05457)
		(end 161.85388 -20.59178)
		(width 0.1397)
		(layer "In2.Cu")
		(net "PCIE_RX_P89")
	)
	(segment
		(start 162.21964 -26.64206)
		(end 162.60953 -27.198574)
		(width 0.1397)
		(layer "In2.Cu")
		(net "PCIE_RX_P89")
	)
	(segment
		(start 222.190564 -27.847798)
		(end 225.560382 -28.441904)
		(width 0.1397)
		(layer "In2.Cu")
		(net "PCIE_RX_P89")
	)
	(segment
		(start 161.488628 -19.974814)
		(end 161.535872 -20.05457)
		(width 0.1397)
		(layer "In2.Cu")
		(net "PCIE_RX_P89")
	)
	(segment
		(start 177.03292 -33.108392)
		(end 179.31003 -33.509966)
		(width 0.1397)
		(layer "In2.Cu")
		(net "PCIE_RX_P89")
	)
	(segment
		(start 225.560382 -28.441904)
		(end 227.253292 -28.143454)
		(width 0.1397)
		(layer "In2.Cu")
		(net "PCIE_RX_P89")
	)
	(segment
		(start 230.29164 -28.763976)
		(end 230.384604 -28.734258)
		(width 0.1016)
		(layer "In2.Cu")
		(net "PCIE_RX_P89")
	)
	(segment
		(start 211.446872 -31.394654)
		(end 214.51824 -29.244036)
		(width 0.1397)
		(layer "In2.Cu")
		(net "PCIE_RX_P89")
	)
	(arc
		(start 157.384496 -17.729962)
		(mid 157.643482 -17.437012)
		(end 158.023052 -17.530572)
		(width 0.1397)
		(layer "In2.Cu")
		(net "PCIE_RX_P89")
	)
	(arc
		(start 230.803958 -29.363924)
		(mid 230.858346 -29.637352)
		(end 231.013254 -29.86913)
		(width 0.1016)
		(layer "In2.Cu")
		(net "PCIE_RX_P89")
	)
	(arc
		(start 231.013254 -29.86913)
		(mid 231.270682 -30.041138)
		(end 231.57434 -30.10154)
		(width 0.1016)
		(layer "In2.Cu")
		(net "PCIE_RX_P89")
	)
	(arc
		(start 231.99852 -30.10154)
		(mid 232.070362 -30.131298)
		(end 232.10012 -30.20314)
		(width 0.1016)
		(layer "In2.Cu")
		(net "PCIE_RX_P89")
	)
	(segment
		(start 231.599994 -31.999936)
		(end 231.100122 -31.500064)
		(width 0.136652)
		(layer "F.Cu")
		(net "PCIE_RX_P88")
	)
	(via
		(at 231.100122 -31.500064)
		(size 0.4572)
		(drill 0.2032)
		(layers "F.Cu" "B.Cu")
		(net "PCIE_RX_P88")
	)
	(segment
		(start 157.245812 -13.476224)
		(end 157.23235 -13.449046)
		(width 0.1397)
		(layer "In2.Cu")
		(net "PCIE_RX_P88")
	)
	(segment
		(start 231.100122 -31.203138)
		(end 231.100122 -31.500064)
		(width 0.1016)
		(layer "In2.Cu")
		(net "PCIE_RX_P88")
	)
	(segment
		(start 232.882186 -28.652216)
		(end 233.078528 -29.14269)
		(width 0.1016)
		(layer "In2.Cu")
		(net "PCIE_RX_P88")
	)
	(segment
		(start 232.323386 -28.111196)
		(end 232.339896 -28.130246)
		(width 0.1016)
		(layer "In2.Cu")
		(net "PCIE_RX_P88")
	)
	(segment
		(start 188.462666 -30.12694)
		(end 192.63106 -30.862016)
		(width 0.1397)
		(layer "In2.Cu")
		(net "PCIE_RX_P88")
	)
	(segment
		(start 230.542084 -26.867612)
		(end 232.241598 -28.017978)
		(width 0.1397)
		(layer "In2.Cu")
		(net "PCIE_RX_P88")
	)
	(segment
		(start 230.848408 -31.110936)
		(end 230.882444 -31.104332)
		(width 0.1016)
		(layer "In2.Cu")
		(net "PCIE_RX_P88")
	)
	(segment
		(start 230.724202 -31.230316)
		(end 230.739442 -31.196788)
		(width 0.1016)
		(layer "In2.Cu")
		(net "PCIE_RX_P88")
	)
	(segment
		(start 198.40829 -29.843222)
		(end 204.507592 -30.91942)
		(width 0.1397)
		(layer "In2.Cu")
		(net "PCIE_RX_P88")
	)
	(segment
		(start 183.541416 -31.137352)
		(end 187.48375 -30.299406)
		(width 0.1397)
		(layer "In2.Cu")
		(net "PCIE_RX_P88")
	)
	(segment
		(start 162.487356 -16.943324)
		(end 163.3601 -18.189448)
		(width 0.1397)
		(layer "In2.Cu")
		(net "PCIE_RX_P88")
	)
	(segment
		(start 232.339896 -28.130246)
		(end 232.429558 -28.136088)
		(width 0.1016)
		(layer "In2.Cu")
		(net "PCIE_RX_P88")
	)
	(segment
		(start 169.877232 -29.895038)
		(end 179.180998 -31.535624)
		(width 0.1397)
		(layer "In2.Cu")
		(net "PCIE_RX_P88")
	)
	(segment
		(start 230.911654 -31.101538)
		(end 230.998522 -31.101538)
		(width 0.1016)
		(layer "In2.Cu")
		(net "PCIE_RX_P88")
	)
	(segment
		(start 163.3601 -18.189448)
		(end 164.594286 -25.188672)
		(width 0.1397)
		(layer "In2.Cu")
		(net "PCIE_RX_P88")
	)
	(segment
		(start 160.913318 -15.601696)
		(end 162.487356 -16.943324)
		(width 0.1397)
		(layer "In2.Cu")
		(net "PCIE_RX_P88")
	)
	(segment
		(start 230.707184 -31.688024)
		(end 230.707184 -31.308294)
		(width 0.1016)
		(layer "In2.Cu")
		(net "PCIE_RX_P88")
	)
	(segment
		(start 232.429558 -28.136088)
		(end 232.882186 -28.652216)
		(width 0.1016)
		(layer "In2.Cu")
		(net "PCIE_RX_P88")
	)
	(segment
		(start 158.716472 -14.8717)
		(end 158.899352 -14.960092)
		(width 0.1397)
		(layer "In2.Cu")
		(net "PCIE_RX_P88")
	)
	(segment
		(start 210.556094 -29.853128)
		(end 214.677752 -26.96591)
		(width 0.1397)
		(layer "In2.Cu")
		(net "PCIE_RX_P88")
	)
	(segment
		(start 159.319976 -15.123414)
		(end 160.913318 -15.601696)
		(width 0.1397)
		(layer "In2.Cu")
		(net "PCIE_RX_P88")
	)
	(segment
		(start 165.977824 -27.164284)
		(end 169.877232 -29.895038)
		(width 0.1397)
		(layer "In2.Cu")
		(net "PCIE_RX_P88")
	)
	(segment
		(start 233.170984 -31.9024)
		(end 230.92156 -31.9024)
		(width 0.1016)
		(layer "In2.Cu")
		(net "PCIE_RX_P88")
	)
	(segment
		(start 157.789626 -13.170154)
		(end 157.893004 -13.37691)
		(width 0.1397)
		(layer "In2.Cu")
		(net "PCIE_RX_P88")
	)
	(segment
		(start 164.594286 -25.188672)
		(end 165.977824 -27.164284)
		(width 0.1397)
		(layer "In2.Cu")
		(net "PCIE_RX_P88")
	)
	(segment
		(start 233.078528 -29.915866)
		(end 233.500422 -30.33776)
		(width 0.1016)
		(layer "In2.Cu")
		(net "PCIE_RX_P88")
	)
	(segment
		(start 204.507592 -30.91942)
		(end 210.556094 -29.853128)
		(width 0.1397)
		(layer "In2.Cu")
		(net "PCIE_RX_P88")
	)
	(segment
		(start 225.58756 -26.460196)
		(end 226.910392 -26.227024)
		(width 0.1397)
		(layer "In2.Cu")
		(net "PCIE_RX_P88")
	)
	(segment
		(start 157.371542 -13.03147)
		(end 157.371796 -13.031216)
		(width 0.1397)
		(layer "In2.Cu")
		(net "PCIE_RX_P88")
	)
	(segment
		(start 233.078528 -29.14269)
		(end 233.078528 -29.915866)
		(width 0.1016)
		(layer "In2.Cu")
		(net "PCIE_RX_P88")
	)
	(segment
		(start 192.63106 -30.862016)
		(end 198.40829 -29.843222)
		(width 0.1397)
		(layer "In2.Cu")
		(net "PCIE_RX_P88")
	)
	(segment
		(start 221.56674 -25.751282)
		(end 225.58756 -26.460196)
		(width 0.1397)
		(layer "In2.Cu")
		(net "PCIE_RX_P88")
	)
	(segment
		(start 157.384496 -13.930122)
		(end 157.268164 -13.532612)
		(width 0.1397)
		(layer "In2.Cu")
		(net "PCIE_RX_P88")
	)
	(segment
		(start 179.180998 -31.535624)
		(end 182.5879 -30.93466)
		(width 0.1397)
		(layer "In2.Cu")
		(net "PCIE_RX_P88")
	)
	(segment
		(start 214.677752 -26.96591)
		(end 221.56674 -25.751282)
		(width 0.1397)
		(layer "In2.Cu")
		(net "PCIE_RX_P88")
	)
	(segment
		(start 233.500422 -30.33776)
		(end 233.500422 -31.572962)
		(width 0.1016)
		(layer "In2.Cu")
		(net "PCIE_RX_P88")
	)
	(segment
		(start 226.910392 -26.227024)
		(end 230.542084 -26.867612)
		(width 0.1397)
		(layer "In2.Cu")
		(net "PCIE_RX_P88")
	)
	(segment
		(start 232.241598 -28.017978)
		(end 232.323386 -28.111196)
		(width 0.1397)
		(layer "In2.Cu")
		(net "PCIE_RX_P88")
	)
	(segment
		(start 182.5879 -30.93466)
		(end 183.541416 -31.137352)
		(width 0.1397)
		(layer "In2.Cu")
		(net "PCIE_RX_P88")
	)
	(segment
		(start 187.48375 -30.299406)
		(end 188.462666 -30.12694)
		(width 0.1397)
		(layer "In2.Cu")
		(net "PCIE_RX_P88")
	)
	(arc
		(start 157.371796 -13.031216)
		(mid 157.609486 -13.01415)
		(end 157.789626 -13.170154)
		(width 0.1397)
		(layer "In2.Cu")
		(net "PCIE_RX_P88")
	)
	(arc
		(start 158.899352 -14.960092)
		(mid 159.106447 -15.050039)
		(end 159.319976 -15.123414)
		(width 0.1397)
		(layer "In2.Cu")
		(net "PCIE_RX_P88")
	)
	(arc
		(start 230.739442 -31.196788)
		(mid 230.783533 -31.140674)
		(end 230.848408 -31.110936)
		(width 0.1016)
		(layer "In2.Cu")
		(net "PCIE_RX_P88")
	)
	(arc
		(start 158.101538 -13.822934)
		(mid 158.246049 -14.442856)
		(end 158.716472 -14.8717)
		(width 0.1397)
		(layer "In2.Cu")
		(net "PCIE_RX_P88")
	)
	(arc
		(start 230.92156 -31.9024)
		(mid 230.769973 -31.839611)
		(end 230.707184 -31.688024)
		(width 0.1016)
		(layer "In2.Cu")
		(net "PCIE_RX_P88")
	)
	(arc
		(start 157.268164 -13.532612)
		(mid 157.25825 -13.503918)
		(end 157.245812 -13.476224)
		(width 0.1397)
		(layer "In2.Cu")
		(net "PCIE_RX_P88")
	)
	(arc
		(start 233.500422 -31.572962)
		(mid 233.403932 -31.80591)
		(end 233.170984 -31.9024)
		(width 0.1016)
		(layer "In2.Cu")
		(net "PCIE_RX_P88")
	)
	(arc
		(start 230.882444 -31.104332)
		(mid 230.896982 -31.102232)
		(end 230.911654 -31.101538)
		(width 0.1016)
		(layer "In2.Cu")
		(net "PCIE_RX_P88")
	)
	(arc
		(start 157.893004 -13.37691)
		(mid 157.956524 -13.489038)
		(end 158.03118 -13.59408)
		(width 0.1397)
		(layer "In2.Cu")
		(net "PCIE_RX_P88")
	)
	(arc
		(start 230.707184 -31.308294)
		(mid 230.711487 -31.268387)
		(end 230.724202 -31.230316)
		(width 0.1016)
		(layer "In2.Cu")
		(net "PCIE_RX_P88")
	)
	(arc
		(start 157.23235 -13.449046)
		(mid 157.215484 -13.211412)
		(end 157.371542 -13.03147)
		(width 0.1397)
		(layer "In2.Cu")
		(net "PCIE_RX_P88")
	)
	(arc
		(start 158.03118 -13.59408)
		(mid 158.087766 -13.701921)
		(end 158.101538 -13.822934)
		(width 0.1397)
		(layer "In2.Cu")
		(net "PCIE_RX_P88")
	)
	(arc
		(start 230.998522 -31.101538)
		(mid 231.070364 -31.131296)
		(end 231.100122 -31.203138)
		(width 0.1016)
		(layer "In2.Cu")
		(net "PCIE_RX_P88")
	)
	(segment
		(start 226.600004 -33.999932)
		(end 226.100132 -33.50006)
		(width 0.136652)
		(layer "F.Cu")
		(net "PCIE_RX_P87")
	)
	(via
		(at 226.100132 -33.50006)
		(size 0.4572)
		(drill 0.2032)
		(layers "F.Cu" "B.Cu")
		(net "PCIE_RX_P87")
	)
	(segment
		(start 201.482706 -33.845754)
		(end 213.226396 -31.774638)
		(width 0.1397)
		(layer "In2.Cu")
		(net "PCIE_RX_P87")
	)
	(segment
		(start 154.587194 -26.369264)
		(end 155.275026 -27.351736)
		(width 0.1397)
		(layer "In2.Cu")
		(net "PCIE_RX_P87")
	)
	(segment
		(start 148.322538 -12.831826)
		(end 148.322792 -12.831572)
		(width 0.1397)
		(layer "In2.Cu")
		(net "PCIE_RX_P87")
	)
	(segment
		(start 154.449526 -21.638514)
		(end 154.4447 -21.6662)
		(width 0.1397)
		(layer "In2.Cu")
		(net "PCIE_RX_P87")
	)
	(segment
		(start 168.862756 -32.303974)
		(end 176.000664 -33.562798)
		(width 0.1397)
		(layer "In2.Cu")
		(net "PCIE_RX_P87")
	)
	(segment
		(start 148.373338 -12.126214)
		(end 149.59838 -10.724896)
		(width 0.1397)
		(layer "In2.Cu")
		(net "PCIE_RX_P87")
	)
	(segment
		(start 157.082744 -28.357322)
		(end 165.560502 -30.159706)
		(width 0.1397)
		(layer "In2.Cu")
		(net "PCIE_RX_P87")
	)
	(segment
		(start 154.4447 -22.101556)
		(end 154.209242 -23.437596)
		(width 0.1397)
		(layer "In2.Cu")
		(net "PCIE_RX_P87")
	)
	(segment
		(start 154.209242 -23.437596)
		(end 154.179016 -25.121616)
		(width 0.1397)
		(layer "In2.Cu")
		(net "PCIE_RX_P87")
	)
	(segment
		(start 221.408752 -32.90316)
		(end 225.080068 -32.90316)
		(width 0.1016)
		(layer "In2.Cu")
		(net "PCIE_RX_P87")
	)
	(segment
		(start 187.39104 -32.95904)
		(end 193.838068 -34.095436)
		(width 0.1397)
		(layer "In2.Cu")
		(net "PCIE_RX_P87")
	)
	(segment
		(start 221.345252 -32.83966)
		(end 221.408752 -32.90316)
		(width 0.1016)
		(layer "In2.Cu")
		(net "PCIE_RX_P87")
	)
	(segment
		(start 198.593964 -33.25749)
		(end 201.482706 -33.845754)
		(width 0.1397)
		(layer "In2.Cu")
		(net "PCIE_RX_P87")
	)
	(segment
		(start 152.55875 -15.838678)
		(end 153.768298 -17.776444)
		(width 0.1397)
		(layer "In2.Cu")
		(net "PCIE_RX_P87")
	)
	(segment
		(start 213.226396 -31.774638)
		(end 219.263976 -32.83966)
		(width 0.1397)
		(layer "In2.Cu")
		(net "PCIE_RX_P87")
	)
	(segment
		(start 179.175664 -34.197798)
		(end 182.501286 -33.532826)
		(width 0.1397)
		(layer "In2.Cu")
		(net "PCIE_RX_P87")
	)
	(segment
		(start 152.552146 -15.82928)
		(end 152.55875 -15.838678)
		(width 0.1397)
		(layer "In2.Cu")
		(net "PCIE_RX_P87")
	)
	(segment
		(start 151.731218 -13.879576)
		(end 151.731218 -13.880084)
		(width 0.1397)
		(layer "In2.Cu")
		(net "PCIE_RX_P87")
	)
	(segment
		(start 176.000664 -33.562798)
		(end 179.175664 -34.197798)
		(width 0.1397)
		(layer "In2.Cu")
		(net "PCIE_RX_P87")
	)
	(segment
		(start 193.838068 -34.095436)
		(end 198.593964 -33.25749)
		(width 0.1397)
		(layer "In2.Cu")
		(net "PCIE_RX_P87")
	)
	(segment
		(start 154.4447 -21.6662)
		(end 154.4447 -22.101556)
		(width 0.1397)
		(layer "In2.Cu")
		(net "PCIE_RX_P87")
	)
	(segment
		(start 154.179016 -25.121616)
		(end 154.587194 -26.369264)
		(width 0.1397)
		(layer "In2.Cu")
		(net "PCIE_RX_P87")
	)
	(segment
		(start 221.319852 -32.83966)
		(end 221.345252 -32.83966)
		(width 0.1016)
		(layer "In2.Cu")
		(net "PCIE_RX_P87")
	)
	(segment
		(start 155.275026 -27.351736)
		(end 156.172154 -27.979624)
		(width 0.1397)
		(layer "In2.Cu")
		(net "PCIE_RX_P87")
	)
	(segment
		(start 151.731218 -13.880084)
		(end 151.984964 -14.696694)
		(width 0.1397)
		(layer "In2.Cu")
		(net "PCIE_RX_P87")
	)
	(segment
		(start 183.24322 -33.69056)
		(end 187.39104 -32.95904)
		(width 0.1397)
		(layer "In2.Cu")
		(net "PCIE_RX_P87")
	)
	(segment
		(start 182.501286 -33.532826)
		(end 183.24322 -33.69056)
		(width 0.1397)
		(layer "In2.Cu")
		(net "PCIE_RX_P87")
	)
	(segment
		(start 219.263976 -32.83966)
		(end 221.319852 -32.83966)
		(width 0.1397)
		(layer "In2.Cu")
		(net "PCIE_RX_P87")
	)
	(segment
		(start 165.560502 -30.159706)
		(end 168.862756 -32.303974)
		(width 0.1397)
		(layer "In2.Cu")
		(net "PCIE_RX_P87")
	)
	(segment
		(start 156.172154 -27.979624)
		(end 157.082744 -28.357322)
		(width 0.1397)
		(layer "In2.Cu")
		(net "PCIE_RX_P87")
	)
	(segment
		(start 153.768298 -17.776444)
		(end 154.449526 -21.638514)
		(width 0.1397)
		(layer "In2.Cu")
		(net "PCIE_RX_P87")
	)
	(arc
		(start 148.45538 -13.125704)
		(mid 148.394963 -12.976051)
		(end 148.322538 -12.831826)
		(width 0.1397)
		(layer "In2.Cu")
		(net "PCIE_RX_P87")
	)
	(arc
		(start 151.984964 -14.696694)
		(mid 152.222126 -15.286239)
		(end 152.552146 -15.82928)
		(width 0.1397)
		(layer "In2.Cu")
		(net "PCIE_RX_P87")
	)
	(arc
		(start 151.064468 -11.24712)
		(mid 151.362431 -12.572317)
		(end 151.731218 -13.879576)
		(width 0.1397)
		(layer "In2.Cu")
		(net "PCIE_RX_P87")
	)
	(arc
		(start 148.63445 -13.930122)
		(mid 148.569698 -13.522396)
		(end 148.45538 -13.125704)
		(width 0.1397)
		(layer "In2.Cu")
		(net "PCIE_RX_P87")
	)
	(arc
		(start 225.477324 -32.972502)
		(mid 225.836197 -33.180235)
		(end 226.100132 -33.50006)
		(width 0.1016)
		(layer "In2.Cu")
		(net "PCIE_RX_P87")
	)
	(arc
		(start 225.080068 -32.90316)
		(mid 225.281709 -32.920575)
		(end 225.477324 -32.972502)
		(width 0.1016)
		(layer "In2.Cu")
		(net "PCIE_RX_P87")
	)
	(arc
		(start 148.343366 -12.166346)
		(mid 148.357606 -12.145723)
		(end 148.373338 -12.126214)
		(width 0.1397)
		(layer "In2.Cu")
		(net "PCIE_RX_P87")
	)
	(arc
		(start 148.322792 -12.831572)
		(mid 148.241782 -12.496147)
		(end 148.343366 -12.166346)
		(width 0.1397)
		(layer "In2.Cu")
		(net "PCIE_RX_P87")
	)
	(arc
		(start 149.59838 -10.724896)
		(mid 150.479998 -10.568988)
		(end 151.064468 -11.24712)
		(width 0.1397)
		(layer "In2.Cu")
		(net "PCIE_RX_P87")
	)
	(segment
		(start 227.600002 -34.99993)
		(end 227.10013 -34.500058)
		(width 0.136652)
		(layer "F.Cu")
		(net "PCIE_RX_P86")
	)
	(via
		(at 227.10013 -34.500058)
		(size 0.4572)
		(drill 0.2032)
		(layers "F.Cu" "B.Cu")
		(net "PCIE_RX_P86")
	)
	(segment
		(start 218.713558 -35.161728)
		(end 218.718384 -35.166554)
		(width 0.1397)
		(layer "In2.Cu")
		(net "PCIE_RX_P86")
	)
	(segment
		(start 168.264332 -34.529014)
		(end 175.939704 -35.882072)
		(width 0.1397)
		(layer "In2.Cu")
		(net "PCIE_RX_P86")
	)
	(segment
		(start 212.977476 -34.150554)
		(end 218.713558 -35.161728)
		(width 0.1397)
		(layer "In2.Cu")
		(net "PCIE_RX_P86")
	)
	(segment
		(start 152.486868 -27.410918)
		(end 153.483818 -28.83535)
		(width 0.1397)
		(layer "In2.Cu")
		(net "PCIE_RX_P86")
	)
	(segment
		(start 226.701604 -34.77895)
		(end 226.701604 -34.67735)
		(width 0.1016)
		(layer "In2.Cu")
		(net "PCIE_RX_P86")
	)
	(segment
		(start 148.75891 -17.6784)
		(end 149.205188 -17.6784)
		(width 0.1397)
		(layer "In2.Cu")
		(net "PCIE_RX_P86")
	)
	(segment
		(start 149.56028 -17.825466)
		(end 151.61768 -19.882866)
		(width 0.1397)
		(layer "In2.Cu")
		(net "PCIE_RX_P86")
	)
	(segment
		(start 226.729798 -34.58464)
		(end 226.730306 -34.584132)
		(width 0.1016)
		(layer "In2.Cu")
		(net "PCIE_RX_P86")
	)
	(segment
		(start 183.251348 -36.07435)
		(end 187.326016 -35.356038)
		(width 0.1397)
		(layer "In2.Cu")
		(net "PCIE_RX_P86")
	)
	(segment
		(start 175.939704 -35.882072)
		(end 179.175664 -36.529264)
		(width 0.1397)
		(layer "In2.Cu")
		(net "PCIE_RX_P86")
	)
	(segment
		(start 153.483818 -28.83535)
		(end 155.34513 -30.138116)
		(width 0.1397)
		(layer "In2.Cu")
		(net "PCIE_RX_P86")
	)
	(segment
		(start 151.868378 -23.902924)
		(end 152.486868 -27.410918)
		(width 0.1397)
		(layer "In2.Cu")
		(net "PCIE_RX_P86")
	)
	(segment
		(start 164.500814 -32.085026)
		(end 168.264332 -34.529014)
		(width 0.1397)
		(layer "In2.Cu")
		(net "PCIE_RX_P86")
	)
	(segment
		(start 218.718384 -35.166554)
		(end 221.35592 -35.166554)
		(width 0.1397)
		(layer "In2.Cu")
		(net "PCIE_RX_P86")
	)
	(segment
		(start 221.35592 -35.166554)
		(end 221.38132 -35.166554)
		(width 0.1016)
		(layer "In2.Cu")
		(net "PCIE_RX_P86")
	)
	(segment
		(start 221.44482 -35.103054)
		(end 226.3775 -35.103054)
		(width 0.1016)
		(layer "In2.Cu")
		(net "PCIE_RX_P86")
	)
	(segment
		(start 226.701604 -34.67735)
		(end 226.699826 -34.677604)
		(width 0.1016)
		(layer "In2.Cu")
		(net "PCIE_RX_P86")
	)
	(segment
		(start 179.175664 -36.529264)
		(end 182.350664 -35.894264)
		(width 0.1397)
		(layer "In2.Cu")
		(net "PCIE_RX_P86")
	)
	(segment
		(start 226.934522 -34.500058)
		(end 227.10013 -34.500058)
		(width 0.1016)
		(layer "In2.Cu")
		(net "PCIE_RX_P86")
	)
	(segment
		(start 182.350664 -35.894264)
		(end 183.251348 -36.07435)
		(width 0.1397)
		(layer "In2.Cu")
		(net "PCIE_RX_P86")
	)
	(segment
		(start 151.61768 -19.882866)
		(end 152.09774 -22.604222)
		(width 0.1397)
		(layer "In2.Cu")
		(net "PCIE_RX_P86")
	)
	(segment
		(start 221.38132 -35.166554)
		(end 221.44482 -35.103054)
		(width 0.1016)
		(layer "In2.Cu")
		(net "PCIE_RX_P86")
	)
	(segment
		(start 152.09774 -22.604222)
		(end 151.868378 -23.902924)
		(width 0.1397)
		(layer "In2.Cu")
		(net "PCIE_RX_P86")
	)
	(segment
		(start 196.1515 -37.118036)
		(end 212.977476 -34.150554)
		(width 0.1397)
		(layer "In2.Cu")
		(net "PCIE_RX_P86")
	)
	(segment
		(start 155.34513 -30.138116)
		(end 164.500814 -32.085026)
		(width 0.1397)
		(layer "In2.Cu")
		(net "PCIE_RX_P86")
	)
	(segment
		(start 226.699826 -34.677604)
		(end 226.699826 -34.656776)
		(width 0.1016)
		(layer "In2.Cu")
		(net "PCIE_RX_P86")
	)
	(segment
		(start 187.326016 -35.356038)
		(end 196.1515 -37.118036)
		(width 0.1397)
		(layer "In2.Cu")
		(net "PCIE_RX_P86")
	)
	(arc
		(start 148.63445 -17.729962)
		(mid 148.691553 -17.691807)
		(end 148.75891 -17.6784)
		(width 0.1397)
		(layer "In2.Cu")
		(net "PCIE_RX_P86")
	)
	(arc
		(start 226.699826 -34.656776)
		(mid 226.707614 -34.617715)
		(end 226.729798 -34.58464)
		(width 0.1016)
		(layer "In2.Cu")
		(net "PCIE_RX_P86")
	)
	(arc
		(start 226.3775 -35.103054)
		(mid 226.606676 -35.008126)
		(end 226.701604 -34.77895)
		(width 0.1016)
		(layer "In2.Cu")
		(net "PCIE_RX_P86")
	)
	(arc
		(start 149.205188 -17.6784)
		(mid 149.397356 -17.716625)
		(end 149.56028 -17.825466)
		(width 0.1397)
		(layer "In2.Cu")
		(net "PCIE_RX_P86")
	)
	(arc
		(start 226.730306 -34.584132)
		(mid 226.8241 -34.521901)
		(end 226.934522 -34.500058)
		(width 0.1016)
		(layer "In2.Cu")
		(net "PCIE_RX_P86")
	)
	(segment
		(start 226.600004 -35.999928)
		(end 226.100132 -35.500056)
		(width 0.136652)
		(layer "F.Cu")
		(net "PCIE_RX_P85")
	)
	(via
		(at 226.100132 -35.500056)
		(size 0.4572)
		(drill 0.2032)
		(layers "F.Cu" "B.Cu")
		(net "PCIE_RX_P85")
	)
	(segment
		(start 165.312344 -36.273994)
		(end 165.486334 -36.006024)
		(width 0.1397)
		(layer "In2.Cu")
		(net "PCIE_RX_P85")
	)
	(segment
		(start 164.78631 -38.197536)
		(end 165.138354 -36.54171)
		(width 0.1397)
		(layer "In2.Cu")
		(net "PCIE_RX_P85")
	)
	(segment
		(start 225.701606 -35.703256)
		(end 225.701606 -35.601656)
		(width 0.1016)
		(layer "In2.Cu")
		(net "PCIE_RX_P85")
	)
	(segment
		(start 221.392496 -36.098226)
		(end 225.306636 -36.098226)
		(width 0.1016)
		(layer "In2.Cu")
		(net "PCIE_RX_P85")
	)
	(segment
		(start 167.644826 -35.210496)
		(end 179.198524 -37.52215)
		(width 0.1397)
		(layer "In2.Cu")
		(net "PCIE_RX_P85")
	)
	(segment
		(start 155.674568 -31.345124)
		(end 156.455872 -32.548068)
		(width 0.1397)
		(layer "In2.Cu")
		(net "PCIE_RX_P85")
	)
	(segment
		(start 186.782964 -36.452302)
		(end 195.961508 -38.288214)
		(width 0.1397)
		(layer "In2.Cu")
		(net "PCIE_RX_P85")
	)
	(segment
		(start 165.138354 -36.54171)
		(end 165.312344 -36.273994)
		(width 0.1397)
		(layer "In2.Cu")
		(net "PCIE_RX_P85")
	)
	(segment
		(start 179.198524 -37.52215)
		(end 182.350664 -36.891722)
		(width 0.1397)
		(layer "In2.Cu")
		(net "PCIE_RX_P85")
	)
	(segment
		(start 150.002494 -19.41195)
		(end 150.568406 -20.042632)
		(width 0.1397)
		(layer "In2.Cu")
		(net "PCIE_RX_P85")
	)
	(segment
		(start 221.303596 -36.161726)
		(end 221.328996 -36.161726)
		(width 0.1016)
		(layer "In2.Cu")
		(net "PCIE_RX_P85")
	)
	(segment
		(start 157.83052 -37.483034)
		(end 161.242756 -39.698168)
		(width 0.1397)
		(layer "In2.Cu")
		(net "PCIE_RX_P85")
	)
	(segment
		(start 225.803206 -35.500056)
		(end 226.100132 -35.500056)
		(width 0.1016)
		(layer "In2.Cu")
		(net "PCIE_RX_P85")
	)
	(segment
		(start 156.455872 -32.548068)
		(end 157.346396 -36.737544)
		(width 0.1397)
		(layer "In2.Cu")
		(net "PCIE_RX_P85")
	)
	(segment
		(start 204.36205 -36.608004)
		(end 212.68309 -35.140646)
		(width 0.1397)
		(layer "In2.Cu")
		(net "PCIE_RX_P85")
	)
	(segment
		(start 162.235642 -39.909496)
		(end 163.59759 -39.619936)
		(width 0.1397)
		(layer "In2.Cu")
		(net "PCIE_RX_P85")
	)
	(segment
		(start 150.568406 -20.042632)
		(end 150.719536 -20.447254)
		(width 0.1397)
		(layer "In2.Cu")
		(net "PCIE_RX_P85")
	)
	(segment
		(start 147.359878 -17.841976)
		(end 147.756118 -18.460974)
		(width 0.1397)
		(layer "In2.Cu")
		(net "PCIE_RX_P85")
	)
	(segment
		(start 218.474544 -36.161726)
		(end 221.303596 -36.161726)
		(width 0.1397)
		(layer "In2.Cu")
		(net "PCIE_RX_P85")
	)
	(segment
		(start 151.08809 -22.538182)
		(end 150.817072 -24.074628)
		(width 0.1397)
		(layer "In2.Cu")
		(net "PCIE_RX_P85")
	)
	(segment
		(start 182.350664 -36.891722)
		(end 183.467756 -37.115242)
		(width 0.1397)
		(layer "In2.Cu")
		(net "PCIE_RX_P85")
	)
	(segment
		(start 165.486334 -36.006024)
		(end 165.486334 -36.00577)
		(width 0.1397)
		(layer "In2.Cu")
		(net "PCIE_RX_P85")
	)
	(segment
		(start 221.328996 -36.161726)
		(end 221.392496 -36.098226)
		(width 0.1016)
		(layer "In2.Cu")
		(net "PCIE_RX_P85")
	)
	(segment
		(start 151.556466 -28.273502)
		(end 151.982932 -28.885642)
		(width 0.1397)
		(layer "In2.Cu")
		(net "PCIE_RX_P85")
	)
	(segment
		(start 212.68309 -35.140646)
		(end 218.474544 -36.161726)
		(width 0.1397)
		(layer "In2.Cu")
		(net "PCIE_RX_P85")
	)
	(segment
		(start 166.256716 -35.505644)
		(end 167.644826 -35.210496)
		(width 0.1397)
		(layer "In2.Cu")
		(net "PCIE_RX_P85")
	)
	(segment
		(start 183.467756 -37.115242)
		(end 186.782964 -36.452302)
		(width 0.1397)
		(layer "In2.Cu")
		(net "PCIE_RX_P85")
	)
	(segment
		(start 163.59759 -39.619936)
		(end 164.055806 -39.322248)
		(width 0.1397)
		(layer "In2.Cu")
		(net "PCIE_RX_P85")
	)
	(segment
		(start 161.242756 -39.698168)
		(end 162.235642 -39.909496)
		(width 0.1397)
		(layer "In2.Cu")
		(net "PCIE_RX_P85")
	)
	(segment
		(start 151.982932 -28.885642)
		(end 155.674568 -31.345124)
		(width 0.1397)
		(layer "In2.Cu")
		(net "PCIE_RX_P85")
	)
	(segment
		(start 150.817072 -24.074628)
		(end 151.556466 -28.273502)
		(width 0.1397)
		(layer "In2.Cu")
		(net "PCIE_RX_P85")
	)
	(segment
		(start 157.346396 -36.737544)
		(end 157.83052 -37.483034)
		(width 0.1397)
		(layer "In2.Cu")
		(net "PCIE_RX_P85")
	)
	(segment
		(start 148.391372 -18.873216)
		(end 150.002494 -19.41195)
		(width 0.1397)
		(layer "In2.Cu")
		(net "PCIE_RX_P85")
	)
	(segment
		(start 147.756118 -18.460974)
		(end 148.391372 -18.873216)
		(width 0.1397)
		(layer "In2.Cu")
		(net "PCIE_RX_P85")
	)
	(segment
		(start 150.719536 -20.447254)
		(end 151.08809 -22.538182)
		(width 0.1397)
		(layer "In2.Cu")
		(net "PCIE_RX_P85")
	)
	(segment
		(start 195.961508 -38.288214)
		(end 204.36205 -36.608004)
		(width 0.1397)
		(layer "In2.Cu")
		(net "PCIE_RX_P85")
	)
	(segment
		(start 165.486334 -36.00577)
		(end 166.256716 -35.505644)
		(width 0.1397)
		(layer "In2.Cu")
		(net "PCIE_RX_P85")
	)
	(segment
		(start 164.055806 -39.322248)
		(end 164.78631 -38.197536)
		(width 0.1397)
		(layer "In2.Cu")
		(net "PCIE_RX_P85")
	)
	(segment
		(start 147.258278 -17.740376)
		(end 147.359878 -17.841976)
		(width 0.1397)
		(layer "In2.Cu")
		(net "PCIE_RX_P85")
	)
	(arc
		(start 146.384518 -17.729962)
		(mid 146.823518 -17.557251)
		(end 147.258278 -17.740376)
		(width 0.1397)
		(layer "In2.Cu")
		(net "PCIE_RX_P85")
	)
	(arc
		(start 225.306636 -36.098226)
		(mid 225.585922 -35.982542)
		(end 225.701606 -35.703256)
		(width 0.1016)
		(layer "In2.Cu")
		(net "PCIE_RX_P85")
	)
	(arc
		(start 225.701606 -35.601656)
		(mid 225.731364 -35.529814)
		(end 225.803206 -35.500056)
		(width 0.1016)
		(layer "In2.Cu")
		(net "PCIE_RX_P85")
	)
	(segment
		(start 227.600002 -36.999926)
		(end 227.10013 -36.500054)
		(width 0.136652)
		(layer "F.Cu")
		(net "PCIE_RX_P84")
	)
	(via
		(at 227.10013 -36.500054)
		(size 0.4572)
		(drill 0.2032)
		(layers "F.Cu" "B.Cu")
		(net "PCIE_RX_P84")
	)
	(segment
		(start 144.6276 -11.5316)
		(end 144.4244 -11.5316)
		(width 0.1397)
		(layer "In2.Cu")
		(net "PCIE_RX_P84")
	)
	(segment
		(start 187.512198 -33.951672)
		(end 196.389498 -35.726878)
		(width 0.1397)
		(layer "In2.Cu")
		(net "PCIE_RX_P84")
	)
	(segment
		(start 221.245938 -33.850326)
		(end 221.29877 -33.903158)
		(width 0.1016)
		(layer "In2.Cu")
		(net "PCIE_RX_P84")
	)
	(segment
		(start 227.36175 -33.903158)
		(end 227.704142 -34.24555)
		(width 0.1016)
		(layer "In2.Cu")
		(net "PCIE_RX_P84")
	)
	(segment
		(start 219.084906 -33.850326)
		(end 221.245938 -33.850326)
		(width 0.1397)
		(layer "In2.Cu")
		(net "PCIE_RX_P84")
	)
	(segment
		(start 226.803204 -36.500054)
		(end 227.10013 -36.500054)
		(width 0.1016)
		(layer "In2.Cu")
		(net "PCIE_RX_P84")
	)
	(segment
		(start 176.000664 -34.560256)
		(end 179.175664 -35.195256)
		(width 0.1397)
		(layer "In2.Cu")
		(net "PCIE_RX_P84")
	)
	(segment
		(start 156.191966 -29.110178)
		(end 165.336728 -31.053786)
		(width 0.1397)
		(layer "In2.Cu")
		(net "PCIE_RX_P84")
	)
	(segment
		(start 152.842976 -18.692876)
		(end 153.3398 -21.510244)
		(width 0.1397)
		(layer "In2.Cu")
		(net "PCIE_RX_P84")
	)
	(segment
		(start 168.774618 -33.285938)
		(end 176.000664 -34.560256)
		(width 0.1397)
		(layer "In2.Cu")
		(net "PCIE_RX_P84")
	)
	(segment
		(start 143.002 -13.2842)
		(end 143.002 -13.84808)
		(width 0.1397)
		(layer "In2.Cu")
		(net "PCIE_RX_P84")
	)
	(segment
		(start 204.724254 -34.256726)
		(end 213.058502 -32.787336)
		(width 0.1397)
		(layer "In2.Cu")
		(net "PCIE_RX_P84")
	)
	(segment
		(start 179.175664 -35.195256)
		(end 182.350664 -34.560256)
		(width 0.1397)
		(layer "In2.Cu")
		(net "PCIE_RX_P84")
	)
	(segment
		(start 150.952962 -16.32712)
		(end 150.962868 -16.340836)
		(width 0.1397)
		(layer "In2.Cu")
		(net "PCIE_RX_P84")
	)
	(segment
		(start 144.276318 -15.087346)
		(end 149.094444 -15.062454)
		(width 0.1397)
		(layer "In2.Cu")
		(net "PCIE_RX_P84")
	)
	(segment
		(start 213.058502 -32.787336)
		(end 219.084906 -33.850326)
		(width 0.1397)
		(layer "In2.Cu")
		(net "PCIE_RX_P84")
	)
	(segment
		(start 183.151526 -34.72053)
		(end 187.512198 -33.951672)
		(width 0.1397)
		(layer "In2.Cu")
		(net "PCIE_RX_P84")
	)
	(segment
		(start 204.724254 -34.25698)
		(end 204.724254 -34.256726)
		(width 0.1397)
		(layer "In2.Cu")
		(net "PCIE_RX_P84")
	)
	(segment
		(start 150.107396 -15.4813)
		(end 150.952962 -16.32712)
		(width 0.1397)
		(layer "In2.Cu")
		(net "PCIE_RX_P84")
	)
	(segment
		(start 226.701604 -36.240466)
		(end 226.701604 -36.398454)
		(width 0.1016)
		(layer "In2.Cu")
		(net "PCIE_RX_P84")
	)
	(segment
		(start 146.574764 -13.008356)
		(end 146.304254 -12.877546)
		(width 0.1397)
		(layer "In2.Cu")
		(net "PCIE_RX_P84")
	)
	(segment
		(start 153.558748 -26.489406)
		(end 154.728164 -28.159456)
		(width 0.1397)
		(layer "In2.Cu")
		(net "PCIE_RX_P84")
	)
	(segment
		(start 165.336728 -31.053786)
		(end 168.774618 -33.285938)
		(width 0.1397)
		(layer "In2.Cu")
		(net "PCIE_RX_P84")
	)
	(segment
		(start 154.728164 -28.159456)
		(end 156.191966 -29.110178)
		(width 0.1397)
		(layer "In2.Cu")
		(net "PCIE_RX_P84")
	)
	(segment
		(start 153.3398 -21.510244)
		(end 153.3398 -25.2476)
		(width 0.1397)
		(layer "In2.Cu")
		(net "PCIE_RX_P84")
	)
	(segment
		(start 182.350664 -34.560256)
		(end 183.151526 -34.72053)
		(width 0.1397)
		(layer "In2.Cu")
		(net "PCIE_RX_P84")
	)
	(segment
		(start 227.450396 -36.103052)
		(end 226.839018 -36.103052)
		(width 0.1016)
		(layer "In2.Cu")
		(net "PCIE_RX_P84")
	)
	(segment
		(start 227.704142 -35.849306)
		(end 227.450396 -36.103052)
		(width 0.1016)
		(layer "In2.Cu")
		(net "PCIE_RX_P84")
	)
	(segment
		(start 143.834104 -11.775948)
		(end 143.480028 -12.130532)
		(width 0.1397)
		(layer "In2.Cu")
		(net "PCIE_RX_P84")
	)
	(segment
		(start 151.509476 -16.788638)
		(end 152.842976 -18.692876)
		(width 0.1397)
		(layer "In2.Cu")
		(net "PCIE_RX_P84")
	)
	(segment
		(start 150.962868 -16.340836)
		(end 151.509476 -16.788638)
		(width 0.1397)
		(layer "In2.Cu")
		(net "PCIE_RX_P84")
	)
	(segment
		(start 221.29877 -33.903158)
		(end 227.36175 -33.903158)
		(width 0.1016)
		(layer "In2.Cu")
		(net "PCIE_RX_P84")
	)
	(segment
		(start 196.389498 -35.726878)
		(end 204.724254 -34.25698)
		(width 0.1397)
		(layer "In2.Cu")
		(net "PCIE_RX_P84")
	)
	(segment
		(start 146.018758 -12.6746)
		(end 145.051526 -11.707368)
		(width 0.1397)
		(layer "In2.Cu")
		(net "PCIE_RX_P84")
	)
	(segment
		(start 227.704142 -34.24555)
		(end 227.704142 -35.849306)
		(width 0.1016)
		(layer "In2.Cu")
		(net "PCIE_RX_P84")
	)
	(segment
		(start 153.3398 -25.2476)
		(end 153.558748 -26.489406)
		(width 0.1397)
		(layer "In2.Cu")
		(net "PCIE_RX_P84")
	)
	(arc
		(start 146.384518 -13.930122)
		(mid 146.838761 -13.543344)
		(end 146.574764 -13.008356)
		(width 0.1397)
		(layer "In2.Cu")
		(net "PCIE_RX_P84")
	)
	(arc
		(start 144.4244 -11.5316)
		(mid 144.104942 -11.595051)
		(end 143.834104 -11.775948)
		(width 0.1397)
		(layer "In2.Cu")
		(net "PCIE_RX_P84")
	)
	(arc
		(start 143.480028 -12.130532)
		(mid 143.126273 -12.659824)
		(end 143.002 -13.2842)
		(width 0.1397)
		(layer "In2.Cu")
		(net "PCIE_RX_P84")
	)
	(arc
		(start 226.839018 -36.103052)
		(mid 226.741852 -36.1433)
		(end 226.701604 -36.240466)
		(width 0.1016)
		(layer "In2.Cu")
		(net "PCIE_RX_P84")
	)
	(arc
		(start 149.094444 -15.062454)
		(mid 149.642595 -15.171073)
		(end 150.107396 -15.4813)
		(width 0.1397)
		(layer "In2.Cu")
		(net "PCIE_RX_P84")
	)
	(arc
		(start 145.051526 -11.707368)
		(mid 144.975563 -11.642972)
		(end 144.889982 -11.592052)
		(width 0.1397)
		(layer "In2.Cu")
		(net "PCIE_RX_P84")
	)
	(arc
		(start 146.304254 -12.877546)
		(mid 146.152975 -12.788072)
		(end 146.018758 -12.6746)
		(width 0.1397)
		(layer "In2.Cu")
		(net "PCIE_RX_P84")
	)
	(arc
		(start 143.3576 -14.7066)
		(mid 143.779137 -14.988225)
		(end 144.276318 -15.087346)
		(width 0.1397)
		(layer "In2.Cu")
		(net "PCIE_RX_P84")
	)
	(arc
		(start 143.002 -13.84808)
		(mid 143.094419 -14.312704)
		(end 143.3576 -14.7066)
		(width 0.1397)
		(layer "In2.Cu")
		(net "PCIE_RX_P84")
	)
	(arc
		(start 226.701604 -36.398454)
		(mid 226.731362 -36.470296)
		(end 226.803204 -36.500054)
		(width 0.1016)
		(layer "In2.Cu")
		(net "PCIE_RX_P84")
	)
	(arc
		(start 144.889982 -11.592052)
		(mid 144.762227 -11.546913)
		(end 144.6276 -11.5316)
		(width 0.1397)
		(layer "In2.Cu")
		(net "PCIE_RX_P84")
	)
	(segment
		(start 226.600004 -37.999924)
		(end 226.100132 -37.500052)
		(width 0.136652)
		(layer "F.Cu")
		(net "PCIE_RX_P83")
	)
	(via
		(at 226.100132 -37.500052)
		(size 0.4572)
		(drill 0.2032)
		(layers "F.Cu" "B.Cu")
		(net "PCIE_RX_P83")
	)
	(segment
		(start 182.352188 -37.552884)
		(end 165.101524 -41.189656)
		(width 0.1397)
		(layer "In2.Cu")
		(net "PCIE_RX_P83")
	)
	(segment
		(start 139.74064 -11.45159)
		(end 139.72921 -11.293094)
		(width 0.1397)
		(layer "In2.Cu")
		(net "PCIE_RX_P83")
	)
	(segment
		(start 152.763728 -30.265878)
		(end 145.93824 -28.643834)
		(width 0.1397)
		(layer "In2.Cu")
		(net "PCIE_RX_P83")
	)
	(segment
		(start 212.823552 -35.871658)
		(end 204.5843 -37.324792)
		(width 0.1397)
		(layer "In2.Cu")
		(net "PCIE_RX_P83")
	)
	(segment
		(start 218.312238 -36.839652)
		(end 212.823552 -35.871658)
		(width 0.1397)
		(layer "In2.Cu")
		(net "PCIE_RX_P83")
	)
	(segment
		(start 155.414726 -32.383476)
		(end 154.969972 -31.698692)
		(width 0.1397)
		(layer "In2.Cu")
		(net "PCIE_RX_P83")
	)
	(segment
		(start 155.59151 -35.104324)
		(end 155.79217 -34.159698)
		(width 0.1397)
		(layer "In2.Cu")
		(net "PCIE_RX_P83")
	)
	(segment
		(start 155.857956 -36.359846)
		(end 155.59151 -35.104324)
		(width 0.1397)
		(layer "In2.Cu")
		(net "PCIE_RX_P83")
	)
	(segment
		(start 165.101524 -41.189656)
		(end 160.560258 -40.224964)
		(width 0.1397)
		(layer "In2.Cu")
		(net "PCIE_RX_P83")
	)
	(segment
		(start 142.08633 -15.752826)
		(end 140.595858 -13.624052)
		(width 0.1397)
		(layer "In2.Cu")
		(net "PCIE_RX_P83")
	)
	(segment
		(start 156.313632 -37.061394)
		(end 156.313378 -37.060886)
		(width 0.1397)
		(layer "In2.Cu")
		(net "PCIE_RX_P83")
	)
	(segment
		(start 138.359134 -10.882122)
		(end 137.505694 -11.97102)
		(width 0.1397)
		(layer "In2.Cu")
		(net "PCIE_RX_P83")
	)
	(segment
		(start 137.505694 -11.97102)
		(end 137.505694 -11.971274)
		(width 0.1397)
		(layer "In2.Cu")
		(net "PCIE_RX_P83")
	)
	(segment
		(start 145.93824 -28.643834)
		(end 144.061688 -27.850846)
		(width 0.1397)
		(layer "In2.Cu")
		(net "PCIE_RX_P83")
	)
	(segment
		(start 196.073522 -39.026846)
		(end 187.11672 -37.235892)
		(width 0.1397)
		(layer "In2.Cu")
		(net "PCIE_RX_P83")
	)
	(segment
		(start 183.941212 -37.870638)
		(end 182.352188 -37.552884)
		(width 0.1397)
		(layer "In2.Cu")
		(net "PCIE_RX_P83")
	)
	(segment
		(start 143.00708 -25.557734)
		(end 143.411194 -23.266908)
		(width 0.1397)
		(layer "In2.Cu")
		(net "PCIE_RX_P83")
	)
	(segment
		(start 156.313378 -37.060886)
		(end 155.857956 -36.359846)
		(width 0.1397)
		(layer "In2.Cu")
		(net "PCIE_RX_P83")
	)
	(segment
		(start 204.5843 -37.324792)
		(end 196.073522 -39.026846)
		(width 0.1397)
		(layer "In2.Cu")
		(net "PCIE_RX_P83")
	)
	(segment
		(start 156.768546 -37.761926)
		(end 156.313632 -37.061394)
		(width 0.1397)
		(layer "In2.Cu")
		(net "PCIE_RX_P83")
	)
	(segment
		(start 138.360404 -10.880598)
		(end 138.359134 -10.882122)
		(width 0.1397)
		(layer "In2.Cu")
		(net "PCIE_RX_P83")
	)
	(segment
		(start 155.79217 -34.159698)
		(end 155.414726 -32.383476)
		(width 0.1397)
		(layer "In2.Cu")
		(net "PCIE_RX_P83")
	)
	(segment
		(start 221.116906 -36.839652)
		(end 218.312238 -36.839652)
		(width 0.1397)
		(layer "In2.Cu")
		(net "PCIE_RX_P83")
	)
	(segment
		(start 154.969972 -31.698692)
		(end 152.763728 -30.265878)
		(width 0.1397)
		(layer "In2.Cu")
		(net "PCIE_RX_P83")
	)
	(segment
		(start 225.183954 -36.903152)
		(end 221.205806 -36.903152)
		(width 0.1016)
		(layer "In2.Cu")
		(net "PCIE_RX_P83")
	)
	(segment
		(start 144.061688 -27.850846)
		(end 143.168878 -26.476198)
		(width 0.1397)
		(layer "In2.Cu")
		(net "PCIE_RX_P83")
	)
	(segment
		(start 140.595858 -13.624052)
		(end 139.74064 -11.45159)
		(width 0.1397)
		(layer "In2.Cu")
		(net "PCIE_RX_P83")
	)
	(segment
		(start 143.168878 -26.476198)
		(end 143.00708 -25.557734)
		(width 0.1397)
		(layer "In2.Cu")
		(net "PCIE_RX_P83")
	)
	(segment
		(start 187.11672 -37.235892)
		(end 183.941212 -37.870638)
		(width 0.1397)
		(layer "In2.Cu")
		(net "PCIE_RX_P83")
	)
	(segment
		(start 221.205806 -36.903152)
		(end 221.142306 -36.839652)
		(width 0.1016)
		(layer "In2.Cu")
		(net "PCIE_RX_P83")
	)
	(segment
		(start 160.560258 -40.224964)
		(end 156.768546 -37.761926)
		(width 0.1397)
		(layer "In2.Cu")
		(net "PCIE_RX_P83")
	)
	(segment
		(start 143.411194 -23.266908)
		(end 142.08633 -15.752826)
		(width 0.1397)
		(layer "In2.Cu")
		(net "PCIE_RX_P83")
	)
	(segment
		(start 221.142306 -36.839652)
		(end 221.116906 -36.839652)
		(width 0.1016)
		(layer "In2.Cu")
		(net "PCIE_RX_P83")
	)
	(arc
		(start 226.100132 -37.500052)
		(mid 225.822879 -37.223155)
		(end 225.505518 -36.993322)
		(width 0.1016)
		(layer "In2.Cu")
		(net "PCIE_RX_P83")
	)
	(arc
		(start 137.354564 -12.875768)
		(mid 137.366624 -12.905872)
		(end 137.381488 -12.934696)
		(width 0.1397)
		(layer "In2.Cu")
		(net "PCIE_RX_P83")
	)
	(arc
		(start 139.72921 -11.293094)
		(mid 139.186897 -10.615501)
		(end 138.360404 -10.880598)
		(width 0.1397)
		(layer "In2.Cu")
		(net "PCIE_RX_P83")
	)
	(arc
		(start 137.505694 -11.971274)
		(mid 137.315183 -12.404316)
		(end 137.354564 -12.875768)
		(width 0.1397)
		(layer "In2.Cu")
		(net "PCIE_RX_P83")
	)
	(arc
		(start 137.381488 -12.934696)
		(mid 137.43345 -13.029784)
		(end 137.479786 -13.127736)
		(width 0.1397)
		(layer "In2.Cu")
		(net "PCIE_RX_P83")
	)
	(arc
		(start 137.479786 -13.127736)
		(mid 137.601761 -13.520322)
		(end 137.634472 -13.930122)
		(width 0.1397)
		(layer "In2.Cu")
		(net "PCIE_RX_P83")
	)
	(arc
		(start 225.505518 -36.993322)
		(mid 225.35096 -36.926032)
		(end 225.183954 -36.903152)
		(width 0.1016)
		(layer "In2.Cu")
		(net "PCIE_RX_P83")
	)
	(segment
		(start 227.600002 -38.999922)
		(end 227.10013 -38.50005)
		(width 0.136652)
		(layer "F.Cu")
		(net "PCIE_RX_P82")
	)
	(via
		(at 227.10013 -38.50005)
		(size 0.4572)
		(drill 0.2032)
		(layers "F.Cu" "B.Cu")
		(net "PCIE_RX_P82")
	)
	(segment
		(start 217.78722 -39.166546)
		(end 212.801454 -38.287452)
		(width 0.1397)
		(layer "In2.Cu")
		(net "PCIE_RX_P82")
	)
	(segment
		(start 142.068042 -35.986974)
		(end 140.004292 -24.284178)
		(width 0.1397)
		(layer "In2.Cu")
		(net "PCIE_RX_P82")
	)
	(segment
		(start 226.302062 -39.103046)
		(end 220.613986 -39.103046)
		(width 0.1016)
		(layer "In2.Cu")
		(net "PCIE_RX_P82")
	)
	(segment
		(start 220.47581 -39.166546)
		(end 217.78722 -39.166546)
		(width 0.1397)
		(layer "In2.Cu")
		(net "PCIE_RX_P82")
	)
	(segment
		(start 227.10013 -38.50005)
		(end 226.803458 -38.50005)
		(width 0.1016)
		(layer "In2.Cu")
		(net "PCIE_RX_P82")
	)
	(segment
		(start 220.613986 -39.103046)
		(end 220.550486 -39.166546)
		(width 0.1016)
		(layer "In2.Cu")
		(net "PCIE_RX_P82")
	)
	(segment
		(start 197.249288 -41.593516)
		(end 187.100464 -39.563802)
		(width 0.1397)
		(layer "In2.Cu")
		(net "PCIE_RX_P82")
	)
	(segment
		(start 182.350664 -39.883842)
		(end 164.629084 -43.427904)
		(width 0.1397)
		(layer "In2.Cu")
		(net "PCIE_RX_P82")
	)
	(segment
		(start 212.801454 -38.287452)
		(end 197.249288 -41.593516)
		(width 0.1397)
		(layer "In2.Cu")
		(net "PCIE_RX_P82")
	)
	(segment
		(start 146.846544 -39.84117)
		(end 142.913608 -37.288724)
		(width 0.1397)
		(layer "In2.Cu")
		(net "PCIE_RX_P82")
	)
	(segment
		(start 164.629084 -43.427904)
		(end 146.846544 -39.84117)
		(width 0.1397)
		(layer "In2.Cu")
		(net "PCIE_RX_P82")
	)
	(segment
		(start 142.913608 -37.288724)
		(end 142.068042 -35.986974)
		(width 0.1397)
		(layer "In2.Cu")
		(net "PCIE_RX_P82")
	)
	(segment
		(start 220.550486 -39.166546)
		(end 220.47581 -39.166546)
		(width 0.1016)
		(layer "In2.Cu")
		(net "PCIE_RX_P82")
	)
	(segment
		(start 140.358876 -22.269704)
		(end 139.79652 -19.080226)
		(width 0.1397)
		(layer "In2.Cu")
		(net "PCIE_RX_P82")
	)
	(segment
		(start 140.004292 -24.284178)
		(end 140.358876 -22.269704)
		(width 0.1397)
		(layer "In2.Cu")
		(net "PCIE_RX_P82")
	)
	(segment
		(start 139.79652 -19.080226)
		(end 138.79322 -18.076926)
		(width 0.1397)
		(layer "In2.Cu")
		(net "PCIE_RX_P82")
	)
	(segment
		(start 183.925464 -40.198802)
		(end 182.350664 -39.883842)
		(width 0.1397)
		(layer "In2.Cu")
		(net "PCIE_RX_P82")
	)
	(segment
		(start 137.955528 -17.729962)
		(end 137.634472 -17.729962)
		(width 0.1397)
		(layer "In2.Cu")
		(net "PCIE_RX_P82")
	)
	(segment
		(start 187.100464 -39.563802)
		(end 183.925464 -40.198802)
		(width 0.1397)
		(layer "In2.Cu")
		(net "PCIE_RX_P82")
	)
	(segment
		(start 226.701858 -38.60165)
		(end 226.701858 -38.70325)
		(width 0.1016)
		(layer "In2.Cu")
		(net "PCIE_RX_P82")
	)
	(arc
		(start 138.79322 -18.076926)
		(mid 138.408884 -17.820121)
		(end 137.955528 -17.729962)
		(width 0.1397)
		(layer "In2.Cu")
		(net "PCIE_RX_P82")
	)
	(arc
		(start 226.701858 -38.70325)
		(mid 226.58476 -38.985948)
		(end 226.302062 -39.103046)
		(width 0.1016)
		(layer "In2.Cu")
		(net "PCIE_RX_P82")
	)
	(arc
		(start 226.803458 -38.50005)
		(mid 226.731616 -38.529808)
		(end 226.701858 -38.60165)
		(width 0.1016)
		(layer "In2.Cu")
		(net "PCIE_RX_P82")
	)
	(segment
		(start 226.600004 -39.99992)
		(end 226.100132 -39.500048)
		(width 0.136652)
		(layer "F.Cu")
		(net "PCIE_RX_P81")
	)
	(via
		(at 226.100132 -39.500048)
		(size 0.4572)
		(drill 0.2032)
		(layers "F.Cu" "B.Cu")
		(net "PCIE_RX_P81")
	)
	(segment
		(start 164.75964 -44.398946)
		(end 146.32559 -40.567864)
		(width 0.1397)
		(layer "In2.Cu")
		(net "PCIE_RX_P81")
	)
	(segment
		(start 212.668104 -39.313104)
		(end 196.942202 -42.65549)
		(width 0.1397)
		(layer "In2.Cu")
		(net "PCIE_RX_P81")
	)
	(segment
		(start 185.34253 -40.845232)
		(end 183.755538 -41.162224)
		(width 0.1397)
		(layer "In2.Cu")
		(net "PCIE_RX_P81")
	)
	(segment
		(start 196.942202 -42.65549)
		(end 186.930538 -40.527478)
		(width 0.1397)
		(layer "In2.Cu")
		(net "PCIE_RX_P81")
	)
	(segment
		(start 142.04569 -37.788342)
		(end 141.203934 -36.491926)
		(width 0.1397)
		(layer "In2.Cu")
		(net "PCIE_RX_P81")
	)
	(segment
		(start 226.100132 -39.500048)
		(end 225.803206 -39.500048)
		(width 0.1016)
		(layer "In2.Cu")
		(net "PCIE_RX_P81")
	)
	(segment
		(start 132.377688 -27.157934)
		(end 131.90601 -26.43124)
		(width 0.1397)
		(layer "In2.Cu")
		(net "PCIE_RX_P81")
	)
	(segment
		(start 131.826762 -20.57273)
		(end 132.50291 -19.607022)
		(width 0.1397)
		(layer "In2.Cu")
		(net "PCIE_RX_P81")
	)
	(segment
		(start 134.739126 -19.058128)
		(end 136.096756 -18.81759)
		(width 0.1397)
		(layer "In2.Cu")
		(net "PCIE_RX_P81")
	)
	(segment
		(start 220.717618 -40.161718)
		(end 220.642942 -40.161718)
		(width 0.1016)
		(layer "In2.Cu")
		(net "PCIE_RX_P81")
	)
	(segment
		(start 225.701606 -39.601648)
		(end 225.701606 -39.703248)
		(width 0.1016)
		(layer "In2.Cu")
		(net "PCIE_RX_P81")
	)
	(segment
		(start 182.350664 -40.8813)
		(end 164.75964 -44.398946)
		(width 0.1397)
		(layer "In2.Cu")
		(net "PCIE_RX_P81")
	)
	(segment
		(start 136.096756 -18.81759)
		(end 136.534652 -18.379694)
		(width 0.1397)
		(layer "In2.Cu")
		(net "PCIE_RX_P81")
	)
	(segment
		(start 135.660892 -29.082492)
		(end 135.19023 -28.982416)
		(width 0.1397)
		(layer "In2.Cu")
		(net "PCIE_RX_P81")
	)
	(segment
		(start 141.203934 -36.491926)
		(end 140.39596 -32.693102)
		(width 0.1397)
		(layer "In2.Cu")
		(net "PCIE_RX_P81")
	)
	(segment
		(start 225.306636 -40.098218)
		(end 220.781118 -40.098218)
		(width 0.1016)
		(layer "In2.Cu")
		(net "PCIE_RX_P81")
	)
	(segment
		(start 131.90601 -26.43124)
		(end 131.81203 -25.989788)
		(width 0.1397)
		(layer "In2.Cu")
		(net "PCIE_RX_P81")
	)
	(segment
		(start 135.889492 -17.729962)
		(end 135.38454 -17.729962)
		(width 0.1397)
		(layer "In2.Cu")
		(net "PCIE_RX_P81")
	)
	(segment
		(start 136.534906 -18.028666)
		(end 136.477502 -17.971262)
		(width 0.1397)
		(layer "In2.Cu")
		(net "PCIE_RX_P81")
	)
	(segment
		(start 135.19023 -28.982416)
		(end 132.377688 -27.157934)
		(width 0.1397)
		(layer "In2.Cu")
		(net "PCIE_RX_P81")
	)
	(segment
		(start 146.32559 -40.567864)
		(end 142.04569 -37.788342)
		(width 0.1397)
		(layer "In2.Cu")
		(net "PCIE_RX_P81")
	)
	(segment
		(start 217.482928 -40.161718)
		(end 212.668104 -39.313104)
		(width 0.1397)
		(layer "In2.Cu")
		(net "PCIE_RX_P81")
	)
	(segment
		(start 132.06603 -24.549354)
		(end 131.6482 -22.177756)
		(width 0.1397)
		(layer "In2.Cu")
		(net "PCIE_RX_P81")
	)
	(segment
		(start 182.350918 -40.8813)
		(end 182.350664 -40.8813)
		(width 0.1397)
		(layer "In2.Cu")
		(net "PCIE_RX_P81")
	)
	(segment
		(start 183.755538 -41.162224)
		(end 182.350918 -40.8813)
		(width 0.1397)
		(layer "In2.Cu")
		(net "PCIE_RX_P81")
	)
	(segment
		(start 140.39596 -32.693102)
		(end 139.793726 -31.765748)
		(width 0.1397)
		(layer "In2.Cu")
		(net "PCIE_RX_P81")
	)
	(segment
		(start 132.50291 -19.607022)
		(end 133.578854 -18.853658)
		(width 0.1397)
		(layer "In2.Cu")
		(net "PCIE_RX_P81")
	)
	(segment
		(start 131.81203 -25.989788)
		(end 132.06603 -24.549354)
		(width 0.1397)
		(layer "In2.Cu")
		(net "PCIE_RX_P81")
	)
	(segment
		(start 185.34253 -40.844978)
		(end 185.34253 -40.845232)
		(width 0.1397)
		(layer "In2.Cu")
		(net "PCIE_RX_P81")
	)
	(segment
		(start 220.642942 -40.161718)
		(end 217.482928 -40.161718)
		(width 0.1397)
		(layer "In2.Cu")
		(net "PCIE_RX_P81")
	)
	(segment
		(start 220.781118 -40.098218)
		(end 220.717618 -40.161718)
		(width 0.1016)
		(layer "In2.Cu")
		(net "PCIE_RX_P81")
	)
	(segment
		(start 186.930538 -40.527478)
		(end 185.34253 -40.844978)
		(width 0.1397)
		(layer "In2.Cu")
		(net "PCIE_RX_P81")
	)
	(segment
		(start 133.578854 -18.853658)
		(end 134.739126 -19.058128)
		(width 0.1397)
		(layer "In2.Cu")
		(net "PCIE_RX_P81")
	)
	(segment
		(start 139.793726 -31.765748)
		(end 135.660892 -29.082492)
		(width 0.1397)
		(layer "In2.Cu")
		(net "PCIE_RX_P81")
	)
	(segment
		(start 131.6482 -21.586444)
		(end 131.826762 -20.57273)
		(width 0.1397)
		(layer "In2.Cu")
		(net "PCIE_RX_P81")
	)
	(segment
		(start 131.6482 -22.177756)
		(end 131.6482 -21.586444)
		(width 0.1397)
		(layer "In2.Cu")
		(net "PCIE_RX_P81")
	)
	(arc
		(start 136.477502 -17.971262)
		(mid 136.207272 -17.792675)
		(end 135.889492 -17.729962)
		(width 0.1397)
		(layer "In2.Cu")
		(net "PCIE_RX_P81")
	)
	(arc
		(start 136.534652 -18.379694)
		(mid 136.607532 -18.204196)
		(end 136.534906 -18.028666)
		(width 0.1397)
		(layer "In2.Cu")
		(net "PCIE_RX_P81")
	)
	(arc
		(start 225.701606 -39.703248)
		(mid 225.585922 -39.982534)
		(end 225.306636 -40.098218)
		(width 0.1016)
		(layer "In2.Cu")
		(net "PCIE_RX_P81")
	)
	(arc
		(start 225.803206 -39.500048)
		(mid 225.731364 -39.529806)
		(end 225.701606 -39.601648)
		(width 0.1016)
		(layer "In2.Cu")
		(net "PCIE_RX_P81")
	)
	(segment
		(start 227.600002 -40.999918)
		(end 227.10013 -40.500046)
		(width 0.136652)
		(layer "F.Cu")
		(net "PCIE_RX_P80")
	)
	(via
		(at 227.10013 -40.500046)
		(size 0.4572)
		(drill 0.2032)
		(layers "F.Cu" "B.Cu")
		(net "PCIE_RX_P80")
	)
	(segment
		(start 226.803204 -40.500046)
		(end 227.10013 -40.500046)
		(width 0.1016)
		(layer "In2.Cu")
		(net "PCIE_RX_P80")
	)
	(segment
		(start 227.35413 -37.89553)
		(end 227.704142 -38.245542)
		(width 0.1016)
		(layer "In2.Cu")
		(net "PCIE_RX_P80")
	)
	(segment
		(start 220.464634 -37.83203)
		(end 220.490034 -37.83203)
		(width 0.1016)
		(layer "In2.Cu")
		(net "PCIE_RX_P80")
	)
	(segment
		(start 132.3594 -13.3096)
		(end 132.3594 -14.087856)
		(width 0.1397)
		(layer "In2.Cu")
		(net "PCIE_RX_P80")
	)
	(segment
		(start 151.203914 -36.435792)
		(end 153.680922 -36.962588)
		(width 0.1397)
		(layer "In2.Cu")
		(net "PCIE_RX_P80")
	)
	(segment
		(start 220.490034 -37.83203)
		(end 220.553534 -37.89553)
		(width 0.1016)
		(layer "In2.Cu")
		(net "PCIE_RX_P80")
	)
	(segment
		(start 142.279624 -27.92349)
		(end 143.205708 -29.3497)
		(width 0.1397)
		(layer "In2.Cu")
		(net "PCIE_RX_P80")
	)
	(segment
		(start 133.5278 -14.976348)
		(end 137.5664 -14.976348)
		(width 0.1397)
		(layer "In2.Cu")
		(net "PCIE_RX_P80")
	)
	(segment
		(start 135.173212 -12.730734)
		(end 134.385812 -11.943334)
		(width 0.1397)
		(layer "In2.Cu")
		(net "PCIE_RX_P80")
	)
	(segment
		(start 141.593062 -24.693372)
		(end 142.279624 -27.92349)
		(width 0.1397)
		(layer "In2.Cu")
		(net "PCIE_RX_P80")
	)
	(segment
		(start 218.030298 -37.83203)
		(end 220.464634 -37.83203)
		(width 0.1397)
		(layer "In2.Cu")
		(net "PCIE_RX_P80")
	)
	(segment
		(start 220.553534 -37.89553)
		(end 227.35413 -37.89553)
		(width 0.1016)
		(layer "In2.Cu")
		(net "PCIE_RX_P80")
	)
	(segment
		(start 182.350664 -38.54958)
		(end 183.980328 -38.875462)
		(width 0.1397)
		(layer "In2.Cu")
		(net "PCIE_RX_P80")
	)
	(segment
		(start 134.0104 -11.7856)
		(end 133.7818 -11.7856)
		(width 0.1397)
		(layer "In2.Cu")
		(net "PCIE_RX_P80")
	)
	(segment
		(start 135.8138 -13.455396)
		(end 135.8138 -13.397738)
		(width 0.1397)
		(layer "In2.Cu")
		(net "PCIE_RX_P80")
	)
	(segment
		(start 227.704142 -39.849298)
		(end 227.450396 -40.103044)
		(width 0.1016)
		(layer "In2.Cu")
		(net "PCIE_RX_P80")
	)
	(segment
		(start 213.310216 -36.82873)
		(end 218.030298 -37.83203)
		(width 0.1397)
		(layer "In2.Cu")
		(net "PCIE_RX_P80")
	)
	(segment
		(start 145.983706 -36.910772)
		(end 147.476972 -37.228018)
		(width 0.1397)
		(layer "In2.Cu")
		(net "PCIE_RX_P80")
	)
	(segment
		(start 142.113 -22.246844)
		(end 141.593062 -24.693372)
		(width 0.1397)
		(layer "In2.Cu")
		(net "PCIE_RX_P80")
	)
	(segment
		(start 164.62375 -42.094404)
		(end 182.350664 -38.54958)
		(width 0.1397)
		(layer "In2.Cu")
		(net "PCIE_RX_P80")
	)
	(segment
		(start 147.476972 -37.228018)
		(end 151.203914 -36.435792)
		(width 0.1397)
		(layer "In2.Cu")
		(net "PCIE_RX_P80")
	)
	(segment
		(start 143.205708 -29.3497)
		(end 144.466818 -35.284918)
		(width 0.1397)
		(layer "In2.Cu")
		(net "PCIE_RX_P80")
	)
	(segment
		(start 183.980328 -38.875462)
		(end 187.155328 -38.240462)
		(width 0.1397)
		(layer "In2.Cu")
		(net "PCIE_RX_P80")
	)
	(segment
		(start 226.701604 -40.161972)
		(end 226.701604 -40.398446)
		(width 0.1016)
		(layer "In2.Cu")
		(net "PCIE_RX_P80")
	)
	(segment
		(start 145.1864 -36.39312)
		(end 145.983706 -36.910772)
		(width 0.1397)
		(layer "In2.Cu")
		(net "PCIE_RX_P80")
	)
	(segment
		(start 226.760532 -40.103044)
		(end 226.701604 -40.161972)
		(width 0.1016)
		(layer "In2.Cu")
		(net "PCIE_RX_P80")
	)
	(segment
		(start 227.450396 -40.103044)
		(end 226.760532 -40.103044)
		(width 0.1016)
		(layer "In2.Cu")
		(net "PCIE_RX_P80")
	)
	(segment
		(start 141.42212 -18.327624)
		(end 142.113 -22.246844)
		(width 0.1397)
		(layer "In2.Cu")
		(net "PCIE_RX_P80")
	)
	(segment
		(start 139.4206 -15.7226)
		(end 140.1826 -16.4846)
		(width 0.1397)
		(layer "In2.Cu")
		(net "PCIE_RX_P80")
	)
	(segment
		(start 144.466818 -35.284918)
		(end 145.1864 -36.39312)
		(width 0.1397)
		(layer "In2.Cu")
		(net "PCIE_RX_P80")
	)
	(segment
		(start 153.680922 -36.962588)
		(end 160.10382 -41.133522)
		(width 0.1397)
		(layer "In2.Cu")
		(net "PCIE_RX_P80")
	)
	(segment
		(start 197.208902 -40.250872)
		(end 210.811872 -37.359844)
		(width 0.1397)
		(layer "In2.Cu")
		(net "PCIE_RX_P80")
	)
	(segment
		(start 227.704142 -38.245542)
		(end 227.704142 -39.849298)
		(width 0.1016)
		(layer "In2.Cu")
		(net "PCIE_RX_P80")
	)
	(segment
		(start 133.1341 -12.0523)
		(end 132.6642 -12.5222)
		(width 0.1397)
		(layer "In2.Cu")
		(net "PCIE_RX_P80")
	)
	(segment
		(start 160.10382 -41.133522)
		(end 164.62375 -42.094404)
		(width 0.1397)
		(layer "In2.Cu")
		(net "PCIE_RX_P80")
	)
	(segment
		(start 187.155328 -38.240462)
		(end 197.208902 -40.250872)
		(width 0.1397)
		(layer "In2.Cu")
		(net "PCIE_RX_P80")
	)
	(segment
		(start 135.320532 -12.82065)
		(end 135.173212 -12.730734)
		(width 0.1397)
		(layer "In2.Cu")
		(net "PCIE_RX_P80")
	)
	(segment
		(start 135.683752 -13.083794)
		(end 135.533638 -12.93368)
		(width 0.1397)
		(layer "In2.Cu")
		(net "PCIE_RX_P80")
	)
	(segment
		(start 210.811872 -37.359844)
		(end 213.310216 -36.82873)
		(width 0.1397)
		(layer "In2.Cu")
		(net "PCIE_RX_P80")
	)
	(segment
		(start 140.1826 -16.4846)
		(end 141.42212 -18.327624)
		(width 0.1397)
		(layer "In2.Cu")
		(net "PCIE_RX_P80")
	)
	(arc
		(start 135.533638 -12.93368)
		(mid 135.511848 -12.915971)
		(end 135.489188 -12.89939)
		(width 0.1397)
		(layer "In2.Cu")
		(net "PCIE_RX_P80")
	)
	(arc
		(start 134.385812 -11.943334)
		(mid 134.214007 -11.826616)
		(end 134.0104 -11.7856)
		(width 0.1397)
		(layer "In2.Cu")
		(net "PCIE_RX_P80")
	)
	(arc
		(start 132.6642 -12.5222)
		(mid 132.438251 -12.88743)
		(end 132.3594 -13.3096)
		(width 0.1397)
		(layer "In2.Cu")
		(net "PCIE_RX_P80")
	)
	(arc
		(start 135.38454 -13.930122)
		(mid 135.536423 -13.900004)
		(end 135.66521 -13.814044)
		(width 0.1397)
		(layer "In2.Cu")
		(net "PCIE_RX_P80")
	)
	(arc
		(start 133.7818 -11.7856)
		(mid 133.649233 -11.795164)
		(end 133.519418 -11.8237)
		(width 0.1397)
		(layer "In2.Cu")
		(net "PCIE_RX_P80")
	)
	(arc
		(start 135.66521 -13.814044)
		(mid 135.775158 -13.649495)
		(end 135.8138 -13.455396)
		(width 0.1397)
		(layer "In2.Cu")
		(net "PCIE_RX_P80")
	)
	(arc
		(start 135.489188 -12.89939)
		(mid 135.474733 -12.889636)
		(end 135.459978 -12.88034)
		(width 0.1397)
		(layer "In2.Cu")
		(net "PCIE_RX_P80")
	)
	(arc
		(start 135.459978 -12.88034)
		(mid 135.392297 -12.845726)
		(end 135.320532 -12.82065)
		(width 0.1397)
		(layer "In2.Cu")
		(net "PCIE_RX_P80")
	)
	(arc
		(start 226.701604 -40.398446)
		(mid 226.731362 -40.470288)
		(end 226.803204 -40.500046)
		(width 0.1016)
		(layer "In2.Cu")
		(net "PCIE_RX_P80")
	)
	(arc
		(start 135.8138 -13.397738)
		(mid 135.780003 -13.22783)
		(end 135.683752 -13.083794)
		(width 0.1397)
		(layer "In2.Cu")
		(net "PCIE_RX_P80")
	)
	(arc
		(start 137.5664 -14.976348)
		(mid 138.406333 -15.109077)
		(end 139.164314 -15.494508)
		(width 0.1397)
		(layer "In2.Cu")
		(net "PCIE_RX_P80")
	)
	(arc
		(start 132.716016 -14.697964)
		(mid 133.098706 -14.904813)
		(end 133.5278 -14.976348)
		(width 0.1397)
		(layer "In2.Cu")
		(net "PCIE_RX_P80")
	)
	(arc
		(start 139.164314 -15.494508)
		(mid 139.298163 -15.602142)
		(end 139.4206 -15.7226)
		(width 0.1397)
		(layer "In2.Cu")
		(net "PCIE_RX_P80")
	)
	(arc
		(start 132.3594 -14.087856)
		(mid 132.396903 -14.302848)
		(end 132.504942 -14.492478)
		(width 0.1397)
		(layer "In2.Cu")
		(net "PCIE_RX_P80")
	)
	(arc
		(start 133.519418 -11.8237)
		(mid 133.312637 -11.914193)
		(end 133.1341 -12.0523)
		(width 0.1397)
		(layer "In2.Cu")
		(net "PCIE_RX_P80")
	)
	(arc
		(start 132.504942 -14.492478)
		(mid 132.604753 -14.601102)
		(end 132.716016 -14.697964)
		(width 0.1397)
		(layer "In2.Cu")
		(net "PCIE_RX_P80")
	)
	(segment
		(start 254.599948 -33.999932)
		(end 255.09982 -33.50006)
		(width 0.136652)
		(layer "F.Cu")
		(net "PCIE_RX_P8")
	)
	(via
		(at 255.09982 -33.50006)
		(size 0.4572)
		(drill 0.2032)
		(layers "F.Cu" "B.Cu")
		(net "PCIE_RX_P8")
	)
	(segment
		(start 294.440864 -29.11602)
		(end 292.9763 -29.409136)
		(width 0.1397)
		(layer "In2.Cu")
		(net "PCIE_RX_P8")
	)
	(segment
		(start 304.17897 -26.58491)
		(end 304.05705 -27.276806)
		(width 0.1397)
		(layer "In2.Cu")
		(net "PCIE_RX_P8")
	)
	(segment
		(start 303.011586 -28.276296)
		(end 300.750986 -28.674822)
		(width 0.1397)
		(layer "In2.Cu")
		(net "PCIE_RX_P8")
	)
	(segment
		(start 304.348134 -22.563074)
		(end 303.908968 -25.052528)
		(width 0.1397)
		(layer "In2.Cu")
		(net "PCIE_RX_P8")
	)
	(segment
		(start 303.908968 -25.052528)
		(end 304.17897 -26.58491)
		(width 0.1397)
		(layer "In2.Cu")
		(net "PCIE_RX_P8")
	)
	(segment
		(start 311.05729 -14.586204)
		(end 310.428894 -15.2146)
		(width 0.1397)
		(layer "In2.Cu")
		(net "PCIE_RX_P8")
	)
	(segment
		(start 304.05705 -27.276806)
		(end 303.689766 -27.80157)
		(width 0.1397)
		(layer "In2.Cu")
		(net "PCIE_RX_P8")
	)
	(segment
		(start 259.691378 -31.697422)
		(end 259.4864 -31.9024)
		(width 0.1016)
		(layer "In2.Cu")
		(net "PCIE_RX_P8")
	)
	(segment
		(start 279.290526 -29.438346)
		(end 275.112988 -30.100016)
		(width 0.1397)
		(layer "In2.Cu")
		(net "PCIE_RX_P8")
	)
	(segment
		(start 305.1048 -17.617694)
		(end 305.1048 -21.482304)
		(width 0.1397)
		(layer "In2.Cu")
		(net "PCIE_RX_P8")
	)
	(segment
		(start 284.537404 -28.60675)
		(end 279.290526 -29.438346)
		(width 0.1397)
		(layer "In2.Cu")
		(net "PCIE_RX_P8")
	)
	(segment
		(start 289.926014 -28.799028)
		(end 287.46577 -29.192474)
		(width 0.1397)
		(layer "In2.Cu")
		(net "PCIE_RX_P8")
	)
	(segment
		(start 310.428894 -15.2146)
		(end 307.507894 -15.2146)
		(width 0.1397)
		(layer "In2.Cu")
		(net "PCIE_RX_P8")
	)
	(segment
		(start 307.507894 -15.2146)
		(end 305.1048 -17.617694)
		(width 0.1397)
		(layer "In2.Cu")
		(net "PCIE_RX_P8")
	)
	(segment
		(start 296.70375 -28.263596)
		(end 295.904158 -28.823412)
		(width 0.1397)
		(layer "In2.Cu")
		(net "PCIE_RX_P8")
	)
	(segment
		(start 275.112988 -30.100016)
		(end 263.865868 -31.882588)
		(width 0.1397)
		(layer "In2.Cu")
		(net "PCIE_RX_P8")
	)
	(segment
		(start 303.689766 -27.80157)
		(end 303.011586 -28.276296)
		(width 0.1397)
		(layer "In2.Cu")
		(net "PCIE_RX_P8")
	)
	(segment
		(start 255.498092 -32.406082)
		(end 255.498092 -33.101788)
		(width 0.1016)
		(layer "In2.Cu")
		(net "PCIE_RX_P8")
	)
	(segment
		(start 310.310022 -13.750544)
		(end 310.310022 -13.577316)
		(width 0.1397)
		(layer "In2.Cu")
		(net "PCIE_RX_P8")
	)
	(segment
		(start 263.865868 -31.882588)
		(end 262.940038 -31.697422)
		(width 0.1397)
		(layer "In2.Cu")
		(net "PCIE_RX_P8")
	)
	(segment
		(start 310.887872 -13.463016)
		(end 310.927242 -13.502386)
		(width 0.1397)
		(layer "In2.Cu")
		(net "PCIE_RX_P8")
	)
	(segment
		(start 297.561 -28.112466)
		(end 296.70375 -28.263596)
		(width 0.1397)
		(layer "In2.Cu")
		(net "PCIE_RX_P8")
	)
	(segment
		(start 305.1048 -21.482304)
		(end 304.348134 -22.563074)
		(width 0.1397)
		(layer "In2.Cu")
		(net "PCIE_RX_P8")
	)
	(segment
		(start 310.526938 -13.3604)
		(end 310.640222 -13.3604)
		(width 0.1397)
		(layer "In2.Cu")
		(net "PCIE_RX_P8")
	)
	(segment
		(start 292.9763 -29.409136)
		(end 289.926014 -28.799028)
		(width 0.1397)
		(layer "In2.Cu")
		(net "PCIE_RX_P8")
	)
	(segment
		(start 287.46577 -29.192474)
		(end 284.537404 -28.60675)
		(width 0.1397)
		(layer "In2.Cu")
		(net "PCIE_RX_P8")
	)
	(segment
		(start 311.05729 -13.81633)
		(end 311.05729 -14.586204)
		(width 0.1397)
		(layer "In2.Cu")
		(net "PCIE_RX_P8")
	)
	(segment
		(start 262.940038 -31.697422)
		(end 259.691378 -31.697422)
		(width 0.1397)
		(layer "In2.Cu")
		(net "PCIE_RX_P8")
	)
	(segment
		(start 300.750986 -28.674822)
		(end 297.561 -28.112466)
		(width 0.1397)
		(layer "In2.Cu")
		(net "PCIE_RX_P8")
	)
	(segment
		(start 295.904158 -28.823412)
		(end 294.440864 -29.11602)
		(width 0.1397)
		(layer "In2.Cu")
		(net "PCIE_RX_P8")
	)
	(segment
		(start 259.4864 -31.9024)
		(end 256.001774 -31.9024)
		(width 0.1016)
		(layer "In2.Cu")
		(net "PCIE_RX_P8")
	)
	(arc
		(start 310.927242 -13.502386)
		(mid 311.023486 -13.646425)
		(end 311.05729 -13.81633)
		(width 0.1397)
		(layer "In2.Cu")
		(net "PCIE_RX_P8")
	)
	(arc
		(start 310.310022 -13.577316)
		(mid 310.373555 -13.423933)
		(end 310.526938 -13.3604)
		(width 0.1397)
		(layer "In2.Cu")
		(net "PCIE_RX_P8")
	)
	(arc
		(start 310.640222 -13.3604)
		(mid 310.774263 -13.387062)
		(end 310.887872 -13.463016)
		(width 0.1397)
		(layer "In2.Cu")
		(net "PCIE_RX_P8")
	)
	(arc
		(start 310.384444 -13.930122)
		(mid 310.329392 -13.847731)
		(end 310.310022 -13.750544)
		(width 0.1397)
		(layer "In2.Cu")
		(net "PCIE_RX_P8")
	)
	(arc
		(start 255.498092 -33.101788)
		(mid 255.381441 -33.383409)
		(end 255.09982 -33.50006)
		(width 0.1016)
		(layer "In2.Cu")
		(net "PCIE_RX_P8")
	)
	(arc
		(start 256.001774 -31.9024)
		(mid 255.645617 -32.049925)
		(end 255.498092 -32.406082)
		(width 0.1016)
		(layer "In2.Cu")
		(net "PCIE_RX_P8")
	)
	(segment
		(start 227.600002 -45.999908)
		(end 227.10013 -45.500036)
		(width 0.136652)
		(layer "F.Cu")
		(net "PCIE_RX_P76")
	)
	(via
		(at 227.10013 -45.500036)
		(size 0.4572)
		(drill 0.2032)
		(layers "F.Cu" "B.Cu")
		(net "PCIE_RX_P76")
	)
	(segment
		(start 212.941662 -45.3644)
		(end 212.396324 -45.3644)
		(width 0.136652)
		(layer "B.Cu")
		(net "PCIE_RX_P76")
	)
	(segment
		(start 226.3648 -46.106334)
		(end 224.644712 -46.106334)
		(width 0.1016)
		(layer "B.Cu")
		(net "PCIE_RX_P76")
	)
	(segment
		(start 223.267778 -45.085)
		(end 223.242378 -45.085)
		(width 0.1016)
		(layer "B.Cu")
		(net "PCIE_RX_P76")
	)
	(segment
		(start 223.318578 -45.0342)
		(end 223.267778 -45.085)
		(width 0.1016)
		(layer "B.Cu")
		(net "PCIE_RX_P76")
	)
	(segment
		(start 223.242378 -45.085)
		(end 213.616286 -45.085)
		(width 0.136652)
		(layer "B.Cu")
		(net "PCIE_RX_P76")
	)
	(segment
		(start 224.644712 -46.106334)
		(end 223.572578 -45.0342)
		(width 0.1016)
		(layer "B.Cu")
		(net "PCIE_RX_P76")
	)
	(segment
		(start 227.10013 -45.500036)
		(end 226.585018 -46.015148)
		(width 0.1016)
		(layer "B.Cu")
		(net "PCIE_RX_P76")
	)
	(segment
		(start 213.292436 -45.241972)
		(end 213.29269 -45.242226)
		(width 0.136652)
		(layer "B.Cu")
		(net "PCIE_RX_P76")
	)
	(segment
		(start 223.572578 -45.0342)
		(end 223.318578 -45.0342)
		(width 0.1016)
		(layer "B.Cu")
		(net "PCIE_RX_P76")
	)
	(arc
		(start 213.29269 -45.242226)
		(mid 213.127508 -45.332984)
		(end 212.941662 -45.3644)
		(width 0.136652)
		(layer "B.Cu")
		(net "PCIE_RX_P76")
	)
	(arc
		(start 213.616286 -45.085)
		(mid 213.566993 -45.0881)
		(end 213.518496 -45.097446)
		(width 0.136652)
		(layer "B.Cu")
		(net "PCIE_RX_P76")
	)
	(arc
		(start 212.396324 -45.3644)
		(mid 212.031235 -45.437021)
		(end 211.7217 -45.6438)
		(width 0.136652)
		(layer "B.Cu")
		(net "PCIE_RX_P76")
	)
	(arc
		(start 213.340696 -45.1993)
		(mid 213.317172 -45.221322)
		(end 213.292436 -45.241972)
		(width 0.136652)
		(layer "B.Cu")
		(net "PCIE_RX_P76")
	)
	(arc
		(start 226.585018 -46.015148)
		(mid 226.483981 -46.082659)
		(end 226.3648 -46.106334)
		(width 0.1016)
		(layer "B.Cu")
		(net "PCIE_RX_P76")
	)
	(arc
		(start 213.518496 -45.097446)
		(mid 213.422762 -45.136445)
		(end 213.340696 -45.1993)
		(width 0.136652)
		(layer "B.Cu")
		(net "PCIE_RX_P76")
	)
	(segment
		(start 226.600004 -46.999906)
		(end 226.100132 -46.500034)
		(width 0.136652)
		(layer "F.Cu")
		(net "PCIE_RX_P75")
	)
	(via
		(at 50.093372 -221.405704)
		(size 0.508)
		(drill 0.254)
		(layers "F.Cu" "B.Cu")
		(net "PCIE_RX_P75")
	)
	(via
		(at 226.100132 -46.500034)
		(size 0.4572)
		(drill 0.2032)
		(layers "F.Cu" "B.Cu")
		(net "PCIE_RX_P75")
	)
	(segment
		(start 50.347626 -224.187512)
		(end 50.347626 -223.596454)
		(width 0.136652)
		(layer "B.Cu")
		(net "PCIE_RX_P75")
	)
	(segment
		(start 50.23993 -224.375726)
		(end 50.29073 -224.324926)
		(width 0.136652)
		(layer "B.Cu")
		(net "PCIE_RX_P75")
	)
	(segment
		(start 50.347626 -223.596454)
		(end 50.347372 -223.5962)
		(width 0.136652)
		(layer "B.Cu")
		(net "PCIE_RX_P75")
	)
	(segment
		(start 50.347372 -223.5962)
		(end 50.347372 -222.01886)
		(width 0.136652)
		(layer "B.Cu")
		(net "PCIE_RX_P75")
	)
	(segment
		(start 50.099976 -225.92538)
		(end 50.099976 -224.713546)
		(width 0.136652)
		(layer "B.Cu")
		(net "PCIE_RX_P75")
	)
	(arc
		(start 50.099976 -224.713546)
		(mid 50.136344 -224.53071)
		(end 50.23993 -224.375726)
		(width 0.136652)
		(layer "B.Cu")
		(net "PCIE_RX_P75")
	)
	(arc
		(start 50.347372 -222.01886)
		(mid 50.281364 -221.687014)
		(end 50.093372 -221.405704)
		(width 0.136652)
		(layer "B.Cu")
		(net "PCIE_RX_P75")
	)
	(arc
		(start 50.29073 -224.324926)
		(mid 50.332856 -224.26188)
		(end 50.347626 -224.187512)
		(width 0.136652)
		(layer "B.Cu")
		(net "PCIE_RX_P75")
	)
	(segment
		(start 59.091576 -200.156064)
		(end 53.5178 -208.115916)
		(width 0.1397)
		(layer "In2.Cu")
		(net "PCIE_RX_P75")
	)
	(segment
		(start 82.252566 -193.559684)
		(end 75.744324 -192.412112)
		(width 0.1397)
		(layer "In2.Cu")
		(net "PCIE_RX_P75")
	)
	(segment
		(start 225.898202 -46.213522)
		(end 225.704908 -46.020228)
		(width 0.1016)
		(layer "In2.Cu")
		(net "PCIE_RX_P75")
	)
	(segment
		(start 88.16594 -192.517014)
		(end 82.252566 -193.559684)
		(width 0.1397)
		(layer "In2.Cu")
		(net "PCIE_RX_P75")
	)
	(segment
		(start 50.3174 -220.078808)
		(end 50.3174 -220.864938)
		(width 0.1397)
		(layer "In2.Cu")
		(net "PCIE_RX_P75")
	)
	(segment
		(start 221.452694 -45.8978)
		(end 218.556078 -45.8978)
		(width 0.1397)
		(layer "In2.Cu")
		(net "PCIE_RX_P75")
	)
	(segment
		(start 75.744324 -192.412112)
		(end 68.267834 -193.730372)
		(width 0.1397)
		(layer "In2.Cu")
		(net "PCIE_RX_P75")
	)
	(segment
		(start 221.59341 -45.757084)
		(end 221.452694 -45.8978)
		(width 0.1397)
		(layer "In2.Cu")
		(net "PCIE_RX_P75")
	)
	(segment
		(start 95.012764 -187.722764)
		(end 88.16594 -192.517014)
		(width 0.1397)
		(layer "In2.Cu")
		(net "PCIE_RX_P75")
	)
	(segment
		(start 218.556078 -45.8978)
		(end 216.241376 -46.305724)
		(width 0.1397)
		(layer "In2.Cu")
		(net "PCIE_RX_P75")
	)
	(segment
		(start 226.040442 -46.355508)
		(end 225.898202 -46.213522)
		(width 0.1016)
		(layer "In2.Cu")
		(net "PCIE_RX_P75")
	)
	(segment
		(start 204.794612 -62.673484)
		(end 204.362304 -65.12687)
		(width 0.1397)
		(layer "In2.Cu")
		(net "PCIE_RX_P75")
	)
	(segment
		(start 68.267834 -193.730372)
		(end 59.091576 -200.156064)
		(width 0.1397)
		(layer "In2.Cu")
		(net "PCIE_RX_P75")
	)
	(segment
		(start 205.678786 -57.660286)
		(end 205.019148 -61.400944)
		(width 0.1397)
		(layer "In2.Cu")
		(net "PCIE_RX_P75")
	)
	(segment
		(start 205.220316 -69.994526)
		(end 204.08646 -76.427076)
		(width 0.1397)
		(layer "In2.Cu")
		(net "PCIE_RX_P75")
	)
	(segment
		(start 224.5106 -45.757084)
		(end 221.59341 -45.757084)
		(width 0.1397)
		(layer "In2.Cu")
		(net "PCIE_RX_P75")
	)
	(segment
		(start 204.08646 -76.427076)
		(end 163.512246 -134.373366)
		(width 0.1397)
		(layer "In2.Cu")
		(net "PCIE_RX_P75")
	)
	(segment
		(start 204.362304 -65.12687)
		(end 205.220316 -69.994526)
		(width 0.1397)
		(layer "In2.Cu")
		(net "PCIE_RX_P75")
	)
	(segment
		(start 216.241376 -46.305724)
		(end 211.117434 -49.893474)
		(width 0.1397)
		(layer "In2.Cu")
		(net "PCIE_RX_P75")
	)
	(segment
		(start 53.5178 -208.115916)
		(end 53.5178 -215.00973)
		(width 0.1397)
		(layer "In2.Cu")
		(net "PCIE_RX_P75")
	)
	(segment
		(start 211.117434 -49.893474)
		(end 205.678786 -57.660286)
		(width 0.1397)
		(layer "In2.Cu")
		(net "PCIE_RX_P75")
	)
	(segment
		(start 163.512246 -134.373366)
		(end 102.410768 -177.157126)
		(width 0.1397)
		(layer "In2.Cu")
		(net "PCIE_RX_P75")
	)
	(segment
		(start 53.5178 -215.00973)
		(end 50.3174 -220.078808)
		(width 0.1397)
		(layer "In2.Cu")
		(net "PCIE_RX_P75")
	)
	(segment
		(start 102.410768 -177.157126)
		(end 95.012764 -187.722764)
		(width 0.1397)
		(layer "In2.Cu")
		(net "PCIE_RX_P75")
	)
	(segment
		(start 205.019148 -61.400944)
		(end 204.794612 -62.673484)
		(width 0.1397)
		(layer "In2.Cu")
		(net "PCIE_RX_P75")
	)
	(segment
		(start 225.3996 -45.893736)
		(end 224.840546 -45.893736)
		(width 0.1016)
		(layer "In2.Cu")
		(net "PCIE_RX_P75")
	)
	(arc
		(start 225.704908 -46.020228)
		(mid 225.670867 -45.989645)
		(end 225.633788 -45.962824)
		(width 0.1016)
		(layer "In2.Cu")
		(net "PCIE_RX_P75")
	)
	(arc
		(start 50.308256 -220.98254)
		(mid 50.234466 -221.21121)
		(end 50.093372 -221.405704)
		(width 0.1397)
		(layer "In2.Cu")
		(net "PCIE_RX_P75")
	)
	(arc
		(start 226.100132 -46.500034)
		(mid 226.08467 -46.42183)
		(end 226.040442 -46.355508)
		(width 0.1016)
		(layer "In2.Cu")
		(net "PCIE_RX_P75")
	)
	(arc
		(start 225.633788 -45.962824)
		(mid 225.521681 -45.911379)
		(end 225.3996 -45.893736)
		(width 0.1016)
		(layer "In2.Cu")
		(net "PCIE_RX_P75")
	)
	(arc
		(start 224.840546 -45.893736)
		(mid 224.661987 -45.858218)
		(end 224.5106 -45.757084)
		(width 0.1016)
		(layer "In2.Cu")
		(net "PCIE_RX_P75")
	)
	(arc
		(start 50.3174 -220.864938)
		(mid 50.315103 -220.923916)
		(end 50.308256 -220.98254)
		(width 0.1397)
		(layer "In2.Cu")
		(net "PCIE_RX_P75")
	)
	(segment
		(start 227.600002 -47.999904)
		(end 227.10013 -48.499776)
		(width 0.136652)
		(layer "F.Cu")
		(net "PCIE_RX_P74")
	)
	(via
		(at 227.10013 -48.499776)
		(size 0.4572)
		(drill 0.2032)
		(layers "F.Cu" "B.Cu")
		(net "PCIE_RX_P74")
	)
	(via
		(at 53.293518 -222.294704)
		(size 0.508)
		(drill 0.254)
		(layers "F.Cu" "B.Cu")
		(net "PCIE_RX_P74")
	)
	(segment
		(start 53.440076 -224.375726)
		(end 53.490876 -224.324926)
		(width 0.136652)
		(layer "B.Cu")
		(net "PCIE_RX_P74")
	)
	(segment
		(start 53.547772 -223.596454)
		(end 53.547518 -223.5962)
		(width 0.136652)
		(layer "B.Cu")
		(net "PCIE_RX_P74")
	)
	(segment
		(start 53.300122 -225.92538)
		(end 53.300122 -224.713546)
		(width 0.136652)
		(layer "B.Cu")
		(net "PCIE_RX_P74")
	)
	(segment
		(start 53.547518 -223.5962)
		(end 53.547518 -222.90786)
		(width 0.136652)
		(layer "B.Cu")
		(net "PCIE_RX_P74")
	)
	(segment
		(start 53.547772 -224.187512)
		(end 53.547772 -223.596454)
		(width 0.136652)
		(layer "B.Cu")
		(net "PCIE_RX_P74")
	)
	(arc
		(start 53.300122 -224.713546)
		(mid 53.33649 -224.53071)
		(end 53.440076 -224.375726)
		(width 0.136652)
		(layer "B.Cu")
		(net "PCIE_RX_P74")
	)
	(arc
		(start 53.490876 -224.324926)
		(mid 53.533002 -224.26188)
		(end 53.547772 -224.187512)
		(width 0.136652)
		(layer "B.Cu")
		(net "PCIE_RX_P74")
	)
	(arc
		(start 53.547518 -222.90786)
		(mid 53.48151 -222.576014)
		(end 53.293518 -222.294704)
		(width 0.136652)
		(layer "B.Cu")
		(net "PCIE_RX_P74")
	)
	(segment
		(start 100.473764 -182.388764)
		(end 95.908622 -188.90869)
		(width 0.1397)
		(layer "In2.Cu")
		(net "PCIE_RX_P74")
	)
	(segment
		(start 67.938396 -198.255382)
		(end 65.316862 -198.717408)
		(width 0.1397)
		(layer "In2.Cu")
		(net "PCIE_RX_P74")
	)
	(segment
		(start 80.220058 -195.975732)
		(end 75.820524 -195.200016)
		(width 0.1397)
		(layer "In2.Cu")
		(net "PCIE_RX_P74")
	)
	(segment
		(start 207.32623 -57.844944)
		(end 205.792832 -66.537586)
		(width 0.1397)
		(layer "In2.Cu")
		(net "PCIE_RX_P74")
	)
	(segment
		(start 226.968812 -48.182784)
		(end 226.968812 -48.082962)
		(width 0.1397)
		(layer "In2.Cu")
		(net "PCIE_RX_P74")
	)
	(segment
		(start 205.792832 -66.537586)
		(end 206.453486 -70.285102)
		(width 0.1397)
		(layer "In2.Cu")
		(net "PCIE_RX_P74")
	)
	(segment
		(start 87.699088 -194.656964)
		(end 80.220058 -195.975732)
		(width 0.1397)
		(layer "In2.Cu")
		(net "PCIE_RX_P74")
	)
	(segment
		(start 206.453486 -70.285102)
		(end 205.086458 -78.035912)
		(width 0.1397)
		(layer "In2.Cu")
		(net "PCIE_RX_P74")
	)
	(segment
		(start 53.534818 -219.998036)
		(end 53.534818 -221.712028)
		(width 0.1397)
		(layer "In2.Cu")
		(net "PCIE_RX_P74")
	)
	(segment
		(start 65.316862 -198.717408)
		(end 60.49264 -202.095608)
		(width 0.1397)
		(layer "In2.Cu")
		(net "PCIE_RX_P74")
	)
	(segment
		(start 71.11746 -196.029326)
		(end 67.938396 -198.255382)
		(width 0.1397)
		(layer "In2.Cu")
		(net "PCIE_RX_P74")
	)
	(segment
		(start 219.097098 -47.4218)
		(end 216.266522 -47.920656)
		(width 0.1397)
		(layer "In2.Cu")
		(net "PCIE_RX_P74")
	)
	(segment
		(start 60.49264 -202.095608)
		(end 56.718708 -207.485488)
		(width 0.1397)
		(layer "In2.Cu")
		(net "PCIE_RX_P74")
	)
	(segment
		(start 226.25558 -47.4218)
		(end 219.097098 -47.4218)
		(width 0.1397)
		(layer "In2.Cu")
		(net "PCIE_RX_P74")
	)
	(segment
		(start 226.7458 -47.625)
		(end 226.745546 -47.624746)
		(width 0.1397)
		(layer "In2.Cu")
		(net "PCIE_RX_P74")
	)
	(segment
		(start 75.820524 -195.200016)
		(end 71.11746 -196.029326)
		(width 0.1397)
		(layer "In2.Cu")
		(net "PCIE_RX_P74")
	)
	(segment
		(start 216.266522 -47.920656)
		(end 212.358732 -50.656998)
		(width 0.1397)
		(layer "In2.Cu")
		(net "PCIE_RX_P74")
	)
	(segment
		(start 95.908622 -188.90869)
		(end 87.699088 -194.656964)
		(width 0.1397)
		(layer "In2.Cu")
		(net "PCIE_RX_P74")
	)
	(segment
		(start 56.718708 -207.485488)
		(end 56.7182 -214.55761)
		(width 0.1397)
		(layer "In2.Cu")
		(net "PCIE_RX_P74")
	)
	(segment
		(start 205.086458 -78.035912)
		(end 162.36061 -139.055094)
		(width 0.1397)
		(layer "In2.Cu")
		(net "PCIE_RX_P74")
	)
	(segment
		(start 56.7182 -214.55761)
		(end 53.534818 -219.998036)
		(width 0.1397)
		(layer "In2.Cu")
		(net "PCIE_RX_P74")
	)
	(segment
		(start 212.358732 -50.656998)
		(end 207.32623 -57.844944)
		(width 0.1397)
		(layer "In2.Cu")
		(net "PCIE_RX_P74")
	)
	(segment
		(start 226.746054 -47.625)
		(end 226.7458 -47.625)
		(width 0.1397)
		(layer "In2.Cu")
		(net "PCIE_RX_P74")
	)
	(segment
		(start 162.36061 -139.055094)
		(end 100.473764 -182.388764)
		(width 0.1397)
		(layer "In2.Cu")
		(net "PCIE_RX_P74")
	)
	(arc
		(start 226.888802 -47.821088)
		(mid 226.825104 -47.717455)
		(end 226.746054 -47.625)
		(width 0.1397)
		(layer "In2.Cu")
		(net "PCIE_RX_P74")
	)
	(arc
		(start 53.534818 -221.712028)
		(mid 53.472097 -222.02735)
		(end 53.293518 -222.294704)
		(width 0.1397)
		(layer "In2.Cu")
		(net "PCIE_RX_P74")
	)
	(arc
		(start 226.968812 -48.082962)
		(mid 226.940402 -47.94848)
		(end 226.888802 -47.821088)
		(width 0.1397)
		(layer "In2.Cu")
		(net "PCIE_RX_P74")
	)
	(arc
		(start 227.10013 -48.499776)
		(mid 227.002952 -48.354339)
		(end 226.968812 -48.182784)
		(width 0.1397)
		(layer "In2.Cu")
		(net "PCIE_RX_P74")
	)
	(arc
		(start 226.745546 -47.624746)
		(mid 226.520748 -47.474541)
		(end 226.25558 -47.4218)
		(width 0.1397)
		(layer "In2.Cu")
		(net "PCIE_RX_P74")
	)
	(segment
		(start 226.600004 -48.999902)
		(end 226.100132 -49.499774)
		(width 0.136652)
		(layer "F.Cu")
		(net "PCIE_RX_P73")
	)
	(via
		(at 56.49341 -222.294704)
		(size 0.508)
		(drill 0.254)
		(layers "F.Cu" "B.Cu")
		(net "PCIE_RX_P73")
	)
	(via
		(at 226.100132 -49.499774)
		(size 0.4572)
		(drill 0.2032)
		(layers "F.Cu" "B.Cu")
		(net "PCIE_RX_P73")
	)
	(segment
		(start 56.747664 -224.187512)
		(end 56.747664 -223.596454)
		(width 0.136652)
		(layer "B.Cu")
		(net "PCIE_RX_P73")
	)
	(segment
		(start 56.639968 -224.375726)
		(end 56.690768 -224.324926)
		(width 0.136652)
		(layer "B.Cu")
		(net "PCIE_RX_P73")
	)
	(segment
		(start 56.74741 -223.5962)
		(end 56.74741 -222.90786)
		(width 0.136652)
		(layer "B.Cu")
		(net "PCIE_RX_P73")
	)
	(segment
		(start 56.500014 -225.92538)
		(end 56.500014 -224.713546)
		(width 0.136652)
		(layer "B.Cu")
		(net "PCIE_RX_P73")
	)
	(segment
		(start 56.747664 -223.596454)
		(end 56.74741 -223.5962)
		(width 0.136652)
		(layer "B.Cu")
		(net "PCIE_RX_P73")
	)
	(arc
		(start 56.690768 -224.324926)
		(mid 56.732894 -224.26188)
		(end 56.747664 -224.187512)
		(width 0.136652)
		(layer "B.Cu")
		(net "PCIE_RX_P73")
	)
	(arc
		(start 56.500014 -224.713546)
		(mid 56.536382 -224.53071)
		(end 56.639968 -224.375726)
		(width 0.136652)
		(layer "B.Cu")
		(net "PCIE_RX_P73")
	)
	(arc
		(start 56.74741 -222.90786)
		(mid 56.681402 -222.576014)
		(end 56.49341 -222.294704)
		(width 0.136652)
		(layer "B.Cu")
		(net "PCIE_RX_P73")
	)
	(segment
		(start 60.461398 -205.845918)
		(end 59.954922 -208.717134)
		(width 0.1397)
		(layer "In2.Cu")
		(net "PCIE_RX_P73")
	)
	(segment
		(start 221.346776 -48.8696)
		(end 218.988132 -48.8696)
		(width 0.1397)
		(layer "In2.Cu")
		(net "PCIE_RX_P73")
	)
	(segment
		(start 59.678062 -215.001602)
		(end 56.73471 -219.205556)
		(width 0.1397)
		(layer "In2.Cu")
		(net "PCIE_RX_P73")
	)
	(segment
		(start 217.547952 -49.123092)
		(end 212.611462 -52.579778)
		(width 0.1397)
		(layer "In2.Cu")
		(net "PCIE_RX_P73")
	)
	(segment
		(start 226.040442 -49.355248)
		(end 225.85807 -49.17313)
		(width 0.1016)
		(layer "In2.Cu")
		(net "PCIE_RX_P73")
	)
	(segment
		(start 221.370652 -48.893476)
		(end 221.346776 -48.8696)
		(width 0.1016)
		(layer "In2.Cu")
		(net "PCIE_RX_P73")
	)
	(segment
		(start 60.370466 -211.074)
		(end 59.678062 -215.001602)
		(width 0.1397)
		(layer "In2.Cu")
		(net "PCIE_RX_P73")
	)
	(segment
		(start 101.474016 -183.302148)
		(end 96.866964 -189.881764)
		(width 0.1397)
		(layer "In2.Cu")
		(net "PCIE_RX_P73")
	)
	(segment
		(start 209.313526 -62.277498)
		(end 210.613752 -69.651626)
		(width 0.1397)
		(layer "In2.Cu")
		(net "PCIE_RX_P73")
	)
	(segment
		(start 218.988132 -48.8696)
		(end 218.620594 -48.934116)
		(width 0.1397)
		(layer "In2.Cu")
		(net "PCIE_RX_P73")
	)
	(segment
		(start 63.084964 -202.099164)
		(end 60.461398 -205.845918)
		(width 0.1397)
		(layer "In2.Cu")
		(net "PCIE_RX_P73")
	)
	(segment
		(start 59.954922 -208.717134)
		(end 60.370466 -211.074)
		(width 0.1397)
		(layer "In2.Cu")
		(net "PCIE_RX_P73")
	)
	(segment
		(start 225.3996 -48.893476)
		(end 221.370652 -48.893476)
		(width 0.1016)
		(layer "In2.Cu")
		(net "PCIE_RX_P73")
	)
	(segment
		(start 225.85807 -49.17313)
		(end 225.704908 -49.019968)
		(width 0.1016)
		(layer "In2.Cu")
		(net "PCIE_RX_P73")
	)
	(segment
		(start 218.620594 -48.934116)
		(end 217.547952 -49.123092)
		(width 0.1397)
		(layer "In2.Cu")
		(net "PCIE_RX_P73")
	)
	(segment
		(start 209.471768 -76.118212)
		(end 166.111428 -138.042396)
		(width 0.1397)
		(layer "In2.Cu")
		(net "PCIE_RX_P73")
	)
	(segment
		(start 66.073782 -200.006458)
		(end 63.084964 -202.099164)
		(width 0.1397)
		(layer "In2.Cu")
		(net "PCIE_RX_P73")
	)
	(segment
		(start 210.489038 -55.61076)
		(end 209.313526 -62.277498)
		(width 0.1397)
		(layer "In2.Cu")
		(net "PCIE_RX_P73")
	)
	(segment
		(start 166.111428 -138.042396)
		(end 101.474016 -183.302148)
		(width 0.1397)
		(layer "In2.Cu")
		(net "PCIE_RX_P73")
	)
	(segment
		(start 212.611462 -52.579778)
		(end 210.489038 -55.61076)
		(width 0.1397)
		(layer "In2.Cu")
		(net "PCIE_RX_P73")
	)
	(segment
		(start 96.866964 -189.881764)
		(end 87.904828 -196.157088)
		(width 0.1397)
		(layer "In2.Cu")
		(net "PCIE_RX_P73")
	)
	(segment
		(start 56.73471 -219.205556)
		(end 56.73471 -221.712028)
		(width 0.1397)
		(layer "In2.Cu")
		(net "PCIE_RX_P73")
	)
	(segment
		(start 87.904828 -196.157088)
		(end 66.073782 -200.006458)
		(width 0.1397)
		(layer "In2.Cu")
		(net "PCIE_RX_P73")
	)
	(segment
		(start 210.613752 -69.651626)
		(end 209.471768 -76.118212)
		(width 0.1397)
		(layer "In2.Cu")
		(net "PCIE_RX_P73")
	)
	(arc
		(start 225.704908 -49.019968)
		(mid 225.670867 -48.989385)
		(end 225.633788 -48.962564)
		(width 0.1016)
		(layer "In2.Cu")
		(net "PCIE_RX_P73")
	)
	(arc
		(start 56.73471 -221.712028)
		(mid 56.671989 -222.02735)
		(end 56.49341 -222.294704)
		(width 0.1397)
		(layer "In2.Cu")
		(net "PCIE_RX_P73")
	)
	(arc
		(start 225.633788 -48.962564)
		(mid 225.521681 -48.911119)
		(end 225.3996 -48.893476)
		(width 0.1016)
		(layer "In2.Cu")
		(net "PCIE_RX_P73")
	)
	(arc
		(start 226.100132 -49.499774)
		(mid 226.08467 -49.42157)
		(end 226.040442 -49.355248)
		(width 0.1016)
		(layer "In2.Cu")
		(net "PCIE_RX_P73")
	)
	(segment
		(start 227.600002 -49.9999)
		(end 227.10013 -50.499772)
		(width 0.136652)
		(layer "F.Cu")
		(net "PCIE_RX_P72")
	)
	(via
		(at 59.693302 -222.294704)
		(size 0.508)
		(drill 0.254)
		(layers "F.Cu" "B.Cu")
		(net "PCIE_RX_P72")
	)
	(via
		(at 227.10013 -50.499772)
		(size 0.4572)
		(drill 0.2032)
		(layers "F.Cu" "B.Cu")
		(net "PCIE_RX_P72")
	)
	(segment
		(start 59.947556 -223.596454)
		(end 59.947302 -223.5962)
		(width 0.136652)
		(layer "B.Cu")
		(net "PCIE_RX_P72")
	)
	(segment
		(start 59.70016 -225.92538)
		(end 59.70016 -224.7138)
		(width 0.136652)
		(layer "B.Cu")
		(net "PCIE_RX_P72")
	)
	(segment
		(start 59.70016 -224.7138)
		(end 59.699906 -224.713546)
		(width 0.136652)
		(layer "B.Cu")
		(net "PCIE_RX_P72")
	)
	(segment
		(start 59.947556 -224.187512)
		(end 59.947556 -223.596454)
		(width 0.136652)
		(layer "B.Cu")
		(net "PCIE_RX_P72")
	)
	(segment
		(start 59.83986 -224.375726)
		(end 59.89066 -224.324926)
		(width 0.136652)
		(layer "B.Cu")
		(net "PCIE_RX_P72")
	)
	(segment
		(start 59.947302 -223.5962)
		(end 59.947302 -222.90786)
		(width 0.136652)
		(layer "B.Cu")
		(net "PCIE_RX_P72")
	)
	(arc
		(start 59.947302 -222.90786)
		(mid 59.881294 -222.576014)
		(end 59.693302 -222.294704)
		(width 0.136652)
		(layer "B.Cu")
		(net "PCIE_RX_P72")
	)
	(arc
		(start 59.89066 -224.324926)
		(mid 59.932786 -224.26188)
		(end 59.947556 -224.187512)
		(width 0.136652)
		(layer "B.Cu")
		(net "PCIE_RX_P72")
	)
	(arc
		(start 59.699906 -224.713546)
		(mid 59.736274 -224.53071)
		(end 59.83986 -224.375726)
		(width 0.136652)
		(layer "B.Cu")
		(net "PCIE_RX_P72")
	)
	(segment
		(start 221.641924 -49.8348)
		(end 219.871544 -49.8348)
		(width 0.1397)
		(layer "In2.Cu")
		(net "PCIE_RX_P72")
	)
	(segment
		(start 61.19622 -209.274156)
		(end 61.513466 -211.074)
		(width 0.1397)
		(layer "In2.Cu")
		(net "PCIE_RX_P72")
	)
	(segment
		(start 61.481716 -207.654144)
		(end 61.19622 -209.274156)
		(width 0.1397)
		(layer "In2.Cu")
		(net "PCIE_RX_P72")
	)
	(segment
		(start 211.110576 -71.29653)
		(end 211.680298 -74.52741)
		(width 0.1397)
		(layer "In2.Cu")
		(net "PCIE_RX_P72")
	)
	(segment
		(start 210.538314 -62.000638)
		(end 211.64423 -68.271898)
		(width 0.1397)
		(layer "In2.Cu")
		(net "PCIE_RX_P72")
	)
	(segment
		(start 218.249246 -50.120804)
		(end 213.336632 -53.560472)
		(width 0.1397)
		(layer "In2.Cu")
		(net "PCIE_RX_P72")
	)
	(segment
		(start 219.871544 -49.8348)
		(end 218.249246 -50.120804)
		(width 0.1397)
		(layer "In2.Cu")
		(net "PCIE_RX_P72")
	)
	(segment
		(start 63.592964 -204.639164)
		(end 61.481716 -207.654144)
		(width 0.1397)
		(layer "In2.Cu")
		(net "PCIE_RX_P72")
	)
	(segment
		(start 211.64423 -68.271898)
		(end 211.110576 -71.29653)
		(width 0.1397)
		(layer "In2.Cu")
		(net "PCIE_RX_P72")
	)
	(segment
		(start 211.421726 -75.99426)
		(end 165.276022 -141.899894)
		(width 0.1397)
		(layer "In2.Cu")
		(net "PCIE_RX_P72")
	)
	(segment
		(start 165.276022 -141.899894)
		(end 99.735386 -187.791344)
		(width 0.1397)
		(layer "In2.Cu")
		(net "PCIE_RX_P72")
	)
	(segment
		(start 227.04044 -50.355246)
		(end 226.704906 -50.019966)
		(width 0.1016)
		(layer "In2.Cu")
		(net "PCIE_RX_P72")
	)
	(segment
		(start 213.336632 -53.560472)
		(end 211.58581 -56.060848)
		(width 0.1397)
		(layer "In2.Cu")
		(net "PCIE_RX_P72")
	)
	(segment
		(start 88.520524 -197.21449)
		(end 69.375782 -200.589896)
		(width 0.1397)
		(layer "In2.Cu")
		(net "PCIE_RX_P72")
	)
	(segment
		(start 97.578164 -190.872364)
		(end 88.520524 -197.21449)
		(width 0.1397)
		(layer "In2.Cu")
		(net "PCIE_RX_P72")
	)
	(segment
		(start 226.399598 -49.893474)
		(end 221.783656 -49.893474)
		(width 0.1016)
		(layer "In2.Cu")
		(net "PCIE_RX_P72")
	)
	(segment
		(start 99.735386 -187.791344)
		(end 97.578164 -190.872364)
		(width 0.1397)
		(layer "In2.Cu")
		(net "PCIE_RX_P72")
	)
	(segment
		(start 59.934602 -220.029532)
		(end 59.934602 -221.712028)
		(width 0.1397)
		(layer "In2.Cu")
		(net "PCIE_RX_P72")
	)
	(segment
		(start 61.513466 -211.074)
		(end 59.934602 -220.029532)
		(width 0.1397)
		(layer "In2.Cu")
		(net "PCIE_RX_P72")
	)
	(segment
		(start 211.680298 -74.52741)
		(end 211.421726 -75.99426)
		(width 0.1397)
		(layer "In2.Cu")
		(net "PCIE_RX_P72")
	)
	(segment
		(start 69.375782 -200.589896)
		(end 63.592964 -204.639164)
		(width 0.1397)
		(layer "In2.Cu")
		(net "PCIE_RX_P72")
	)
	(segment
		(start 211.58581 -56.060848)
		(end 210.538314 -62.000638)
		(width 0.1397)
		(layer "In2.Cu")
		(net "PCIE_RX_P72")
	)
	(arc
		(start 227.10013 -50.499772)
		(mid 227.084668 -50.421568)
		(end 227.04044 -50.355246)
		(width 0.1016)
		(layer "In2.Cu")
		(net "PCIE_RX_P72")
	)
	(arc
		(start 221.783656 -49.893474)
		(mid 221.706964 -49.878219)
		(end 221.641924 -49.8348)
		(width 0.1016)
		(layer "In2.Cu")
		(net "PCIE_RX_P72")
	)
	(arc
		(start 226.633786 -49.962562)
		(mid 226.521679 -49.911117)
		(end 226.399598 -49.893474)
		(width 0.1016)
		(layer "In2.Cu")
		(net "PCIE_RX_P72")
	)
	(arc
		(start 59.934602 -221.712028)
		(mid 59.871881 -222.02735)
		(end 59.693302 -222.294704)
		(width 0.1397)
		(layer "In2.Cu")
		(net "PCIE_RX_P72")
	)
	(arc
		(start 226.704906 -50.019966)
		(mid 226.670865 -49.989383)
		(end 226.633786 -49.962562)
		(width 0.1016)
		(layer "In2.Cu")
		(net "PCIE_RX_P72")
	)
	(segment
		(start 226.600004 -51.999896)
		(end 226.100132 -52.499768)
		(width 0.136652)
		(layer "F.Cu")
		(net "PCIE_RX_P71")
	)
	(via
		(at 65.293494 -222.294704)
		(size 0.508)
		(drill 0.254)
		(layers "F.Cu" "B.Cu")
		(net "PCIE_RX_P71")
	)
	(via
		(at 226.100132 -52.499768)
		(size 0.4572)
		(drill 0.2032)
		(layers "F.Cu" "B.Cu")
		(net "PCIE_RX_P71")
	)
	(segment
		(start 65.440052 -224.375726)
		(end 65.490852 -224.324926)
		(width 0.136652)
		(layer "B.Cu")
		(net "PCIE_RX_P71")
	)
	(segment
		(start 65.547748 -224.187512)
		(end 65.547748 -223.596454)
		(width 0.136652)
		(layer "B.Cu")
		(net "PCIE_RX_P71")
	)
	(segment
		(start 65.547748 -223.596454)
		(end 65.547494 -223.5962)
		(width 0.136652)
		(layer "B.Cu")
		(net "PCIE_RX_P71")
	)
	(segment
		(start 65.300098 -225.92538)
		(end 65.300098 -224.713546)
		(width 0.136652)
		(layer "B.Cu")
		(net "PCIE_RX_P71")
	)
	(segment
		(start 65.547494 -223.5962)
		(end 65.547494 -222.90786)
		(width 0.136652)
		(layer "B.Cu")
		(net "PCIE_RX_P71")
	)
	(arc
		(start 65.547494 -222.90786)
		(mid 65.481486 -222.576014)
		(end 65.293494 -222.294704)
		(width 0.136652)
		(layer "B.Cu")
		(net "PCIE_RX_P71")
	)
	(arc
		(start 65.490852 -224.324926)
		(mid 65.532978 -224.26188)
		(end 65.547748 -224.187512)
		(width 0.136652)
		(layer "B.Cu")
		(net "PCIE_RX_P71")
	)
	(arc
		(start 65.300098 -224.713546)
		(mid 65.336466 -224.53071)
		(end 65.440052 -224.375726)
		(width 0.136652)
		(layer "B.Cu")
		(net "PCIE_RX_P71")
	)
	(segment
		(start 87.089488 -199.620886)
		(end 71.198232 -202.423522)
		(width 0.1397)
		(layer "In2.Cu")
		(net "PCIE_RX_P71")
	)
	(segment
		(start 66.437764 -205.756764)
		(end 65.5828 -206.977996)
		(width 0.1397)
		(layer "In2.Cu")
		(net "PCIE_RX_P71")
	)
	(segment
		(start 219.325444 -51.8414)
		(end 217.609166 -52.14366)
		(width 0.1397)
		(layer "In2.Cu")
		(net "PCIE_RX_P71")
	)
	(segment
		(start 225.3996 -51.89347)
		(end 221.63913 -51.89347)
		(width 0.1016)
		(layer "In2.Cu")
		(net "PCIE_RX_P71")
	)
	(segment
		(start 71.198232 -202.423522)
		(end 66.437764 -205.756764)
		(width 0.1397)
		(layer "In2.Cu")
		(net "PCIE_RX_P71")
	)
	(segment
		(start 97.991676 -191.98717)
		(end 87.089488 -199.620886)
		(width 0.1397)
		(layer "In2.Cu")
		(net "PCIE_RX_P71")
	)
	(segment
		(start 215.196166 -53.833268)
		(end 212.824314 -57.220612)
		(width 0.1397)
		(layer "In2.Cu")
		(net "PCIE_RX_P71")
	)
	(segment
		(start 99.735132 -189.497462)
		(end 99.734878 -189.497716)
		(width 0.1397)
		(layer "In2.Cu")
		(net "PCIE_RX_P71")
	)
	(segment
		(start 65.5828 -206.977996)
		(end 65.5828 -211.934044)
		(width 0.1397)
		(layer "In2.Cu")
		(net "PCIE_RX_P71")
	)
	(segment
		(start 213.027006 -74.434446)
		(end 213.027006 -74.87539)
		(width 0.1397)
		(layer "In2.Cu")
		(net "PCIE_RX_P71")
	)
	(segment
		(start 212.476588 -71.248778)
		(end 212.476588 -71.310754)
		(width 0.1397)
		(layer "In2.Cu")
		(net "PCIE_RX_P71")
	)
	(segment
		(start 213.085934 -67.792092)
		(end 212.476588 -71.248778)
		(width 0.1397)
		(layer "In2.Cu")
		(net "PCIE_RX_P71")
	)
	(segment
		(start 212.480906 -71.338186)
		(end 213.027006 -74.434446)
		(width 0.1397)
		(layer "In2.Cu")
		(net "PCIE_RX_P71")
	)
	(segment
		(start 213.027006 -74.87539)
		(end 212.415628 -78.341982)
		(width 0.1397)
		(layer "In2.Cu")
		(net "PCIE_RX_P71")
	)
	(segment
		(start 212.476588 -71.310754)
		(end 212.480906 -71.338186)
		(width 0.1397)
		(layer "In2.Cu")
		(net "PCIE_RX_P71")
	)
	(segment
		(start 168.104566 -141.624558)
		(end 99.735132 -189.497462)
		(width 0.1397)
		(layer "In2.Cu")
		(net "PCIE_RX_P71")
	)
	(segment
		(start 226.040442 -52.355242)
		(end 225.85807 -52.173124)
		(width 0.1016)
		(layer "In2.Cu")
		(net "PCIE_RX_P71")
	)
	(segment
		(start 221.5134 -51.8414)
		(end 219.325444 -51.8414)
		(width 0.1397)
		(layer "In2.Cu")
		(net "PCIE_RX_P71")
	)
	(segment
		(start 65.160398 -219.522294)
		(end 65.534794 -221.643956)
		(width 0.1397)
		(layer "In2.Cu")
		(net "PCIE_RX_P71")
	)
	(segment
		(start 65.822576 -215.76665)
		(end 65.160398 -219.522294)
		(width 0.1397)
		(layer "In2.Cu")
		(net "PCIE_RX_P71")
	)
	(segment
		(start 225.85807 -52.173124)
		(end 225.704908 -52.019962)
		(width 0.1016)
		(layer "In2.Cu")
		(net "PCIE_RX_P71")
	)
	(segment
		(start 65.364868 -213.169246)
		(end 65.822576 -215.76665)
		(width 0.1397)
		(layer "In2.Cu")
		(net "PCIE_RX_P71")
	)
	(segment
		(start 212.022944 -61.763656)
		(end 213.085934 -67.792092)
		(width 0.1397)
		(layer "In2.Cu")
		(net "PCIE_RX_P71")
	)
	(segment
		(start 212.415628 -78.341982)
		(end 168.104566 -141.624558)
		(width 0.1397)
		(layer "In2.Cu")
		(net "PCIE_RX_P71")
	)
	(segment
		(start 65.534794 -221.643956)
		(end 65.534794 -221.712028)
		(width 0.1397)
		(layer "In2.Cu")
		(net "PCIE_RX_P71")
	)
	(segment
		(start 212.824314 -57.220612)
		(end 212.022944 -61.763656)
		(width 0.1397)
		(layer "In2.Cu")
		(net "PCIE_RX_P71")
	)
	(segment
		(start 217.609166 -52.14366)
		(end 215.196166 -53.833268)
		(width 0.1397)
		(layer "In2.Cu")
		(net "PCIE_RX_P71")
	)
	(segment
		(start 99.734878 -189.497716)
		(end 97.991676 -191.98717)
		(width 0.1397)
		(layer "In2.Cu")
		(net "PCIE_RX_P71")
	)
	(segment
		(start 65.5828 -211.934044)
		(end 65.364868 -213.169246)
		(width 0.1397)
		(layer "In2.Cu")
		(net "PCIE_RX_P71")
	)
	(arc
		(start 225.633788 -51.962558)
		(mid 225.521681 -51.911113)
		(end 225.3996 -51.89347)
		(width 0.1016)
		(layer "In2.Cu")
		(net "PCIE_RX_P71")
	)
	(arc
		(start 221.63913 -51.89347)
		(mid 221.571089 -51.879936)
		(end 221.5134 -51.8414)
		(width 0.1016)
		(layer "In2.Cu")
		(net "PCIE_RX_P71")
	)
	(arc
		(start 65.534794 -221.712028)
		(mid 65.472073 -222.02735)
		(end 65.293494 -222.294704)
		(width 0.1397)
		(layer "In2.Cu")
		(net "PCIE_RX_P71")
	)
	(arc
		(start 225.704908 -52.019962)
		(mid 225.670867 -51.989379)
		(end 225.633788 -51.962558)
		(width 0.1016)
		(layer "In2.Cu")
		(net "PCIE_RX_P71")
	)
	(arc
		(start 226.100132 -52.499768)
		(mid 226.08467 -52.421564)
		(end 226.040442 -52.355242)
		(width 0.1016)
		(layer "In2.Cu")
		(net "PCIE_RX_P71")
	)
	(segment
		(start 227.600002 -52.999894)
		(end 227.10013 -53.499766)
		(width 0.136652)
		(layer "F.Cu")
		(net "PCIE_RX_P70")
	)
	(via
		(at 227.10013 -53.499766)
		(size 0.4572)
		(drill 0.2032)
		(layers "F.Cu" "B.Cu")
		(net "PCIE_RX_P70")
	)
	(via
		(at 68.493386 -222.294704)
		(size 0.508)
		(drill 0.254)
		(layers "F.Cu" "B.Cu")
		(net "PCIE_RX_P70")
	)
	(segment
		(start 68.74764 -224.187512)
		(end 68.74764 -223.596454)
		(width 0.136652)
		(layer "B.Cu")
		(net "PCIE_RX_P70")
	)
	(segment
		(start 68.49999 -225.92538)
		(end 68.49999 -224.713546)
		(width 0.136652)
		(layer "B.Cu")
		(net "PCIE_RX_P70")
	)
	(segment
		(start 68.747386 -223.5962)
		(end 68.747386 -222.90786)
		(width 0.136652)
		(layer "B.Cu")
		(net "PCIE_RX_P70")
	)
	(segment
		(start 68.639944 -224.375726)
		(end 68.690744 -224.324926)
		(width 0.136652)
		(layer "B.Cu")
		(net "PCIE_RX_P70")
	)
	(segment
		(start 68.74764 -223.596454)
		(end 68.747386 -223.5962)
		(width 0.136652)
		(layer "B.Cu")
		(net "PCIE_RX_P70")
	)
	(arc
		(start 68.49999 -224.713546)
		(mid 68.536358 -224.53071)
		(end 68.639944 -224.375726)
		(width 0.136652)
		(layer "B.Cu")
		(net "PCIE_RX_P70")
	)
	(arc
		(start 68.747386 -222.90786)
		(mid 68.681378 -222.576014)
		(end 68.493386 -222.294704)
		(width 0.136652)
		(layer "B.Cu")
		(net "PCIE_RX_P70")
	)
	(arc
		(start 68.690744 -224.324926)
		(mid 68.73287 -224.26188)
		(end 68.74764 -224.187512)
		(width 0.136652)
		(layer "B.Cu")
		(net "PCIE_RX_P70")
	)
	(segment
		(start 69.957696 -206.226664)
		(end 72.320404 -204.572108)
		(width 0.1397)
		(layer "In2.Cu")
		(net "PCIE_RX_P70")
	)
	(segment
		(start 100.564188 -190.135002)
		(end 168.93794 -142.25905)
		(width 0.1397)
		(layer "In2.Cu")
		(net "PCIE_RX_P70")
	)
	(segment
		(start 214.209884 -67.617594)
		(end 213.524846 -63.73241)
		(width 0.1397)
		(layer "In2.Cu")
		(net "PCIE_RX_P70")
	)
	(segment
		(start 68.7578 -214.700866)
		(end 68.7578 -209.013044)
		(width 0.1397)
		(layer "In2.Cu")
		(net "PCIE_RX_P70")
	)
	(segment
		(start 213.524846 -63.73241)
		(end 214.83193 -56.319166)
		(width 0.1397)
		(layer "In2.Cu")
		(net "PCIE_RX_P70")
	)
	(segment
		(start 213.322662 -78.87208)
		(end 214.208106 -73.850754)
		(width 0.1397)
		(layer "In2.Cu")
		(net "PCIE_RX_P70")
	)
	(segment
		(start 69.148198 -216.915746)
		(end 68.7578 -214.700866)
		(width 0.1397)
		(layer "In2.Cu")
		(net "PCIE_RX_P70")
	)
	(segment
		(start 87.577676 -201.882756)
		(end 96.917764 -195.342764)
		(width 0.1397)
		(layer "In2.Cu")
		(net "PCIE_RX_P70")
	)
	(segment
		(start 226.704906 -53.01996)
		(end 226.858068 -53.173122)
		(width 0.1016)
		(layer "In2.Cu")
		(net "PCIE_RX_P70")
	)
	(segment
		(start 68.7578 -209.013044)
		(end 69.010276 -207.579468)
		(width 0.1397)
		(layer "In2.Cu")
		(net "PCIE_RX_P70")
	)
	(segment
		(start 219.884244 -52.832)
		(end 221.742 -52.832)
		(width 0.1397)
		(layer "In2.Cu")
		(net "PCIE_RX_P70")
	)
	(segment
		(start 68.734686 -221.712028)
		(end 68.734686 -219.262452)
		(width 0.1397)
		(layer "In2.Cu")
		(net "PCIE_RX_P70")
	)
	(segment
		(start 215.979502 -54.680358)
		(end 218.194128 -53.129688)
		(width 0.1397)
		(layer "In2.Cu")
		(net "PCIE_RX_P70")
	)
	(segment
		(start 221.890336 -52.893468)
		(end 226.399598 -52.893468)
		(width 0.1016)
		(layer "In2.Cu")
		(net "PCIE_RX_P70")
	)
	(segment
		(start 218.194128 -53.129688)
		(end 219.884244 -52.832)
		(width 0.1397)
		(layer "In2.Cu")
		(net "PCIE_RX_P70")
	)
	(segment
		(start 226.858068 -53.173122)
		(end 227.04044 -53.35524)
		(width 0.1016)
		(layer "In2.Cu")
		(net "PCIE_RX_P70")
	)
	(segment
		(start 69.010276 -207.579468)
		(end 69.957696 -206.226664)
		(width 0.1397)
		(layer "In2.Cu")
		(net "PCIE_RX_P70")
	)
	(segment
		(start 72.320404 -204.572108)
		(end 87.577676 -201.882756)
		(width 0.1397)
		(layer "In2.Cu")
		(net "PCIE_RX_P70")
	)
	(segment
		(start 96.917764 -195.342764)
		(end 100.564188 -190.135002)
		(width 0.1397)
		(layer "In2.Cu")
		(net "PCIE_RX_P70")
	)
	(segment
		(start 214.208106 -73.850754)
		(end 213.659466 -70.739)
		(width 0.1397)
		(layer "In2.Cu")
		(net "PCIE_RX_P70")
	)
	(segment
		(start 68.734686 -219.262452)
		(end 69.148198 -216.915746)
		(width 0.1397)
		(layer "In2.Cu")
		(net "PCIE_RX_P70")
	)
	(segment
		(start 168.93794 -142.25905)
		(end 213.322662 -78.87208)
		(width 0.1397)
		(layer "In2.Cu")
		(net "PCIE_RX_P70")
	)
	(segment
		(start 213.659466 -70.739)
		(end 214.209884 -67.617594)
		(width 0.1397)
		(layer "In2.Cu")
		(net "PCIE_RX_P70")
	)
	(segment
		(start 214.83193 -56.319166)
		(end 215.979502 -54.680358)
		(width 0.1397)
		(layer "In2.Cu")
		(net "PCIE_RX_P70")
	)
	(arc
		(start 226.399598 -52.893468)
		(mid 226.521683 -52.911097)
		(end 226.633786 -52.962556)
		(width 0.1016)
		(layer "In2.Cu")
		(net "PCIE_RX_P70")
	)
	(arc
		(start 221.742 -52.832)
		(mid 221.810057 -52.877474)
		(end 221.890336 -52.893468)
		(width 0.1016)
		(layer "In2.Cu")
		(net "PCIE_RX_P70")
	)
	(arc
		(start 227.04044 -53.35524)
		(mid 227.084663 -53.421564)
		(end 227.10013 -53.499766)
		(width 0.1016)
		(layer "In2.Cu")
		(net "PCIE_RX_P70")
	)
	(arc
		(start 226.633786 -52.962556)
		(mid 226.670875 -52.989364)
		(end 226.704906 -53.01996)
		(width 0.1016)
		(layer "In2.Cu")
		(net "PCIE_RX_P70")
	)
	(arc
		(start 68.493386 -222.294704)
		(mid 68.672013 -222.02737)
		(end 68.734686 -221.712028)
		(width 0.1397)
		(layer "In2.Cu")
		(net "PCIE_RX_P70")
	)
	(segment
		(start 249.599958 -31.999936)
		(end 250.09983 -31.500064)
		(width 0.136652)
		(layer "F.Cu")
		(net "PCIE_RX_P7")
	)
	(via
		(at 250.09983 -31.500064)
		(size 0.4572)
		(drill 0.2032)
		(layers "F.Cu" "B.Cu")
		(net "PCIE_RX_P7")
	)
	(segment
		(start 297.797982 -22.530308)
		(end 296.927778 -23.139654)
		(width 0.1397)
		(layer "In2.Cu")
		(net "PCIE_RX_P7")
	)
	(segment
		(start 296.927778 -23.139654)
		(end 296.004742 -24.457914)
		(width 0.1397)
		(layer "In2.Cu")
		(net "PCIE_RX_P7")
	)
	(segment
		(start 302.410368 -14.068806)
		(end 303.67478 -15.333218)
		(width 0.1397)
		(layer "In2.Cu")
		(net "PCIE_RX_P7")
	)
	(segment
		(start 249.6312 -30.3022)
		(end 249.6312 -30.7848)
		(width 0.1397)
		(layer "In2.Cu")
		(net "PCIE_RX_P7")
	)
	(segment
		(start 303.932082 -20.9296)
		(end 303.313084 -21.81352)
		(width 0.1397)
		(layer "In2.Cu")
		(net "PCIE_RX_P7")
	)
	(segment
		(start 265.10615 -24.155908)
		(end 261.433818 -24.803862)
		(width 0.1397)
		(layer "In2.Cu")
		(net "PCIE_RX_P7")
	)
	(segment
		(start 294.348662 -27.955748)
		(end 292.674802 -28.250896)
		(width 0.1397)
		(layer "In2.Cu")
		(net "PCIE_RX_P7")
	)
	(segment
		(start 289.81527 -27.767026)
		(end 287.698688 -28.140152)
		(width 0.1397)
		(layer "In2.Cu")
		(net "PCIE_RX_P7")
	)
	(segment
		(start 296.004742 -24.457914)
		(end 295.601136 -26.746454)
		(width 0.1397)
		(layer "In2.Cu")
		(net "PCIE_RX_P7")
	)
	(segment
		(start 249.812556 -31.21279)
		(end 250.09983 -31.500064)
		(width 0.1397)
		(layer "In2.Cu")
		(net "PCIE_RX_P7")
	)
	(segment
		(start 287.698688 -28.140152)
		(end 265.10615 -24.155908)
		(width 0.1397)
		(layer "In2.Cu")
		(net "PCIE_RX_P7")
	)
	(segment
		(start 250.2408 -29.092652)
		(end 250.2408 -29.6926)
		(width 0.1397)
		(layer "In2.Cu")
		(net "PCIE_RX_P7")
	)
	(segment
		(start 295.144698 -27.398218)
		(end 294.348662 -27.955748)
		(width 0.1397)
		(layer "In2.Cu")
		(net "PCIE_RX_P7")
	)
	(segment
		(start 261.433818 -24.803862)
		(end 258.323334 -24.181816)
		(width 0.1397)
		(layer "In2.Cu")
		(net "PCIE_RX_P7")
	)
	(segment
		(start 289.86861 -27.756358)
		(end 289.81527 -27.767026)
		(width 0.1397)
		(layer "In2.Cu")
		(net "PCIE_RX_P7")
	)
	(segment
		(start 298.793662 -22.354794)
		(end 297.797982 -22.530308)
		(width 0.1397)
		(layer "In2.Cu")
		(net "PCIE_RX_P7")
	)
	(segment
		(start 295.601136 -26.746454)
		(end 295.144698 -27.398218)
		(width 0.1397)
		(layer "In2.Cu")
		(net "PCIE_RX_P7")
	)
	(segment
		(start 303.67478 -15.333218)
		(end 303.9872 -17.11833)
		(width 0.1397)
		(layer "In2.Cu")
		(net "PCIE_RX_P7")
	)
	(segment
		(start 303.9872 -17.11833)
		(end 303.9872 -20.754848)
		(width 0.1397)
		(layer "In2.Cu")
		(net "PCIE_RX_P7")
	)
	(segment
		(start 300.656244 -22.683216)
		(end 298.793662 -22.354794)
		(width 0.1397)
		(layer "In2.Cu")
		(net "PCIE_RX_P7")
	)
	(segment
		(start 258.323334 -24.181816)
		(end 254.543052 -24.7904)
		(width 0.1397)
		(layer "In2.Cu")
		(net "PCIE_RX_P7")
	)
	(segment
		(start 250.2408 -29.6926)
		(end 249.6312 -30.3022)
		(width 0.1397)
		(layer "In2.Cu")
		(net "PCIE_RX_P7")
	)
	(segment
		(start 302.54702 -22.349968)
		(end 300.656244 -22.683216)
		(width 0.1397)
		(layer "In2.Cu")
		(net "PCIE_RX_P7")
	)
	(segment
		(start 292.674802 -28.250896)
		(end 289.86861 -27.756358)
		(width 0.1397)
		(layer "In2.Cu")
		(net "PCIE_RX_P7")
	)
	(segment
		(start 303.313084 -21.81352)
		(end 302.54702 -22.349968)
		(width 0.1397)
		(layer "In2.Cu")
		(net "PCIE_RX_P7")
	)
	(segment
		(start 249.805698 -31.205678)
		(end 249.812556 -31.21279)
		(width 0.1397)
		(layer "In2.Cu")
		(net "PCIE_RX_P7")
	)
	(segment
		(start 254.543052 -24.7904)
		(end 250.2408 -29.092652)
		(width 0.1397)
		(layer "In2.Cu")
		(net "PCIE_RX_P7")
	)
	(arc
		(start 303.9872 -20.754848)
		(mid 303.973113 -20.84648)
		(end 303.932082 -20.9296)
		(width 0.1397)
		(layer "In2.Cu")
		(net "PCIE_RX_P7")
	)
	(arc
		(start 249.6312 -30.7848)
		(mid 249.676603 -31.012587)
		(end 249.805698 -31.205678)
		(width 0.1397)
		(layer "In2.Cu")
		(net "PCIE_RX_P7")
	)
	(arc
		(start 301.634398 -13.930122)
		(mid 302.044179 -13.877577)
		(end 302.410368 -14.068806)
		(width 0.1397)
		(layer "In2.Cu")
		(net "PCIE_RX_P7")
	)
	(segment
		(start 226.600004 -53.999892)
		(end 226.100132 -54.499764)
		(width 0.136652)
		(layer "F.Cu")
		(net "PCIE_RX_P69")
	)
	(via
		(at 226.100132 -54.499764)
		(size 0.4572)
		(drill 0.2032)
		(layers "F.Cu" "B.Cu")
		(net "PCIE_RX_P69")
	)
	(via
		(at 71.7042 -220.0148)
		(size 0.508)
		(drill 0.254)
		(layers "F.Cu" "B.Cu")
		(net "PCIE_RX_P69")
	)
	(segment
		(start 71.947532 -223.5962)
		(end 71.947532 -220.602302)
		(width 0.136652)
		(layer "B.Cu")
		(net "PCIE_RX_P69")
	)
	(segment
		(start 71.700136 -225.92538)
		(end 71.700136 -224.713546)
		(width 0.136652)
		(layer "B.Cu")
		(net "PCIE_RX_P69")
	)
	(segment
		(start 71.947786 -224.187512)
		(end 71.947786 -223.596454)
		(width 0.136652)
		(layer "B.Cu")
		(net "PCIE_RX_P69")
	)
	(segment
		(start 71.84009 -224.375726)
		(end 71.89089 -224.324926)
		(width 0.136652)
		(layer "B.Cu")
		(net "PCIE_RX_P69")
	)
	(segment
		(start 71.947786 -223.596454)
		(end 71.947532 -223.5962)
		(width 0.136652)
		(layer "B.Cu")
		(net "PCIE_RX_P69")
	)
	(arc
		(start 71.700136 -224.713546)
		(mid 71.736504 -224.53071)
		(end 71.84009 -224.375726)
		(width 0.136652)
		(layer "B.Cu")
		(net "PCIE_RX_P69")
	)
	(arc
		(start 71.89089 -224.324926)
		(mid 71.933016 -224.26188)
		(end 71.947786 -224.187512)
		(width 0.136652)
		(layer "B.Cu")
		(net "PCIE_RX_P69")
	)
	(arc
		(start 71.947532 -220.602302)
		(mid 71.884289 -220.284356)
		(end 71.7042 -220.0148)
		(width 0.136652)
		(layer "B.Cu")
		(net "PCIE_RX_P69")
	)
	(segment
		(start 72.05091 -217.233754)
		(end 71.876158 -216.244678)
		(width 0.1397)
		(layer "In2.Cu")
		(net "PCIE_RX_P69")
	)
	(segment
		(start 170.13936 -144.210786)
		(end 213.80577 -81.84896)
		(width 0.1397)
		(layer "In2.Cu")
		(net "PCIE_RX_P69")
	)
	(segment
		(start 71.9455 -217.832686)
		(end 72.05091 -217.233754)
		(width 0.1397)
		(layer "In2.Cu")
		(net "PCIE_RX_P69")
	)
	(segment
		(start 72.98944 -209.931762)
		(end 73.422764 -209.312764)
		(width 0.1397)
		(layer "In2.Cu")
		(net "PCIE_RX_P69")
	)
	(segment
		(start 71.9455 -219.432124)
		(end 71.9455 -217.832686)
		(width 0.1397)
		(layer "In2.Cu")
		(net "PCIE_RX_P69")
	)
	(segment
		(start 73.422764 -209.312764)
		(end 76.127356 -207.41894)
		(width 0.1397)
		(layer "In2.Cu")
		(net "PCIE_RX_P69")
	)
	(segment
		(start 214.8078 -63.412624)
		(end 215.94064 -56.98871)
		(width 0.1397)
		(layer "In2.Cu")
		(net "PCIE_RX_P69")
	)
	(segment
		(start 220.316044 -53.848)
		(end 221.5642 -53.848)
		(width 0.1397)
		(layer "In2.Cu")
		(net "PCIE_RX_P69")
	)
	(segment
		(start 218.801442 -54.114954)
		(end 220.316044 -53.848)
		(width 0.1397)
		(layer "In2.Cu")
		(net "PCIE_RX_P69")
	)
	(segment
		(start 215.32596 -73.230994)
		(end 214.931498 -70.993254)
		(width 0.1397)
		(layer "In2.Cu")
		(net "PCIE_RX_P69")
	)
	(segment
		(start 213.80577 -81.84896)
		(end 215.32596 -73.230994)
		(width 0.1397)
		(layer "In2.Cu")
		(net "PCIE_RX_P69")
	)
	(segment
		(start 215.94064 -56.98871)
		(end 217.136472 -55.280814)
		(width 0.1397)
		(layer "In2.Cu")
		(net "PCIE_RX_P69")
	)
	(segment
		(start 214.931498 -70.993254)
		(end 215.53805 -67.553586)
		(width 0.1397)
		(layer "In2.Cu")
		(net "PCIE_RX_P69")
	)
	(segment
		(start 84.134452 -206.007462)
		(end 97.926906 -196.350382)
		(width 0.1397)
		(layer "In2.Cu")
		(net "PCIE_RX_P69")
	)
	(segment
		(start 217.136472 -55.280814)
		(end 218.801442 -54.114954)
		(width 0.1397)
		(layer "In2.Cu")
		(net "PCIE_RX_P69")
	)
	(segment
		(start 221.673928 -53.893466)
		(end 225.3996 -53.893466)
		(width 0.1016)
		(layer "In2.Cu")
		(net "PCIE_RX_P69")
	)
	(segment
		(start 97.926906 -196.350382)
		(end 100.090986 -193.259202)
		(width 0.1397)
		(layer "In2.Cu")
		(net "PCIE_RX_P69")
	)
	(segment
		(start 71.876158 -216.244678)
		(end 72.98944 -209.931762)
		(width 0.1397)
		(layer "In2.Cu")
		(net "PCIE_RX_P69")
	)
	(segment
		(start 215.53805 -67.553586)
		(end 214.8078 -63.412624)
		(width 0.1397)
		(layer "In2.Cu")
		(net "PCIE_RX_P69")
	)
	(segment
		(start 76.127356 -207.41894)
		(end 84.134452 -206.007462)
		(width 0.1397)
		(layer "In2.Cu")
		(net "PCIE_RX_P69")
	)
	(segment
		(start 225.704908 -54.019958)
		(end 226.040442 -54.355238)
		(width 0.1016)
		(layer "In2.Cu")
		(net "PCIE_RX_P69")
	)
	(segment
		(start 100.090986 -193.259202)
		(end 170.13936 -144.210786)
		(width 0.1397)
		(layer "In2.Cu")
		(net "PCIE_RX_P69")
	)
	(arc
		(start 225.633788 -53.962554)
		(mid 225.670877 -53.989362)
		(end 225.704908 -54.019958)
		(width 0.1016)
		(layer "In2.Cu")
		(net "PCIE_RX_P69")
	)
	(arc
		(start 225.3996 -53.893466)
		(mid 225.521685 -53.911095)
		(end 225.633788 -53.962554)
		(width 0.1016)
		(layer "In2.Cu")
		(net "PCIE_RX_P69")
	)
	(arc
		(start 226.040442 -54.355238)
		(mid 226.084665 -54.421562)
		(end 226.100132 -54.499764)
		(width 0.1016)
		(layer "In2.Cu")
		(net "PCIE_RX_P69")
	)
	(arc
		(start 71.7042 -220.0148)
		(mid 71.882827 -219.747466)
		(end 71.9455 -219.432124)
		(width 0.1397)
		(layer "In2.Cu")
		(net "PCIE_RX_P69")
	)
	(arc
		(start 221.5642 -53.848)
		(mid 221.614544 -53.881639)
		(end 221.673928 -53.893466)
		(width 0.1016)
		(layer "In2.Cu")
		(net "PCIE_RX_P69")
	)
	(segment
		(start 227.600002 -54.99989)
		(end 227.10013 -55.499762)
		(width 0.136652)
		(layer "F.Cu")
		(net "PCIE_RX_P68")
	)
	(via
		(at 227.10013 -55.499762)
		(size 0.4572)
		(drill 0.2032)
		(layers "F.Cu" "B.Cu")
		(net "PCIE_RX_P68")
	)
	(via
		(at 78.16977 -219.881704)
		(size 0.508)
		(drill 0.254)
		(layers "F.Cu" "B.Cu")
		(net "PCIE_RX_P68")
	)
	(segment
		(start 78.240128 -224.375726)
		(end 78.290928 -224.324926)
		(width 0.136652)
		(layer "B.Cu")
		(net "PCIE_RX_P68")
	)
	(segment
		(start 78.34757 -223.5962)
		(end 78.34757 -220.310964)
		(width 0.136652)
		(layer "B.Cu")
		(net "PCIE_RX_P68")
	)
	(segment
		(start 78.100174 -225.92538)
		(end 78.100174 -224.713546)
		(width 0.136652)
		(layer "B.Cu")
		(net "PCIE_RX_P68")
	)
	(segment
		(start 78.347824 -223.596454)
		(end 78.34757 -223.5962)
		(width 0.136652)
		(layer "B.Cu")
		(net "PCIE_RX_P68")
	)
	(segment
		(start 78.347824 -224.187512)
		(end 78.347824 -223.596454)
		(width 0.136652)
		(layer "B.Cu")
		(net "PCIE_RX_P68")
	)
	(arc
		(start 78.34757 -220.310964)
		(mid 78.30136 -220.078652)
		(end 78.16977 -219.881704)
		(width 0.136652)
		(layer "B.Cu")
		(net "PCIE_RX_P68")
	)
	(arc
		(start 78.290928 -224.324926)
		(mid 78.333054 -224.26188)
		(end 78.347824 -224.187512)
		(width 0.136652)
		(layer "B.Cu")
		(net "PCIE_RX_P68")
	)
	(arc
		(start 78.100174 -224.713546)
		(mid 78.136542 -224.53071)
		(end 78.240128 -224.375726)
		(width 0.136652)
		(layer "B.Cu")
		(net "PCIE_RX_P68")
	)
	(segment
		(start 98.822764 -196.993764)
		(end 100.550726 -194.525646)
		(width 0.1397)
		(layer "In2.Cu")
		(net "PCIE_RX_P68")
	)
	(segment
		(start 100.550726 -194.525646)
		(end 170.887898 -145.277078)
		(width 0.1397)
		(layer "In2.Cu")
		(net "PCIE_RX_P68")
	)
	(segment
		(start 222.012002 -54.893464)
		(end 226.399598 -54.893464)
		(width 0.1016)
		(layer "In2.Cu")
		(net "PCIE_RX_P68")
	)
	(segment
		(start 78.41107 -219.299028)
		(end 78.41107 -216.870534)
		(width 0.1397)
		(layer "In2.Cu")
		(net "PCIE_RX_P68")
	)
	(segment
		(start 78.41107 -216.870534)
		(end 77.500734 -211.709)
		(width 0.1397)
		(layer "In2.Cu")
		(net "PCIE_RX_P68")
	)
	(segment
		(start 170.887898 -145.277078)
		(end 215.028526 -82.24012)
		(width 0.1397)
		(layer "In2.Cu")
		(net "PCIE_RX_P68")
	)
	(segment
		(start 216.050876 -72.009254)
		(end 216.834466 -67.564)
		(width 0.1397)
		(layer "In2.Cu")
		(net "PCIE_RX_P68")
	)
	(segment
		(start 216.600786 -58.260996)
		(end 218.280234 -55.862474)
		(width 0.1397)
		(layer "In2.Cu")
		(net "PCIE_RX_P68")
	)
	(segment
		(start 215.897206 -62.249304)
		(end 216.600786 -58.260996)
		(width 0.1397)
		(layer "In2.Cu")
		(net "PCIE_RX_P68")
	)
	(segment
		(start 216.442036 -74.227436)
		(end 216.050876 -72.009254)
		(width 0.1397)
		(layer "In2.Cu")
		(net "PCIE_RX_P68")
	)
	(segment
		(start 216.834466 -67.564)
		(end 215.897206 -62.249304)
		(width 0.1397)
		(layer "In2.Cu")
		(net "PCIE_RX_P68")
	)
	(segment
		(start 79.250286 -209.03438)
		(end 82.477102 -208.440528)
		(width 0.1397)
		(layer "In2.Cu")
		(net "PCIE_RX_P68")
	)
	(segment
		(start 226.704906 -55.019956)
		(end 227.04044 -55.355236)
		(width 0.1016)
		(layer "In2.Cu")
		(net "PCIE_RX_P68")
	)
	(segment
		(start 219.444062 -55.047388)
		(end 220.773244 -54.8132)
		(width 0.1397)
		(layer "In2.Cu")
		(net "PCIE_RX_P68")
	)
	(segment
		(start 77.500734 -211.709)
		(end 77.792326 -210.05546)
		(width 0.1397)
		(layer "In2.Cu")
		(net "PCIE_RX_P68")
	)
	(segment
		(start 77.792326 -210.05546)
		(end 79.250286 -209.03438)
		(width 0.1397)
		(layer "In2.Cu")
		(net "PCIE_RX_P68")
	)
	(segment
		(start 218.280234 -55.862474)
		(end 219.444062 -55.047388)
		(width 0.1397)
		(layer "In2.Cu")
		(net "PCIE_RX_P68")
	)
	(segment
		(start 220.773244 -54.8132)
		(end 221.8182 -54.8132)
		(width 0.1397)
		(layer "In2.Cu")
		(net "PCIE_RX_P68")
	)
	(segment
		(start 215.028526 -82.24012)
		(end 216.442036 -74.227436)
		(width 0.1397)
		(layer "In2.Cu")
		(net "PCIE_RX_P68")
	)
	(segment
		(start 82.477102 -208.440528)
		(end 98.822764 -196.993764)
		(width 0.1397)
		(layer "In2.Cu")
		(net "PCIE_RX_P68")
	)
	(arc
		(start 226.633786 -54.962552)
		(mid 226.670875 -54.98936)
		(end 226.704906 -55.019956)
		(width 0.1016)
		(layer "In2.Cu")
		(net "PCIE_RX_P68")
	)
	(arc
		(start 227.04044 -55.355236)
		(mid 227.084663 -55.42156)
		(end 227.10013 -55.499762)
		(width 0.1016)
		(layer "In2.Cu")
		(net "PCIE_RX_P68")
	)
	(arc
		(start 226.399598 -54.893464)
		(mid 226.521683 -54.911093)
		(end 226.633786 -54.962552)
		(width 0.1016)
		(layer "In2.Cu")
		(net "PCIE_RX_P68")
	)
	(arc
		(start 221.8182 -54.8132)
		(mid 221.907117 -54.872613)
		(end 222.012002 -54.893464)
		(width 0.1016)
		(layer "In2.Cu")
		(net "PCIE_RX_P68")
	)
	(arc
		(start 78.16977 -219.881704)
		(mid 78.348397 -219.61437)
		(end 78.41107 -219.299028)
		(width 0.1397)
		(layer "In2.Cu")
		(net "PCIE_RX_P68")
	)
	(segment
		(start 226.600004 -55.999888)
		(end 226.100132 -56.49976)
		(width 0.136652)
		(layer "F.Cu")
		(net "PCIE_RX_P67")
	)
	(via
		(at 226.100132 -56.49976)
		(size 0.4572)
		(drill 0.2032)
		(layers "F.Cu" "B.Cu")
		(net "PCIE_RX_P67")
	)
	(via
		(at 81.293462 -222.294704)
		(size 0.508)
		(drill 0.254)
		(layers "F.Cu" "B.Cu")
		(net "PCIE_RX_P67")
	)
	(segment
		(start 81.300066 -225.92538)
		(end 81.300066 -224.713546)
		(width 0.136652)
		(layer "B.Cu")
		(net "PCIE_RX_P67")
	)
	(segment
		(start 81.547716 -224.187512)
		(end 81.547716 -223.596454)
		(width 0.136652)
		(layer "B.Cu")
		(net "PCIE_RX_P67")
	)
	(segment
		(start 81.44002 -224.375726)
		(end 81.49082 -224.324926)
		(width 0.136652)
		(layer "B.Cu")
		(net "PCIE_RX_P67")
	)
	(segment
		(start 81.547462 -223.5962)
		(end 81.547462 -222.90786)
		(width 0.136652)
		(layer "B.Cu")
		(net "PCIE_RX_P67")
	)
	(segment
		(start 81.547716 -223.596454)
		(end 81.547462 -223.5962)
		(width 0.136652)
		(layer "B.Cu")
		(net "PCIE_RX_P67")
	)
	(arc
		(start 81.547462 -222.90786)
		(mid 81.481454 -222.576014)
		(end 81.293462 -222.294704)
		(width 0.136652)
		(layer "B.Cu")
		(net "PCIE_RX_P67")
	)
	(arc
		(start 81.49082 -224.324926)
		(mid 81.532946 -224.26188)
		(end 81.547716 -224.187512)
		(width 0.136652)
		(layer "B.Cu")
		(net "PCIE_RX_P67")
	)
	(arc
		(start 81.300066 -224.713546)
		(mid 81.336434 -224.53071)
		(end 81.44002 -224.375726)
		(width 0.136652)
		(layer "B.Cu")
		(net "PCIE_RX_P67")
	)
	(segment
		(start 84.216494 -215.648794)
		(end 84.7598 -212.569044)
		(width 0.1397)
		(layer "In2.Cu")
		(net "PCIE_RX_P67")
	)
	(segment
		(start 221.190058 -55.8292)
		(end 221.3864 -55.8292)
		(width 0.1397)
		(layer "In2.Cu")
		(net "PCIE_RX_P67")
	)
	(segment
		(start 216.231724 -83.000088)
		(end 217.935302 -73.345802)
		(width 0.1397)
		(layer "In2.Cu")
		(net "PCIE_RX_P67")
	)
	(segment
		(start 101.358446 -195.295266)
		(end 172.499528 -145.451322)
		(width 0.1397)
		(layer "In2.Cu")
		(net "PCIE_RX_P67")
	)
	(segment
		(start 221.744794 -55.893462)
		(end 225.3996 -55.893462)
		(width 0.1016)
		(layer "In2.Cu")
		(net "PCIE_RX_P67")
	)
	(segment
		(start 81.534762 -219.47886)
		(end 84.216494 -215.648794)
		(width 0.1397)
		(layer "In2.Cu")
		(net "PCIE_RX_P67")
	)
	(segment
		(start 81.534762 -221.712028)
		(end 81.534762 -219.47886)
		(width 0.1397)
		(layer "In2.Cu")
		(net "PCIE_RX_P67")
	)
	(segment
		(start 99.356926 -198.154036)
		(end 101.358446 -195.295266)
		(width 0.1397)
		(layer "In2.Cu")
		(net "PCIE_RX_P67")
	)
	(segment
		(start 172.499528 -145.451322)
		(end 216.231724 -83.000088)
		(width 0.1397)
		(layer "In2.Cu")
		(net "PCIE_RX_P67")
	)
	(segment
		(start 85.535008 -207.830166)
		(end 99.356926 -198.154036)
		(width 0.1397)
		(layer "In2.Cu")
		(net "PCIE_RX_P67")
	)
	(segment
		(start 217.935302 -73.345802)
		(end 217.442796 -70.482206)
		(width 0.1397)
		(layer "In2.Cu")
		(net "PCIE_RX_P67")
	)
	(segment
		(start 217.955114 -67.575176)
		(end 216.984072 -62.067948)
		(width 0.1397)
		(layer "In2.Cu")
		(net "PCIE_RX_P67")
	)
	(segment
		(start 225.704908 -56.019954)
		(end 226.040442 -56.355234)
		(width 0.1016)
		(layer "In2.Cu")
		(net "PCIE_RX_P67")
	)
	(segment
		(start 217.442796 -70.482206)
		(end 217.955114 -67.575176)
		(width 0.1397)
		(layer "In2.Cu")
		(net "PCIE_RX_P67")
	)
	(segment
		(start 220.094048 -56.02224)
		(end 221.190058 -55.8292)
		(width 0.1397)
		(layer "In2.Cu")
		(net "PCIE_RX_P67")
	)
	(segment
		(start 217.587576 -58.646314)
		(end 218.781376 -56.941466)
		(width 0.1397)
		(layer "In2.Cu")
		(net "PCIE_RX_P67")
	)
	(segment
		(start 84.7598 -212.569044)
		(end 84.7598 -208.93786)
		(width 0.1397)
		(layer "In2.Cu")
		(net "PCIE_RX_P67")
	)
	(segment
		(start 218.781376 -56.941466)
		(end 220.094048 -56.02224)
		(width 0.1397)
		(layer "In2.Cu")
		(net "PCIE_RX_P67")
	)
	(segment
		(start 216.984072 -62.067948)
		(end 217.587576 -58.646314)
		(width 0.1397)
		(layer "In2.Cu")
		(net "PCIE_RX_P67")
	)
	(segment
		(start 84.7598 -208.93786)
		(end 85.535008 -207.830166)
		(width 0.1397)
		(layer "In2.Cu")
		(net "PCIE_RX_P67")
	)
	(arc
		(start 225.3996 -55.893462)
		(mid 225.521685 -55.911091)
		(end 225.633788 -55.96255)
		(width 0.1016)
		(layer "In2.Cu")
		(net "PCIE_RX_P67")
	)
	(arc
		(start 81.293462 -222.294704)
		(mid 81.472089 -222.02737)
		(end 81.534762 -221.712028)
		(width 0.1397)
		(layer "In2.Cu")
		(net "PCIE_RX_P67")
	)
	(arc
		(start 226.040442 -56.355234)
		(mid 226.084665 -56.421558)
		(end 226.100132 -56.49976)
		(width 0.1016)
		(layer "In2.Cu")
		(net "PCIE_RX_P67")
	)
	(arc
		(start 225.633788 -55.96255)
		(mid 225.670877 -55.989358)
		(end 225.704908 -56.019954)
		(width 0.1016)
		(layer "In2.Cu")
		(net "PCIE_RX_P67")
	)
	(arc
		(start 221.3864 -55.8292)
		(mid 221.562739 -55.877271)
		(end 221.744794 -55.893462)
		(width 0.1016)
		(layer "In2.Cu")
		(net "PCIE_RX_P67")
	)
	(segment
		(start 227.600002 -56.999886)
		(end 227.10013 -57.499758)
		(width 0.136652)
		(layer "F.Cu")
		(net "PCIE_RX_P66")
	)
	(via
		(at 227.10013 -57.499758)
		(size 0.4572)
		(drill 0.2032)
		(layers "F.Cu" "B.Cu")
		(net "PCIE_RX_P66")
	)
	(via
		(at 84.493354 -222.294704)
		(size 0.508)
		(drill 0.254)
		(layers "F.Cu" "B.Cu")
		(net "PCIE_RX_P66")
	)
	(segment
		(start 84.747354 -223.5962)
		(end 84.747354 -222.90786)
		(width 0.136652)
		(layer "B.Cu")
		(net "PCIE_RX_P66")
	)
	(segment
		(start 84.639912 -224.375726)
		(end 84.690712 -224.324926)
		(width 0.136652)
		(layer "B.Cu")
		(net "PCIE_RX_P66")
	)
	(segment
		(start 84.747608 -223.596454)
		(end 84.747354 -223.5962)
		(width 0.136652)
		(layer "B.Cu")
		(net "PCIE_RX_P66")
	)
	(segment
		(start 84.747608 -224.187512)
		(end 84.747608 -223.596454)
		(width 0.136652)
		(layer "B.Cu")
		(net "PCIE_RX_P66")
	)
	(segment
		(start 84.499958 -225.92538)
		(end 84.499958 -224.713546)
		(width 0.136652)
		(layer "B.Cu")
		(net "PCIE_RX_P66")
	)
	(arc
		(start 84.690712 -224.324926)
		(mid 84.732838 -224.26188)
		(end 84.747608 -224.187512)
		(width 0.136652)
		(layer "B.Cu")
		(net "PCIE_RX_P66")
	)
	(arc
		(start 84.747354 -222.90786)
		(mid 84.681346 -222.576014)
		(end 84.493354 -222.294704)
		(width 0.136652)
		(layer "B.Cu")
		(net "PCIE_RX_P66")
	)
	(arc
		(start 84.499958 -224.713546)
		(mid 84.536326 -224.53071)
		(end 84.639912 -224.375726)
		(width 0.136652)
		(layer "B.Cu")
		(net "PCIE_RX_P66")
	)
	(segment
		(start 227.04044 -57.355232)
		(end 226.704906 -57.019952)
		(width 0.1016)
		(layer "In2.Cu")
		(net "PCIE_RX_P66")
	)
	(segment
		(start 219.586048 -67.20459)
		(end 218.91117 -71.032116)
		(width 0.1397)
		(layer "In2.Cu")
		(net "PCIE_RX_P66")
	)
	(segment
		(start 88.96223 -206.6925)
		(end 87.927434 -208.17078)
		(width 0.1397)
		(layer "In2.Cu")
		(net "PCIE_RX_P66")
	)
	(segment
		(start 221.4118 -56.8706)
		(end 219.05087 -59.23153)
		(width 0.1397)
		(layer "In2.Cu")
		(net "PCIE_RX_P66")
	)
	(segment
		(start 84.734654 -220.457776)
		(end 84.734654 -221.712028)
		(width 0.1397)
		(layer "In2.Cu")
		(net "PCIE_RX_P66")
	)
	(segment
		(start 85.009482 -218.898724)
		(end 84.734654 -220.457776)
		(width 0.1397)
		(layer "In2.Cu")
		(net "PCIE_RX_P66")
	)
	(segment
		(start 217.779854 -82.229706)
		(end 172.350684 -147.110196)
		(width 0.1397)
		(layer "In2.Cu")
		(net "PCIE_RX_P66")
	)
	(segment
		(start 172.350684 -147.110196)
		(end 101.730302 -196.560186)
		(width 0.1397)
		(layer "In2.Cu")
		(net "PCIE_RX_P66")
	)
	(segment
		(start 101.730302 -196.560186)
		(end 100.092764 -198.898764)
		(width 0.1397)
		(layer "In2.Cu")
		(net "PCIE_RX_P66")
	)
	(segment
		(start 100.092764 -198.898764)
		(end 88.96223 -206.6925)
		(width 0.1397)
		(layer "In2.Cu")
		(net "PCIE_RX_P66")
	)
	(segment
		(start 219.332556 -73.423272)
		(end 217.779854 -82.229706)
		(width 0.1397)
		(layer "In2.Cu")
		(net "PCIE_RX_P66")
	)
	(segment
		(start 218.91117 -71.032116)
		(end 219.332556 -73.423272)
		(width 0.1397)
		(layer "In2.Cu")
		(net "PCIE_RX_P66")
	)
	(segment
		(start 221.8182 -56.8706)
		(end 221.4118 -56.8706)
		(width 0.1397)
		(layer "In2.Cu")
		(net "PCIE_RX_P66")
	)
	(segment
		(start 221.84106 -56.89346)
		(end 221.8182 -56.8706)
		(width 0.1016)
		(layer "In2.Cu")
		(net "PCIE_RX_P66")
	)
	(segment
		(start 226.399598 -56.89346)
		(end 221.84106 -56.89346)
		(width 0.1016)
		(layer "In2.Cu")
		(net "PCIE_RX_P66")
	)
	(segment
		(start 219.05087 -59.23153)
		(end 218.615768 -61.700156)
		(width 0.1397)
		(layer "In2.Cu")
		(net "PCIE_RX_P66")
	)
	(segment
		(start 87.927434 -208.17078)
		(end 87.927434 -213.458044)
		(width 0.1397)
		(layer "In2.Cu")
		(net "PCIE_RX_P66")
	)
	(segment
		(start 87.927434 -213.458044)
		(end 87.627206 -215.160098)
		(width 0.1397)
		(layer "In2.Cu")
		(net "PCIE_RX_P66")
	)
	(segment
		(start 87.627206 -215.160098)
		(end 85.009482 -218.898724)
		(width 0.1397)
		(layer "In2.Cu")
		(net "PCIE_RX_P66")
	)
	(segment
		(start 218.615768 -61.700156)
		(end 219.586048 -67.20459)
		(width 0.1397)
		(layer "In2.Cu")
		(net "PCIE_RX_P66")
	)
	(arc
		(start 84.734654 -221.712028)
		(mid 84.671933 -222.02735)
		(end 84.493354 -222.294704)
		(width 0.1397)
		(layer "In2.Cu")
		(net "PCIE_RX_P66")
	)
	(arc
		(start 226.704906 -57.019952)
		(mid 226.670865 -56.989369)
		(end 226.633786 -56.962548)
		(width 0.1016)
		(layer "In2.Cu")
		(net "PCIE_RX_P66")
	)
	(arc
		(start 226.633786 -56.962548)
		(mid 226.521679 -56.911103)
		(end 226.399598 -56.89346)
		(width 0.1016)
		(layer "In2.Cu")
		(net "PCIE_RX_P66")
	)
	(arc
		(start 227.10013 -57.499758)
		(mid 227.084668 -57.421554)
		(end 227.04044 -57.355232)
		(width 0.1016)
		(layer "In2.Cu")
		(net "PCIE_RX_P66")
	)
	(segment
		(start 226.600004 -57.999884)
		(end 226.100132 -58.499756)
		(width 0.136652)
		(layer "F.Cu")
		(net "PCIE_RX_P65")
	)
	(via
		(at 226.100132 -58.499756)
		(size 0.4572)
		(drill 0.2032)
		(layers "F.Cu" "B.Cu")
		(net "PCIE_RX_P65")
	)
	(via
		(at 87.6935 -222.294704)
		(size 0.508)
		(drill 0.254)
		(layers "F.Cu" "B.Cu")
		(net "PCIE_RX_P65")
	)
	(segment
		(start 87.947754 -224.187512)
		(end 87.947754 -223.596454)
		(width 0.136652)
		(layer "B.Cu")
		(net "PCIE_RX_P65")
	)
	(segment
		(start 87.9475 -223.5962)
		(end 87.9475 -222.90786)
		(width 0.136652)
		(layer "B.Cu")
		(net "PCIE_RX_P65")
	)
	(segment
		(start 87.840058 -224.375726)
		(end 87.890858 -224.324926)
		(width 0.136652)
		(layer "B.Cu")
		(net "PCIE_RX_P65")
	)
	(segment
		(start 87.947754 -223.596454)
		(end 87.9475 -223.5962)
		(width 0.136652)
		(layer "B.Cu")
		(net "PCIE_RX_P65")
	)
	(segment
		(start 87.700104 -225.92538)
		(end 87.700104 -224.713546)
		(width 0.136652)
		(layer "B.Cu")
		(net "PCIE_RX_P65")
	)
	(arc
		(start 87.700104 -224.713546)
		(mid 87.736472 -224.53071)
		(end 87.840058 -224.375726)
		(width 0.136652)
		(layer "B.Cu")
		(net "PCIE_RX_P65")
	)
	(arc
		(start 87.9475 -222.90786)
		(mid 87.881492 -222.576014)
		(end 87.6935 -222.294704)
		(width 0.136652)
		(layer "B.Cu")
		(net "PCIE_RX_P65")
	)
	(arc
		(start 87.890858 -224.324926)
		(mid 87.932984 -224.26188)
		(end 87.947754 -224.187512)
		(width 0.136652)
		(layer "B.Cu")
		(net "PCIE_RX_P65")
	)
	(segment
		(start 87.9348 -221.712028)
		(end 87.9348 -221.259654)
		(width 0.1397)
		(layer "In2.Cu")
		(net "PCIE_RX_P65")
	)
	(segment
		(start 87.9348 -221.259654)
		(end 88.313768 -219.109544)
		(width 0.1397)
		(layer "In2.Cu")
		(net "PCIE_RX_P65")
	)
	(segment
		(start 221.894146 -57.893458)
		(end 225.3996 -57.893458)
		(width 0.1016)
		(layer "In2.Cu")
		(net "PCIE_RX_P65")
	)
	(segment
		(start 219.657422 -62.511432)
		(end 220.222826 -59.30392)
		(width 0.1397)
		(layer "In2.Cu")
		(net "PCIE_RX_P65")
	)
	(segment
		(start 220.222826 -59.30392)
		(end 221.448884 -58.077862)
		(width 0.1397)
		(layer "In2.Cu")
		(net "PCIE_RX_P65")
	)
	(segment
		(start 102.565708 -197.688708)
		(end 172.43171 -148.767292)
		(width 0.1397)
		(layer "In2.Cu")
		(net "PCIE_RX_P65")
	)
	(segment
		(start 90.778584 -215.589358)
		(end 91.1098 -213.712044)
		(width 0.1397)
		(layer "In2.Cu")
		(net "PCIE_RX_P65")
	)
	(segment
		(start 101.10343 -199.777096)
		(end 102.565708 -197.688708)
		(width 0.1397)
		(layer "In2.Cu")
		(net "PCIE_RX_P65")
	)
	(segment
		(start 218.949524 -82.333846)
		(end 220.491812 -73.584816)
		(width 0.1397)
		(layer "In2.Cu")
		(net "PCIE_RX_P65")
	)
	(segment
		(start 225.704908 -58.01995)
		(end 226.040442 -58.35523)
		(width 0.1016)
		(layer "In2.Cu")
		(net "PCIE_RX_P65")
	)
	(segment
		(start 88.313768 -219.109544)
		(end 90.778584 -215.589358)
		(width 0.1397)
		(layer "In2.Cu")
		(net "PCIE_RX_P65")
	)
	(segment
		(start 92.685362 -205.671674)
		(end 101.10343 -199.777096)
		(width 0.1397)
		(layer "In2.Cu")
		(net "PCIE_RX_P65")
	)
	(segment
		(start 220.491812 -73.584816)
		(end 219.898722 -70.044056)
		(width 0.1397)
		(layer "In2.Cu")
		(net "PCIE_RX_P65")
	)
	(segment
		(start 220.483176 -67.121786)
		(end 219.657422 -62.988952)
		(width 0.1397)
		(layer "In2.Cu")
		(net "PCIE_RX_P65")
	)
	(segment
		(start 91.1098 -213.712044)
		(end 91.1098 -207.92186)
		(width 0.1397)
		(layer "In2.Cu")
		(net "PCIE_RX_P65")
	)
	(segment
		(start 91.1098 -207.92186)
		(end 92.685362 -205.671674)
		(width 0.1397)
		(layer "In2.Cu")
		(net "PCIE_RX_P65")
	)
	(segment
		(start 219.657422 -62.988952)
		(end 219.657422 -62.511432)
		(width 0.1397)
		(layer "In2.Cu")
		(net "PCIE_RX_P65")
	)
	(segment
		(start 219.898722 -70.044056)
		(end 220.483176 -67.121786)
		(width 0.1397)
		(layer "In2.Cu")
		(net "PCIE_RX_P65")
	)
	(segment
		(start 172.43171 -148.767292)
		(end 218.949524 -82.333846)
		(width 0.1397)
		(layer "In2.Cu")
		(net "PCIE_RX_P65")
	)
	(arc
		(start 225.3996 -57.893458)
		(mid 225.521685 -57.911087)
		(end 225.633788 -57.962546)
		(width 0.1016)
		(layer "In2.Cu")
		(net "PCIE_RX_P65")
	)
	(arc
		(start 225.633788 -57.962546)
		(mid 225.670877 -57.989354)
		(end 225.704908 -58.01995)
		(width 0.1016)
		(layer "In2.Cu")
		(net "PCIE_RX_P65")
	)
	(arc
		(start 226.040442 -58.35523)
		(mid 226.084665 -58.421554)
		(end 226.100132 -58.499756)
		(width 0.1016)
		(layer "In2.Cu")
		(net "PCIE_RX_P65")
	)
	(arc
		(start 87.6935 -222.294704)
		(mid 87.872127 -222.02737)
		(end 87.9348 -221.712028)
		(width 0.1397)
		(layer "In2.Cu")
		(net "PCIE_RX_P65")
	)
	(arc
		(start 221.448884 -58.077862)
		(mid 221.653172 -57.941361)
		(end 221.894146 -57.893458)
		(width 0.1016)
		(layer "In2.Cu")
		(net "PCIE_RX_P65")
	)
	(segment
		(start 227.600002 -58.999882)
		(end 227.10013 -59.499754)
		(width 0.136652)
		(layer "F.Cu")
		(net "PCIE_RX_P64")
	)
	(via
		(at 90.893392 -222.294704)
		(size 0.508)
		(drill 0.254)
		(layers "F.Cu" "B.Cu")
		(net "PCIE_RX_P64")
	)
	(via
		(at 227.10013 -59.499754)
		(size 0.4572)
		(drill 0.2032)
		(layers "F.Cu" "B.Cu")
		(net "PCIE_RX_P64")
	)
	(segment
		(start 91.03995 -224.375726)
		(end 91.09075 -224.324926)
		(width 0.136652)
		(layer "B.Cu")
		(net "PCIE_RX_P64")
	)
	(segment
		(start 91.147646 -224.187512)
		(end 91.147646 -223.596454)
		(width 0.136652)
		(layer "B.Cu")
		(net "PCIE_RX_P64")
	)
	(segment
		(start 91.147392 -223.5962)
		(end 91.147392 -222.90786)
		(width 0.136652)
		(layer "B.Cu")
		(net "PCIE_RX_P64")
	)
	(segment
		(start 90.899996 -225.92538)
		(end 90.899996 -224.713546)
		(width 0.136652)
		(layer "B.Cu")
		(net "PCIE_RX_P64")
	)
	(segment
		(start 91.147646 -223.596454)
		(end 91.147392 -223.5962)
		(width 0.136652)
		(layer "B.Cu")
		(net "PCIE_RX_P64")
	)
	(arc
		(start 91.09075 -224.324926)
		(mid 91.132876 -224.26188)
		(end 91.147646 -224.187512)
		(width 0.136652)
		(layer "B.Cu")
		(net "PCIE_RX_P64")
	)
	(arc
		(start 90.899996 -224.713546)
		(mid 90.936364 -224.53071)
		(end 91.03995 -224.375726)
		(width 0.136652)
		(layer "B.Cu")
		(net "PCIE_RX_P64")
	)
	(arc
		(start 91.147392 -222.90786)
		(mid 91.081384 -222.576014)
		(end 90.893392 -222.294704)
		(width 0.136652)
		(layer "B.Cu")
		(net "PCIE_RX_P64")
	)
	(segment
		(start 219.946474 -83.542886)
		(end 174.56785 -148.350478)
		(width 0.1397)
		(layer "In2.Cu")
		(net "PCIE_RX_P64")
	)
	(segment
		(start 94.178374 -214.569802)
		(end 91.381326 -218.56446)
		(width 0.1397)
		(layer "In2.Cu")
		(net "PCIE_RX_P64")
	)
	(segment
		(start 222.19412 -58.948574)
		(end 221.109286 -60.033154)
		(width 0.1397)
		(layer "In2.Cu")
		(net "PCIE_RX_P64")
	)
	(segment
		(start 220.596714 -63.413894)
		(end 221.33814 -67.121786)
		(width 0.1397)
		(layer "In2.Cu")
		(net "PCIE_RX_P64")
	)
	(segment
		(start 102.940612 -198.504556)
		(end 101.659944 -200.33361)
		(width 0.1397)
		(layer "In2.Cu")
		(net "PCIE_RX_P64")
	)
	(segment
		(start 221.009464 -68.766944)
		(end 221.7801 -73.140824)
		(width 0.1397)
		(layer "In2.Cu")
		(net "PCIE_RX_P64")
	)
	(segment
		(start 221.33814 -67.121786)
		(end 221.009464 -68.766944)
		(width 0.1397)
		(layer "In2.Cu")
		(net "PCIE_RX_P64")
	)
	(segment
		(start 95.461582 -207.29321)
		(end 94.178374 -214.569802)
		(width 0.1397)
		(layer "In2.Cu")
		(net "PCIE_RX_P64")
	)
	(segment
		(start 91.381326 -218.56446)
		(end 91.134692 -219.963238)
		(width 0.1397)
		(layer "In2.Cu")
		(net "PCIE_RX_P64")
	)
	(segment
		(start 91.134692 -219.963238)
		(end 91.134692 -221.712028)
		(width 0.1397)
		(layer "In2.Cu")
		(net "PCIE_RX_P64")
	)
	(segment
		(start 226.399598 -58.893456)
		(end 222.327216 -58.893456)
		(width 0.1016)
		(layer "In2.Cu")
		(net "PCIE_RX_P64")
	)
	(segment
		(start 221.7801 -73.140824)
		(end 219.946474 -83.542886)
		(width 0.1397)
		(layer "In2.Cu")
		(net "PCIE_RX_P64")
	)
	(segment
		(start 220.596714 -62.938914)
		(end 220.596714 -63.413894)
		(width 0.1397)
		(layer "In2.Cu")
		(net "PCIE_RX_P64")
	)
	(segment
		(start 101.659944 -200.33361)
		(end 99.059492 -202.154536)
		(width 0.1397)
		(layer "In2.Cu")
		(net "PCIE_RX_P64")
	)
	(segment
		(start 174.56785 -148.350478)
		(end 102.940612 -198.504556)
		(width 0.1397)
		(layer "In2.Cu")
		(net "PCIE_RX_P64")
	)
	(segment
		(start 221.109286 -60.033154)
		(end 220.596714 -62.938914)
		(width 0.1397)
		(layer "In2.Cu")
		(net "PCIE_RX_P64")
	)
	(segment
		(start 99.059492 -202.154536)
		(end 95.461582 -207.29321)
		(width 0.1397)
		(layer "In2.Cu")
		(net "PCIE_RX_P64")
	)
	(segment
		(start 227.04044 -59.355228)
		(end 226.704906 -59.019948)
		(width 0.1016)
		(layer "In2.Cu")
		(net "PCIE_RX_P64")
	)
	(arc
		(start 226.704906 -59.019948)
		(mid 226.670865 -58.989365)
		(end 226.633786 -58.962544)
		(width 0.1016)
		(layer "In2.Cu")
		(net "PCIE_RX_P64")
	)
	(arc
		(start 222.327216 -58.893456)
		(mid 222.25519 -58.907783)
		(end 222.19412 -58.948574)
		(width 0.1016)
		(layer "In2.Cu")
		(net "PCIE_RX_P64")
	)
	(arc
		(start 91.134692 -221.712028)
		(mid 91.071971 -222.02735)
		(end 90.893392 -222.294704)
		(width 0.1397)
		(layer "In2.Cu")
		(net "PCIE_RX_P64")
	)
	(arc
		(start 227.10013 -59.499754)
		(mid 227.084668 -59.42155)
		(end 227.04044 -59.355228)
		(width 0.1016)
		(layer "In2.Cu")
		(net "PCIE_RX_P64")
	)
	(arc
		(start 226.633786 -58.962544)
		(mid 226.521679 -58.911099)
		(end 226.399598 -58.893456)
		(width 0.1016)
		(layer "In2.Cu")
		(net "PCIE_RX_P64")
	)
	(segment
		(start 223.60001 -61.999876)
		(end 223.100138 -62.499748)
		(width 0.136652)
		(layer "F.Cu")
		(net "PCIE_RX_P63")
	)
	(via
		(at 223.100138 -62.499748)
		(size 0.4572)
		(drill 0.2032)
		(layers "F.Cu" "B.Cu")
		(net "PCIE_RX_P63")
	)
	(via
		(at 96.493584 -222.294704)
		(size 0.508)
		(drill 0.254)
		(layers "F.Cu" "B.Cu")
		(net "PCIE_RX_P63")
	)
	(segment
		(start 96.500188 -225.92538)
		(end 96.500188 -224.713546)
		(width 0.136652)
		(layer "B.Cu")
		(net "PCIE_RX_P63")
	)
	(segment
		(start 96.747584 -223.5962)
		(end 96.747584 -222.90786)
		(width 0.136652)
		(layer "B.Cu")
		(net "PCIE_RX_P63")
	)
	(segment
		(start 96.640142 -224.375726)
		(end 96.690942 -224.324926)
		(width 0.136652)
		(layer "B.Cu")
		(net "PCIE_RX_P63")
	)
	(segment
		(start 96.747838 -224.187512)
		(end 96.747838 -223.596454)
		(width 0.136652)
		(layer "B.Cu")
		(net "PCIE_RX_P63")
	)
	(segment
		(start 96.747838 -223.596454)
		(end 96.747584 -223.5962)
		(width 0.136652)
		(layer "B.Cu")
		(net "PCIE_RX_P63")
	)
	(arc
		(start 96.500188 -224.713546)
		(mid 96.536556 -224.53071)
		(end 96.640142 -224.375726)
		(width 0.136652)
		(layer "B.Cu")
		(net "PCIE_RX_P63")
	)
	(arc
		(start 96.747584 -222.90786)
		(mid 96.681576 -222.576014)
		(end 96.493584 -222.294704)
		(width 0.136652)
		(layer "B.Cu")
		(net "PCIE_RX_P63")
	)
	(arc
		(start 96.690942 -224.324926)
		(mid 96.733068 -224.26188)
		(end 96.747838 -224.187512)
		(width 0.136652)
		(layer "B.Cu")
		(net "PCIE_RX_P63")
	)
	(segment
		(start 95.540068 -213.037166)
		(end 96.330516 -208.554066)
		(width 0.1397)
		(layer "In2.Cu")
		(net "PCIE_RX_P63")
	)
	(segment
		(start 222.3897 -66.775076)
		(end 222.49384 -66.670936)
		(width 0.1016)
		(layer "In2.Cu")
		(net "PCIE_RX_P63")
	)
	(segment
		(start 222.904558 -62.748414)
		(end 223.026224 -62.652402)
		(width 0.1016)
		(layer "In2.Cu")
		(net "PCIE_RX_P63")
	)
	(segment
		(start 96.734884 -220.739716)
		(end 96.816418 -220.276928)
		(width 0.1397)
		(layer "In2.Cu")
		(net "PCIE_RX_P63")
	)
	(segment
		(start 222.3897 -70.96252)
		(end 222.3897 -66.775076)
		(width 0.1397)
		(layer "In2.Cu")
		(net "PCIE_RX_P63")
	)
	(segment
		(start 96.816418 -220.276928)
		(end 95.540068 -213.037166)
		(width 0.1397)
		(layer "In2.Cu")
		(net "PCIE_RX_P63")
	)
	(segment
		(start 222.674942 -62.92977)
		(end 222.75419 -62.866524)
		(width 0.1016)
		(layer "In2.Cu")
		(net "PCIE_RX_P63")
	)
	(segment
		(start 222.902018 -62.7507)
		(end 222.904558 -62.748414)
		(width 0.1016)
		(layer "In2.Cu")
		(net "PCIE_RX_P63")
	)
	(segment
		(start 222.75419 -62.866524)
		(end 222.754698 -62.866016)
		(width 0.1016)
		(layer "In2.Cu")
		(net "PCIE_RX_P63")
	)
	(segment
		(start 98.822764 -204.994764)
		(end 101.089206 -203.407772)
		(width 0.1397)
		(layer "In2.Cu")
		(net "PCIE_RX_P63")
	)
	(segment
		(start 222.797878 -62.831726)
		(end 222.818452 -62.815724)
		(width 0.1016)
		(layer "In2.Cu")
		(net "PCIE_RX_P63")
	)
	(segment
		(start 222.851218 -62.79007)
		(end 222.851472 -62.79007)
		(width 0.1016)
		(layer "In2.Cu")
		(net "PCIE_RX_P63")
	)
	(segment
		(start 222.851472 -62.79007)
		(end 222.858076 -62.784736)
		(width 0.1016)
		(layer "In2.Cu")
		(net "PCIE_RX_P63")
	)
	(segment
		(start 101.089206 -203.407772)
		(end 104.034844 -199.200008)
		(width 0.1397)
		(layer "In2.Cu")
		(net "PCIE_RX_P63")
	)
	(segment
		(start 176.298098 -148.600922)
		(end 220.802708 -85.040724)
		(width 0.1397)
		(layer "In2.Cu")
		(net "PCIE_RX_P63")
	)
	(segment
		(start 222.773494 -73.140824)
		(end 222.3897 -70.96252)
		(width 0.1397)
		(layer "In2.Cu")
		(net "PCIE_RX_P63")
	)
	(segment
		(start 222.824294 -62.811152)
		(end 222.829374 -62.807342)
		(width 0.1016)
		(layer "In2.Cu")
		(net "PCIE_RX_P63")
	)
	(segment
		(start 96.734884 -221.712028)
		(end 96.734884 -220.739716)
		(width 0.1397)
		(layer "In2.Cu")
		(net "PCIE_RX_P63")
	)
	(segment
		(start 222.858076 -62.784736)
		(end 222.895922 -62.755272)
		(width 0.1016)
		(layer "In2.Cu")
		(net "PCIE_RX_P63")
	)
	(segment
		(start 222.49384 -66.670936)
		(end 222.49384 -63.302134)
		(width 0.1016)
		(layer "In2.Cu")
		(net "PCIE_RX_P63")
	)
	(segment
		(start 96.330516 -208.554066)
		(end 98.822764 -204.994764)
		(width 0.1397)
		(layer "In2.Cu")
		(net "PCIE_RX_P63")
	)
	(segment
		(start 220.802708 -85.040724)
		(end 222.773494 -73.140824)
		(width 0.1397)
		(layer "In2.Cu")
		(net "PCIE_RX_P63")
	)
	(segment
		(start 222.829374 -62.807342)
		(end 222.851218 -62.79007)
		(width 0.1016)
		(layer "In2.Cu")
		(net "PCIE_RX_P63")
	)
	(segment
		(start 222.754698 -62.866016)
		(end 222.797878 -62.831726)
		(width 0.1016)
		(layer "In2.Cu")
		(net "PCIE_RX_P63")
	)
	(segment
		(start 222.641414 -62.958726)
		(end 222.642684 -62.95771)
		(width 0.1016)
		(layer "In2.Cu")
		(net "PCIE_RX_P63")
	)
	(segment
		(start 222.895922 -62.755272)
		(end 222.902018 -62.7507)
		(width 0.1016)
		(layer "In2.Cu")
		(net "PCIE_RX_P63")
	)
	(segment
		(start 222.818452 -62.815724)
		(end 222.824294 -62.811152)
		(width 0.1016)
		(layer "In2.Cu")
		(net "PCIE_RX_P63")
	)
	(segment
		(start 104.034844 -199.200008)
		(end 176.298098 -148.600922)
		(width 0.1397)
		(layer "In2.Cu")
		(net "PCIE_RX_P63")
	)
	(arc
		(start 96.493584 -222.294704)
		(mid 96.672211 -222.02737)
		(end 96.734884 -221.712028)
		(width 0.1397)
		(layer "In2.Cu")
		(net "PCIE_RX_P63")
	)
	(arc
		(start 223.026224 -62.652402)
		(mid 223.080696 -62.584554)
		(end 223.100138 -62.499748)
		(width 0.1016)
		(layer "In2.Cu")
		(net "PCIE_RX_P63")
	)
	(arc
		(start 222.49384 -63.302134)
		(mid 222.506437 -63.193453)
		(end 222.543624 -63.090552)
		(width 0.1016)
		(layer "In2.Cu")
		(net "PCIE_RX_P63")
	)
	(arc
		(start 222.642684 -62.95771)
		(mid 222.658487 -62.943363)
		(end 222.674942 -62.92977)
		(width 0.1016)
		(layer "In2.Cu")
		(net "PCIE_RX_P63")
	)
	(arc
		(start 222.543624 -63.090552)
		(mid 222.586761 -63.020368)
		(end 222.641414 -62.958726)
		(width 0.1016)
		(layer "In2.Cu")
		(net "PCIE_RX_P63")
	)
	(segment
		(start 224.600008 -60.999878)
		(end 224.100136 -61.49975)
		(width 0.136652)
		(layer "F.Cu")
		(net "PCIE_RX_P62")
	)
	(via
		(at 99.693476 -222.294704)
		(size 0.508)
		(drill 0.254)
		(layers "F.Cu" "B.Cu")
		(net "PCIE_RX_P62")
	)
	(via
		(at 224.100136 -61.49975)
		(size 0.4572)
		(drill 0.2032)
		(layers "F.Cu" "B.Cu")
		(net "PCIE_RX_P62")
	)
	(segment
		(start 99.70008 -225.92538)
		(end 99.70008 -224.713546)
		(width 0.136652)
		(layer "B.Cu")
		(net "PCIE_RX_P62")
	)
	(segment
		(start 99.94773 -223.596454)
		(end 99.947476 -223.5962)
		(width 0.136652)
		(layer "B.Cu")
		(net "PCIE_RX_P62")
	)
	(segment
		(start 99.840034 -224.375726)
		(end 99.890834 -224.324926)
		(width 0.136652)
		(layer "B.Cu")
		(net "PCIE_RX_P62")
	)
	(segment
		(start 99.94773 -224.187512)
		(end 99.94773 -223.596454)
		(width 0.136652)
		(layer "B.Cu")
		(net "PCIE_RX_P62")
	)
	(segment
		(start 99.947476 -223.5962)
		(end 99.947476 -222.90786)
		(width 0.136652)
		(layer "B.Cu")
		(net "PCIE_RX_P62")
	)
	(arc
		(start 99.947476 -222.90786)
		(mid 99.881468 -222.576014)
		(end 99.693476 -222.294704)
		(width 0.136652)
		(layer "B.Cu")
		(net "PCIE_RX_P62")
	)
	(arc
		(start 99.70008 -224.713546)
		(mid 99.736448 -224.53071)
		(end 99.840034 -224.375726)
		(width 0.136652)
		(layer "B.Cu")
		(net "PCIE_RX_P62")
	)
	(arc
		(start 99.890834 -224.324926)
		(mid 99.93296 -224.26188)
		(end 99.94773 -224.187512)
		(width 0.136652)
		(layer "B.Cu")
		(net "PCIE_RX_P62")
	)
	(segment
		(start 175.804576 -151.207216)
		(end 222.193104 -84.95919)
		(width 0.1397)
		(layer "In2.Cu")
		(net "PCIE_RX_P62")
	)
	(segment
		(start 99.89566 -208.667858)
		(end 105.81513 -200.21423)
		(width 0.1397)
		(layer "In2.Cu")
		(net "PCIE_RX_P62")
	)
	(segment
		(start 105.81513 -200.21423)
		(end 175.804576 -151.207216)
		(width 0.1397)
		(layer "In2.Cu")
		(net "PCIE_RX_P62")
	)
	(segment
		(start 99.89566 -213.585044)
		(end 99.89566 -208.667858)
		(width 0.1397)
		(layer "In2.Cu")
		(net "PCIE_RX_P62")
	)
	(segment
		(start 223.641412 -61.958728)
		(end 223.642682 -61.957712)
		(width 0.1016)
		(layer "In2.Cu")
		(net "PCIE_RX_P62")
	)
	(segment
		(start 99.533202 -215.639142)
		(end 99.89566 -213.585044)
		(width 0.1397)
		(layer "In2.Cu")
		(net "PCIE_RX_P62")
	)
	(segment
		(start 222.193104 -84.95919)
		(end 224.06864 -74.315574)
		(width 0.1397)
		(layer "In2.Cu")
		(net "PCIE_RX_P62")
	)
	(segment
		(start 223.4438 -66.7766)
		(end 223.493838 -66.726562)
		(width 0.1016)
		(layer "In2.Cu")
		(net "PCIE_RX_P62")
	)
	(segment
		(start 223.425258 -69.156326)
		(end 223.4438 -66.7766)
		(width 0.1397)
		(layer "In2.Cu")
		(net "PCIE_RX_P62")
	)
	(segment
		(start 224.06864 -74.315574)
		(end 223.425258 -69.156326)
		(width 0.1397)
		(layer "In2.Cu")
		(net "PCIE_RX_P62")
	)
	(segment
		(start 99.934776 -221.712028)
		(end 99.934776 -221.31909)
		(width 0.1397)
		(layer "In2.Cu")
		(net "PCIE_RX_P62")
	)
	(segment
		(start 223.67494 -61.929772)
		(end 224.025714 -61.65342)
		(width 0.1016)
		(layer "In2.Cu")
		(net "PCIE_RX_P62")
	)
	(segment
		(start 223.493838 -66.726562)
		(end 223.493838 -62.302136)
		(width 0.1016)
		(layer "In2.Cu")
		(net "PCIE_RX_P62")
	)
	(segment
		(start 99.934776 -221.31909)
		(end 100.23475 -219.617798)
		(width 0.1397)
		(layer "In2.Cu")
		(net "PCIE_RX_P62")
	)
	(segment
		(start 100.23475 -219.617798)
		(end 99.533202 -215.639142)
		(width 0.1397)
		(layer "In2.Cu")
		(net "PCIE_RX_P62")
	)
	(arc
		(start 223.642682 -61.957712)
		(mid 223.658485 -61.943365)
		(end 223.67494 -61.929772)
		(width 0.1016)
		(layer "In2.Cu")
		(net "PCIE_RX_P62")
	)
	(arc
		(start 224.025714 -61.65342)
		(mid 224.080628 -61.585145)
		(end 224.100136 -61.49975)
		(width 0.1016)
		(layer "In2.Cu")
		(net "PCIE_RX_P62")
	)
	(arc
		(start 99.693476 -222.294704)
		(mid 99.872103 -222.02737)
		(end 99.934776 -221.712028)
		(width 0.1397)
		(layer "In2.Cu")
		(net "PCIE_RX_P62")
	)
	(arc
		(start 223.493838 -62.302136)
		(mid 223.532234 -62.115216)
		(end 223.641412 -61.958728)
		(width 0.1016)
		(layer "In2.Cu")
		(net "PCIE_RX_P62")
	)
	(segment
		(start 225.600006 -61.999876)
		(end 225.100134 -62.499748)
		(width 0.136652)
		(layer "F.Cu")
		(net "PCIE_RX_P61")
	)
	(via
		(at 102.893368 -222.294704)
		(size 0.508)
		(drill 0.254)
		(layers "F.Cu" "B.Cu")
		(net "PCIE_RX_P61")
	)
	(via
		(at 225.100134 -62.499748)
		(size 0.4572)
		(drill 0.2032)
		(layers "F.Cu" "B.Cu")
		(net "PCIE_RX_P61")
	)
	(segment
		(start 102.899972 -225.92538)
		(end 102.899972 -224.713546)
		(width 0.136652)
		(layer "B.Cu")
		(net "PCIE_RX_P61")
	)
	(segment
		(start 103.147368 -223.5962)
		(end 103.147368 -222.90786)
		(width 0.136652)
		(layer "B.Cu")
		(net "PCIE_RX_P61")
	)
	(segment
		(start 103.147622 -224.187512)
		(end 103.147622 -223.596454)
		(width 0.136652)
		(layer "B.Cu")
		(net "PCIE_RX_P61")
	)
	(segment
		(start 103.039926 -224.375726)
		(end 103.090726 -224.324926)
		(width 0.136652)
		(layer "B.Cu")
		(net "PCIE_RX_P61")
	)
	(segment
		(start 103.147622 -223.596454)
		(end 103.147368 -223.5962)
		(width 0.136652)
		(layer "B.Cu")
		(net "PCIE_RX_P61")
	)
	(arc
		(start 103.147368 -222.90786)
		(mid 103.08136 -222.576014)
		(end 102.893368 -222.294704)
		(width 0.136652)
		(layer "B.Cu")
		(net "PCIE_RX_P61")
	)
	(arc
		(start 102.899972 -224.713546)
		(mid 102.93634 -224.53071)
		(end 103.039926 -224.375726)
		(width 0.136652)
		(layer "B.Cu")
		(net "PCIE_RX_P61")
	)
	(arc
		(start 103.090726 -224.324926)
		(mid 103.132852 -224.26188)
		(end 103.147622 -224.187512)
		(width 0.136652)
		(layer "B.Cu")
		(net "PCIE_RX_P61")
	)
	(segment
		(start 225.24847 -74.066654)
		(end 224.4217 -69.26453)
		(width 0.1397)
		(layer "In2.Cu")
		(net "PCIE_RX_P61")
	)
	(segment
		(start 224.674938 -62.92977)
		(end 225.025712 -62.653418)
		(width 0.1016)
		(layer "In2.Cu")
		(net "PCIE_RX_P61")
	)
	(segment
		(start 224.4217 -67.1322)
		(end 224.493836 -67.060064)
		(width 0.1016)
		(layer "In2.Cu")
		(net "PCIE_RX_P61")
	)
	(segment
		(start 224.64141 -62.958726)
		(end 224.64268 -62.95771)
		(width 0.1016)
		(layer "In2.Cu")
		(net "PCIE_RX_P61")
	)
	(segment
		(start 103.175816 -213.712044)
		(end 103.175816 -209.304636)
		(width 0.1397)
		(layer "In2.Cu")
		(net "PCIE_RX_P61")
	)
	(segment
		(start 103.175816 -209.304636)
		(end 103.446326 -207.76946)
		(width 0.1397)
		(layer "In2.Cu")
		(net "PCIE_RX_P61")
	)
	(segment
		(start 224.4217 -69.26453)
		(end 224.4217 -67.1322)
		(width 0.1397)
		(layer "In2.Cu")
		(net "PCIE_RX_P61")
	)
	(segment
		(start 103.446326 -207.76946)
		(end 108.808266 -200.111614)
		(width 0.1397)
		(layer "In2.Cu")
		(net "PCIE_RX_P61")
	)
	(segment
		(start 103.134668 -221.050866)
		(end 103.413814 -219.46743)
		(width 0.1397)
		(layer "In2.Cu")
		(net "PCIE_RX_P61")
	)
	(segment
		(start 176.634394 -152.620472)
		(end 223.096582 -86.264496)
		(width 0.1397)
		(layer "In2.Cu")
		(net "PCIE_RX_P61")
	)
	(segment
		(start 223.096582 -86.264496)
		(end 225.24847 -74.066654)
		(width 0.1397)
		(layer "In2.Cu")
		(net "PCIE_RX_P61")
	)
	(segment
		(start 108.808266 -200.111614)
		(end 176.634394 -152.620472)
		(width 0.1397)
		(layer "In2.Cu")
		(net "PCIE_RX_P61")
	)
	(segment
		(start 103.134668 -221.712028)
		(end 103.134668 -221.050866)
		(width 0.1397)
		(layer "In2.Cu")
		(net "PCIE_RX_P61")
	)
	(segment
		(start 102.787196 -215.914478)
		(end 103.175816 -213.712044)
		(width 0.1397)
		(layer "In2.Cu")
		(net "PCIE_RX_P61")
	)
	(segment
		(start 224.493836 -67.060064)
		(end 224.493836 -63.302134)
		(width 0.1016)
		(layer "In2.Cu")
		(net "PCIE_RX_P61")
	)
	(segment
		(start 103.413814 -219.46743)
		(end 102.787196 -215.914478)
		(width 0.1397)
		(layer "In2.Cu")
		(net "PCIE_RX_P61")
	)
	(arc
		(start 225.025712 -62.653418)
		(mid 225.080626 -62.585143)
		(end 225.100134 -62.499748)
		(width 0.1016)
		(layer "In2.Cu")
		(net "PCIE_RX_P61")
	)
	(arc
		(start 224.64268 -62.95771)
		(mid 224.658483 -62.943363)
		(end 224.674938 -62.92977)
		(width 0.1016)
		(layer "In2.Cu")
		(net "PCIE_RX_P61")
	)
	(arc
		(start 224.493836 -63.302134)
		(mid 224.532232 -63.115214)
		(end 224.64141 -62.958726)
		(width 0.1016)
		(layer "In2.Cu")
		(net "PCIE_RX_P61")
	)
	(arc
		(start 102.893368 -222.294704)
		(mid 103.071995 -222.02737)
		(end 103.134668 -221.712028)
		(width 0.1397)
		(layer "In2.Cu")
		(net "PCIE_RX_P61")
	)
	(segment
		(start 226.600004 -60.999878)
		(end 226.100132 -61.49975)
		(width 0.136652)
		(layer "F.Cu")
		(net "PCIE_RX_P60")
	)
	(via
		(at 226.100132 -61.49975)
		(size 0.4572)
		(drill 0.2032)
		(layers "F.Cu" "B.Cu")
		(net "PCIE_RX_P60")
	)
	(via
		(at 106.093514 -222.294704)
		(size 0.508)
		(drill 0.254)
		(layers "F.Cu" "B.Cu")
		(net "PCIE_RX_P60")
	)
	(segment
		(start 106.240072 -224.375726)
		(end 106.290872 -224.324926)
		(width 0.136652)
		(layer "B.Cu")
		(net "PCIE_RX_P60")
	)
	(segment
		(start 106.347514 -223.5962)
		(end 106.347514 -222.90786)
		(width 0.136652)
		(layer "B.Cu")
		(net "PCIE_RX_P60")
	)
	(segment
		(start 106.347768 -224.187512)
		(end 106.347768 -223.596454)
		(width 0.136652)
		(layer "B.Cu")
		(net "PCIE_RX_P60")
	)
	(segment
		(start 106.100118 -225.92538)
		(end 106.100118 -224.713546)
		(width 0.136652)
		(layer "B.Cu")
		(net "PCIE_RX_P60")
	)
	(segment
		(start 106.347768 -223.596454)
		(end 106.347514 -223.5962)
		(width 0.136652)
		(layer "B.Cu")
		(net "PCIE_RX_P60")
	)
	(arc
		(start 106.347514 -222.90786)
		(mid 106.281506 -222.576014)
		(end 106.093514 -222.294704)
		(width 0.136652)
		(layer "B.Cu")
		(net "PCIE_RX_P60")
	)
	(arc
		(start 106.100118 -224.713546)
		(mid 106.136486 -224.53071)
		(end 106.240072 -224.375726)
		(width 0.136652)
		(layer "B.Cu")
		(net "PCIE_RX_P60")
	)
	(arc
		(start 106.290872 -224.324926)
		(mid 106.332998 -224.26188)
		(end 106.347768 -224.187512)
		(width 0.136652)
		(layer "B.Cu")
		(net "PCIE_RX_P60")
	)
	(segment
		(start 106.571034 -219.695522)
		(end 105.921556 -216.012014)
		(width 0.1397)
		(layer "In2.Cu")
		(net "PCIE_RX_P60")
	)
	(segment
		(start 107.028996 -206.007716)
		(end 109.074458 -203.086462)
		(width 0.1397)
		(layer "In2.Cu")
		(net "PCIE_RX_P60")
	)
	(segment
		(start 225.493834 -67.339718)
		(end 225.493834 -62.302898)
		(width 0.1016)
		(layer "In2.Cu")
		(net "PCIE_RX_P60")
	)
	(segment
		(start 225.641408 -61.958728)
		(end 225.642678 -61.957712)
		(width 0.1016)
		(layer "In2.Cu")
		(net "PCIE_RX_P60")
	)
	(segment
		(start 106.3498 -209.860134)
		(end 107.028996 -206.007716)
		(width 0.1397)
		(layer "In2.Cu")
		(net "PCIE_RX_P60")
	)
	(segment
		(start 106.334814 -221.712028)
		(end 106.334814 -221.035118)
		(width 0.1397)
		(layer "In2.Cu")
		(net "PCIE_RX_P60")
	)
	(segment
		(start 225.4377 -69.492622)
		(end 225.4377 -67.351148)
		(width 0.1397)
		(layer "In2.Cu")
		(net "PCIE_RX_P60")
	)
	(segment
		(start 105.921556 -216.012014)
		(end 106.143044 -214.755984)
		(width 0.1397)
		(layer "In2.Cu")
		(net "PCIE_RX_P60")
	)
	(segment
		(start 111.110776 -200.177654)
		(end 178.368706 -153.082752)
		(width 0.1397)
		(layer "In2.Cu")
		(net "PCIE_RX_P60")
	)
	(segment
		(start 106.3498 -213.585044)
		(end 106.3498 -209.860134)
		(width 0.1397)
		(layer "In2.Cu")
		(net "PCIE_RX_P60")
	)
	(segment
		(start 225.4377 -67.351148)
		(end 225.493834 -67.339718)
		(width 0.1016)
		(layer "In2.Cu")
		(net "PCIE_RX_P60")
	)
	(segment
		(start 178.368706 -153.082752)
		(end 224.085404 -87.789512)
		(width 0.1397)
		(layer "In2.Cu")
		(net "PCIE_RX_P60")
	)
	(segment
		(start 109.074458 -203.086462)
		(end 111.110776 -200.177654)
		(width 0.1397)
		(layer "In2.Cu")
		(net "PCIE_RX_P60")
	)
	(segment
		(start 106.334814 -221.035118)
		(end 106.571034 -219.695522)
		(width 0.1397)
		(layer "In2.Cu")
		(net "PCIE_RX_P60")
	)
	(segment
		(start 226.374452 -74.806048)
		(end 225.4377 -69.492622)
		(width 0.1397)
		(layer "In2.Cu")
		(net "PCIE_RX_P60")
	)
	(segment
		(start 106.143044 -214.755984)
		(end 106.3498 -213.585044)
		(width 0.1397)
		(layer "In2.Cu")
		(net "PCIE_RX_P60")
	)
	(segment
		(start 224.085404 -87.789512)
		(end 226.374452 -74.806048)
		(width 0.1397)
		(layer "In2.Cu")
		(net "PCIE_RX_P60")
	)
	(segment
		(start 225.674936 -61.929772)
		(end 226.02571 -61.65342)
		(width 0.1016)
		(layer "In2.Cu")
		(net "PCIE_RX_P60")
	)
	(arc
		(start 225.493834 -62.302898)
		(mid 225.532078 -62.115566)
		(end 225.641408 -61.958728)
		(width 0.1016)
		(layer "In2.Cu")
		(net "PCIE_RX_P60")
	)
	(arc
		(start 106.093514 -222.294704)
		(mid 106.272141 -222.02737)
		(end 106.334814 -221.712028)
		(width 0.1397)
		(layer "In2.Cu")
		(net "PCIE_RX_P60")
	)
	(arc
		(start 225.642678 -61.957712)
		(mid 225.658481 -61.943365)
		(end 225.674936 -61.929772)
		(width 0.1016)
		(layer "In2.Cu")
		(net "PCIE_RX_P60")
	)
	(arc
		(start 226.02571 -61.65342)
		(mid 226.080624 -61.585145)
		(end 226.100132 -61.49975)
		(width 0.1016)
		(layer "In2.Cu")
		(net "PCIE_RX_P60")
	)
	(segment
		(start 248.59996 -30.999938)
		(end 249.099832 -30.500066)
		(width 0.136652)
		(layer "F.Cu")
		(net "PCIE_RX_P6")
	)
	(via
		(at 249.099832 -30.500066)
		(size 0.4572)
		(drill 0.2032)
		(layers "F.Cu" "B.Cu")
		(net "PCIE_RX_P6")
	)
	(segment
		(start 293.373048 -25.048718)
		(end 292.85311 -25.412954)
		(width 0.1397)
		(layer "In2.Cu")
		(net "PCIE_RX_P6")
	)
	(segment
		(start 302.204882 -18.341848)
		(end 301.954946 -18.652744)
		(width 0.1397)
		(layer "In2.Cu")
		(net "PCIE_RX_P6")
	)
	(segment
		(start 285.605728 -26.035)
		(end 284.157674 -25.494234)
		(width 0.1397)
		(layer "In2.Cu")
		(net "PCIE_RX_P6")
	)
	(segment
		(start 277.654766 -24.347424)
		(end 274.235418 -24.950674)
		(width 0.1397)
		(layer "In2.Cu")
		(net "PCIE_RX_P6")
	)
	(segment
		(start 248.665238 -29.19476)
		(end 248.665238 -29.42971)
		(width 0.1397)
		(layer "In2.Cu")
		(net "PCIE_RX_P6")
	)
	(segment
		(start 295.60266 -20.250658)
		(end 295.222168 -22.407626)
		(width 0.1397)
		(layer "In2.Cu")
		(net "PCIE_RX_P6")
	)
	(segment
		(start 301.954946 -18.652744)
		(end 301.436024 -18.913094)
		(width 0.1397)
		(layer "In2.Cu")
		(net "PCIE_RX_P6")
	)
	(segment
		(start 264.223246 -22.967696)
		(end 261.049262 -23.602188)
		(width 0.1397)
		(layer "In2.Cu")
		(net "PCIE_RX_P6")
	)
	(segment
		(start 300.791626 -18.9992)
		(end 300.57471 -19.027902)
		(width 0.1397)
		(layer "In2.Cu")
		(net "PCIE_RX_P6")
	)
	(segment
		(start 299.311314 -18.67027)
		(end 296.925746 -19.287744)
		(width 0.1397)
		(layer "In2.Cu")
		(net "PCIE_RX_P6")
	)
	(segment
		(start 292.852856 -25.412954)
		(end 292.33241 -25.777444)
		(width 0.1397)
		(layer "In2.Cu")
		(net "PCIE_RX_P6")
	)
	(segment
		(start 290.87191 -26.035)
		(end 285.605728 -26.035)
		(width 0.1397)
		(layer "In2.Cu")
		(net "PCIE_RX_P6")
	)
	(segment
		(start 292.33241 -25.777444)
		(end 290.87191 -26.035)
		(width 0.1397)
		(layer "In2.Cu")
		(net "PCIE_RX_P6")
	)
	(segment
		(start 296.925746 -19.287744)
		(end 295.60266 -20.250658)
		(width 0.1397)
		(layer "In2.Cu")
		(net "PCIE_RX_P6")
	)
	(segment
		(start 300.57471 -19.027902)
		(end 300.019974 -18.87093)
		(width 0.1397)
		(layer "In2.Cu")
		(net "PCIE_RX_P6")
	)
	(segment
		(start 295.222168 -22.407626)
		(end 293.373048 -25.048718)
		(width 0.1397)
		(layer "In2.Cu")
		(net "PCIE_RX_P6")
	)
	(segment
		(start 274.235418 -24.950674)
		(end 264.223246 -22.967696)
		(width 0.1397)
		(layer "In2.Cu")
		(net "PCIE_RX_P6")
	)
	(segment
		(start 284.157674 -25.494234)
		(end 277.654766 -24.347424)
		(width 0.1397)
		(layer "In2.Cu")
		(net "PCIE_RX_P6")
	)
	(segment
		(start 261.049262 -23.602188)
		(end 257.877818 -22.968458)
		(width 0.1397)
		(layer "In2.Cu")
		(net "PCIE_RX_P6")
	)
	(segment
		(start 292.85311 -25.412954)
		(end 292.852856 -25.412954)
		(width 0.1397)
		(layer "In2.Cu")
		(net "PCIE_RX_P6")
	)
	(segment
		(start 257.877818 -22.968458)
		(end 253.490984 -23.724616)
		(width 0.1397)
		(layer "In2.Cu")
		(net "PCIE_RX_P6")
	)
	(segment
		(start 301.436024 -18.913094)
		(end 300.791626 -18.9992)
		(width 0.1397)
		(layer "In2.Cu")
		(net "PCIE_RX_P6")
	)
	(segment
		(start 253.490984 -23.724616)
		(end 249.079258 -28.136342)
		(width 0.1397)
		(layer "In2.Cu")
		(net "PCIE_RX_P6")
	)
	(segment
		(start 300.019974 -18.87093)
		(end 299.311314 -18.67027)
		(width 0.1397)
		(layer "In2.Cu")
		(net "PCIE_RX_P6")
	)
	(arc
		(start 249.079258 -28.136342)
		(mid 248.805245 -28.548927)
		(end 248.674382 -29.026612)
		(width 0.1397)
		(layer "In2.Cu")
		(net "PCIE_RX_P6")
	)
	(arc
		(start 302.07839 -17.438624)
		(mid 302.129885 -17.469057)
		(end 302.174656 -17.508728)
		(width 0.1397)
		(layer "In2.Cu")
		(net "PCIE_RX_P6")
	)
	(arc
		(start 248.674382 -29.026612)
		(mid 248.667539 -29.110563)
		(end 248.665238 -29.19476)
		(width 0.1397)
		(layer "In2.Cu")
		(net "PCIE_RX_P6")
	)
	(arc
		(start 248.665238 -29.42971)
		(mid 248.778027 -30.007323)
		(end 249.099832 -30.500066)
		(width 0.1397)
		(layer "In2.Cu")
		(net "PCIE_RX_P6")
	)
	(arc
		(start 302.174656 -17.508728)
		(mid 302.345136 -17.91967)
		(end 302.204882 -18.341848)
		(width 0.1397)
		(layer "In2.Cu")
		(net "PCIE_RX_P6")
	)
	(arc
		(start 301.634398 -17.729962)
		(mid 301.775126 -17.460444)
		(end 302.07839 -17.438624)
		(width 0.1397)
		(layer "In2.Cu")
		(net "PCIE_RX_P6")
	)
	(segment
		(start 227.600002 -61.999876)
		(end 227.10013 -62.499748)
		(width 0.136652)
		(layer "F.Cu")
		(net "PCIE_RX_P59")
	)
	(via
		(at 227.10013 -62.499748)
		(size 0.4572)
		(drill 0.2032)
		(layers "F.Cu" "B.Cu")
		(net "PCIE_RX_P59")
	)
	(via
		(at 136.893554 -222.294704)
		(size 0.508)
		(drill 0.254)
		(layers "F.Cu" "B.Cu")
		(net "PCIE_RX_P59")
	)
	(segment
		(start 137.147554 -223.5962)
		(end 137.147554 -222.90786)
		(width 0.136652)
		(layer "B.Cu")
		(net "PCIE_RX_P59")
	)
	(segment
		(start 137.147808 -224.187512)
		(end 137.147808 -223.596454)
		(width 0.136652)
		(layer "B.Cu")
		(net "PCIE_RX_P59")
	)
	(segment
		(start 137.147808 -223.596454)
		(end 137.147554 -223.5962)
		(width 0.136652)
		(layer "B.Cu")
		(net "PCIE_RX_P59")
	)
	(segment
		(start 136.900158 -225.92538)
		(end 136.900158 -224.713546)
		(width 0.136652)
		(layer "B.Cu")
		(net "PCIE_RX_P59")
	)
	(segment
		(start 137.040112 -224.375726)
		(end 137.090912 -224.324926)
		(width 0.136652)
		(layer "B.Cu")
		(net "PCIE_RX_P59")
	)
	(arc
		(start 136.900158 -224.713546)
		(mid 136.936526 -224.53071)
		(end 137.040112 -224.375726)
		(width 0.136652)
		(layer "B.Cu")
		(net "PCIE_RX_P59")
	)
	(arc
		(start 137.090912 -224.324926)
		(mid 137.133038 -224.26188)
		(end 137.147808 -224.187512)
		(width 0.136652)
		(layer "B.Cu")
		(net "PCIE_RX_P59")
	)
	(arc
		(start 137.147554 -222.90786)
		(mid 137.081546 -222.576014)
		(end 136.893554 -222.294704)
		(width 0.136652)
		(layer "B.Cu")
		(net "PCIE_RX_P59")
	)
	(segment
		(start 137.134854 -221.712028)
		(end 137.134854 -219.652596)
		(width 0.1397)
		(layer "In2.Cu")
		(net "PCIE_RX_P59")
	)
	(segment
		(start 227.495608 -75.319636)
		(end 226.4283 -69.26453)
		(width 0.1397)
		(layer "In2.Cu")
		(net "PCIE_RX_P59")
	)
	(segment
		(start 140.007594 -215.54948)
		(end 140.3096 -213.839044)
		(width 0.1397)
		(layer "In2.Cu")
		(net "PCIE_RX_P59")
	)
	(segment
		(start 226.641406 -62.958726)
		(end 226.642676 -62.95771)
		(width 0.1016)
		(layer "In2.Cu")
		(net "PCIE_RX_P59")
	)
	(segment
		(start 142.907766 -205.648052)
		(end 143.999966 -204.555598)
		(width 0.1397)
		(layer "In2.Cu")
		(net "PCIE_RX_P59")
	)
	(segment
		(start 143.999966 -204.555598)
		(end 226.194366 -87.17026)
		(width 0.1397)
		(layer "In2.Cu")
		(net "PCIE_RX_P59")
	)
	(segment
		(start 140.3096 -209.358992)
		(end 142.907766 -205.648052)
		(width 0.1397)
		(layer "In2.Cu")
		(net "PCIE_RX_P59")
	)
	(segment
		(start 226.4283 -69.26453)
		(end 226.4283 -67.1195)
		(width 0.1397)
		(layer "In2.Cu")
		(net "PCIE_RX_P59")
	)
	(segment
		(start 226.194366 -87.17026)
		(end 226.746816 -79.5655)
		(width 0.1397)
		(layer "In2.Cu")
		(net "PCIE_RX_P59")
	)
	(segment
		(start 137.134854 -219.652596)
		(end 140.007594 -215.54948)
		(width 0.1397)
		(layer "In2.Cu")
		(net "PCIE_RX_P59")
	)
	(segment
		(start 140.3096 -213.839044)
		(end 140.3096 -209.358992)
		(width 0.1397)
		(layer "In2.Cu")
		(net "PCIE_RX_P59")
	)
	(segment
		(start 226.493832 -67.053968)
		(end 226.493832 -63.302134)
		(width 0.1016)
		(layer "In2.Cu")
		(net "PCIE_RX_P59")
	)
	(segment
		(start 226.746816 -79.5655)
		(end 227.495608 -75.319636)
		(width 0.1397)
		(layer "In2.Cu")
		(net "PCIE_RX_P59")
	)
	(segment
		(start 226.674934 -62.92977)
		(end 227.025708 -62.653418)
		(width 0.1016)
		(layer "In2.Cu")
		(net "PCIE_RX_P59")
	)
	(segment
		(start 226.4283 -67.1195)
		(end 226.493832 -67.053968)
		(width 0.1016)
		(layer "In2.Cu")
		(net "PCIE_RX_P59")
	)
	(arc
		(start 227.025708 -62.653418)
		(mid 227.080622 -62.585143)
		(end 227.10013 -62.499748)
		(width 0.1016)
		(layer "In2.Cu")
		(net "PCIE_RX_P59")
	)
	(arc
		(start 136.893554 -222.294704)
		(mid 137.072181 -222.02737)
		(end 137.134854 -221.712028)
		(width 0.1397)
		(layer "In2.Cu")
		(net "PCIE_RX_P59")
	)
	(arc
		(start 226.493832 -63.302134)
		(mid 226.532228 -63.115214)
		(end 226.641406 -62.958726)
		(width 0.1016)
		(layer "In2.Cu")
		(net "PCIE_RX_P59")
	)
	(arc
		(start 226.642676 -62.95771)
		(mid 226.658479 -62.943363)
		(end 226.674934 -62.92977)
		(width 0.1016)
		(layer "In2.Cu")
		(net "PCIE_RX_P59")
	)
	(segment
		(start 228.6 -60.999878)
		(end 228.100128 -61.49975)
		(width 0.136652)
		(layer "F.Cu")
		(net "PCIE_RX_P58")
	)
	(via
		(at 228.100128 -61.49975)
		(size 0.4572)
		(drill 0.2032)
		(layers "F.Cu" "B.Cu")
		(net "PCIE_RX_P58")
	)
	(via
		(at 140.0937 -222.294704)
		(size 0.508)
		(drill 0.254)
		(layers "F.Cu" "B.Cu")
		(net "PCIE_RX_P58")
	)
	(segment
		(start 140.3477 -223.5962)
		(end 140.3477 -222.90786)
		(width 0.136652)
		(layer "B.Cu")
		(net "PCIE_RX_P58")
	)
	(segment
		(start 140.347954 -224.187512)
		(end 140.347954 -223.596454)
		(width 0.136652)
		(layer "B.Cu")
		(net "PCIE_RX_P58")
	)
	(segment
		(start 140.10005 -225.92538)
		(end 140.10005 -224.7138)
		(width 0.136652)
		(layer "B.Cu")
		(net "PCIE_RX_P58")
	)
	(segment
		(start 140.240258 -224.375726)
		(end 140.291058 -224.324926)
		(width 0.136652)
		(layer "B.Cu")
		(net "PCIE_RX_P58")
	)
	(segment
		(start 140.10005 -224.7138)
		(end 140.100304 -224.713546)
		(width 0.136652)
		(layer "B.Cu")
		(net "PCIE_RX_P58")
	)
	(segment
		(start 140.347954 -223.596454)
		(end 140.3477 -223.5962)
		(width 0.136652)
		(layer "B.Cu")
		(net "PCIE_RX_P58")
	)
	(arc
		(start 140.100304 -224.713546)
		(mid 140.136672 -224.53071)
		(end 140.240258 -224.375726)
		(width 0.136652)
		(layer "B.Cu")
		(net "PCIE_RX_P58")
	)
	(arc
		(start 140.291058 -224.324926)
		(mid 140.333184 -224.26188)
		(end 140.347954 -224.187512)
		(width 0.136652)
		(layer "B.Cu")
		(net "PCIE_RX_P58")
	)
	(arc
		(start 140.3477 -222.90786)
		(mid 140.281692 -222.576014)
		(end 140.0937 -222.294704)
		(width 0.136652)
		(layer "B.Cu")
		(net "PCIE_RX_P58")
	)
	(segment
		(start 228.528118 -75.376532)
		(end 227.45065 -69.26453)
		(width 0.1397)
		(layer "In2.Cu")
		(net "PCIE_RX_P58")
	)
	(segment
		(start 227.45065 -67.1322)
		(end 227.49383 -67.08902)
		(width 0.1016)
		(layer "In2.Cu")
		(net "PCIE_RX_P58")
	)
	(segment
		(start 143.4846 -213.737444)
		(end 143.4846 -209.394044)
		(width 0.1397)
		(layer "In2.Cu")
		(net "PCIE_RX_P58")
	)
	(segment
		(start 143.046196 -216.221818)
		(end 143.4846 -213.737444)
		(width 0.1397)
		(layer "In2.Cu")
		(net "PCIE_RX_P58")
	)
	(segment
		(start 143.823436 -207.47101)
		(end 226.98456 -88.70569)
		(width 0.1397)
		(layer "In2.Cu")
		(net "PCIE_RX_P58")
	)
	(segment
		(start 140.335 -220.094048)
		(end 143.046196 -216.221818)
		(width 0.1397)
		(layer "In2.Cu")
		(net "PCIE_RX_P58")
	)
	(segment
		(start 227.49383 -67.08902)
		(end 227.49383 -62.302136)
		(width 0.1016)
		(layer "In2.Cu")
		(net "PCIE_RX_P58")
	)
	(segment
		(start 228.26218 -81.46034)
		(end 227.858574 -79.172054)
		(width 0.1397)
		(layer "In2.Cu")
		(net "PCIE_RX_P58")
	)
	(segment
		(start 227.674932 -61.929772)
		(end 228.025706 -61.65342)
		(width 0.1016)
		(layer "In2.Cu")
		(net "PCIE_RX_P58")
	)
	(segment
		(start 140.335 -221.712028)
		(end 140.335 -220.094048)
		(width 0.1397)
		(layer "In2.Cu")
		(net "PCIE_RX_P58")
	)
	(segment
		(start 227.858574 -79.172054)
		(end 228.528118 -75.376532)
		(width 0.1397)
		(layer "In2.Cu")
		(net "PCIE_RX_P58")
	)
	(segment
		(start 226.98456 -88.70569)
		(end 228.26218 -81.46034)
		(width 0.1397)
		(layer "In2.Cu")
		(net "PCIE_RX_P58")
	)
	(segment
		(start 227.641404 -61.958728)
		(end 227.642674 -61.957712)
		(width 0.1016)
		(layer "In2.Cu")
		(net "PCIE_RX_P58")
	)
	(segment
		(start 227.45065 -69.26453)
		(end 227.45065 -67.1322)
		(width 0.1397)
		(layer "In2.Cu")
		(net "PCIE_RX_P58")
	)
	(segment
		(start 143.4846 -209.394044)
		(end 143.823436 -207.47101)
		(width 0.1397)
		(layer "In2.Cu")
		(net "PCIE_RX_P58")
	)
	(arc
		(start 228.025706 -61.65342)
		(mid 228.08062 -61.585145)
		(end 228.100128 -61.49975)
		(width 0.1016)
		(layer "In2.Cu")
		(net "PCIE_RX_P58")
	)
	(arc
		(start 140.0937 -222.294704)
		(mid 140.272327 -222.02737)
		(end 140.335 -221.712028)
		(width 0.1397)
		(layer "In2.Cu")
		(net "PCIE_RX_P58")
	)
	(arc
		(start 227.49383 -62.302136)
		(mid 227.532226 -62.115216)
		(end 227.641404 -61.958728)
		(width 0.1016)
		(layer "In2.Cu")
		(net "PCIE_RX_P58")
	)
	(arc
		(start 227.642674 -61.957712)
		(mid 227.658477 -61.943365)
		(end 227.674932 -61.929772)
		(width 0.1016)
		(layer "In2.Cu")
		(net "PCIE_RX_P58")
	)
	(segment
		(start 229.599998 -61.999876)
		(end 229.100126 -62.499748)
		(width 0.136652)
		(layer "F.Cu")
		(net "PCIE_RX_P57")
	)
	(via
		(at 143.293592 -222.294704)
		(size 0.508)
		(drill 0.254)
		(layers "F.Cu" "B.Cu")
		(net "PCIE_RX_P57")
	)
	(via
		(at 229.100126 -62.499748)
		(size 0.4572)
		(drill 0.2032)
		(layers "F.Cu" "B.Cu")
		(net "PCIE_RX_P57")
	)
	(segment
		(start 143.547592 -223.5962)
		(end 143.547592 -222.90786)
		(width 0.136652)
		(layer "B.Cu")
		(net "PCIE_RX_P57")
	)
	(segment
		(start 143.300196 -225.92538)
		(end 143.300196 -224.713546)
		(width 0.136652)
		(layer "B.Cu")
		(net "PCIE_RX_P57")
	)
	(segment
		(start 143.44015 -224.375726)
		(end 143.49095 -224.324926)
		(width 0.136652)
		(layer "B.Cu")
		(net "PCIE_RX_P57")
	)
	(segment
		(start 143.547846 -223.596454)
		(end 143.547592 -223.5962)
		(width 0.136652)
		(layer "B.Cu")
		(net "PCIE_RX_P57")
	)
	(segment
		(start 143.547846 -224.187512)
		(end 143.547846 -223.596454)
		(width 0.136652)
		(layer "B.Cu")
		(net "PCIE_RX_P57")
	)
	(arc
		(start 143.547592 -222.90786)
		(mid 143.481584 -222.576014)
		(end 143.293592 -222.294704)
		(width 0.136652)
		(layer "B.Cu")
		(net "PCIE_RX_P57")
	)
	(arc
		(start 143.300196 -224.713546)
		(mid 143.336564 -224.53071)
		(end 143.44015 -224.375726)
		(width 0.136652)
		(layer "B.Cu")
		(net "PCIE_RX_P57")
	)
	(arc
		(start 143.49095 -224.324926)
		(mid 143.533076 -224.26188)
		(end 143.547846 -224.187512)
		(width 0.136652)
		(layer "B.Cu")
		(net "PCIE_RX_P57")
	)
	(segment
		(start 146.7104 -208.97088)
		(end 147.47621 -204.626972)
		(width 0.1397)
		(layer "In2.Cu")
		(net "PCIE_RX_P57")
	)
	(segment
		(start 229.55504 -75.546458)
		(end 228.4476 -69.26453)
		(width 0.1397)
		(layer "In2.Cu")
		(net "PCIE_RX_P57")
	)
	(segment
		(start 228.4476 -69.26453)
		(end 228.4476 -67.1576)
		(width 0.1397)
		(layer "In2.Cu")
		(net "PCIE_RX_P57")
	)
	(segment
		(start 228.67493 -62.92977)
		(end 229.025704 -62.653418)
		(width 0.1016)
		(layer "In2.Cu")
		(net "PCIE_RX_P57")
	)
	(segment
		(start 143.534892 -219.329508)
		(end 146.383248 -215.261444)
		(width 0.1397)
		(layer "In2.Cu")
		(net "PCIE_RX_P57")
	)
	(segment
		(start 228.4476 -67.1576)
		(end 228.493828 -67.111372)
		(width 0.1016)
		(layer "In2.Cu")
		(net "PCIE_RX_P57")
	)
	(segment
		(start 228.641402 -62.958726)
		(end 228.642672 -62.95771)
		(width 0.1016)
		(layer "In2.Cu")
		(net "PCIE_RX_P57")
	)
	(segment
		(start 228.90861 -79.21244)
		(end 229.55504 -75.546458)
		(width 0.1397)
		(layer "In2.Cu")
		(net "PCIE_RX_P57")
	)
	(segment
		(start 229.399592 -81.99755)
		(end 228.90861 -79.21244)
		(width 0.1397)
		(layer "In2.Cu")
		(net "PCIE_RX_P57")
	)
	(segment
		(start 143.534892 -221.712028)
		(end 143.534892 -219.329508)
		(width 0.1397)
		(layer "In2.Cu")
		(net "PCIE_RX_P57")
	)
	(segment
		(start 146.7104 -213.407244)
		(end 146.7104 -208.97088)
		(width 0.1397)
		(layer "In2.Cu")
		(net "PCIE_RX_P57")
	)
	(segment
		(start 146.383248 -215.261444)
		(end 146.7104 -213.407244)
		(width 0.1397)
		(layer "In2.Cu")
		(net "PCIE_RX_P57")
	)
	(segment
		(start 228.072188 -89.52611)
		(end 229.399592 -81.99755)
		(width 0.1397)
		(layer "In2.Cu")
		(net "PCIE_RX_P57")
	)
	(segment
		(start 147.47621 -204.626972)
		(end 228.072188 -89.52611)
		(width 0.1397)
		(layer "In2.Cu")
		(net "PCIE_RX_P57")
	)
	(segment
		(start 228.493828 -67.111372)
		(end 228.493828 -63.302134)
		(width 0.1016)
		(layer "In2.Cu")
		(net "PCIE_RX_P57")
	)
	(arc
		(start 228.642672 -62.95771)
		(mid 228.658475 -62.943363)
		(end 228.67493 -62.92977)
		(width 0.1016)
		(layer "In2.Cu")
		(net "PCIE_RX_P57")
	)
	(arc
		(start 143.293592 -222.294704)
		(mid 143.472219 -222.02737)
		(end 143.534892 -221.712028)
		(width 0.1397)
		(layer "In2.Cu")
		(net "PCIE_RX_P57")
	)
	(arc
		(start 228.493828 -63.302134)
		(mid 228.532224 -63.115214)
		(end 228.641402 -62.958726)
		(width 0.1016)
		(layer "In2.Cu")
		(net "PCIE_RX_P57")
	)
	(arc
		(start 229.025704 -62.653418)
		(mid 229.080618 -62.585143)
		(end 229.100126 -62.499748)
		(width 0.1016)
		(layer "In2.Cu")
		(net "PCIE_RX_P57")
	)
	(segment
		(start 230.599996 -60.999878)
		(end 230.100124 -61.49975)
		(width 0.136652)
		(layer "F.Cu")
		(net "PCIE_RX_P56")
	)
	(via
		(at 230.100124 -61.49975)
		(size 0.4572)
		(drill 0.2032)
		(layers "F.Cu" "B.Cu")
		(net "PCIE_RX_P56")
	)
	(via
		(at 146.493738 -222.294704)
		(size 0.508)
		(drill 0.254)
		(layers "F.Cu" "B.Cu")
		(net "PCIE_RX_P56")
	)
	(segment
		(start 146.747738 -223.5962)
		(end 146.747738 -222.90786)
		(width 0.136652)
		(layer "B.Cu")
		(net "PCIE_RX_P56")
	)
	(segment
		(start 146.747992 -224.187512)
		(end 146.747992 -223.596454)
		(width 0.136652)
		(layer "B.Cu")
		(net "PCIE_RX_P56")
	)
	(segment
		(start 146.500088 -224.7138)
		(end 146.500342 -224.713546)
		(width 0.136652)
		(layer "B.Cu")
		(net "PCIE_RX_P56")
	)
	(segment
		(start 146.747992 -223.596454)
		(end 146.747738 -223.5962)
		(width 0.136652)
		(layer "B.Cu")
		(net "PCIE_RX_P56")
	)
	(segment
		(start 146.500088 -225.92538)
		(end 146.500088 -224.7138)
		(width 0.136652)
		(layer "B.Cu")
		(net "PCIE_RX_P56")
	)
	(segment
		(start 146.640296 -224.375726)
		(end 146.691096 -224.324926)
		(width 0.136652)
		(layer "B.Cu")
		(net "PCIE_RX_P56")
	)
	(arc
		(start 146.747738 -222.90786)
		(mid 146.68173 -222.576014)
		(end 146.493738 -222.294704)
		(width 0.136652)
		(layer "B.Cu")
		(net "PCIE_RX_P56")
	)
	(arc
		(start 146.691096 -224.324926)
		(mid 146.733222 -224.26188)
		(end 146.747992 -224.187512)
		(width 0.136652)
		(layer "B.Cu")
		(net "PCIE_RX_P56")
	)
	(arc
		(start 146.500342 -224.713546)
		(mid 146.53671 -224.53071)
		(end 146.640296 -224.375726)
		(width 0.136652)
		(layer "B.Cu")
		(net "PCIE_RX_P56")
	)
	(segment
		(start 149.686264 -215.119458)
		(end 149.9616 -213.559644)
		(width 0.1397)
		(layer "In2.Cu")
		(net "PCIE_RX_P56")
	)
	(segment
		(start 230.523796 -96.505268)
		(end 232.014014 -88.054942)
		(width 0.1397)
		(layer "In2.Cu")
		(net "PCIE_RX_P56")
	)
	(segment
		(start 229.79888 -61.831474)
		(end 229.829614 -61.807598)
		(width 0.1016)
		(layer "In2.Cu")
		(net "PCIE_RX_P56")
	)
	(segment
		(start 149.9616 -213.559644)
		(end 149.9616 -206.423514)
		(width 0.1397)
		(layer "In2.Cu")
		(net "PCIE_RX_P56")
	)
	(segment
		(start 229.493826 -67.101974)
		(end 229.493826 -62.302136)
		(width 0.1016)
		(layer "In2.Cu")
		(net "PCIE_RX_P56")
	)
	(segment
		(start 230.538274 -75.505056)
		(end 229.4382 -69.26453)
		(width 0.1397)
		(layer "In2.Cu")
		(net "PCIE_RX_P56")
	)
	(segment
		(start 149.9616 -206.423514)
		(end 150.436326 -203.73086)
		(width 0.1397)
		(layer "In2.Cu")
		(net "PCIE_RX_P56")
	)
	(segment
		(start 146.493738 -222.294704)
		(end 146.676364 -222.111824)
		(width 0.1397)
		(layer "In2.Cu")
		(net "PCIE_RX_P56")
	)
	(segment
		(start 229.829614 -61.807598)
		(end 229.87127 -61.774832)
		(width 0.1016)
		(layer "In2.Cu")
		(net "PCIE_RX_P56")
	)
	(segment
		(start 229.798118 -61.832236)
		(end 229.79888 -61.831474)
		(width 0.1016)
		(layer "In2.Cu")
		(net "PCIE_RX_P56")
	)
	(segment
		(start 150.436326 -203.73086)
		(end 158.213806 -192.62344)
		(width 0.1397)
		(layer "In2.Cu")
		(net "PCIE_RX_P56")
	)
	(segment
		(start 229.674928 -61.929772)
		(end 229.798118 -61.832236)
		(width 0.1016)
		(layer "In2.Cu")
		(net "PCIE_RX_P56")
	)
	(segment
		(start 168.037764 -185.744866)
		(end 230.523796 -96.505268)
		(width 0.1397)
		(layer "In2.Cu")
		(net "PCIE_RX_P56")
	)
	(segment
		(start 146.735038 -221.9706)
		(end 146.735038 -219.334588)
		(width 0.1397)
		(layer "In2.Cu")
		(net "PCIE_RX_P56")
	)
	(segment
		(start 158.213806 -192.62344)
		(end 168.037764 -185.744866)
		(width 0.1397)
		(layer "In2.Cu")
		(net "PCIE_RX_P56")
	)
	(segment
		(start 229.87127 -61.774832)
		(end 229.871524 -61.774324)
		(width 0.1016)
		(layer "In2.Cu")
		(net "PCIE_RX_P56")
	)
	(segment
		(start 229.6414 -61.958728)
		(end 229.64267 -61.957712)
		(width 0.1016)
		(layer "In2.Cu")
		(net "PCIE_RX_P56")
	)
	(segment
		(start 232.014014 -88.054942)
		(end 230.169466 -77.597)
		(width 0.1397)
		(layer "In2.Cu")
		(net "PCIE_RX_P56")
	)
	(segment
		(start 229.4382 -69.26453)
		(end 229.4382 -67.1576)
		(width 0.1397)
		(layer "In2.Cu")
		(net "PCIE_RX_P56")
	)
	(segment
		(start 229.871524 -61.774324)
		(end 230.025702 -61.65342)
		(width 0.1016)
		(layer "In2.Cu")
		(net "PCIE_RX_P56")
	)
	(segment
		(start 230.169466 -77.597)
		(end 230.538274 -75.505056)
		(width 0.1397)
		(layer "In2.Cu")
		(net "PCIE_RX_P56")
	)
	(segment
		(start 229.4382 -67.1576)
		(end 229.493826 -67.101974)
		(width 0.1016)
		(layer "In2.Cu")
		(net "PCIE_RX_P56")
	)
	(segment
		(start 146.735038 -219.334588)
		(end 149.686264 -215.119458)
		(width 0.1397)
		(layer "In2.Cu")
		(net "PCIE_RX_P56")
	)
	(arc
		(start 146.676364 -222.111824)
		(mid 146.719741 -222.047045)
		(end 146.735038 -221.9706)
		(width 0.1397)
		(layer "In2.Cu")
		(net "PCIE_RX_P56")
	)
	(arc
		(start 229.64267 -61.957712)
		(mid 229.658473 -61.943365)
		(end 229.674928 -61.929772)
		(width 0.1016)
		(layer "In2.Cu")
		(net "PCIE_RX_P56")
	)
	(arc
		(start 229.493826 -62.302136)
		(mid 229.532222 -62.115216)
		(end 229.6414 -61.958728)
		(width 0.1016)
		(layer "In2.Cu")
		(net "PCIE_RX_P56")
	)
	(arc
		(start 230.025702 -61.65342)
		(mid 230.080616 -61.585145)
		(end 230.100124 -61.49975)
		(width 0.1016)
		(layer "In2.Cu")
		(net "PCIE_RX_P56")
	)
	(segment
		(start 232.599992 -61.999876)
		(end 232.10012 -62.499748)
		(width 0.136652)
		(layer "F.Cu")
		(net "PCIE_RX_P55")
	)
	(via
		(at 232.10012 -62.499748)
		(size 0.4572)
		(drill 0.2032)
		(layers "F.Cu" "B.Cu")
		(net "PCIE_RX_P55")
	)
	(via
		(at 149.69363 -222.294704)
		(size 0.508)
		(drill 0.254)
		(layers "F.Cu" "B.Cu")
		(net "PCIE_RX_P55")
	)
	(segment
		(start 149.700234 -225.92538)
		(end 149.700234 -224.713546)
		(width 0.136652)
		(layer "B.Cu")
		(net "PCIE_RX_P55")
	)
	(segment
		(start 149.840188 -224.375726)
		(end 149.890988 -224.324926)
		(width 0.136652)
		(layer "B.Cu")
		(net "PCIE_RX_P55")
	)
	(segment
		(start 149.947884 -224.187512)
		(end 149.947884 -223.596454)
		(width 0.136652)
		(layer "B.Cu")
		(net "PCIE_RX_P55")
	)
	(segment
		(start 149.947884 -223.596454)
		(end 149.94763 -223.5962)
		(width 0.136652)
		(layer "B.Cu")
		(net "PCIE_RX_P55")
	)
	(segment
		(start 149.94763 -223.5962)
		(end 149.94763 -222.90786)
		(width 0.136652)
		(layer "B.Cu")
		(net "PCIE_RX_P55")
	)
	(arc
		(start 149.700234 -224.713546)
		(mid 149.736602 -224.53071)
		(end 149.840188 -224.375726)
		(width 0.136652)
		(layer "B.Cu")
		(net "PCIE_RX_P55")
	)
	(arc
		(start 149.94763 -222.90786)
		(mid 149.881622 -222.576014)
		(end 149.69363 -222.294704)
		(width 0.136652)
		(layer "B.Cu")
		(net "PCIE_RX_P55")
	)
	(arc
		(start 149.890988 -224.324926)
		(mid 149.933114 -224.26188)
		(end 149.947884 -224.187512)
		(width 0.136652)
		(layer "B.Cu")
		(net "PCIE_RX_P55")
	)
	(segment
		(start 232.078022 -74.40168)
		(end 231.290622 -69.935852)
		(width 0.1397)
		(layer "In2.Cu")
		(net "PCIE_RX_P55")
	)
	(segment
		(start 231.829356 -62.807342)
		(end 231.8512 -62.79007)
		(width 0.1016)
		(layer "In2.Cu")
		(net "PCIE_RX_P55")
	)
	(segment
		(start 231.90454 -62.748414)
		(end 232.026206 -62.652402)
		(width 0.1016)
		(layer "In2.Cu")
		(net "PCIE_RX_P55")
	)
	(segment
		(start 231.895904 -62.755272)
		(end 231.902 -62.7507)
		(width 0.1016)
		(layer "In2.Cu")
		(net "PCIE_RX_P55")
	)
	(segment
		(start 233.153204 -87.272114)
		(end 231.481122 -77.7875)
		(width 0.1397)
		(layer "In2.Cu")
		(net "PCIE_RX_P55")
	)
	(segment
		(start 231.4194 -67.2846)
		(end 231.493822 -67.210178)
		(width 0.1016)
		(layer "In2.Cu")
		(net "PCIE_RX_P55")
	)
	(segment
		(start 231.290622 -69.935852)
		(end 231.4194 -69.206618)
		(width 0.1397)
		(layer "In2.Cu")
		(net "PCIE_RX_P55")
	)
	(segment
		(start 152.7302 -216.06002)
		(end 153.162254 -213.610444)
		(width 0.1397)
		(layer "In2.Cu")
		(net "PCIE_RX_P55")
	)
	(segment
		(start 231.818434 -62.815724)
		(end 231.824276 -62.811152)
		(width 0.1016)
		(layer "In2.Cu")
		(net "PCIE_RX_P55")
	)
	(segment
		(start 153.162254 -213.610444)
		(end 153.162254 -209.532474)
		(width 0.1397)
		(layer "In2.Cu")
		(net "PCIE_RX_P55")
	)
	(segment
		(start 231.858058 -62.784736)
		(end 231.895904 -62.755272)
		(width 0.1016)
		(layer "In2.Cu")
		(net "PCIE_RX_P55")
	)
	(segment
		(start 153.162254 -209.532474)
		(end 231.262936 -97.992692)
		(width 0.1397)
		(layer "In2.Cu")
		(net "PCIE_RX_P55")
	)
	(segment
		(start 231.674924 -62.92977)
		(end 231.754172 -62.866524)
		(width 0.1016)
		(layer "In2.Cu")
		(net "PCIE_RX_P55")
	)
	(segment
		(start 231.493822 -67.210178)
		(end 231.493822 -63.302134)
		(width 0.1016)
		(layer "In2.Cu")
		(net "PCIE_RX_P55")
	)
	(segment
		(start 231.4194 -69.206618)
		(end 231.4194 -67.359276)
		(width 0.1397)
		(layer "In2.Cu")
		(net "PCIE_RX_P55")
	)
	(segment
		(start 231.262936 -97.992692)
		(end 233.153204 -87.272114)
		(width 0.1397)
		(layer "In2.Cu")
		(net "PCIE_RX_P55")
	)
	(segment
		(start 231.79786 -62.831726)
		(end 231.818434 -62.815724)
		(width 0.1016)
		(layer "In2.Cu")
		(net "PCIE_RX_P55")
	)
	(segment
		(start 231.641396 -62.958726)
		(end 231.642666 -62.95771)
		(width 0.1016)
		(layer "In2.Cu")
		(net "PCIE_RX_P55")
	)
	(segment
		(start 231.8512 -62.79007)
		(end 231.851454 -62.79007)
		(width 0.1016)
		(layer "In2.Cu")
		(net "PCIE_RX_P55")
	)
	(segment
		(start 231.902 -62.7507)
		(end 231.90454 -62.748414)
		(width 0.1016)
		(layer "In2.Cu")
		(net "PCIE_RX_P55")
	)
	(segment
		(start 149.93493 -220.052392)
		(end 152.7302 -216.06002)
		(width 0.1397)
		(layer "In2.Cu")
		(net "PCIE_RX_P55")
	)
	(segment
		(start 149.93493 -221.712028)
		(end 149.93493 -220.052392)
		(width 0.1397)
		(layer "In2.Cu")
		(net "PCIE_RX_P55")
	)
	(segment
		(start 231.4194 -67.359276)
		(end 231.4194 -67.2846)
		(width 0.1016)
		(layer "In2.Cu")
		(net "PCIE_RX_P55")
	)
	(segment
		(start 231.481122 -77.7875)
		(end 232.078022 -74.40168)
		(width 0.1397)
		(layer "In2.Cu")
		(net "PCIE_RX_P55")
	)
	(segment
		(start 231.851454 -62.79007)
		(end 231.858058 -62.784736)
		(width 0.1016)
		(layer "In2.Cu")
		(net "PCIE_RX_P55")
	)
	(segment
		(start 231.75468 -62.866016)
		(end 231.79786 -62.831726)
		(width 0.1016)
		(layer "In2.Cu")
		(net "PCIE_RX_P55")
	)
	(segment
		(start 231.754172 -62.866524)
		(end 231.75468 -62.866016)
		(width 0.1016)
		(layer "In2.Cu")
		(net "PCIE_RX_P55")
	)
	(segment
		(start 231.824276 -62.811152)
		(end 231.829356 -62.807342)
		(width 0.1016)
		(layer "In2.Cu")
		(net "PCIE_RX_P55")
	)
	(arc
		(start 149.69363 -222.294704)
		(mid 149.872257 -222.02737)
		(end 149.93493 -221.712028)
		(width 0.1397)
		(layer "In2.Cu")
		(net "PCIE_RX_P55")
	)
	(arc
		(start 231.543606 -63.090552)
		(mid 231.586743 -63.020368)
		(end 231.641396 -62.958726)
		(width 0.1016)
		(layer "In2.Cu")
		(net "PCIE_RX_P55")
	)
	(arc
		(start 231.493822 -63.302134)
		(mid 231.506419 -63.193453)
		(end 231.543606 -63.090552)
		(width 0.1016)
		(layer "In2.Cu")
		(net "PCIE_RX_P55")
	)
	(arc
		(start 232.026206 -62.652402)
		(mid 232.080678 -62.584554)
		(end 232.10012 -62.499748)
		(width 0.1016)
		(layer "In2.Cu")
		(net "PCIE_RX_P55")
	)
	(arc
		(start 231.642666 -62.95771)
		(mid 231.658469 -62.943363)
		(end 231.674924 -62.92977)
		(width 0.1016)
		(layer "In2.Cu")
		(net "PCIE_RX_P55")
	)
	(segment
		(start 233.59999 -60.999878)
		(end 233.100118 -61.49975)
		(width 0.136652)
		(layer "F.Cu")
		(net "PCIE_RX_P54")
	)
	(via
		(at 233.100118 -61.49975)
		(size 0.4572)
		(drill 0.2032)
		(layers "F.Cu" "B.Cu")
		(net "PCIE_RX_P54")
	)
	(via
		(at 152.893776 -222.294704)
		(size 0.508)
		(drill 0.254)
		(layers "F.Cu" "B.Cu")
		(net "PCIE_RX_P54")
	)
	(segment
		(start 153.14803 -224.187512)
		(end 153.14803 -223.596454)
		(width 0.136652)
		(layer "B.Cu")
		(net "PCIE_RX_P54")
	)
	(segment
		(start 153.14803 -223.596454)
		(end 153.147776 -223.5962)
		(width 0.136652)
		(layer "B.Cu")
		(net "PCIE_RX_P54")
	)
	(segment
		(start 153.147776 -223.5962)
		(end 153.147776 -222.90786)
		(width 0.136652)
		(layer "B.Cu")
		(net "PCIE_RX_P54")
	)
	(segment
		(start 152.900126 -225.92538)
		(end 152.900126 -224.7138)
		(width 0.136652)
		(layer "B.Cu")
		(net "PCIE_RX_P54")
	)
	(segment
		(start 152.900126 -224.7138)
		(end 152.90038 -224.713546)
		(width 0.136652)
		(layer "B.Cu")
		(net "PCIE_RX_P54")
	)
	(segment
		(start 153.040334 -224.375726)
		(end 153.091134 -224.324926)
		(width 0.136652)
		(layer "B.Cu")
		(net "PCIE_RX_P54")
	)
	(arc
		(start 153.091134 -224.324926)
		(mid 153.13326 -224.26188)
		(end 153.14803 -224.187512)
		(width 0.136652)
		(layer "B.Cu")
		(net "PCIE_RX_P54")
	)
	(arc
		(start 153.147776 -222.90786)
		(mid 153.081768 -222.576014)
		(end 152.893776 -222.294704)
		(width 0.136652)
		(layer "B.Cu")
		(net "PCIE_RX_P54")
	)
	(arc
		(start 152.90038 -224.713546)
		(mid 152.936748 -224.53071)
		(end 153.040334 -224.375726)
		(width 0.136652)
		(layer "B.Cu")
		(net "PCIE_RX_P54")
	)
	(segment
		(start 165.01872 -201.062082)
		(end 166.49827 -192.671446)
		(width 0.1397)
		(layer "In2.Cu")
		(net "PCIE_RX_P54")
	)
	(segment
		(start 232.858056 -61.784738)
		(end 232.895902 -61.755274)
		(width 0.1016)
		(layer "In2.Cu")
		(net "PCIE_RX_P54")
	)
	(segment
		(start 232.754678 -61.866018)
		(end 232.797858 -61.831728)
		(width 0.1016)
		(layer "In2.Cu")
		(net "PCIE_RX_P54")
	)
	(segment
		(start 232.4354 -69.206618)
		(end 232.4354 -67.308476)
		(width 0.1397)
		(layer "In2.Cu")
		(net "PCIE_RX_P54")
	)
	(segment
		(start 232.904538 -61.748416)
		(end 233.026204 -61.652404)
		(width 0.1016)
		(layer "In2.Cu")
		(net "PCIE_RX_P54")
	)
	(segment
		(start 159.512 -213.331044)
		(end 159.512 -208.926938)
		(width 0.1397)
		(layer "In2.Cu")
		(net "PCIE_RX_P54")
	)
	(segment
		(start 232.829354 -61.807344)
		(end 232.851198 -61.790072)
		(width 0.1016)
		(layer "In2.Cu")
		(net "PCIE_RX_P54")
	)
	(segment
		(start 232.51795 -77.675232)
		(end 233.037126 -74.730102)
		(width 0.1397)
		(layer "In2.Cu")
		(net "PCIE_RX_P54")
	)
	(segment
		(start 232.851452 -61.790072)
		(end 232.858056 -61.784738)
		(width 0.1016)
		(layer "In2.Cu")
		(net "PCIE_RX_P54")
	)
	(segment
		(start 232.75417 -61.866526)
		(end 232.754678 -61.866018)
		(width 0.1016)
		(layer "In2.Cu")
		(net "PCIE_RX_P54")
	)
	(segment
		(start 166.49827 -192.671446)
		(end 232.146094 -98.91649)
		(width 0.1397)
		(layer "In2.Cu")
		(net "PCIE_RX_P54")
	)
	(segment
		(start 232.824274 -61.811154)
		(end 232.829354 -61.807344)
		(width 0.1016)
		(layer "In2.Cu")
		(net "PCIE_RX_P54")
	)
	(segment
		(start 232.49382 -67.17538)
		(end 232.49382 -62.302136)
		(width 0.1016)
		(layer "In2.Cu")
		(net "PCIE_RX_P54")
	)
	(segment
		(start 234.204764 -87.241634)
		(end 232.51795 -77.675232)
		(width 0.1397)
		(layer "In2.Cu")
		(net "PCIE_RX_P54")
	)
	(segment
		(start 232.901998 -61.750702)
		(end 232.904538 -61.748416)
		(width 0.1016)
		(layer "In2.Cu")
		(net "PCIE_RX_P54")
	)
	(segment
		(start 232.851198 -61.790072)
		(end 232.851452 -61.790072)
		(width 0.1016)
		(layer "In2.Cu")
		(net "PCIE_RX_P54")
	)
	(segment
		(start 232.4354 -67.2338)
		(end 232.49382 -67.17538)
		(width 0.1016)
		(layer "In2.Cu")
		(net "PCIE_RX_P54")
	)
	(segment
		(start 232.146094 -98.91649)
		(end 234.204764 -87.241634)
		(width 0.1397)
		(layer "In2.Cu")
		(net "PCIE_RX_P54")
	)
	(segment
		(start 153.135076 -221.712028)
		(end 153.135076 -220.21038)
		(width 0.1397)
		(layer "In2.Cu")
		(net "PCIE_RX_P54")
	)
	(segment
		(start 232.818432 -61.815726)
		(end 232.824274 -61.811154)
		(width 0.1016)
		(layer "In2.Cu")
		(net "PCIE_RX_P54")
	)
	(segment
		(start 153.135076 -220.21038)
		(end 153.806144 -219.251784)
		(width 0.1397)
		(layer "In2.Cu")
		(net "PCIE_RX_P54")
	)
	(segment
		(start 158.665926 -215.848946)
		(end 159.202882 -215.08212)
		(width 0.1397)
		(layer "In2.Cu")
		(net "PCIE_RX_P54")
	)
	(segment
		(start 232.4354 -67.308476)
		(end 232.4354 -67.2338)
		(width 0.1016)
		(layer "In2.Cu")
		(net "PCIE_RX_P54")
	)
	(segment
		(start 232.641394 -61.958728)
		(end 232.642664 -61.957712)
		(width 0.1016)
		(layer "In2.Cu")
		(net "PCIE_RX_P54")
	)
	(segment
		(start 232.797858 -61.831728)
		(end 232.818432 -61.815726)
		(width 0.1016)
		(layer "In2.Cu")
		(net "PCIE_RX_P54")
	)
	(segment
		(start 153.806144 -219.251784)
		(end 158.665926 -215.848946)
		(width 0.1397)
		(layer "In2.Cu")
		(net "PCIE_RX_P54")
	)
	(segment
		(start 159.202882 -215.08212)
		(end 159.512 -213.331044)
		(width 0.1397)
		(layer "In2.Cu")
		(net "PCIE_RX_P54")
	)
	(segment
		(start 232.674922 -61.929772)
		(end 232.75417 -61.866526)
		(width 0.1016)
		(layer "In2.Cu")
		(net "PCIE_RX_P54")
	)
	(segment
		(start 159.512 -208.926938)
		(end 165.01872 -201.062082)
		(width 0.1397)
		(layer "In2.Cu")
		(net "PCIE_RX_P54")
	)
	(segment
		(start 232.895902 -61.755274)
		(end 232.901998 -61.750702)
		(width 0.1016)
		(layer "In2.Cu")
		(net "PCIE_RX_P54")
	)
	(segment
		(start 232.249218 -70.261734)
		(end 232.4354 -69.206618)
		(width 0.1397)
		(layer "In2.Cu")
		(net "PCIE_RX_P54")
	)
	(segment
		(start 233.037126 -74.730102)
		(end 232.249218 -70.261734)
		(width 0.1397)
		(layer "In2.Cu")
		(net "PCIE_RX_P54")
	)
	(arc
		(start 152.893776 -222.294704)
		(mid 153.072403 -222.02737)
		(end 153.135076 -221.712028)
		(width 0.1397)
		(layer "In2.Cu")
		(net "PCIE_RX_P54")
	)
	(arc
		(start 232.543604 -62.090554)
		(mid 232.586741 -62.02037)
		(end 232.641394 -61.958728)
		(width 0.1016)
		(layer "In2.Cu")
		(net "PCIE_RX_P54")
	)
	(arc
		(start 232.49382 -62.302136)
		(mid 232.506417 -62.193455)
		(end 232.543604 -62.090554)
		(width 0.1016)
		(layer "In2.Cu")
		(net "PCIE_RX_P54")
	)
	(arc
		(start 233.026204 -61.652404)
		(mid 233.080676 -61.584556)
		(end 233.100118 -61.49975)
		(width 0.1016)
		(layer "In2.Cu")
		(net "PCIE_RX_P54")
	)
	(arc
		(start 232.642664 -61.957712)
		(mid 232.658467 -61.943365)
		(end 232.674922 -61.929772)
		(width 0.1016)
		(layer "In2.Cu")
		(net "PCIE_RX_P54")
	)
	(segment
		(start 234.599988 -61.999876)
		(end 234.100116 -62.499748)
		(width 0.136652)
		(layer "F.Cu")
		(net "PCIE_RX_P53")
	)
	(via
		(at 156.093668 -222.294704)
		(size 0.508)
		(drill 0.254)
		(layers "F.Cu" "B.Cu")
		(net "PCIE_RX_P53")
	)
	(via
		(at 234.100116 -62.499748)
		(size 0.4572)
		(drill 0.2032)
		(layers "F.Cu" "B.Cu")
		(net "PCIE_RX_P53")
	)
	(segment
		(start 156.100018 -225.92538)
		(end 156.100018 -224.7138)
		(width 0.136652)
		(layer "B.Cu")
		(net "PCIE_RX_P53")
	)
	(segment
		(start 156.347668 -223.5962)
		(end 156.347668 -222.90786)
		(width 0.136652)
		(layer "B.Cu")
		(net "PCIE_RX_P53")
	)
	(segment
		(start 156.347922 -223.596454)
		(end 156.347668 -223.5962)
		(width 0.136652)
		(layer "B.Cu")
		(net "PCIE_RX_P53")
	)
	(segment
		(start 156.347922 -224.187512)
		(end 156.347922 -223.596454)
		(width 0.136652)
		(layer "B.Cu")
		(net "PCIE_RX_P53")
	)
	(segment
		(start 156.100018 -224.7138)
		(end 156.100272 -224.713546)
		(width 0.136652)
		(layer "B.Cu")
		(net "PCIE_RX_P53")
	)
	(segment
		(start 156.240226 -224.375726)
		(end 156.291026 -224.324926)
		(width 0.136652)
		(layer "B.Cu")
		(net "PCIE_RX_P53")
	)
	(arc
		(start 156.291026 -224.324926)
		(mid 156.333152 -224.26188)
		(end 156.347922 -224.187512)
		(width 0.136652)
		(layer "B.Cu")
		(net "PCIE_RX_P53")
	)
	(arc
		(start 156.100272 -224.713546)
		(mid 156.13664 -224.53071)
		(end 156.240226 -224.375726)
		(width 0.136652)
		(layer "B.Cu")
		(net "PCIE_RX_P53")
	)
	(arc
		(start 156.347668 -222.90786)
		(mid 156.28166 -222.576014)
		(end 156.093668 -222.294704)
		(width 0.136652)
		(layer "B.Cu")
		(net "PCIE_RX_P53")
	)
	(segment
		(start 233.797856 -62.831726)
		(end 233.81843 -62.815724)
		(width 0.1016)
		(layer "In2.Cu")
		(net "PCIE_RX_P53")
	)
	(segment
		(start 233.904536 -62.748414)
		(end 234.026202 -62.652402)
		(width 0.1016)
		(layer "In2.Cu")
		(net "PCIE_RX_P53")
	)
	(segment
		(start 233.4006 -69.206618)
		(end 233.4006 -67.2338)
		(width 0.1397)
		(layer "In2.Cu")
		(net "PCIE_RX_P53")
	)
	(segment
		(start 156.334968 -221.712028)
		(end 156.334968 -220.523054)
		(width 0.1397)
		(layer "In2.Cu")
		(net "PCIE_RX_P53")
	)
	(segment
		(start 233.641392 -62.958726)
		(end 233.642662 -62.95771)
		(width 0.1016)
		(layer "In2.Cu")
		(net "PCIE_RX_P53")
	)
	(segment
		(start 233.851196 -62.79007)
		(end 233.85145 -62.79007)
		(width 0.1016)
		(layer "In2.Cu")
		(net "PCIE_RX_P53")
	)
	(segment
		(start 233.901996 -62.7507)
		(end 233.904536 -62.748414)
		(width 0.1016)
		(layer "In2.Cu")
		(net "PCIE_RX_P53")
	)
	(segment
		(start 233.8959 -62.755272)
		(end 233.901996 -62.7507)
		(width 0.1016)
		(layer "In2.Cu")
		(net "PCIE_RX_P53")
	)
	(segment
		(start 233.67492 -62.92977)
		(end 233.754168 -62.866524)
		(width 0.1016)
		(layer "In2.Cu")
		(net "PCIE_RX_P53")
	)
	(segment
		(start 156.334968 -220.523054)
		(end 157.196028 -219.293186)
		(width 0.1397)
		(layer "In2.Cu")
		(net "PCIE_RX_P53")
	)
	(segment
		(start 165.707822 -203.393294)
		(end 231.273858 -109.754924)
		(width 0.1397)
		(layer "In2.Cu")
		(net "PCIE_RX_P53")
	)
	(segment
		(start 233.858054 -62.784736)
		(end 233.8959 -62.755272)
		(width 0.1016)
		(layer "In2.Cu")
		(net "PCIE_RX_P53")
	)
	(segment
		(start 233.504232 -77.625194)
		(end 233.979466 -74.93)
		(width 0.1397)
		(layer "In2.Cu")
		(net "PCIE_RX_P53")
	)
	(segment
		(start 233.185462 -70.427088)
		(end 233.4006 -69.206618)
		(width 0.1397)
		(layer "In2.Cu")
		(net "PCIE_RX_P53")
	)
	(segment
		(start 233.979466 -74.93)
		(end 233.185462 -70.427088)
		(width 0.1397)
		(layer "In2.Cu")
		(net "PCIE_RX_P53")
	)
	(segment
		(start 233.754168 -62.866524)
		(end 233.754676 -62.866016)
		(width 0.1016)
		(layer "In2.Cu")
		(net "PCIE_RX_P53")
	)
	(segment
		(start 233.824272 -62.811152)
		(end 233.829352 -62.807342)
		(width 0.1016)
		(layer "In2.Cu")
		(net "PCIE_RX_P53")
	)
	(segment
		(start 161.509964 -216.272364)
		(end 164.08527 -212.594444)
		(width 0.1397)
		(layer "In2.Cu")
		(net "PCIE_RX_P53")
	)
	(segment
		(start 233.829352 -62.807342)
		(end 233.851196 -62.79007)
		(width 0.1016)
		(layer "In2.Cu")
		(net "PCIE_RX_P53")
	)
	(segment
		(start 157.196028 -219.293186)
		(end 161.509964 -216.272364)
		(width 0.1397)
		(layer "In2.Cu")
		(net "PCIE_RX_P53")
	)
	(segment
		(start 233.754676 -62.866016)
		(end 233.797856 -62.831726)
		(width 0.1016)
		(layer "In2.Cu")
		(net "PCIE_RX_P53")
	)
	(segment
		(start 233.493818 -67.140582)
		(end 233.493818 -63.302134)
		(width 0.1016)
		(layer "In2.Cu")
		(net "PCIE_RX_P53")
	)
	(segment
		(start 235.22178 -87.36584)
		(end 233.504232 -77.625194)
		(width 0.1397)
		(layer "In2.Cu")
		(net "PCIE_RX_P53")
	)
	(segment
		(start 231.273858 -109.754924)
		(end 235.22178 -87.36584)
		(width 0.1397)
		(layer "In2.Cu")
		(net "PCIE_RX_P53")
	)
	(segment
		(start 233.85145 -62.79007)
		(end 233.858054 -62.784736)
		(width 0.1016)
		(layer "In2.Cu")
		(net "PCIE_RX_P53")
	)
	(segment
		(start 233.81843 -62.815724)
		(end 233.824272 -62.811152)
		(width 0.1016)
		(layer "In2.Cu")
		(net "PCIE_RX_P53")
	)
	(segment
		(start 233.4006 -67.2338)
		(end 233.493818 -67.140582)
		(width 0.1016)
		(layer "In2.Cu")
		(net "PCIE_RX_P53")
	)
	(segment
		(start 164.08527 -212.594444)
		(end 165.707822 -203.393294)
		(width 0.1397)
		(layer "In2.Cu")
		(net "PCIE_RX_P53")
	)
	(arc
		(start 233.493818 -63.302134)
		(mid 233.506415 -63.193453)
		(end 233.543602 -63.090552)
		(width 0.1016)
		(layer "In2.Cu")
		(net "PCIE_RX_P53")
	)
	(arc
		(start 233.642662 -62.95771)
		(mid 233.658465 -62.943363)
		(end 233.67492 -62.92977)
		(width 0.1016)
		(layer "In2.Cu")
		(net "PCIE_RX_P53")
	)
	(arc
		(start 233.543602 -63.090552)
		(mid 233.586739 -63.020368)
		(end 233.641392 -62.958726)
		(width 0.1016)
		(layer "In2.Cu")
		(net "PCIE_RX_P53")
	)
	(arc
		(start 234.026202 -62.652402)
		(mid 234.080674 -62.584554)
		(end 234.100116 -62.499748)
		(width 0.1016)
		(layer "In2.Cu")
		(net "PCIE_RX_P53")
	)
	(arc
		(start 156.093668 -222.294704)
		(mid 156.272295 -222.02737)
		(end 156.334968 -221.712028)
		(width 0.1397)
		(layer "In2.Cu")
		(net "PCIE_RX_P53")
	)
	(segment
		(start 235.599986 -60.999878)
		(end 235.100114 -61.49975)
		(width 0.136652)
		(layer "F.Cu")
		(net "PCIE_RX_P52")
	)
	(via
		(at 159.29356 -222.294704)
		(size 0.508)
		(drill 0.254)
		(layers "F.Cu" "B.Cu")
		(net "PCIE_RX_P52")
	)
	(via
		(at 235.100114 -61.49975)
		(size 0.4572)
		(drill 0.2032)
		(layers "F.Cu" "B.Cu")
		(net "PCIE_RX_P52")
	)
	(segment
		(start 159.547814 -223.596454)
		(end 159.54756 -223.5962)
		(width 0.136652)
		(layer "B.Cu")
		(net "PCIE_RX_P52")
	)
	(segment
		(start 159.300164 -225.92538)
		(end 159.300164 -224.713546)
		(width 0.136652)
		(layer "B.Cu")
		(net "PCIE_RX_P52")
	)
	(segment
		(start 159.54756 -223.5962)
		(end 159.54756 -222.90786)
		(width 0.136652)
		(layer "B.Cu")
		(net "PCIE_RX_P52")
	)
	(segment
		(start 159.547814 -224.187512)
		(end 159.547814 -223.596454)
		(width 0.136652)
		(layer "B.Cu")
		(net "PCIE_RX_P52")
	)
	(segment
		(start 159.440118 -224.375726)
		(end 159.490918 -224.324926)
		(width 0.136652)
		(layer "B.Cu")
		(net "PCIE_RX_P52")
	)
	(arc
		(start 159.54756 -222.90786)
		(mid 159.481552 -222.576014)
		(end 159.29356 -222.294704)
		(width 0.136652)
		(layer "B.Cu")
		(net "PCIE_RX_P52")
	)
	(arc
		(start 159.490918 -224.324926)
		(mid 159.533044 -224.26188)
		(end 159.547814 -224.187512)
		(width 0.136652)
		(layer "B.Cu")
		(net "PCIE_RX_P52")
	)
	(arc
		(start 159.300164 -224.713546)
		(mid 159.336532 -224.53071)
		(end 159.440118 -224.375726)
		(width 0.136652)
		(layer "B.Cu")
		(net "PCIE_RX_P52")
	)
	(segment
		(start 234.797854 -61.831728)
		(end 234.818428 -61.815726)
		(width 0.1016)
		(layer "In2.Cu")
		(net "PCIE_RX_P52")
	)
	(segment
		(start 161.337244 -218.40952)
		(end 164.118798 -217.919046)
		(width 0.1397)
		(layer "In2.Cu")
		(net "PCIE_RX_P52")
	)
	(segment
		(start 234.895898 -61.755274)
		(end 234.901994 -61.750702)
		(width 0.1016)
		(layer "In2.Cu")
		(net "PCIE_RX_P52")
	)
	(segment
		(start 159.53486 -221.712028)
		(end 159.53486 -220.037406)
		(width 0.1397)
		(layer "In2.Cu")
		(net "PCIE_RX_P52")
	)
	(segment
		(start 168.103042 -214.256112)
		(end 168.574466 -211.582)
		(width 0.1397)
		(layer "In2.Cu")
		(net "PCIE_RX_P52")
	)
	(segment
		(start 169.97553 -200.46188)
		(end 232.053384 -111.806228)
		(width 0.1397)
		(layer "In2.Cu")
		(net "PCIE_RX_P52")
	)
	(segment
		(start 164.118798 -217.919046)
		(end 164.382196 -217.734642)
		(width 0.1397)
		(layer "In2.Cu")
		(net "PCIE_RX_P52")
	)
	(segment
		(start 234.858052 -61.784738)
		(end 234.895898 -61.755274)
		(width 0.1016)
		(layer "In2.Cu")
		(net "PCIE_RX_P52")
	)
	(segment
		(start 234.64139 -61.958728)
		(end 234.64266 -61.957712)
		(width 0.1016)
		(layer "In2.Cu")
		(net "PCIE_RX_P52")
	)
	(segment
		(start 234.851194 -61.790072)
		(end 234.851448 -61.790072)
		(width 0.1016)
		(layer "In2.Cu")
		(net "PCIE_RX_P52")
	)
	(segment
		(start 235.038646 -75.475084)
		(end 234.187492 -70.648576)
		(width 0.1397)
		(layer "In2.Cu")
		(net "PCIE_RX_P52")
	)
	(segment
		(start 234.901994 -61.750702)
		(end 234.904534 -61.748416)
		(width 0.1016)
		(layer "In2.Cu")
		(net "PCIE_RX_P52")
	)
	(segment
		(start 234.754166 -61.866526)
		(end 234.754674 -61.866018)
		(width 0.1016)
		(layer "In2.Cu")
		(net "PCIE_RX_P52")
	)
	(segment
		(start 234.493816 -67.181984)
		(end 234.493816 -62.302136)
		(width 0.1016)
		(layer "In2.Cu")
		(net "PCIE_RX_P52")
	)
	(segment
		(start 234.442 -67.2338)
		(end 234.493816 -67.181984)
		(width 0.1016)
		(layer "In2.Cu")
		(net "PCIE_RX_P52")
	)
	(segment
		(start 232.053384 -111.806228)
		(end 236.313218 -87.648288)
		(width 0.1397)
		(layer "In2.Cu")
		(net "PCIE_RX_P52")
	)
	(segment
		(start 234.851448 -61.790072)
		(end 234.858052 -61.784738)
		(width 0.1016)
		(layer "In2.Cu")
		(net "PCIE_RX_P52")
	)
	(segment
		(start 234.442 -67.308476)
		(end 234.442 -67.2338)
		(width 0.1016)
		(layer "In2.Cu")
		(net "PCIE_RX_P52")
	)
	(segment
		(start 160.036764 -219.320364)
		(end 161.337244 -218.40952)
		(width 0.1397)
		(layer "In2.Cu")
		(net "PCIE_RX_P52")
	)
	(segment
		(start 234.602782 -77.94752)
		(end 235.038646 -75.475084)
		(width 0.1397)
		(layer "In2.Cu")
		(net "PCIE_RX_P52")
	)
	(segment
		(start 234.818428 -61.815726)
		(end 234.82427 -61.811154)
		(width 0.1016)
		(layer "In2.Cu")
		(net "PCIE_RX_P52")
	)
	(segment
		(start 234.754674 -61.866018)
		(end 234.797854 -61.831728)
		(width 0.1016)
		(layer "In2.Cu")
		(net "PCIE_RX_P52")
	)
	(segment
		(start 159.53486 -220.037406)
		(end 160.036764 -219.320364)
		(width 0.1397)
		(layer "In2.Cu")
		(net "PCIE_RX_P52")
	)
	(segment
		(start 166.903654 -215.968834)
		(end 168.103042 -214.256112)
		(width 0.1397)
		(layer "In2.Cu")
		(net "PCIE_RX_P52")
	)
	(segment
		(start 234.442 -69.206618)
		(end 234.442 -67.308476)
		(width 0.1397)
		(layer "In2.Cu")
		(net "PCIE_RX_P52")
	)
	(segment
		(start 234.674918 -61.929772)
		(end 234.754166 -61.866526)
		(width 0.1016)
		(layer "In2.Cu")
		(net "PCIE_RX_P52")
	)
	(segment
		(start 236.313218 -87.648288)
		(end 234.602782 -77.94752)
		(width 0.1397)
		(layer "In2.Cu")
		(net "PCIE_RX_P52")
	)
	(segment
		(start 168.294558 -209.9945)
		(end 169.97553 -200.46188)
		(width 0.1397)
		(layer "In2.Cu")
		(net "PCIE_RX_P52")
	)
	(segment
		(start 234.187492 -70.648576)
		(end 234.442 -69.206618)
		(width 0.1397)
		(layer "In2.Cu")
		(net "PCIE_RX_P52")
	)
	(segment
		(start 234.82935 -61.807344)
		(end 234.851194 -61.790072)
		(width 0.1016)
		(layer "In2.Cu")
		(net "PCIE_RX_P52")
	)
	(segment
		(start 234.82427 -61.811154)
		(end 234.82935 -61.807344)
		(width 0.1016)
		(layer "In2.Cu")
		(net "PCIE_RX_P52")
	)
	(segment
		(start 164.382196 -217.734642)
		(end 166.903654 -215.968834)
		(width 0.1397)
		(layer "In2.Cu")
		(net "PCIE_RX_P52")
	)
	(segment
		(start 234.904534 -61.748416)
		(end 235.0262 -61.652404)
		(width 0.1016)
		(layer "In2.Cu")
		(net "PCIE_RX_P52")
	)
	(segment
		(start 168.574466 -211.582)
		(end 168.294558 -209.9945)
		(width 0.1397)
		(layer "In2.Cu")
		(net "PCIE_RX_P52")
	)
	(arc
		(start 234.5436 -62.090554)
		(mid 234.586737 -62.02037)
		(end 234.64139 -61.958728)
		(width 0.1016)
		(layer "In2.Cu")
		(net "PCIE_RX_P52")
	)
	(arc
		(start 159.29356 -222.294704)
		(mid 159.472187 -222.02737)
		(end 159.53486 -221.712028)
		(width 0.1397)
		(layer "In2.Cu")
		(net "PCIE_RX_P52")
	)
	(arc
		(start 235.0262 -61.652404)
		(mid 235.080672 -61.584556)
		(end 235.100114 -61.49975)
		(width 0.1016)
		(layer "In2.Cu")
		(net "PCIE_RX_P52")
	)
	(arc
		(start 234.493816 -62.302136)
		(mid 234.506413 -62.193455)
		(end 234.5436 -62.090554)
		(width 0.1016)
		(layer "In2.Cu")
		(net "PCIE_RX_P52")
	)
	(arc
		(start 234.64266 -61.957712)
		(mid 234.658463 -61.943365)
		(end 234.674918 -61.929772)
		(width 0.1016)
		(layer "In2.Cu")
		(net "PCIE_RX_P52")
	)
	(segment
		(start 236.599984 -61.999876)
		(end 236.100112 -62.499748)
		(width 0.136652)
		(layer "F.Cu")
		(net "PCIE_RX_P51")
	)
	(via
		(at 164.893752 -222.294704)
		(size 0.508)
		(drill 0.254)
		(layers "F.Cu" "B.Cu")
		(net "PCIE_RX_P51")
	)
	(via
		(at 236.100112 -62.499748)
		(size 0.4572)
		(drill 0.2032)
		(layers "F.Cu" "B.Cu")
		(net "PCIE_RX_P51")
	)
	(segment
		(start 164.900102 -225.92538)
		(end 164.900102 -224.7138)
		(width 0.136652)
		(layer "B.Cu")
		(net "PCIE_RX_P51")
	)
	(segment
		(start 165.147752 -223.5962)
		(end 165.147752 -222.90786)
		(width 0.136652)
		(layer "B.Cu")
		(net "PCIE_RX_P51")
	)
	(segment
		(start 164.900102 -224.7138)
		(end 164.900356 -224.713546)
		(width 0.136652)
		(layer "B.Cu")
		(net "PCIE_RX_P51")
	)
	(segment
		(start 165.04031 -224.375726)
		(end 165.09111 -224.324926)
		(width 0.136652)
		(layer "B.Cu")
		(net "PCIE_RX_P51")
	)
	(segment
		(start 165.148006 -224.187512)
		(end 165.148006 -223.596454)
		(width 0.136652)
		(layer "B.Cu")
		(net "PCIE_RX_P51")
	)
	(segment
		(start 165.148006 -223.596454)
		(end 165.147752 -223.5962)
		(width 0.136652)
		(layer "B.Cu")
		(net "PCIE_RX_P51")
	)
	(arc
		(start 164.900356 -224.713546)
		(mid 164.936724 -224.53071)
		(end 165.04031 -224.375726)
		(width 0.136652)
		(layer "B.Cu")
		(net "PCIE_RX_P51")
	)
	(arc
		(start 165.09111 -224.324926)
		(mid 165.133236 -224.26188)
		(end 165.148006 -224.187512)
		(width 0.136652)
		(layer "B.Cu")
		(net "PCIE_RX_P51")
	)
	(arc
		(start 165.147752 -222.90786)
		(mid 165.081744 -222.576014)
		(end 164.893752 -222.294704)
		(width 0.136652)
		(layer "B.Cu")
		(net "PCIE_RX_P51")
	)
	(segment
		(start 237.44047 -88.072468)
		(end 233.214164 -112.041686)
		(width 0.1397)
		(layer "In2.Cu")
		(net "PCIE_RX_P51")
	)
	(segment
		(start 235.85805 -62.784736)
		(end 235.851446 -62.79007)
		(width 0.1016)
		(layer "In2.Cu")
		(net "PCIE_RX_P51")
	)
	(segment
		(start 176.598834 -192.89649)
		(end 174.312326 -205.86446)
		(width 0.1397)
		(layer "In2.Cu")
		(net "PCIE_RX_P51")
	)
	(segment
		(start 235.904532 -62.748414)
		(end 235.901992 -62.7507)
		(width 0.1016)
		(layer "In2.Cu")
		(net "PCIE_RX_P51")
	)
	(segment
		(start 174.312326 -205.86446)
		(end 171.5008 -209.8802)
		(width 0.1397)
		(layer "In2.Cu")
		(net "PCIE_RX_P51")
	)
	(segment
		(start 235.754672 -62.866016)
		(end 235.754164 -62.866524)
		(width 0.1016)
		(layer "In2.Cu")
		(net "PCIE_RX_P51")
	)
	(segment
		(start 235.818426 -62.815724)
		(end 235.797852 -62.831726)
		(width 0.1016)
		(layer "In2.Cu")
		(net "PCIE_RX_P51")
	)
	(segment
		(start 235.642658 -62.95771)
		(end 235.641388 -62.958726)
		(width 0.1016)
		(layer "In2.Cu")
		(net "PCIE_RX_P51")
	)
	(segment
		(start 235.493814 -67.253866)
		(end 235.4326 -67.31508)
		(width 0.1016)
		(layer "In2.Cu")
		(net "PCIE_RX_P51")
	)
	(segment
		(start 235.895896 -62.755272)
		(end 235.85805 -62.784736)
		(width 0.1016)
		(layer "In2.Cu")
		(net "PCIE_RX_P51")
	)
	(segment
		(start 235.797852 -62.831726)
		(end 235.754672 -62.866016)
		(width 0.1016)
		(layer "In2.Cu")
		(net "PCIE_RX_P51")
	)
	(segment
		(start 236.538516 -75.538838)
		(end 235.884466 -79.248)
		(width 0.1397)
		(layer "In2.Cu")
		(net "PCIE_RX_P51")
	)
	(segment
		(start 235.901992 -62.7507)
		(end 235.895896 -62.755272)
		(width 0.1016)
		(layer "In2.Cu")
		(net "PCIE_RX_P51")
	)
	(segment
		(start 171.35221 -214.223092)
		(end 169.90187 -216.294462)
		(width 0.1397)
		(layer "In2.Cu")
		(net "PCIE_RX_P51")
	)
	(segment
		(start 235.829348 -62.807342)
		(end 235.824268 -62.811152)
		(width 0.1016)
		(layer "In2.Cu")
		(net "PCIE_RX_P51")
	)
	(segment
		(start 235.851446 -62.79007)
		(end 235.851192 -62.79007)
		(width 0.1016)
		(layer "In2.Cu")
		(net "PCIE_RX_P51")
	)
	(segment
		(start 235.754164 -62.866524)
		(end 235.674916 -62.92977)
		(width 0.1016)
		(layer "In2.Cu")
		(net "PCIE_RX_P51")
	)
	(segment
		(start 235.884466 -79.248)
		(end 237.44047 -88.072468)
		(width 0.1397)
		(layer "In2.Cu")
		(net "PCIE_RX_P51")
	)
	(segment
		(start 236.026198 -62.652402)
		(end 235.904532 -62.748414)
		(width 0.1016)
		(layer "In2.Cu")
		(net "PCIE_RX_P51")
	)
	(segment
		(start 235.851192 -62.79007)
		(end 235.829348 -62.807342)
		(width 0.1016)
		(layer "In2.Cu")
		(net "PCIE_RX_P51")
	)
	(segment
		(start 169.90187 -216.294462)
		(end 166.264844 -218.841066)
		(width 0.1397)
		(layer "In2.Cu")
		(net "PCIE_RX_P51")
	)
	(segment
		(start 235.4326 -69.26453)
		(end 236.538516 -75.538838)
		(width 0.1397)
		(layer "In2.Cu")
		(net "PCIE_RX_P51")
	)
	(segment
		(start 235.824268 -62.811152)
		(end 235.818426 -62.815724)
		(width 0.1016)
		(layer "In2.Cu")
		(net "PCIE_RX_P51")
	)
	(segment
		(start 235.493814 -63.302134)
		(end 235.493814 -67.253866)
		(width 0.1016)
		(layer "In2.Cu")
		(net "PCIE_RX_P51")
	)
	(segment
		(start 171.5008 -213.381844)
		(end 171.35221 -214.223092)
		(width 0.1397)
		(layer "In2.Cu")
		(net "PCIE_RX_P51")
	)
	(segment
		(start 165.135052 -220.454728)
		(end 165.135052 -221.712028)
		(width 0.1397)
		(layer "In2.Cu")
		(net "PCIE_RX_P51")
	)
	(segment
		(start 235.4326 -67.31508)
		(end 235.4326 -67.34048)
		(width 0.1016)
		(layer "In2.Cu")
		(net "PCIE_RX_P51")
	)
	(segment
		(start 171.5008 -209.8802)
		(end 171.5008 -213.381844)
		(width 0.1397)
		(layer "In2.Cu")
		(net "PCIE_RX_P51")
	)
	(segment
		(start 235.4326 -67.34048)
		(end 235.4326 -69.26453)
		(width 0.1397)
		(layer "In2.Cu")
		(net "PCIE_RX_P51")
	)
	(segment
		(start 233.214164 -112.041686)
		(end 176.598834 -192.89649)
		(width 0.1397)
		(layer "In2.Cu")
		(net "PCIE_RX_P51")
	)
	(segment
		(start 166.264844 -218.841066)
		(end 165.135052 -220.454728)
		(width 0.1397)
		(layer "In2.Cu")
		(net "PCIE_RX_P51")
	)
	(arc
		(start 236.100112 -62.499748)
		(mid 236.080659 -62.584549)
		(end 236.026198 -62.652402)
		(width 0.1016)
		(layer "In2.Cu")
		(net "PCIE_RX_P51")
	)
	(arc
		(start 235.674916 -62.92977)
		(mid 235.658465 -62.943368)
		(end 235.642658 -62.95771)
		(width 0.1016)
		(layer "In2.Cu")
		(net "PCIE_RX_P51")
	)
	(arc
		(start 235.543598 -63.090552)
		(mid 235.506362 -63.193441)
		(end 235.493814 -63.302134)
		(width 0.1016)
		(layer "In2.Cu")
		(net "PCIE_RX_P51")
	)
	(arc
		(start 165.135052 -221.712028)
		(mid 165.072331 -222.02735)
		(end 164.893752 -222.294704)
		(width 0.1397)
		(layer "In2.Cu")
		(net "PCIE_RX_P51")
	)
	(arc
		(start 235.641388 -62.958726)
		(mid 235.586724 -63.02036)
		(end 235.543598 -63.090552)
		(width 0.1016)
		(layer "In2.Cu")
		(net "PCIE_RX_P51")
	)
	(segment
		(start 237.599982 -60.999878)
		(end 237.10011 -61.49975)
		(width 0.136652)
		(layer "F.Cu")
		(net "PCIE_RX_P50")
	)
	(via
		(at 237.10011 -61.49975)
		(size 0.4572)
		(drill 0.2032)
		(layers "F.Cu" "B.Cu")
		(net "PCIE_RX_P50")
	)
	(via
		(at 168.093644 -222.294704)
		(size 0.508)
		(drill 0.254)
		(layers "F.Cu" "B.Cu")
		(net "PCIE_RX_P50")
	)
	(segment
		(start 168.347644 -223.5962)
		(end 168.347644 -222.90786)
		(width 0.136652)
		(layer "B.Cu")
		(net "PCIE_RX_P50")
	)
	(segment
		(start 168.347898 -223.596454)
		(end 168.347644 -223.5962)
		(width 0.136652)
		(layer "B.Cu")
		(net "PCIE_RX_P50")
	)
	(segment
		(start 168.240202 -224.375726)
		(end 168.291002 -224.324926)
		(width 0.136652)
		(layer "B.Cu")
		(net "PCIE_RX_P50")
	)
	(segment
		(start 168.099994 -224.7138)
		(end 168.100248 -224.713546)
		(width 0.136652)
		(layer "B.Cu")
		(net "PCIE_RX_P50")
	)
	(segment
		(start 168.099994 -225.92538)
		(end 168.099994 -224.7138)
		(width 0.136652)
		(layer "B.Cu")
		(net "PCIE_RX_P50")
	)
	(segment
		(start 168.347898 -224.187512)
		(end 168.347898 -223.596454)
		(width 0.136652)
		(layer "B.Cu")
		(net "PCIE_RX_P50")
	)
	(arc
		(start 168.291002 -224.324926)
		(mid 168.333128 -224.26188)
		(end 168.347898 -224.187512)
		(width 0.136652)
		(layer "B.Cu")
		(net "PCIE_RX_P50")
	)
	(arc
		(start 168.100248 -224.713546)
		(mid 168.136616 -224.53071)
		(end 168.240202 -224.375726)
		(width 0.136652)
		(layer "B.Cu")
		(net "PCIE_RX_P50")
	)
	(arc
		(start 168.347644 -222.90786)
		(mid 168.281636 -222.576014)
		(end 168.093644 -222.294704)
		(width 0.136652)
		(layer "B.Cu")
		(net "PCIE_RX_P50")
	)
	(segment
		(start 236.895894 -61.755274)
		(end 236.858048 -61.784738)
		(width 0.1016)
		(layer "In2.Cu")
		(net "PCIE_RX_P50")
	)
	(segment
		(start 236.78388 -79.167736)
		(end 238.38916 -88.27135)
		(width 0.1397)
		(layer "In2.Cu")
		(net "PCIE_RX_P50")
	)
	(segment
		(start 236.493812 -67.213988)
		(end 236.4232 -67.2846)
		(width 0.1016)
		(layer "In2.Cu")
		(net "PCIE_RX_P50")
	)
	(segment
		(start 236.493812 -62.302136)
		(end 236.493812 -67.213988)
		(width 0.1016)
		(layer "In2.Cu")
		(net "PCIE_RX_P50")
	)
	(segment
		(start 236.754162 -61.866526)
		(end 236.674914 -61.929772)
		(width 0.1016)
		(layer "In2.Cu")
		(net "PCIE_RX_P50")
	)
	(segment
		(start 236.829346 -61.807344)
		(end 236.824266 -61.811154)
		(width 0.1016)
		(layer "In2.Cu")
		(net "PCIE_RX_P50")
	)
	(segment
		(start 236.75467 -61.866018)
		(end 236.754162 -61.866526)
		(width 0.1016)
		(layer "In2.Cu")
		(net "PCIE_RX_P50")
	)
	(segment
		(start 236.642656 -61.957712)
		(end 236.641386 -61.958728)
		(width 0.1016)
		(layer "In2.Cu")
		(net "PCIE_RX_P50")
	)
	(segment
		(start 236.90199 -61.750702)
		(end 236.895894 -61.755274)
		(width 0.1016)
		(layer "In2.Cu")
		(net "PCIE_RX_P50")
	)
	(segment
		(start 236.90453 -61.748416)
		(end 236.90199 -61.750702)
		(width 0.1016)
		(layer "In2.Cu")
		(net "PCIE_RX_P50")
	)
	(segment
		(start 183.837326 -196.84746)
		(end 174.7266 -209.859118)
		(width 0.1397)
		(layer "In2.Cu")
		(net "PCIE_RX_P50")
	)
	(segment
		(start 168.334944 -220.409262)
		(end 168.334944 -221.712028)
		(width 0.1397)
		(layer "In2.Cu")
		(net "PCIE_RX_P50")
	)
	(segment
		(start 174.7266 -213.458044)
		(end 174.549816 -214.460074)
		(width 0.1397)
		(layer "In2.Cu")
		(net "PCIE_RX_P50")
	)
	(segment
		(start 237.476538 -75.239118)
		(end 236.78388 -79.167736)
		(width 0.1397)
		(layer "In2.Cu")
		(net "PCIE_RX_P50")
	)
	(segment
		(start 234.20578 -111.996474)
		(end 186.881516 -179.582572)
		(width 0.1397)
		(layer "In2.Cu")
		(net "PCIE_RX_P50")
	)
	(segment
		(start 173.287944 -216.262204)
		(end 169.267124 -219.07754)
		(width 0.1397)
		(layer "In2.Cu")
		(net "PCIE_RX_P50")
	)
	(segment
		(start 174.549816 -214.460074)
		(end 173.287944 -216.262204)
		(width 0.1397)
		(layer "In2.Cu")
		(net "PCIE_RX_P50")
	)
	(segment
		(start 186.881516 -179.582572)
		(end 183.837326 -196.84746)
		(width 0.1397)
		(layer "In2.Cu")
		(net "PCIE_RX_P50")
	)
	(segment
		(start 237.026196 -61.652404)
		(end 236.90453 -61.748416)
		(width 0.1016)
		(layer "In2.Cu")
		(net "PCIE_RX_P50")
	)
	(segment
		(start 236.858048 -61.784738)
		(end 236.851444 -61.790072)
		(width 0.1016)
		(layer "In2.Cu")
		(net "PCIE_RX_P50")
	)
	(segment
		(start 236.85119 -61.790072)
		(end 236.829346 -61.807344)
		(width 0.1016)
		(layer "In2.Cu")
		(net "PCIE_RX_P50")
	)
	(segment
		(start 236.79785 -61.831728)
		(end 236.75467 -61.866018)
		(width 0.1016)
		(layer "In2.Cu")
		(net "PCIE_RX_P50")
	)
	(segment
		(start 236.4232 -67.2846)
		(end 236.4232 -67.359276)
		(width 0.1016)
		(layer "In2.Cu")
		(net "PCIE_RX_P50")
	)
	(segment
		(start 236.4232 -67.359276)
		(end 236.4232 -69.26453)
		(width 0.1397)
		(layer "In2.Cu")
		(net "PCIE_RX_P50")
	)
	(segment
		(start 238.38916 -88.27135)
		(end 234.20578 -111.996474)
		(width 0.1397)
		(layer "In2.Cu")
		(net "PCIE_RX_P50")
	)
	(segment
		(start 236.4232 -69.26453)
		(end 237.476538 -75.239118)
		(width 0.1397)
		(layer "In2.Cu")
		(net "PCIE_RX_P50")
	)
	(segment
		(start 169.267124 -219.07754)
		(end 168.334944 -220.409262)
		(width 0.1397)
		(layer "In2.Cu")
		(net "PCIE_RX_P50")
	)
	(segment
		(start 174.7266 -209.859118)
		(end 174.7266 -213.458044)
		(width 0.1397)
		(layer "In2.Cu")
		(net "PCIE_RX_P50")
	)
	(segment
		(start 236.818424 -61.815726)
		(end 236.79785 -61.831728)
		(width 0.1016)
		(layer "In2.Cu")
		(net "PCIE_RX_P50")
	)
	(segment
		(start 236.851444 -61.790072)
		(end 236.85119 -61.790072)
		(width 0.1016)
		(layer "In2.Cu")
		(net "PCIE_RX_P50")
	)
	(segment
		(start 236.824266 -61.811154)
		(end 236.818424 -61.815726)
		(width 0.1016)
		(layer "In2.Cu")
		(net "PCIE_RX_P50")
	)
	(arc
		(start 237.10011 -61.49975)
		(mid 237.080657 -61.584551)
		(end 237.026196 -61.652404)
		(width 0.1016)
		(layer "In2.Cu")
		(net "PCIE_RX_P50")
	)
	(arc
		(start 236.641386 -61.958728)
		(mid 236.586722 -62.020362)
		(end 236.543596 -62.090554)
		(width 0.1016)
		(layer "In2.Cu")
		(net "PCIE_RX_P50")
	)
	(arc
		(start 168.334944 -221.712028)
		(mid 168.272223 -222.02735)
		(end 168.093644 -222.294704)
		(width 0.1397)
		(layer "In2.Cu")
		(net "PCIE_RX_P50")
	)
	(arc
		(start 236.674914 -61.929772)
		(mid 236.658463 -61.94337)
		(end 236.642656 -61.957712)
		(width 0.1016)
		(layer "In2.Cu")
		(net "PCIE_RX_P50")
	)
	(arc
		(start 236.543596 -62.090554)
		(mid 236.50636 -62.193443)
		(end 236.493812 -62.302136)
		(width 0.1016)
		(layer "In2.Cu")
		(net "PCIE_RX_P50")
	)
	(segment
		(start 247.599962 -31.999936)
		(end 248.099834 -31.500064)
		(width 0.136652)
		(layer "F.Cu")
		(net "PCIE_RX_P5")
	)
	(via
		(at 248.099834 -31.500064)
		(size 0.4572)
		(drill 0.2032)
		(layers "F.Cu" "B.Cu")
		(net "PCIE_RX_P5")
	)
	(segment
		(start 294.376602 -17.789652)
		(end 294.49141 -18.441162)
		(width 0.1397)
		(layer "In2.Cu")
		(net "PCIE_RX_P5")
	)
	(segment
		(start 263.661906 -22.1234)
		(end 260.487414 -22.758146)
		(width 0.1397)
		(layer "In2.Cu")
		(net "PCIE_RX_P5")
	)
	(segment
		(start 297.601386 -15.388082)
		(end 294.891206 -16.604742)
		(width 0.1397)
		(layer "In2.Cu")
		(net "PCIE_RX_P5")
	)
	(segment
		(start 293.753286 -21.879814)
		(end 293.720012 -21.927058)
		(width 0.1397)
		(layer "In2.Cu")
		(net "PCIE_RX_P5")
	)
	(segment
		(start 273.950684 -22.377654)
		(end 271.504664 -21.946362)
		(width 0.1397)
		(layer "In2.Cu")
		(net "PCIE_RX_P5")
	)
	(segment
		(start 293.753286 -21.87956)
		(end 293.753286 -21.879814)
		(width 0.1397)
		(layer "In2.Cu")
		(net "PCIE_RX_P5")
	)
	(segment
		(start 260.487414 -22.758146)
		(end 257.311906 -22.1234)
		(width 0.1397)
		(layer "In2.Cu")
		(net "PCIE_RX_P5")
	)
	(segment
		(start 276.93493 -21.85162)
		(end 273.950684 -22.377654)
		(width 0.1397)
		(layer "In2.Cu")
		(net "PCIE_RX_P5")
	)
	(segment
		(start 298.472352 -15.706344)
		(end 298.326556 -15.609824)
		(width 0.1397)
		(layer "In2.Cu")
		(net "PCIE_RX_P5")
	)
	(segment
		(start 292.723062 -22.625812)
		(end 289.89528 -23.124414)
		(width 0.1397)
		(layer "In2.Cu")
		(net "PCIE_RX_P5")
	)
	(segment
		(start 298.180506 -15.51305)
		(end 297.601386 -15.388082)
		(width 0.1397)
		(layer "In2.Cu")
		(net "PCIE_RX_P5")
	)
	(segment
		(start 294.626538 -19.207226)
		(end 294.290242 -21.112988)
		(width 0.1397)
		(layer "In2.Cu")
		(net "PCIE_RX_P5")
	)
	(segment
		(start 253.628906 -22.7584)
		(end 248.340372 -28.04668)
		(width 0.1397)
		(layer "In2.Cu")
		(net "PCIE_RX_P5")
	)
	(segment
		(start 284.403038 -23.168356)
		(end 276.93493 -21.85162)
		(width 0.1397)
		(layer "In2.Cu")
		(net "PCIE_RX_P5")
	)
	(segment
		(start 293.720012 -21.927058)
		(end 292.723062 -22.625812)
		(width 0.1397)
		(layer "In2.Cu")
		(net "PCIE_RX_P5")
	)
	(segment
		(start 294.290242 -21.112988)
		(end 293.753286 -21.87956)
		(width 0.1397)
		(layer "In2.Cu")
		(net "PCIE_RX_P5")
	)
	(segment
		(start 248.340372 -28.04668)
		(end 248.340372 -29.525976)
		(width 0.1397)
		(layer "In2.Cu")
		(net "PCIE_RX_P5")
	)
	(segment
		(start 266.866116 -22.764242)
		(end 263.661906 -22.1234)
		(width 0.1397)
		(layer "In2.Cu")
		(net "PCIE_RX_P5")
	)
	(segment
		(start 271.504664 -21.946362)
		(end 266.866116 -22.764242)
		(width 0.1397)
		(layer "In2.Cu")
		(net "PCIE_RX_P5")
	)
	(segment
		(start 289.89528 -23.124414)
		(end 287.274 -22.662134)
		(width 0.1397)
		(layer "In2.Cu")
		(net "PCIE_RX_P5")
	)
	(segment
		(start 298.326556 -15.609824)
		(end 298.180506 -15.51305)
		(width 0.1397)
		(layer "In2.Cu")
		(net "PCIE_RX_P5")
	)
	(segment
		(start 294.49141 -18.441162)
		(end 294.626538 -19.207226)
		(width 0.1397)
		(layer "In2.Cu")
		(net "PCIE_RX_P5")
	)
	(segment
		(start 294.464486 -17.291558)
		(end 294.376602 -17.789652)
		(width 0.1397)
		(layer "In2.Cu")
		(net "PCIE_RX_P5")
	)
	(segment
		(start 294.50157 -17.080992)
		(end 294.464486 -17.291558)
		(width 0.1397)
		(layer "In2.Cu")
		(net "PCIE_RX_P5")
	)
	(segment
		(start 257.311906 -22.1234)
		(end 253.628906 -22.7584)
		(width 0.1397)
		(layer "In2.Cu")
		(net "PCIE_RX_P5")
	)
	(segment
		(start 294.891206 -16.604742)
		(end 294.50157 -17.080992)
		(width 0.1397)
		(layer "In2.Cu")
		(net "PCIE_RX_P5")
	)
	(segment
		(start 287.274 -22.662134)
		(end 284.403038 -23.168356)
		(width 0.1397)
		(layer "In2.Cu")
		(net "PCIE_RX_P5")
	)
	(arc
		(start 299.384466 -17.729962)
		(mid 299.336733 -17.230906)
		(end 299.14469 -16.76781)
		(width 0.1397)
		(layer "In2.Cu")
		(net "PCIE_RX_P5")
	)
	(arc
		(start 299.14469 -16.76781)
		(mid 299.091367 -16.66098)
		(end 299.055536 -16.547084)
		(width 0.1397)
		(layer "In2.Cu")
		(net "PCIE_RX_P5")
	)
	(arc
		(start 248.513346 -30.639258)
		(mid 248.379911 -31.104879)
		(end 248.099834 -31.500064)
		(width 0.1397)
		(layer "In2.Cu")
		(net "PCIE_RX_P5")
	)
	(arc
		(start 248.340372 -29.525976)
		(mid 248.346411 -29.672524)
		(end 248.364502 -29.818076)
		(width 0.1397)
		(layer "In2.Cu")
		(net "PCIE_RX_P5")
	)
	(arc
		(start 248.424446 -30.066742)
		(mid 248.506969 -30.347087)
		(end 248.513346 -30.639258)
		(width 0.1397)
		(layer "In2.Cu")
		(net "PCIE_RX_P5")
	)
	(arc
		(start 299.055536 -16.547084)
		(mid 298.844751 -16.070671)
		(end 298.472352 -15.706344)
		(width 0.1397)
		(layer "In2.Cu")
		(net "PCIE_RX_P5")
	)
	(arc
		(start 248.364502 -29.818076)
		(mid 248.390013 -29.943484)
		(end 248.424446 -30.066742)
		(width 0.1397)
		(layer "In2.Cu")
		(net "PCIE_RX_P5")
	)
	(segment
		(start 238.59998 -61.999876)
		(end 238.100108 -62.499748)
		(width 0.136652)
		(layer "F.Cu")
		(net "PCIE_RX_P49")
	)
	(via
		(at 238.100108 -62.499748)
		(size 0.4572)
		(drill 0.2032)
		(layers "F.Cu" "B.Cu")
		(net "PCIE_RX_P49")
	)
	(via
		(at 171.29379 -222.294704)
		(size 0.508)
		(drill 0.254)
		(layers "F.Cu" "B.Cu")
		(net "PCIE_RX_P49")
	)
	(segment
		(start 171.54779 -223.5962)
		(end 171.54779 -222.90786)
		(width 0.136652)
		(layer "B.Cu")
		(net "PCIE_RX_P49")
	)
	(segment
		(start 171.548044 -223.596454)
		(end 171.54779 -223.5962)
		(width 0.136652)
		(layer "B.Cu")
		(net "PCIE_RX_P49")
	)
	(segment
		(start 171.440348 -224.375726)
		(end 171.491148 -224.324926)
		(width 0.136652)
		(layer "B.Cu")
		(net "PCIE_RX_P49")
	)
	(segment
		(start 171.548044 -224.187512)
		(end 171.548044 -223.596454)
		(width 0.136652)
		(layer "B.Cu")
		(net "PCIE_RX_P49")
	)
	(segment
		(start 171.30014 -225.92538)
		(end 171.30014 -224.7138)
		(width 0.136652)
		(layer "B.Cu")
		(net "PCIE_RX_P49")
	)
	(segment
		(start 171.30014 -224.7138)
		(end 171.300394 -224.713546)
		(width 0.136652)
		(layer "B.Cu")
		(net "PCIE_RX_P49")
	)
	(arc
		(start 171.300394 -224.713546)
		(mid 171.336762 -224.53071)
		(end 171.440348 -224.375726)
		(width 0.136652)
		(layer "B.Cu")
		(net "PCIE_RX_P49")
	)
	(arc
		(start 171.491148 -224.324926)
		(mid 171.533274 -224.26188)
		(end 171.548044 -224.187512)
		(width 0.136652)
		(layer "B.Cu")
		(net "PCIE_RX_P49")
	)
	(arc
		(start 171.54779 -222.90786)
		(mid 171.481782 -222.576014)
		(end 171.29379 -222.294704)
		(width 0.136652)
		(layer "B.Cu")
		(net "PCIE_RX_P49")
	)
	(segment
		(start 237.901988 -62.7507)
		(end 237.895892 -62.755272)
		(width 0.1016)
		(layer "In2.Cu")
		(net "PCIE_RX_P49")
	)
	(segment
		(start 237.824264 -62.811152)
		(end 237.818422 -62.815724)
		(width 0.1016)
		(layer "In2.Cu")
		(net "PCIE_RX_P49")
	)
	(segment
		(start 237.818422 -62.815724)
		(end 237.797848 -62.831726)
		(width 0.1016)
		(layer "In2.Cu")
		(net "PCIE_RX_P49")
	)
	(segment
		(start 237.858046 -62.784736)
		(end 237.851442 -62.79007)
		(width 0.1016)
		(layer "In2.Cu")
		(net "PCIE_RX_P49")
	)
	(segment
		(start 237.4138 -69.704966)
		(end 238.424466 -75.438)
		(width 0.1397)
		(layer "In2.Cu")
		(net "PCIE_RX_P49")
	)
	(segment
		(start 237.49381 -63.302134)
		(end 237.49381 -67.22999)
		(width 0.1016)
		(layer "In2.Cu")
		(net "PCIE_RX_P49")
	)
	(segment
		(start 237.754668 -62.866016)
		(end 237.75416 -62.866524)
		(width 0.1016)
		(layer "In2.Cu")
		(net "PCIE_RX_P49")
	)
	(segment
		(start 235.067094 -113.327434)
		(end 196.57441 -168.301416)
		(width 0.1397)
		(layer "In2.Cu")
		(net "PCIE_RX_P49")
	)
	(segment
		(start 237.851442 -62.79007)
		(end 237.851188 -62.79007)
		(width 0.1016)
		(layer "In2.Cu")
		(net "PCIE_RX_P49")
	)
	(segment
		(start 238.424466 -75.438)
		(end 237.748572 -79.270606)
		(width 0.1397)
		(layer "In2.Cu")
		(net "PCIE_RX_P49")
	)
	(segment
		(start 191.064134 -199.552052)
		(end 187.24499 -205.006448)
		(width 0.1397)
		(layer "In2.Cu")
		(net "PCIE_RX_P49")
	)
	(segment
		(start 172.422058 -218.725496)
		(end 171.53509 -219.992194)
		(width 0.1397)
		(layer "In2.Cu")
		(net "PCIE_RX_P49")
	)
	(segment
		(start 237.829344 -62.807342)
		(end 237.824264 -62.811152)
		(width 0.1016)
		(layer "In2.Cu")
		(net "PCIE_RX_P49")
	)
	(segment
		(start 237.748572 -79.270606)
		(end 239.410494 -88.696038)
		(width 0.1397)
		(layer "In2.Cu")
		(net "PCIE_RX_P49")
	)
	(segment
		(start 237.75416 -62.866524)
		(end 237.674912 -62.92977)
		(width 0.1016)
		(layer "In2.Cu")
		(net "PCIE_RX_P49")
	)
	(segment
		(start 196.57441 -168.301416)
		(end 191.064134 -199.552052)
		(width 0.1397)
		(layer "In2.Cu")
		(net "PCIE_RX_P49")
	)
	(segment
		(start 187.24499 -205.006448)
		(end 183.4896 -207.3148)
		(width 0.1397)
		(layer "In2.Cu")
		(net "PCIE_RX_P49")
	)
	(segment
		(start 171.53509 -219.992194)
		(end 171.53509 -221.712028)
		(width 0.1397)
		(layer "In2.Cu")
		(net "PCIE_RX_P49")
	)
	(segment
		(start 238.026194 -62.652402)
		(end 237.904528 -62.748414)
		(width 0.1016)
		(layer "In2.Cu")
		(net "PCIE_RX_P49")
	)
	(segment
		(start 175.540162 -216.542112)
		(end 172.422058 -218.725496)
		(width 0.1397)
		(layer "In2.Cu")
		(net "PCIE_RX_P49")
	)
	(segment
		(start 237.49381 -67.22999)
		(end 237.4138 -67.31)
		(width 0.1016)
		(layer "In2.Cu")
		(net "PCIE_RX_P49")
	)
	(segment
		(start 237.851188 -62.79007)
		(end 237.829344 -62.807342)
		(width 0.1016)
		(layer "In2.Cu")
		(net "PCIE_RX_P49")
	)
	(segment
		(start 237.642654 -62.95771)
		(end 237.641384 -62.958726)
		(width 0.1016)
		(layer "In2.Cu")
		(net "PCIE_RX_P49")
	)
	(segment
		(start 183.4896 -207.3148)
		(end 179.336446 -211.120736)
		(width 0.1397)
		(layer "In2.Cu")
		(net "PCIE_RX_P49")
	)
	(segment
		(start 239.410494 -88.696038)
		(end 235.067094 -113.327434)
		(width 0.1397)
		(layer "In2.Cu")
		(net "PCIE_RX_P49")
	)
	(segment
		(start 237.904528 -62.748414)
		(end 237.901988 -62.7507)
		(width 0.1016)
		(layer "In2.Cu")
		(net "PCIE_RX_P49")
	)
	(segment
		(start 237.895892 -62.755272)
		(end 237.858046 -62.784736)
		(width 0.1016)
		(layer "In2.Cu")
		(net "PCIE_RX_P49")
	)
	(segment
		(start 179.336446 -211.120736)
		(end 175.540162 -216.542112)
		(width 0.1397)
		(layer "In2.Cu")
		(net "PCIE_RX_P49")
	)
	(segment
		(start 237.4138 -67.31)
		(end 237.4138 -69.704966)
		(width 0.1397)
		(layer "In2.Cu")
		(net "PCIE_RX_P49")
	)
	(segment
		(start 237.797848 -62.831726)
		(end 237.754668 -62.866016)
		(width 0.1016)
		(layer "In2.Cu")
		(net "PCIE_RX_P49")
	)
	(arc
		(start 238.100108 -62.499748)
		(mid 238.080655 -62.584549)
		(end 238.026194 -62.652402)
		(width 0.1016)
		(layer "In2.Cu")
		(net "PCIE_RX_P49")
	)
	(arc
		(start 237.641384 -62.958726)
		(mid 237.58672 -63.02036)
		(end 237.543594 -63.090552)
		(width 0.1016)
		(layer "In2.Cu")
		(net "PCIE_RX_P49")
	)
	(arc
		(start 171.53509 -221.712028)
		(mid 171.472369 -222.02735)
		(end 171.29379 -222.294704)
		(width 0.1397)
		(layer "In2.Cu")
		(net "PCIE_RX_P49")
	)
	(arc
		(start 237.674912 -62.92977)
		(mid 237.658461 -62.943368)
		(end 237.642654 -62.95771)
		(width 0.1016)
		(layer "In2.Cu")
		(net "PCIE_RX_P49")
	)
	(arc
		(start 237.543594 -63.090552)
		(mid 237.506358 -63.193441)
		(end 237.49381 -63.302134)
		(width 0.1016)
		(layer "In2.Cu")
		(net "PCIE_RX_P49")
	)
	(segment
		(start 239.599978 -60.999878)
		(end 239.100106 -61.49975)
		(width 0.136652)
		(layer "F.Cu")
		(net "PCIE_RX_P48")
	)
	(via
		(at 239.100106 -61.49975)
		(size 0.4572)
		(drill 0.2032)
		(layers "F.Cu" "B.Cu")
		(net "PCIE_RX_P48")
	)
	(via
		(at 174.493682 -222.294704)
		(size 0.508)
		(drill 0.254)
		(layers "F.Cu" "B.Cu")
		(net "PCIE_RX_P48")
	)
	(segment
		(start 174.500032 -224.7138)
		(end 174.500286 -224.713546)
		(width 0.136652)
		(layer "B.Cu")
		(net "PCIE_RX_P48")
	)
	(segment
		(start 174.64024 -224.375726)
		(end 174.69104 -224.324926)
		(width 0.136652)
		(layer "B.Cu")
		(net "PCIE_RX_P48")
	)
	(segment
		(start 174.500032 -225.92538)
		(end 174.500032 -224.7138)
		(width 0.136652)
		(layer "B.Cu")
		(net "PCIE_RX_P48")
	)
	(segment
		(start 174.747936 -223.596454)
		(end 174.747682 -223.5962)
		(width 0.136652)
		(layer "B.Cu")
		(net "PCIE_RX_P48")
	)
	(segment
		(start 174.747936 -224.187512)
		(end 174.747936 -223.596454)
		(width 0.136652)
		(layer "B.Cu")
		(net "PCIE_RX_P48")
	)
	(segment
		(start 174.747682 -223.5962)
		(end 174.747682 -222.90786)
		(width 0.136652)
		(layer "B.Cu")
		(net "PCIE_RX_P48")
	)
	(arc
		(start 174.69104 -224.324926)
		(mid 174.733166 -224.26188)
		(end 174.747936 -224.187512)
		(width 0.136652)
		(layer "B.Cu")
		(net "PCIE_RX_P48")
	)
	(arc
		(start 174.500286 -224.713546)
		(mid 174.536654 -224.53071)
		(end 174.64024 -224.375726)
		(width 0.136652)
		(layer "B.Cu")
		(net "PCIE_RX_P48")
	)
	(arc
		(start 174.747682 -222.90786)
		(mid 174.681674 -222.576014)
		(end 174.493682 -222.294704)
		(width 0.136652)
		(layer "B.Cu")
		(net "PCIE_RX_P48")
	)
	(segment
		(start 238.4298 -67.3354)
		(end 238.4298 -69.26453)
		(width 0.1397)
		(layer "In2.Cu")
		(net "PCIE_RX_P48")
	)
	(segment
		(start 238.824262 -61.811154)
		(end 238.81842 -61.815726)
		(width 0.1016)
		(layer "In2.Cu")
		(net "PCIE_RX_P48")
	)
	(segment
		(start 238.754158 -61.866526)
		(end 238.67491 -61.929772)
		(width 0.1016)
		(layer "In2.Cu")
		(net "PCIE_RX_P48")
	)
	(segment
		(start 238.858044 -61.784738)
		(end 238.85144 -61.790072)
		(width 0.1016)
		(layer "In2.Cu")
		(net "PCIE_RX_P48")
	)
	(segment
		(start 238.493808 -62.302136)
		(end 238.493808 -67.271392)
		(width 0.1016)
		(layer "In2.Cu")
		(net "PCIE_RX_P48")
	)
	(segment
		(start 238.901986 -61.750702)
		(end 238.89589 -61.755274)
		(width 0.1016)
		(layer "In2.Cu")
		(net "PCIE_RX_P48")
	)
	(segment
		(start 238.4298 -69.26453)
		(end 239.557306 -75.662028)
		(width 0.1397)
		(layer "In2.Cu")
		(net "PCIE_RX_P48")
	)
	(segment
		(start 238.493808 -67.271392)
		(end 238.4298 -67.3354)
		(width 0.1016)
		(layer "In2.Cu")
		(net "PCIE_RX_P48")
	)
	(segment
		(start 238.85144 -61.790072)
		(end 238.851186 -61.790072)
		(width 0.1016)
		(layer "In2.Cu")
		(net "PCIE_RX_P48")
	)
	(segment
		(start 238.829342 -61.807344)
		(end 238.824262 -61.811154)
		(width 0.1016)
		(layer "In2.Cu")
		(net "PCIE_RX_P48")
	)
	(segment
		(start 187.363608 -206.775812)
		(end 183.7436 -208.3308)
		(width 0.1397)
		(layer "In2.Cu")
		(net "PCIE_RX_P48")
	)
	(segment
		(start 174.734982 -219.870528)
		(end 174.734982 -221.712028)
		(width 0.1397)
		(layer "In2.Cu")
		(net "PCIE_RX_P48")
	)
	(segment
		(start 238.642652 -61.957712)
		(end 238.641382 -61.958728)
		(width 0.1016)
		(layer "In2.Cu")
		(net "PCIE_RX_P48")
	)
	(segment
		(start 238.851186 -61.790072)
		(end 238.829342 -61.807344)
		(width 0.1016)
		(layer "In2.Cu")
		(net "PCIE_RX_P48")
	)
	(segment
		(start 239.557306 -75.662028)
		(end 238.828326 -79.796894)
		(width 0.1397)
		(layer "In2.Cu")
		(net "PCIE_RX_P48")
	)
	(segment
		(start 197.475602 -169.49166)
		(end 192.092326 -200.02246)
		(width 0.1397)
		(layer "In2.Cu")
		(net "PCIE_RX_P48")
	)
	(segment
		(start 238.797846 -61.831728)
		(end 238.754666 -61.866018)
		(width 0.1016)
		(layer "In2.Cu")
		(net "PCIE_RX_P48")
	)
	(segment
		(start 238.81842 -61.815726)
		(end 238.797846 -61.831728)
		(width 0.1016)
		(layer "In2.Cu")
		(net "PCIE_RX_P48")
	)
	(segment
		(start 239.026192 -61.652404)
		(end 238.904526 -61.748416)
		(width 0.1016)
		(layer "In2.Cu")
		(net "PCIE_RX_P48")
	)
	(segment
		(start 240.444528 -88.9635)
		(end 235.929678 -114.573812)
		(width 0.1397)
		(layer "In2.Cu")
		(net "PCIE_RX_P48")
	)
	(segment
		(start 238.754666 -61.866018)
		(end 238.754158 -61.866526)
		(width 0.1016)
		(layer "In2.Cu")
		(net "PCIE_RX_P48")
	)
	(segment
		(start 235.929678 -114.573812)
		(end 197.475602 -169.49166)
		(width 0.1397)
		(layer "In2.Cu")
		(net "PCIE_RX_P48")
	)
	(segment
		(start 180.575204 -211.529168)
		(end 174.734982 -219.870528)
		(width 0.1397)
		(layer "In2.Cu")
		(net "PCIE_RX_P48")
	)
	(segment
		(start 192.092326 -200.02246)
		(end 187.363608 -206.775812)
		(width 0.1397)
		(layer "In2.Cu")
		(net "PCIE_RX_P48")
	)
	(segment
		(start 238.904526 -61.748416)
		(end 238.901986 -61.750702)
		(width 0.1016)
		(layer "In2.Cu")
		(net "PCIE_RX_P48")
	)
	(segment
		(start 238.828326 -79.796894)
		(end 240.444528 -88.9635)
		(width 0.1397)
		(layer "In2.Cu")
		(net "PCIE_RX_P48")
	)
	(segment
		(start 238.89589 -61.755274)
		(end 238.858044 -61.784738)
		(width 0.1016)
		(layer "In2.Cu")
		(net "PCIE_RX_P48")
	)
	(segment
		(start 183.7436 -208.3308)
		(end 180.575204 -211.529168)
		(width 0.1397)
		(layer "In2.Cu")
		(net "PCIE_RX_P48")
	)
	(arc
		(start 174.734982 -221.712028)
		(mid 174.672261 -222.02735)
		(end 174.493682 -222.294704)
		(width 0.1397)
		(layer "In2.Cu")
		(net "PCIE_RX_P48")
	)
	(arc
		(start 238.641382 -61.958728)
		(mid 238.586718 -62.020362)
		(end 238.543592 -62.090554)
		(width 0.1016)
		(layer "In2.Cu")
		(net "PCIE_RX_P48")
	)
	(arc
		(start 239.100106 -61.49975)
		(mid 239.080653 -61.584551)
		(end 239.026192 -61.652404)
		(width 0.1016)
		(layer "In2.Cu")
		(net "PCIE_RX_P48")
	)
	(arc
		(start 238.67491 -61.929772)
		(mid 238.658459 -61.94337)
		(end 238.642652 -61.957712)
		(width 0.1016)
		(layer "In2.Cu")
		(net "PCIE_RX_P48")
	)
	(arc
		(start 238.543592 -62.090554)
		(mid 238.506356 -62.193443)
		(end 238.493808 -62.302136)
		(width 0.1016)
		(layer "In2.Cu")
		(net "PCIE_RX_P48")
	)
	(segment
		(start 241.599974 -60.999878)
		(end 242.099846 -61.49975)
		(width 0.136652)
		(layer "F.Cu")
		(net "PCIE_RX_P47")
	)
	(via
		(at 242.099846 -61.49975)
		(size 0.4572)
		(drill 0.2032)
		(layers "F.Cu" "B.Cu")
		(net "PCIE_RX_P47")
	)
	(via
		(at 177.5968 -220.6752)
		(size 0.508)
		(drill 0.254)
		(layers "F.Cu" "B.Cu")
		(net "PCIE_RX_P47")
	)
	(segment
		(start 177.840132 -224.375726)
		(end 177.890932 -224.324926)
		(width 0.136652)
		(layer "B.Cu")
		(net "PCIE_RX_P47")
	)
	(segment
		(start 177.947828 -224.187512)
		(end 177.947828 -223.596454)
		(width 0.136652)
		(layer "B.Cu")
		(net "PCIE_RX_P47")
	)
	(segment
		(start 177.947574 -223.5962)
		(end 177.947574 -221.279212)
		(width 0.136652)
		(layer "B.Cu")
		(net "PCIE_RX_P47")
	)
	(segment
		(start 177.947828 -223.596454)
		(end 177.947574 -223.5962)
		(width 0.136652)
		(layer "B.Cu")
		(net "PCIE_RX_P47")
	)
	(segment
		(start 177.768504 -220.846904)
		(end 177.5968 -220.6752)
		(width 0.136652)
		(layer "B.Cu")
		(net "PCIE_RX_P47")
	)
	(segment
		(start 177.700178 -225.92538)
		(end 177.700178 -224.713546)
		(width 0.136652)
		(layer "B.Cu")
		(net "PCIE_RX_P47")
	)
	(arc
		(start 177.890932 -224.324926)
		(mid 177.933058 -224.26188)
		(end 177.947828 -224.187512)
		(width 0.136652)
		(layer "B.Cu")
		(net "PCIE_RX_P47")
	)
	(arc
		(start 177.700178 -224.713546)
		(mid 177.736546 -224.53071)
		(end 177.840132 -224.375726)
		(width 0.136652)
		(layer "B.Cu")
		(net "PCIE_RX_P47")
	)
	(arc
		(start 177.947574 -221.279212)
		(mid 177.901036 -221.045248)
		(end 177.768504 -220.846904)
		(width 0.136652)
		(layer "B.Cu")
		(net "PCIE_RX_P47")
	)
	(segment
		(start 241.753898 -61.866526)
		(end 241.67465 -61.929772)
		(width 0.1016)
		(layer "In2.Cu")
		(net "PCIE_RX_P47")
	)
	(segment
		(start 241.493548 -62.302136)
		(end 241.493548 -67.141852)
		(width 0.1016)
		(layer "In2.Cu")
		(net "PCIE_RX_P47")
	)
	(segment
		(start 177.8381 -218.49969)
		(end 177.8381 -220.008196)
		(width 0.1397)
		(layer "In2.Cu")
		(net "PCIE_RX_P47")
	)
	(segment
		(start 241.599466 -89.281)
		(end 237.071662 -114.960146)
		(width 0.1397)
		(layer "In2.Cu")
		(net "PCIE_RX_P47")
	)
	(segment
		(start 189.0776 -209.463894)
		(end 189.0776 -213.331044)
		(width 0.1397)
		(layer "In2.Cu")
		(net "PCIE_RX_P47")
	)
	(segment
		(start 200.09993 -167.760904)
		(end 193.532252 -205.008988)
		(width 0.1397)
		(layer "In2.Cu")
		(net "PCIE_RX_P47")
	)
	(segment
		(start 237.071662 -114.960146)
		(end 200.09993 -167.760904)
		(width 0.1397)
		(layer "In2.Cu")
		(net "PCIE_RX_P47")
	)
	(segment
		(start 241.850926 -61.790072)
		(end 241.829082 -61.807344)
		(width 0.1016)
		(layer "In2.Cu")
		(net "PCIE_RX_P47")
	)
	(segment
		(start 241.797586 -61.831728)
		(end 241.754406 -61.866018)
		(width 0.1016)
		(layer "In2.Cu")
		(net "PCIE_RX_P47")
	)
	(segment
		(start 241.754406 -61.866018)
		(end 241.753898 -61.866526)
		(width 0.1016)
		(layer "In2.Cu")
		(net "PCIE_RX_P47")
	)
	(segment
		(start 241.901726 -61.750702)
		(end 241.89563 -61.755274)
		(width 0.1016)
		(layer "In2.Cu")
		(net "PCIE_RX_P47")
	)
	(segment
		(start 241.89563 -61.755274)
		(end 241.883692 -61.764164)
		(width 0.1016)
		(layer "In2.Cu")
		(net "PCIE_RX_P47")
	)
	(segment
		(start 241.642392 -61.957712)
		(end 241.641122 -61.958728)
		(width 0.1016)
		(layer "In2.Cu")
		(net "PCIE_RX_P47")
	)
	(segment
		(start 187.000388 -216.033858)
		(end 185.258964 -216.753948)
		(width 0.1397)
		(layer "In2.Cu")
		(net "PCIE_RX_P47")
	)
	(segment
		(start 181.3814 -216.732866)
		(end 179.240688 -217.11031)
		(width 0.1397)
		(layer "In2.Cu")
		(net "PCIE_RX_P47")
	)
	(segment
		(start 241.81816 -61.815726)
		(end 241.797586 -61.831728)
		(width 0.1016)
		(layer "In2.Cu")
		(net "PCIE_RX_P47")
	)
	(segment
		(start 178.397408 -217.70086)
		(end 177.8381 -218.49969)
		(width 0.1397)
		(layer "In2.Cu")
		(net "PCIE_RX_P47")
	)
	(segment
		(start 241.4016 -71.263764)
		(end 239.91189 -79.710534)
		(width 0.1397)
		(layer "In2.Cu")
		(net "PCIE_RX_P47")
	)
	(segment
		(start 189.0776 -213.331044)
		(end 188.934598 -214.140288)
		(width 0.1397)
		(layer "In2.Cu")
		(net "PCIE_RX_P47")
	)
	(segment
		(start 241.879628 -61.767466)
		(end 241.857784 -61.784738)
		(width 0.1016)
		(layer "In2.Cu")
		(net "PCIE_RX_P47")
	)
	(segment
		(start 241.883692 -61.764164)
		(end 241.879628 -61.767466)
		(width 0.1016)
		(layer "In2.Cu")
		(net "PCIE_RX_P47")
	)
	(segment
		(start 188.194188 -215.197944)
		(end 187.001404 -216.03335)
		(width 0.1397)
		(layer "In2.Cu")
		(net "PCIE_RX_P47")
	)
	(segment
		(start 187.001404 -216.03335)
		(end 187.000388 -216.033858)
		(width 0.1397)
		(layer "In2.Cu")
		(net "PCIE_RX_P47")
	)
	(segment
		(start 193.532252 -205.008988)
		(end 189.0776 -209.463894)
		(width 0.1397)
		(layer "In2.Cu")
		(net "PCIE_RX_P47")
	)
	(segment
		(start 185.258964 -216.753948)
		(end 183.380126 -217.085418)
		(width 0.1397)
		(layer "In2.Cu")
		(net "PCIE_RX_P47")
	)
	(segment
		(start 241.4016 -67.2338)
		(end 241.4016 -71.263764)
		(width 0.1397)
		(layer "In2.Cu")
		(net "PCIE_RX_P47")
	)
	(segment
		(start 188.934598 -214.140288)
		(end 188.194188 -215.197944)
		(width 0.1397)
		(layer "In2.Cu")
		(net "PCIE_RX_P47")
	)
	(segment
		(start 242.025932 -61.652404)
		(end 241.904266 -61.748416)
		(width 0.1016)
		(layer "In2.Cu")
		(net "PCIE_RX_P47")
	)
	(segment
		(start 179.240688 -217.11031)
		(end 178.397408 -217.70086)
		(width 0.1397)
		(layer "In2.Cu")
		(net "PCIE_RX_P47")
	)
	(segment
		(start 241.904266 -61.748416)
		(end 241.901726 -61.750702)
		(width 0.1016)
		(layer "In2.Cu")
		(net "PCIE_RX_P47")
	)
	(segment
		(start 241.493548 -67.141852)
		(end 241.4016 -67.2338)
		(width 0.1016)
		(layer "In2.Cu")
		(net "PCIE_RX_P47")
	)
	(segment
		(start 241.829082 -61.807344)
		(end 241.824002 -61.811154)
		(width 0.1016)
		(layer "In2.Cu")
		(net "PCIE_RX_P47")
	)
	(segment
		(start 241.857784 -61.784738)
		(end 241.85118 -61.790072)
		(width 0.1016)
		(layer "In2.Cu")
		(net "PCIE_RX_P47")
	)
	(segment
		(start 241.85118 -61.790072)
		(end 241.850926 -61.790072)
		(width 0.1016)
		(layer "In2.Cu")
		(net "PCIE_RX_P47")
	)
	(segment
		(start 183.380126 -217.085418)
		(end 181.3814 -216.732866)
		(width 0.1397)
		(layer "In2.Cu")
		(net "PCIE_RX_P47")
	)
	(segment
		(start 239.91189 -79.710534)
		(end 241.599466 -89.281)
		(width 0.1397)
		(layer "In2.Cu")
		(net "PCIE_RX_P47")
	)
	(segment
		(start 241.824002 -61.811154)
		(end 241.81816 -61.815726)
		(width 0.1016)
		(layer "In2.Cu")
		(net "PCIE_RX_P47")
	)
	(arc
		(start 241.641122 -61.958728)
		(mid 241.586458 -62.020362)
		(end 241.543332 -62.090554)
		(width 0.1016)
		(layer "In2.Cu")
		(net "PCIE_RX_P47")
	)
	(arc
		(start 241.543332 -62.090554)
		(mid 241.506096 -62.193443)
		(end 241.493548 -62.302136)
		(width 0.1016)
		(layer "In2.Cu")
		(net "PCIE_RX_P47")
	)
	(arc
		(start 241.67465 -61.929772)
		(mid 241.658199 -61.94337)
		(end 241.642392 -61.957712)
		(width 0.1016)
		(layer "In2.Cu")
		(net "PCIE_RX_P47")
	)
	(arc
		(start 177.8381 -220.008196)
		(mid 177.775916 -220.362847)
		(end 177.5968 -220.6752)
		(width 0.1397)
		(layer "In2.Cu")
		(net "PCIE_RX_P47")
	)
	(arc
		(start 242.099846 -61.49975)
		(mid 242.080393 -61.584551)
		(end 242.025932 -61.652404)
		(width 0.1016)
		(layer "In2.Cu")
		(net "PCIE_RX_P47")
	)
	(segment
		(start 242.599972 -61.999876)
		(end 243.099844 -62.499748)
		(width 0.136652)
		(layer "F.Cu")
		(net "PCIE_RX_P46")
	)
	(via
		(at 185.693558 -222.294704)
		(size 0.508)
		(drill 0.254)
		(layers "F.Cu" "B.Cu")
		(net "PCIE_RX_P46")
	)
	(via
		(at 243.099844 -62.499748)
		(size 0.4572)
		(drill 0.2032)
		(layers "F.Cu" "B.Cu")
		(net "PCIE_RX_P46")
	)
	(segment
		(start 185.947558 -223.5962)
		(end 185.947558 -222.90786)
		(width 0.136652)
		(layer "B.Cu")
		(net "PCIE_RX_P46")
	)
	(segment
		(start 185.947812 -223.596454)
		(end 185.947558 -223.5962)
		(width 0.136652)
		(layer "B.Cu")
		(net "PCIE_RX_P46")
	)
	(segment
		(start 185.840116 -224.375726)
		(end 185.890916 -224.324926)
		(width 0.136652)
		(layer "B.Cu")
		(net "PCIE_RX_P46")
	)
	(segment
		(start 185.700162 -225.92538)
		(end 185.700162 -224.713546)
		(width 0.136652)
		(layer "B.Cu")
		(net "PCIE_RX_P46")
	)
	(segment
		(start 185.947812 -224.187512)
		(end 185.947812 -223.596454)
		(width 0.136652)
		(layer "B.Cu")
		(net "PCIE_RX_P46")
	)
	(arc
		(start 185.700162 -224.713546)
		(mid 185.73653 -224.53071)
		(end 185.840116 -224.375726)
		(width 0.136652)
		(layer "B.Cu")
		(net "PCIE_RX_P46")
	)
	(arc
		(start 185.890916 -224.324926)
		(mid 185.933042 -224.26188)
		(end 185.947812 -224.187512)
		(width 0.136652)
		(layer "B.Cu")
		(net "PCIE_RX_P46")
	)
	(arc
		(start 185.947558 -222.90786)
		(mid 185.88155 -222.576014)
		(end 185.693558 -222.294704)
		(width 0.136652)
		(layer "B.Cu")
		(net "PCIE_RX_P46")
	)
	(segment
		(start 194.53225 -206.588614)
		(end 201.368914 -167.812466)
		(width 0.1397)
		(layer "In2.Cu")
		(net "PCIE_RX_P46")
	)
	(segment
		(start 242.544346 -89.718896)
		(end 240.938812 -80.626712)
		(width 0.1397)
		(layer "In2.Cu")
		(net "PCIE_RX_P46")
	)
	(segment
		(start 242.895628 -62.755272)
		(end 242.901724 -62.7507)
		(width 0.1016)
		(layer "In2.Cu")
		(net "PCIE_RX_P46")
	)
	(segment
		(start 185.934858 -221.712028)
		(end 185.934858 -220.86189)
		(width 0.1397)
		(layer "In2.Cu")
		(net "PCIE_RX_P46")
	)
	(segment
		(start 242.850924 -62.79007)
		(end 242.851178 -62.79007)
		(width 0.1016)
		(layer "In2.Cu")
		(net "PCIE_RX_P46")
	)
	(segment
		(start 237.998254 -115.50269)
		(end 242.544346 -89.718896)
		(width 0.1397)
		(layer "In2.Cu")
		(net "PCIE_RX_P46")
	)
	(segment
		(start 242.851178 -62.79007)
		(end 242.857782 -62.784736)
		(width 0.1016)
		(layer "In2.Cu")
		(net "PCIE_RX_P46")
	)
	(segment
		(start 242.493546 -67.132454)
		(end 242.493546 -63.302134)
		(width 0.1016)
		(layer "In2.Cu")
		(net "PCIE_RX_P46")
	)
	(segment
		(start 242.443 -72.097646)
		(end 242.443 -67.183)
		(width 0.1397)
		(layer "In2.Cu")
		(net "PCIE_RX_P46")
	)
	(segment
		(start 242.824 -62.811152)
		(end 242.82908 -62.807342)
		(width 0.1016)
		(layer "In2.Cu")
		(net "PCIE_RX_P46")
	)
	(segment
		(start 190.262002 -217.07729)
		(end 192.296288 -214.171784)
		(width 0.1397)
		(layer "In2.Cu")
		(net "PCIE_RX_P46")
	)
	(segment
		(start 201.368914 -167.812466)
		(end 237.998254 -115.50269)
		(width 0.1397)
		(layer "In2.Cu")
		(net "PCIE_RX_P46")
	)
	(segment
		(start 192.39992 -209.634582)
		(end 194.53225 -206.588614)
		(width 0.1397)
		(layer "In2.Cu")
		(net "PCIE_RX_P46")
	)
	(segment
		(start 186.971432 -219.381324)
		(end 190.262002 -217.07729)
		(width 0.1397)
		(layer "In2.Cu")
		(net "PCIE_RX_P46")
	)
	(segment
		(start 242.64112 -62.958726)
		(end 242.64239 -62.95771)
		(width 0.1016)
		(layer "In2.Cu")
		(net "PCIE_RX_P46")
	)
	(segment
		(start 192.296288 -214.171784)
		(end 192.39992 -213.585044)
		(width 0.1397)
		(layer "In2.Cu")
		(net "PCIE_RX_P46")
	)
	(segment
		(start 242.82908 -62.807342)
		(end 242.850924 -62.79007)
		(width 0.1016)
		(layer "In2.Cu")
		(net "PCIE_RX_P46")
	)
	(segment
		(start 242.797584 -62.831726)
		(end 242.818158 -62.815724)
		(width 0.1016)
		(layer "In2.Cu")
		(net "PCIE_RX_P46")
	)
	(segment
		(start 242.753896 -62.866524)
		(end 242.754404 -62.866016)
		(width 0.1016)
		(layer "In2.Cu")
		(net "PCIE_RX_P46")
	)
	(segment
		(start 242.818158 -62.815724)
		(end 242.824 -62.811152)
		(width 0.1016)
		(layer "In2.Cu")
		(net "PCIE_RX_P46")
	)
	(segment
		(start 185.934858 -220.86189)
		(end 186.971432 -219.381324)
		(width 0.1397)
		(layer "In2.Cu")
		(net "PCIE_RX_P46")
	)
	(segment
		(start 240.938812 -80.626712)
		(end 242.443 -72.097646)
		(width 0.1397)
		(layer "In2.Cu")
		(net "PCIE_RX_P46")
	)
	(segment
		(start 242.901724 -62.7507)
		(end 242.904264 -62.748414)
		(width 0.1016)
		(layer "In2.Cu")
		(net "PCIE_RX_P46")
	)
	(segment
		(start 242.754404 -62.866016)
		(end 242.797584 -62.831726)
		(width 0.1016)
		(layer "In2.Cu")
		(net "PCIE_RX_P46")
	)
	(segment
		(start 242.857782 -62.784736)
		(end 242.895628 -62.755272)
		(width 0.1016)
		(layer "In2.Cu")
		(net "PCIE_RX_P46")
	)
	(segment
		(start 242.674648 -62.92977)
		(end 242.753896 -62.866524)
		(width 0.1016)
		(layer "In2.Cu")
		(net "PCIE_RX_P46")
	)
	(segment
		(start 242.904264 -62.748414)
		(end 243.02593 -62.652402)
		(width 0.1016)
		(layer "In2.Cu")
		(net "PCIE_RX_P46")
	)
	(segment
		(start 242.443 -67.183)
		(end 242.493546 -67.132454)
		(width 0.1016)
		(layer "In2.Cu")
		(net "PCIE_RX_P46")
	)
	(segment
		(start 192.39992 -213.585044)
		(end 192.39992 -209.634582)
		(width 0.1397)
		(layer "In2.Cu")
		(net "PCIE_RX_P46")
	)
	(arc
		(start 243.02593 -62.652402)
		(mid 243.080402 -62.584554)
		(end 243.099844 -62.499748)
		(width 0.1016)
		(layer "In2.Cu")
		(net "PCIE_RX_P46")
	)
	(arc
		(start 242.493546 -63.302134)
		(mid 242.506143 -63.193453)
		(end 242.54333 -63.090552)
		(width 0.1016)
		(layer "In2.Cu")
		(net "PCIE_RX_P46")
	)
	(arc
		(start 242.54333 -63.090552)
		(mid 242.586467 -63.020368)
		(end 242.64112 -62.958726)
		(width 0.1016)
		(layer "In2.Cu")
		(net "PCIE_RX_P46")
	)
	(arc
		(start 242.64239 -62.95771)
		(mid 242.658193 -62.943363)
		(end 242.674648 -62.92977)
		(width 0.1016)
		(layer "In2.Cu")
		(net "PCIE_RX_P46")
	)
	(arc
		(start 185.693558 -222.294704)
		(mid 185.872185 -222.02737)
		(end 185.934858 -221.712028)
		(width 0.1397)
		(layer "In2.Cu")
		(net "PCIE_RX_P46")
	)
	(segment
		(start 243.59997 -60.999878)
		(end 244.099842 -61.49975)
		(width 0.136652)
		(layer "F.Cu")
		(net "PCIE_RX_P45")
	)
	(via
		(at 244.099842 -61.49975)
		(size 0.4572)
		(drill 0.2032)
		(layers "F.Cu" "B.Cu")
		(net "PCIE_RX_P45")
	)
	(via
		(at 188.893704 -222.294704)
		(size 0.508)
		(drill 0.254)
		(layers "F.Cu" "B.Cu")
		(net "PCIE_RX_P45")
	)
	(segment
		(start 189.040262 -224.375726)
		(end 189.091062 -224.324926)
		(width 0.136652)
		(layer "B.Cu")
		(net "PCIE_RX_P45")
	)
	(segment
		(start 188.900054 -225.92538)
		(end 188.900054 -224.7138)
		(width 0.136652)
		(layer "B.Cu")
		(net "PCIE_RX_P45")
	)
	(segment
		(start 189.147704 -223.5962)
		(end 189.147704 -222.90786)
		(width 0.136652)
		(layer "B.Cu")
		(net "PCIE_RX_P45")
	)
	(segment
		(start 189.147958 -223.596454)
		(end 189.147704 -223.5962)
		(width 0.136652)
		(layer "B.Cu")
		(net "PCIE_RX_P45")
	)
	(segment
		(start 189.147958 -224.187512)
		(end 189.147958 -223.596454)
		(width 0.136652)
		(layer "B.Cu")
		(net "PCIE_RX_P45")
	)
	(segment
		(start 188.900054 -224.7138)
		(end 188.900308 -224.713546)
		(width 0.136652)
		(layer "B.Cu")
		(net "PCIE_RX_P45")
	)
	(arc
		(start 188.900308 -224.713546)
		(mid 188.936676 -224.53071)
		(end 189.040262 -224.375726)
		(width 0.136652)
		(layer "B.Cu")
		(net "PCIE_RX_P45")
	)
	(arc
		(start 189.147704 -222.90786)
		(mid 189.081696 -222.576014)
		(end 188.893704 -222.294704)
		(width 0.136652)
		(layer "B.Cu")
		(net "PCIE_RX_P45")
	)
	(arc
		(start 189.091062 -224.324926)
		(mid 189.133188 -224.26188)
		(end 189.147958 -224.187512)
		(width 0.136652)
		(layer "B.Cu")
		(net "PCIE_RX_P45")
	)
	(segment
		(start 195.5546 -209.172556)
		(end 195.5546 -213.610444)
		(width 0.1397)
		(layer "In2.Cu")
		(net "PCIE_RX_P45")
	)
	(segment
		(start 243.851176 -61.790072)
		(end 243.850922 -61.790072)
		(width 0.1016)
		(layer "In2.Cu")
		(net "PCIE_RX_P45")
	)
	(segment
		(start 189.135004 -220.616018)
		(end 189.135004 -221.712028)
		(width 0.1397)
		(layer "In2.Cu")
		(net "PCIE_RX_P45")
	)
	(segment
		(start 202.433428 -168.59631)
		(end 195.416678 -208.391252)
		(width 0.1397)
		(layer "In2.Cu")
		(net "PCIE_RX_P45")
	)
	(segment
		(start 243.818156 -61.815726)
		(end 243.797582 -61.831728)
		(width 0.1016)
		(layer "In2.Cu")
		(net "PCIE_RX_P45")
	)
	(segment
		(start 243.439442 -67.183)
		(end 243.439442 -72.400922)
		(width 0.1397)
		(layer "In2.Cu")
		(net "PCIE_RX_P45")
	)
	(segment
		(start 243.753894 -61.866526)
		(end 243.674646 -61.929772)
		(width 0.1016)
		(layer "In2.Cu")
		(net "PCIE_RX_P45")
	)
	(segment
		(start 242.268756 -81.384394)
		(end 243.584476 -88.846152)
		(width 0.1397)
		(layer "In2.Cu")
		(net "PCIE_RX_P45")
	)
	(segment
		(start 243.493544 -62.302136)
		(end 243.493544 -67.128898)
		(width 0.1016)
		(layer "In2.Cu")
		(net "PCIE_RX_P45")
	)
	(segment
		(start 244.025928 -61.652404)
		(end 243.904262 -61.748416)
		(width 0.1016)
		(layer "In2.Cu")
		(net "PCIE_RX_P45")
	)
	(segment
		(start 243.901722 -61.750702)
		(end 243.895626 -61.755274)
		(width 0.1016)
		(layer "In2.Cu")
		(net "PCIE_RX_P45")
	)
	(segment
		(start 243.642388 -61.957712)
		(end 243.641118 -61.958728)
		(width 0.1016)
		(layer "In2.Cu")
		(net "PCIE_RX_P45")
	)
	(segment
		(start 195.416678 -208.391252)
		(end 195.5546 -209.172556)
		(width 0.1397)
		(layer "In2.Cu")
		(net "PCIE_RX_P45")
	)
	(segment
		(start 189.945518 -219.458286)
		(end 189.135004 -220.616018)
		(width 0.1397)
		(layer "In2.Cu")
		(net "PCIE_RX_P45")
	)
	(segment
		(start 243.823998 -61.811154)
		(end 243.818156 -61.815726)
		(width 0.1016)
		(layer "In2.Cu")
		(net "PCIE_RX_P45")
	)
	(segment
		(start 243.645944 -73.573894)
		(end 242.268756 -81.384394)
		(width 0.1397)
		(layer "In2.Cu")
		(net "PCIE_RX_P45")
	)
	(segment
		(start 243.829078 -61.807344)
		(end 243.823998 -61.811154)
		(width 0.1016)
		(layer "In2.Cu")
		(net "PCIE_RX_P45")
	)
	(segment
		(start 243.797582 -61.831728)
		(end 243.754402 -61.866018)
		(width 0.1016)
		(layer "In2.Cu")
		(net "PCIE_RX_P45")
	)
	(segment
		(start 243.584476 -88.846152)
		(end 238.640112 -116.887498)
		(width 0.1397)
		(layer "In2.Cu")
		(net "PCIE_RX_P45")
	)
	(segment
		(start 195.288916 -215.11514)
		(end 194.461892 -216.295986)
		(width 0.1397)
		(layer "In2.Cu")
		(net "PCIE_RX_P45")
	)
	(segment
		(start 243.754402 -61.866018)
		(end 243.753894 -61.866526)
		(width 0.1016)
		(layer "In2.Cu")
		(net "PCIE_RX_P45")
	)
	(segment
		(start 238.640112 -116.887498)
		(end 202.433428 -168.59631)
		(width 0.1397)
		(layer "In2.Cu")
		(net "PCIE_RX_P45")
	)
	(segment
		(start 194.461892 -216.295986)
		(end 189.945518 -219.458286)
		(width 0.1397)
		(layer "In2.Cu")
		(net "PCIE_RX_P45")
	)
	(segment
		(start 243.904262 -61.748416)
		(end 243.901722 -61.750702)
		(width 0.1016)
		(layer "In2.Cu")
		(net "PCIE_RX_P45")
	)
	(segment
		(start 243.850922 -61.790072)
		(end 243.829078 -61.807344)
		(width 0.1016)
		(layer "In2.Cu")
		(net "PCIE_RX_P45")
	)
	(segment
		(start 243.895626 -61.755274)
		(end 243.85778 -61.784738)
		(width 0.1016)
		(layer "In2.Cu")
		(net "PCIE_RX_P45")
	)
	(segment
		(start 195.5546 -213.610444)
		(end 195.288916 -215.11514)
		(width 0.1397)
		(layer "In2.Cu")
		(net "PCIE_RX_P45")
	)
	(segment
		(start 243.439442 -72.400922)
		(end 243.645944 -73.573894)
		(width 0.1397)
		(layer "In2.Cu")
		(net "PCIE_RX_P45")
	)
	(segment
		(start 243.493544 -67.128898)
		(end 243.439442 -67.183)
		(width 0.1016)
		(layer "In2.Cu")
		(net "PCIE_RX_P45")
	)
	(segment
		(start 243.85778 -61.784738)
		(end 243.851176 -61.790072)
		(width 0.1016)
		(layer "In2.Cu")
		(net "PCIE_RX_P45")
	)
	(arc
		(start 243.674646 -61.929772)
		(mid 243.658195 -61.94337)
		(end 243.642388 -61.957712)
		(width 0.1016)
		(layer "In2.Cu")
		(net "PCIE_RX_P45")
	)
	(arc
		(start 244.099842 -61.49975)
		(mid 244.080389 -61.584551)
		(end 244.025928 -61.652404)
		(width 0.1016)
		(layer "In2.Cu")
		(net "PCIE_RX_P45")
	)
	(arc
		(start 243.641118 -61.958728)
		(mid 243.586454 -62.020362)
		(end 243.543328 -62.090554)
		(width 0.1016)
		(layer "In2.Cu")
		(net "PCIE_RX_P45")
	)
	(arc
		(start 243.543328 -62.090554)
		(mid 243.506092 -62.193443)
		(end 243.493544 -62.302136)
		(width 0.1016)
		(layer "In2.Cu")
		(net "PCIE_RX_P45")
	)
	(arc
		(start 189.135004 -221.712028)
		(mid 189.072283 -222.02735)
		(end 188.893704 -222.294704)
		(width 0.1397)
		(layer "In2.Cu")
		(net "PCIE_RX_P45")
	)
	(segment
		(start 244.599968 -61.999876)
		(end 245.09984 -62.499748)
		(width 0.136652)
		(layer "F.Cu")
		(net "PCIE_RX_P44")
	)
	(via
		(at 245.09984 -62.499748)
		(size 0.4572)
		(drill 0.2032)
		(layers "F.Cu" "B.Cu")
		(net "PCIE_RX_P44")
	)
	(via
		(at 192.093596 -222.294704)
		(size 0.508)
		(drill 0.254)
		(layers "F.Cu" "B.Cu")
		(net "PCIE_RX_P44")
	)
	(segment
		(start 192.347596 -223.5962)
		(end 192.347596 -222.90786)
		(width 0.136652)
		(layer "B.Cu")
		(net "PCIE_RX_P44")
	)
	(segment
		(start 192.240154 -224.375726)
		(end 192.290954 -224.324926)
		(width 0.136652)
		(layer "B.Cu")
		(net "PCIE_RX_P44")
	)
	(segment
		(start 192.1002 -225.92538)
		(end 192.1002 -224.713546)
		(width 0.136652)
		(layer "B.Cu")
		(net "PCIE_RX_P44")
	)
	(segment
		(start 192.34785 -224.187512)
		(end 192.34785 -223.596454)
		(width 0.136652)
		(layer "B.Cu")
		(net "PCIE_RX_P44")
	)
	(segment
		(start 192.34785 -223.596454)
		(end 192.347596 -223.5962)
		(width 0.136652)
		(layer "B.Cu")
		(net "PCIE_RX_P44")
	)
	(arc
		(start 192.290954 -224.324926)
		(mid 192.33308 -224.26188)
		(end 192.34785 -224.187512)
		(width 0.136652)
		(layer "B.Cu")
		(net "PCIE_RX_P44")
	)
	(arc
		(start 192.1002 -224.713546)
		(mid 192.136568 -224.53071)
		(end 192.240154 -224.375726)
		(width 0.136652)
		(layer "B.Cu")
		(net "PCIE_RX_P44")
	)
	(arc
		(start 192.347596 -222.90786)
		(mid 192.281588 -222.576014)
		(end 192.093596 -222.294704)
		(width 0.136652)
		(layer "B.Cu")
		(net "PCIE_RX_P44")
	)
	(segment
		(start 244.85092 -62.79007)
		(end 244.851174 -62.79007)
		(width 0.1016)
		(layer "In2.Cu")
		(net "PCIE_RX_P44")
	)
	(segment
		(start 244.7544 -62.866016)
		(end 244.79758 -62.831726)
		(width 0.1016)
		(layer "In2.Cu")
		(net "PCIE_RX_P44")
	)
	(segment
		(start 198.399146 -215.18753)
		(end 198.693532 -213.519512)
		(width 0.1397)
		(layer "In2.Cu")
		(net "PCIE_RX_P44")
	)
	(segment
		(start 192.334896 -221.487492)
		(end 193.436494 -219.913962)
		(width 0.1397)
		(layer "In2.Cu")
		(net "PCIE_RX_P44")
	)
	(segment
		(start 244.79758 -62.831726)
		(end 244.818154 -62.815724)
		(width 0.1016)
		(layer "In2.Cu")
		(net "PCIE_RX_P44")
	)
	(segment
		(start 244.857778 -62.784736)
		(end 244.895624 -62.755272)
		(width 0.1016)
		(layer "In2.Cu")
		(net "PCIE_RX_P44")
	)
	(segment
		(start 198.693532 -213.519512)
		(end 198.693532 -209.565494)
		(width 0.1397)
		(layer "In2.Cu")
		(net "PCIE_RX_P44")
	)
	(segment
		(start 244.90426 -62.748414)
		(end 245.025926 -62.652402)
		(width 0.1016)
		(layer "In2.Cu")
		(net "PCIE_RX_P44")
	)
	(segment
		(start 244.430042 -71.451216)
		(end 244.430042 -67.183)
		(width 0.1397)
		(layer "In2.Cu")
		(net "PCIE_RX_P44")
	)
	(segment
		(start 244.493542 -67.1195)
		(end 244.493542 -63.302134)
		(width 0.1016)
		(layer "In2.Cu")
		(net "PCIE_RX_P44")
	)
	(segment
		(start 244.895624 -62.755272)
		(end 244.90172 -62.7507)
		(width 0.1016)
		(layer "In2.Cu")
		(net "PCIE_RX_P44")
	)
	(segment
		(start 244.641116 -62.958726)
		(end 244.642386 -62.95771)
		(width 0.1016)
		(layer "In2.Cu")
		(net "PCIE_RX_P44")
	)
	(segment
		(start 196.67982 -217.642948)
		(end 198.399146 -215.18753)
		(width 0.1397)
		(layer "In2.Cu")
		(net "PCIE_RX_P44")
	)
	(segment
		(start 244.90172 -62.7507)
		(end 244.90426 -62.748414)
		(width 0.1016)
		(layer "In2.Cu")
		(net "PCIE_RX_P44")
	)
	(segment
		(start 198.693532 -209.565494)
		(end 199.054466 -207.518)
		(width 0.1397)
		(layer "In2.Cu")
		(net "PCIE_RX_P44")
	)
	(segment
		(start 244.430042 -67.183)
		(end 244.493542 -67.1195)
		(width 0.1016)
		(layer "In2.Cu")
		(net "PCIE_RX_P44")
	)
	(segment
		(start 192.334896 -221.712028)
		(end 192.334896 -221.487492)
		(width 0.1397)
		(layer "In2.Cu")
		(net "PCIE_RX_P44")
	)
	(segment
		(start 193.436494 -219.913962)
		(end 196.67982 -217.642948)
		(width 0.1397)
		(layer "In2.Cu")
		(net "PCIE_RX_P44")
	)
	(segment
		(start 198.778622 -205.954376)
		(end 205.910942 -165.505638)
		(width 0.1397)
		(layer "In2.Cu")
		(net "PCIE_RX_P44")
	)
	(segment
		(start 239.771174 -117.148102)
		(end 244.774466 -88.773)
		(width 0.1397)
		(layer "In2.Cu")
		(net "PCIE_RX_P44")
	)
	(segment
		(start 205.910942 -165.505638)
		(end 239.771174 -117.148102)
		(width 0.1397)
		(layer "In2.Cu")
		(net "PCIE_RX_P44")
	)
	(segment
		(start 244.822472 -73.678288)
		(end 244.430042 -71.451216)
		(width 0.1397)
		(layer "In2.Cu")
		(net "PCIE_RX_P44")
	)
	(segment
		(start 244.774466 -88.773)
		(end 243.467636 -81.361534)
		(width 0.1397)
		(layer "In2.Cu")
		(net "PCIE_RX_P44")
	)
	(segment
		(start 244.829076 -62.807342)
		(end 244.85092 -62.79007)
		(width 0.1016)
		(layer "In2.Cu")
		(net "PCIE_RX_P44")
	)
	(segment
		(start 199.054466 -207.518)
		(end 198.778622 -205.954376)
		(width 0.1397)
		(layer "In2.Cu")
		(net "PCIE_RX_P44")
	)
	(segment
		(start 243.467636 -81.361534)
		(end 244.822472 -73.678288)
		(width 0.1397)
		(layer "In2.Cu")
		(net "PCIE_RX_P44")
	)
	(segment
		(start 244.674644 -62.92977)
		(end 244.753892 -62.866524)
		(width 0.1016)
		(layer "In2.Cu")
		(net "PCIE_RX_P44")
	)
	(segment
		(start 244.851174 -62.79007)
		(end 244.857778 -62.784736)
		(width 0.1016)
		(layer "In2.Cu")
		(net "PCIE_RX_P44")
	)
	(segment
		(start 244.753892 -62.866524)
		(end 244.7544 -62.866016)
		(width 0.1016)
		(layer "In2.Cu")
		(net "PCIE_RX_P44")
	)
	(segment
		(start 244.823996 -62.811152)
		(end 244.829076 -62.807342)
		(width 0.1016)
		(layer "In2.Cu")
		(net "PCIE_RX_P44")
	)
	(segment
		(start 244.818154 -62.815724)
		(end 244.823996 -62.811152)
		(width 0.1016)
		(layer "In2.Cu")
		(net "PCIE_RX_P44")
	)
	(arc
		(start 244.493542 -63.302134)
		(mid 244.506139 -63.193453)
		(end 244.543326 -63.090552)
		(width 0.1016)
		(layer "In2.Cu")
		(net "PCIE_RX_P44")
	)
	(arc
		(start 192.093596 -222.294704)
		(mid 192.272223 -222.02737)
		(end 192.334896 -221.712028)
		(width 0.1397)
		(layer "In2.Cu")
		(net "PCIE_RX_P44")
	)
	(arc
		(start 244.642386 -62.95771)
		(mid 244.658189 -62.943363)
		(end 244.674644 -62.92977)
		(width 0.1016)
		(layer "In2.Cu")
		(net "PCIE_RX_P44")
	)
	(arc
		(start 245.025926 -62.652402)
		(mid 245.080398 -62.584554)
		(end 245.09984 -62.499748)
		(width 0.1016)
		(layer "In2.Cu")
		(net "PCIE_RX_P44")
	)
	(arc
		(start 244.543326 -63.090552)
		(mid 244.586463 -63.020368)
		(end 244.641116 -62.958726)
		(width 0.1016)
		(layer "In2.Cu")
		(net "PCIE_RX_P44")
	)
	(segment
		(start 245.599966 -60.999878)
		(end 246.099838 -61.49975)
		(width 0.136652)
		(layer "F.Cu")
		(net "PCIE_RX_P43")
	)
	(via
		(at 195.293742 -222.294704)
		(size 0.508)
		(drill 0.254)
		(layers "F.Cu" "B.Cu")
		(net "PCIE_RX_P43")
	)
	(via
		(at 246.099838 -61.49975)
		(size 0.4572)
		(drill 0.2032)
		(layers "F.Cu" "B.Cu")
		(net "PCIE_RX_P43")
	)
	(segment
		(start 195.547996 -223.596454)
		(end 195.547742 -223.5962)
		(width 0.136652)
		(layer "B.Cu")
		(net "PCIE_RX_P43")
	)
	(segment
		(start 195.547996 -224.187512)
		(end 195.547996 -223.596454)
		(width 0.136652)
		(layer "B.Cu")
		(net "PCIE_RX_P43")
	)
	(segment
		(start 195.300092 -224.7138)
		(end 195.300346 -224.713546)
		(width 0.136652)
		(layer "B.Cu")
		(net "PCIE_RX_P43")
	)
	(segment
		(start 195.300092 -225.92538)
		(end 195.300092 -224.7138)
		(width 0.136652)
		(layer "B.Cu")
		(net "PCIE_RX_P43")
	)
	(segment
		(start 195.547742 -223.5962)
		(end 195.547742 -222.90786)
		(width 0.136652)
		(layer "B.Cu")
		(net "PCIE_RX_P43")
	)
	(segment
		(start 195.4403 -224.375726)
		(end 195.4911 -224.324926)
		(width 0.136652)
		(layer "B.Cu")
		(net "PCIE_RX_P43")
	)
	(arc
		(start 195.4911 -224.324926)
		(mid 195.533226 -224.26188)
		(end 195.547996 -224.187512)
		(width 0.136652)
		(layer "B.Cu")
		(net "PCIE_RX_P43")
	)
	(arc
		(start 195.300346 -224.713546)
		(mid 195.336714 -224.53071)
		(end 195.4403 -224.375726)
		(width 0.136652)
		(layer "B.Cu")
		(net "PCIE_RX_P43")
	)
	(arc
		(start 195.547742 -222.90786)
		(mid 195.481734 -222.576014)
		(end 195.293742 -222.294704)
		(width 0.136652)
		(layer "B.Cu")
		(net "PCIE_RX_P43")
	)
	(segment
		(start 207.210152 -165.529006)
		(end 241.145568 -117.064536)
		(width 0.1397)
		(layer "In2.Cu")
		(net "PCIE_RX_P43")
	)
	(segment
		(start 245.851172 -61.790072)
		(end 245.857776 -61.784738)
		(width 0.1016)
		(layer "In2.Cu")
		(net "PCIE_RX_P43")
	)
	(segment
		(start 200.56602 -203.209652)
		(end 200.56602 -203.209398)
		(width 0.1397)
		(layer "In2.Cu")
		(net "PCIE_RX_P43")
	)
	(segment
		(start 201.494644 -208.638648)
		(end 200.56856 -203.383642)
		(width 0.1397)
		(layer "In2.Cu")
		(net "PCIE_RX_P43")
	)
	(segment
		(start 245.75389 -61.866526)
		(end 245.754398 -61.866018)
		(width 0.1016)
		(layer "In2.Cu")
		(net "PCIE_RX_P43")
	)
	(segment
		(start 200.56602 -203.209398)
		(end 207.210152 -165.529006)
		(width 0.1397)
		(layer "In2.Cu")
		(net "PCIE_RX_P43")
	)
	(segment
		(start 201.944478 -209.28076)
		(end 201.494644 -208.638648)
		(width 0.1397)
		(layer "In2.Cu")
		(net "PCIE_RX_P43")
	)
	(segment
		(start 245.904258 -61.748416)
		(end 246.025924 -61.652404)
		(width 0.1016)
		(layer "In2.Cu")
		(net "PCIE_RX_P43")
	)
	(segment
		(start 245.857776 -61.784738)
		(end 245.895622 -61.755274)
		(width 0.1016)
		(layer "In2.Cu")
		(net "PCIE_RX_P43")
	)
	(segment
		(start 199.395588 -217.984324)
		(end 201.753216 -214.617046)
		(width 0.1397)
		(layer "In2.Cu")
		(net "PCIE_RX_P43")
	)
	(segment
		(start 195.535042 -221.244922)
		(end 196.30009 -220.151706)
		(width 0.1397)
		(layer "In2.Cu")
		(net "PCIE_RX_P43")
	)
	(segment
		(start 246.044466 -73.787)
		(end 245.439438 -70.354444)
		(width 0.1397)
		(layer "In2.Cu")
		(net "PCIE_RX_P43")
	)
	(segment
		(start 245.895622 -61.755274)
		(end 245.901718 -61.750702)
		(width 0.1016)
		(layer "In2.Cu")
		(net "PCIE_RX_P43")
	)
	(segment
		(start 195.535042 -221.712028)
		(end 195.535042 -221.244922)
		(width 0.1397)
		(layer "In2.Cu")
		(net "PCIE_RX_P43")
	)
	(segment
		(start 245.829074 -61.807344)
		(end 245.850918 -61.790072)
		(width 0.1016)
		(layer "In2.Cu")
		(net "PCIE_RX_P43")
	)
	(segment
		(start 201.944478 -213.534244)
		(end 201.944478 -209.28076)
		(width 0.1397)
		(layer "In2.Cu")
		(net "PCIE_RX_P43")
	)
	(segment
		(start 245.641114 -61.958728)
		(end 245.642384 -61.957712)
		(width 0.1016)
		(layer "In2.Cu")
		(net "PCIE_RX_P43")
	)
	(segment
		(start 245.823994 -61.811154)
		(end 245.829074 -61.807344)
		(width 0.1016)
		(layer "In2.Cu")
		(net "PCIE_RX_P43")
	)
	(segment
		(start 245.850918 -61.790072)
		(end 245.851172 -61.790072)
		(width 0.1016)
		(layer "In2.Cu")
		(net "PCIE_RX_P43")
	)
	(segment
		(start 245.439438 -70.354444)
		(end 245.439438 -67.182238)
		(width 0.1397)
		(layer "In2.Cu")
		(net "PCIE_RX_P43")
	)
	(segment
		(start 245.818152 -61.815726)
		(end 245.823994 -61.811154)
		(width 0.1016)
		(layer "In2.Cu")
		(net "PCIE_RX_P43")
	)
	(segment
		(start 244.678454 -81.534)
		(end 246.044466 -73.787)
		(width 0.1397)
		(layer "In2.Cu")
		(net "PCIE_RX_P43")
	)
	(segment
		(start 200.56856 -203.383642)
		(end 200.56856 -203.212192)
		(width 0.1397)
		(layer "In2.Cu")
		(net "PCIE_RX_P43")
	)
	(segment
		(start 241.145568 -117.064536)
		(end 246.044466 -89.281)
		(width 0.1397)
		(layer "In2.Cu")
		(net "PCIE_RX_P43")
	)
	(segment
		(start 245.797578 -61.831728)
		(end 245.818152 -61.815726)
		(width 0.1016)
		(layer "In2.Cu")
		(net "PCIE_RX_P43")
	)
	(segment
		(start 245.901718 -61.750702)
		(end 245.904258 -61.748416)
		(width 0.1016)
		(layer "In2.Cu")
		(net "PCIE_RX_P43")
	)
	(segment
		(start 245.49354 -67.128136)
		(end 245.49354 -62.302136)
		(width 0.1016)
		(layer "In2.Cu")
		(net "PCIE_RX_P43")
	)
	(segment
		(start 200.56856 -203.212192)
		(end 200.56602 -203.209652)
		(width 0.1397)
		(layer "In2.Cu")
		(net "PCIE_RX_P43")
	)
	(segment
		(start 196.30009 -220.151706)
		(end 199.395588 -217.984324)
		(width 0.1397)
		(layer "In2.Cu")
		(net "PCIE_RX_P43")
	)
	(segment
		(start 245.439438 -67.182238)
		(end 245.49354 -67.128136)
		(width 0.1016)
		(layer "In2.Cu")
		(net "PCIE_RX_P43")
	)
	(segment
		(start 245.754398 -61.866018)
		(end 245.797578 -61.831728)
		(width 0.1016)
		(layer "In2.Cu")
		(net "PCIE_RX_P43")
	)
	(segment
		(start 245.674642 -61.929772)
		(end 245.75389 -61.866526)
		(width 0.1016)
		(layer "In2.Cu")
		(net "PCIE_RX_P43")
	)
	(segment
		(start 246.044466 -89.281)
		(end 244.678454 -81.534)
		(width 0.1397)
		(layer "In2.Cu")
		(net "PCIE_RX_P43")
	)
	(segment
		(start 201.753216 -214.617046)
		(end 201.944478 -213.534244)
		(width 0.1397)
		(layer "In2.Cu")
		(net "PCIE_RX_P43")
	)
	(arc
		(start 245.642384 -61.957712)
		(mid 245.658187 -61.943365)
		(end 245.674642 -61.929772)
		(width 0.1016)
		(layer "In2.Cu")
		(net "PCIE_RX_P43")
	)
	(arc
		(start 245.543324 -62.090554)
		(mid 245.586461 -62.02037)
		(end 245.641114 -61.958728)
		(width 0.1016)
		(layer "In2.Cu")
		(net "PCIE_RX_P43")
	)
	(arc
		(start 245.49354 -62.302136)
		(mid 245.506137 -62.193455)
		(end 245.543324 -62.090554)
		(width 0.1016)
		(layer "In2.Cu")
		(net "PCIE_RX_P43")
	)
	(arc
		(start 195.293742 -222.294704)
		(mid 195.472369 -222.02737)
		(end 195.535042 -221.712028)
		(width 0.1397)
		(layer "In2.Cu")
		(net "PCIE_RX_P43")
	)
	(arc
		(start 246.025924 -61.652404)
		(mid 246.080396 -61.584556)
		(end 246.099838 -61.49975)
		(width 0.1016)
		(layer "In2.Cu")
		(net "PCIE_RX_P43")
	)
	(segment
		(start 246.599964 -61.999876)
		(end 247.099836 -62.499748)
		(width 0.136652)
		(layer "F.Cu")
		(net "PCIE_RX_P42")
	)
	(via
		(at 247.099836 -62.499748)
		(size 0.4572)
		(drill 0.2032)
		(layers "F.Cu" "B.Cu")
		(net "PCIE_RX_P42")
	)
	(via
		(at 198.493634 -222.294704)
		(size 0.508)
		(drill 0.254)
		(layers "F.Cu" "B.Cu")
		(net "PCIE_RX_P42")
	)
	(segment
		(start 198.640192 -224.375726)
		(end 198.690992 -224.324926)
		(width 0.136652)
		(layer "B.Cu")
		(net "PCIE_RX_P42")
	)
	(segment
		(start 198.500238 -225.92538)
		(end 198.500238 -224.713546)
		(width 0.136652)
		(layer "B.Cu")
		(net "PCIE_RX_P42")
	)
	(segment
		(start 198.747888 -224.187512)
		(end 198.747888 -223.596454)
		(width 0.136652)
		(layer "B.Cu")
		(net "PCIE_RX_P42")
	)
	(segment
		(start 198.747888 -223.596454)
		(end 198.747634 -223.5962)
		(width 0.136652)
		(layer "B.Cu")
		(net "PCIE_RX_P42")
	)
	(segment
		(start 198.747634 -223.5962)
		(end 198.747634 -222.90786)
		(width 0.136652)
		(layer "B.Cu")
		(net "PCIE_RX_P42")
	)
	(arc
		(start 198.500238 -224.713546)
		(mid 198.536606 -224.53071)
		(end 198.640192 -224.375726)
		(width 0.136652)
		(layer "B.Cu")
		(net "PCIE_RX_P42")
	)
	(arc
		(start 198.690992 -224.324926)
		(mid 198.733118 -224.26188)
		(end 198.747888 -224.187512)
		(width 0.136652)
		(layer "B.Cu")
		(net "PCIE_RX_P42")
	)
	(arc
		(start 198.747634 -222.90786)
		(mid 198.681626 -222.576014)
		(end 198.493634 -222.294704)
		(width 0.136652)
		(layer "B.Cu")
		(net "PCIE_RX_P42")
	)
	(segment
		(start 246.493538 -67.169538)
		(end 246.493538 -63.302134)
		(width 0.1016)
		(layer "In2.Cu")
		(net "PCIE_RX_P42")
	)
	(segment
		(start 246.823992 -62.811152)
		(end 246.829072 -62.807342)
		(width 0.1016)
		(layer "In2.Cu")
		(net "PCIE_RX_P42")
	)
	(segment
		(start 208.3562 -166.76878)
		(end 242.679474 -117.748558)
		(width 0.1397)
		(layer "In2.Cu")
		(net "PCIE_RX_P42")
	)
	(segment
		(start 246.67464 -62.92977)
		(end 246.753888 -62.866524)
		(width 0.1016)
		(layer "In2.Cu")
		(net "PCIE_RX_P42")
	)
	(segment
		(start 205.1558 -213.585044)
		(end 205.1558 -209.215736)
		(width 0.1397)
		(layer "In2.Cu")
		(net "PCIE_RX_P42")
	)
	(segment
		(start 246.09171 -80.257396)
		(end 247.229884 -73.801986)
		(width 0.1397)
		(layer "In2.Cu")
		(net "PCIE_RX_P42")
	)
	(segment
		(start 203.92009 -217.24493)
		(end 204.70876 -216.118694)
		(width 0.1397)
		(layer "In2.Cu")
		(net "PCIE_RX_P42")
	)
	(segment
		(start 246.857774 -62.784736)
		(end 246.89562 -62.755272)
		(width 0.1016)
		(layer "In2.Cu")
		(net "PCIE_RX_P42")
	)
	(segment
		(start 246.641112 -62.958726)
		(end 246.642382 -62.95771)
		(width 0.1016)
		(layer "In2.Cu")
		(net "PCIE_RX_P42")
	)
	(segment
		(start 204.70876 -216.118694)
		(end 205.1558 -213.585044)
		(width 0.1397)
		(layer "In2.Cu")
		(net "PCIE_RX_P42")
	)
	(segment
		(start 246.89562 -62.755272)
		(end 246.901716 -62.7507)
		(width 0.1016)
		(layer "In2.Cu")
		(net "PCIE_RX_P42")
	)
	(segment
		(start 246.904256 -62.748414)
		(end 247.025922 -62.652402)
		(width 0.1016)
		(layer "In2.Cu")
		(net "PCIE_RX_P42")
	)
	(segment
		(start 246.430038 -69.26453)
		(end 246.430038 -67.233038)
		(width 0.1397)
		(layer "In2.Cu")
		(net "PCIE_RX_P42")
	)
	(segment
		(start 198.734934 -221.712028)
		(end 198.734934 -221.314518)
		(width 0.1397)
		(layer "In2.Cu")
		(net "PCIE_RX_P42")
	)
	(segment
		(start 246.797576 -62.831726)
		(end 246.81815 -62.815724)
		(width 0.1016)
		(layer "In2.Cu")
		(net "PCIE_RX_P42")
	)
	(segment
		(start 205.1558 -209.215736)
		(end 203.014072 -197.070218)
		(width 0.1397)
		(layer "In2.Cu")
		(net "PCIE_RX_P42")
	)
	(segment
		(start 246.430038 -67.233038)
		(end 246.493538 -67.169538)
		(width 0.1016)
		(layer "In2.Cu")
		(net "PCIE_RX_P42")
	)
	(segment
		(start 247.229884 -73.801986)
		(end 246.430038 -69.26453)
		(width 0.1397)
		(layer "In2.Cu")
		(net "PCIE_RX_P42")
	)
	(segment
		(start 246.850916 -62.79007)
		(end 246.85117 -62.79007)
		(width 0.1016)
		(layer "In2.Cu")
		(net "PCIE_RX_P42")
	)
	(segment
		(start 246.85117 -62.79007)
		(end 246.857774 -62.784736)
		(width 0.1016)
		(layer "In2.Cu")
		(net "PCIE_RX_P42")
	)
	(segment
		(start 246.753888 -62.866524)
		(end 246.754396 -62.866016)
		(width 0.1016)
		(layer "In2.Cu")
		(net "PCIE_RX_P42")
	)
	(segment
		(start 198.734934 -221.314518)
		(end 199.337422 -220.453712)
		(width 0.1397)
		(layer "In2.Cu")
		(net "PCIE_RX_P42")
	)
	(segment
		(start 242.679474 -117.748558)
		(end 247.690894 -89.32672)
		(width 0.1397)
		(layer "In2.Cu")
		(net "PCIE_RX_P42")
	)
	(segment
		(start 203.014072 -197.070218)
		(end 208.3562 -166.76878)
		(width 0.1397)
		(layer "In2.Cu")
		(net "PCIE_RX_P42")
	)
	(segment
		(start 246.829072 -62.807342)
		(end 246.850916 -62.79007)
		(width 0.1016)
		(layer "In2.Cu")
		(net "PCIE_RX_P42")
	)
	(segment
		(start 247.690894 -89.32672)
		(end 246.09171 -80.257396)
		(width 0.1397)
		(layer "In2.Cu")
		(net "PCIE_RX_P42")
	)
	(segment
		(start 246.901716 -62.7507)
		(end 246.904256 -62.748414)
		(width 0.1016)
		(layer "In2.Cu")
		(net "PCIE_RX_P42")
	)
	(segment
		(start 246.754396 -62.866016)
		(end 246.797576 -62.831726)
		(width 0.1016)
		(layer "In2.Cu")
		(net "PCIE_RX_P42")
	)
	(segment
		(start 246.81815 -62.815724)
		(end 246.823992 -62.811152)
		(width 0.1016)
		(layer "In2.Cu")
		(net "PCIE_RX_P42")
	)
	(segment
		(start 199.337422 -220.453712)
		(end 203.92009 -217.24493)
		(width 0.1397)
		(layer "In2.Cu")
		(net "PCIE_RX_P42")
	)
	(arc
		(start 198.493634 -222.294704)
		(mid 198.672261 -222.02737)
		(end 198.734934 -221.712028)
		(width 0.1397)
		(layer "In2.Cu")
		(net "PCIE_RX_P42")
	)
	(arc
		(start 246.543322 -63.090552)
		(mid 246.586459 -63.020368)
		(end 246.641112 -62.958726)
		(width 0.1016)
		(layer "In2.Cu")
		(net "PCIE_RX_P42")
	)
	(arc
		(start 247.025922 -62.652402)
		(mid 247.080394 -62.584554)
		(end 247.099836 -62.499748)
		(width 0.1016)
		(layer "In2.Cu")
		(net "PCIE_RX_P42")
	)
	(arc
		(start 246.493538 -63.302134)
		(mid 246.506135 -63.193453)
		(end 246.543322 -63.090552)
		(width 0.1016)
		(layer "In2.Cu")
		(net "PCIE_RX_P42")
	)
	(arc
		(start 246.642382 -62.95771)
		(mid 246.658185 -62.943363)
		(end 246.67464 -62.92977)
		(width 0.1016)
		(layer "In2.Cu")
		(net "PCIE_RX_P42")
	)
	(segment
		(start 247.599962 -60.999878)
		(end 248.099834 -61.49975)
		(width 0.136652)
		(layer "F.Cu")
		(net "PCIE_RX_P41")
	)
	(via
		(at 201.69378 -222.294704)
		(size 0.508)
		(drill 0.254)
		(layers "F.Cu" "B.Cu")
		(net "PCIE_RX_P41")
	)
	(via
		(at 248.099834 -61.49975)
		(size 0.4572)
		(drill 0.2032)
		(layers "F.Cu" "B.Cu")
		(net "PCIE_RX_P41")
	)
	(segment
		(start 201.70013 -225.92538)
		(end 201.70013 -224.7138)
		(width 0.136652)
		(layer "B.Cu")
		(net "PCIE_RX_P41")
	)
	(segment
		(start 201.70013 -224.7138)
		(end 201.700384 -224.713546)
		(width 0.136652)
		(layer "B.Cu")
		(net "PCIE_RX_P41")
	)
	(segment
		(start 201.840338 -224.375726)
		(end 201.891138 -224.324926)
		(width 0.136652)
		(layer "B.Cu")
		(net "PCIE_RX_P41")
	)
	(segment
		(start 201.94778 -223.5962)
		(end 201.94778 -222.90786)
		(width 0.136652)
		(layer "B.Cu")
		(net "PCIE_RX_P41")
	)
	(segment
		(start 201.948034 -223.596454)
		(end 201.94778 -223.5962)
		(width 0.136652)
		(layer "B.Cu")
		(net "PCIE_RX_P41")
	)
	(segment
		(start 201.948034 -224.187512)
		(end 201.948034 -223.596454)
		(width 0.136652)
		(layer "B.Cu")
		(net "PCIE_RX_P41")
	)
	(arc
		(start 201.700384 -224.713546)
		(mid 201.736752 -224.53071)
		(end 201.840338 -224.375726)
		(width 0.136652)
		(layer "B.Cu")
		(net "PCIE_RX_P41")
	)
	(arc
		(start 201.94778 -222.90786)
		(mid 201.881772 -222.576014)
		(end 201.69378 -222.294704)
		(width 0.136652)
		(layer "B.Cu")
		(net "PCIE_RX_P41")
	)
	(arc
		(start 201.891138 -224.324926)
		(mid 201.933264 -224.26188)
		(end 201.948034 -224.187512)
		(width 0.136652)
		(layer "B.Cu")
		(net "PCIE_RX_P41")
	)
	(segment
		(start 247.851168 -61.790072)
		(end 247.857772 -61.784738)
		(width 0.1016)
		(layer "In2.Cu")
		(net "PCIE_RX_P41")
	)
	(segment
		(start 247.901714 -61.750702)
		(end 247.904254 -61.748416)
		(width 0.1016)
		(layer "In2.Cu")
		(net "PCIE_RX_P41")
	)
	(segment
		(start 247.085866 -80.335628)
		(end 248.229628 -73.849484)
		(width 0.1397)
		(layer "In2.Cu")
		(net "PCIE_RX_P41")
	)
	(segment
		(start 247.674638 -61.929772)
		(end 247.753886 -61.866526)
		(width 0.1016)
		(layer "In2.Cu")
		(net "PCIE_RX_P41")
	)
	(segment
		(start 209.572606 -167.922702)
		(end 243.38915 -119.627142)
		(width 0.1397)
		(layer "In2.Cu")
		(net "PCIE_RX_P41")
	)
	(segment
		(start 201.93508 -221.712028)
		(end 201.93508 -220.955616)
		(width 0.1397)
		(layer "In2.Cu")
		(net "PCIE_RX_P41")
	)
	(segment
		(start 247.850914 -61.790072)
		(end 247.851168 -61.790072)
		(width 0.1016)
		(layer "In2.Cu")
		(net "PCIE_RX_P41")
	)
	(segment
		(start 247.493536 -67.110864)
		(end 247.493536 -62.302136)
		(width 0.1016)
		(layer "In2.Cu")
		(net "PCIE_RX_P41")
	)
	(segment
		(start 206.039466 -187.96)
		(end 209.572606 -167.922702)
		(width 0.1397)
		(layer "In2.Cu")
		(net "PCIE_RX_P41")
	)
	(segment
		(start 247.895618 -61.755274)
		(end 247.901714 -61.750702)
		(width 0.1016)
		(layer "In2.Cu")
		(net "PCIE_RX_P41")
	)
	(segment
		(start 247.64111 -61.958728)
		(end 247.64238 -61.957712)
		(width 0.1016)
		(layer "In2.Cu")
		(net "PCIE_RX_P41")
	)
	(segment
		(start 248.70156 -89.499186)
		(end 247.085866 -80.335628)
		(width 0.1397)
		(layer "In2.Cu")
		(net "PCIE_RX_P41")
	)
	(segment
		(start 206.262732 -217.309954)
		(end 207.65643 -215.31961)
		(width 0.1397)
		(layer "In2.Cu")
		(net "PCIE_RX_P41")
	)
	(segment
		(start 247.753886 -61.866526)
		(end 247.754394 -61.866018)
		(width 0.1016)
		(layer "In2.Cu")
		(net "PCIE_RX_P41")
	)
	(segment
		(start 247.904254 -61.748416)
		(end 248.02592 -61.652404)
		(width 0.1016)
		(layer "In2.Cu")
		(net "PCIE_RX_P41")
	)
	(segment
		(start 247.82399 -61.811154)
		(end 247.82907 -61.807344)
		(width 0.1016)
		(layer "In2.Cu")
		(net "PCIE_RX_P41")
	)
	(segment
		(start 201.93508 -220.955616)
		(end 202.780138 -219.748608)
		(width 0.1397)
		(layer "In2.Cu")
		(net "PCIE_RX_P41")
	)
	(segment
		(start 247.4214 -69.26453)
		(end 247.4214 -67.183)
		(width 0.1397)
		(layer "In2.Cu")
		(net "PCIE_RX_P41")
	)
	(segment
		(start 202.780138 -219.748608)
		(end 206.262732 -217.309954)
		(width 0.1397)
		(layer "In2.Cu")
		(net "PCIE_RX_P41")
	)
	(segment
		(start 247.82907 -61.807344)
		(end 247.850914 -61.790072)
		(width 0.1016)
		(layer "In2.Cu")
		(net "PCIE_RX_P41")
	)
	(segment
		(start 247.4214 -67.183)
		(end 247.493536 -67.110864)
		(width 0.1016)
		(layer "In2.Cu")
		(net "PCIE_RX_P41")
	)
	(segment
		(start 247.797574 -61.831728)
		(end 247.818148 -61.815726)
		(width 0.1016)
		(layer "In2.Cu")
		(net "PCIE_RX_P41")
	)
	(segment
		(start 243.38915 -119.627142)
		(end 248.70156 -89.499186)
		(width 0.1397)
		(layer "In2.Cu")
		(net "PCIE_RX_P41")
	)
	(segment
		(start 247.818148 -61.815726)
		(end 247.82399 -61.811154)
		(width 0.1016)
		(layer "In2.Cu")
		(net "PCIE_RX_P41")
	)
	(segment
		(start 247.754394 -61.866018)
		(end 247.797574 -61.831728)
		(width 0.1016)
		(layer "In2.Cu")
		(net "PCIE_RX_P41")
	)
	(segment
		(start 247.857772 -61.784738)
		(end 247.895618 -61.755274)
		(width 0.1016)
		(layer "In2.Cu")
		(net "PCIE_RX_P41")
	)
	(segment
		(start 207.65643 -215.31961)
		(end 209.259932 -206.224886)
		(width 0.1397)
		(layer "In2.Cu")
		(net "PCIE_RX_P41")
	)
	(segment
		(start 209.259932 -206.224886)
		(end 206.039466 -187.96)
		(width 0.1397)
		(layer "In2.Cu")
		(net "PCIE_RX_P41")
	)
	(segment
		(start 248.229628 -73.849484)
		(end 247.4214 -69.26453)
		(width 0.1397)
		(layer "In2.Cu")
		(net "PCIE_RX_P41")
	)
	(arc
		(start 247.54332 -62.090554)
		(mid 247.586457 -62.02037)
		(end 247.64111 -61.958728)
		(width 0.1016)
		(layer "In2.Cu")
		(net "PCIE_RX_P41")
	)
	(arc
		(start 248.02592 -61.652404)
		(mid 248.080392 -61.584556)
		(end 248.099834 -61.49975)
		(width 0.1016)
		(layer "In2.Cu")
		(net "PCIE_RX_P41")
	)
	(arc
		(start 201.69378 -222.294704)
		(mid 201.872407 -222.02737)
		(end 201.93508 -221.712028)
		(width 0.1397)
		(layer "In2.Cu")
		(net "PCIE_RX_P41")
	)
	(arc
		(start 247.64238 -61.957712)
		(mid 247.658183 -61.943365)
		(end 247.674638 -61.929772)
		(width 0.1016)
		(layer "In2.Cu")
		(net "PCIE_RX_P41")
	)
	(arc
		(start 247.493536 -62.302136)
		(mid 247.506133 -62.193455)
		(end 247.54332 -62.090554)
		(width 0.1016)
		(layer "In2.Cu")
		(net "PCIE_RX_P41")
	)
	(segment
		(start 248.59996 -61.999876)
		(end 249.099832 -62.499748)
		(width 0.136652)
		(layer "F.Cu")
		(net "PCIE_RX_P40")
	)
	(via
		(at 249.099832 -62.499748)
		(size 0.4572)
		(drill 0.2032)
		(layers "F.Cu" "B.Cu")
		(net "PCIE_RX_P40")
	)
	(via
		(at 204.893672 -222.294704)
		(size 0.508)
		(drill 0.254)
		(layers "F.Cu" "B.Cu")
		(net "PCIE_RX_P40")
	)
	(segment
		(start 204.900022 -224.7138)
		(end 204.900276 -224.713546)
		(width 0.136652)
		(layer "B.Cu")
		(net "PCIE_RX_P40")
	)
	(segment
		(start 205.147672 -223.5962)
		(end 205.147672 -222.90786)
		(width 0.136652)
		(layer "B.Cu")
		(net "PCIE_RX_P40")
	)
	(segment
		(start 205.04023 -224.375726)
		(end 205.09103 -224.324926)
		(width 0.136652)
		(layer "B.Cu")
		(net "PCIE_RX_P40")
	)
	(segment
		(start 205.147926 -224.187512)
		(end 205.147926 -223.596454)
		(width 0.136652)
		(layer "B.Cu")
		(net "PCIE_RX_P40")
	)
	(segment
		(start 204.900022 -225.92538)
		(end 204.900022 -224.7138)
		(width 0.136652)
		(layer "B.Cu")
		(net "PCIE_RX_P40")
	)
	(segment
		(start 205.147926 -223.596454)
		(end 205.147672 -223.5962)
		(width 0.136652)
		(layer "B.Cu")
		(net "PCIE_RX_P40")
	)
	(arc
		(start 205.09103 -224.324926)
		(mid 205.133156 -224.26188)
		(end 205.147926 -224.187512)
		(width 0.136652)
		(layer "B.Cu")
		(net "PCIE_RX_P40")
	)
	(arc
		(start 205.147672 -222.90786)
		(mid 205.081664 -222.576014)
		(end 204.893672 -222.294704)
		(width 0.136652)
		(layer "B.Cu")
		(net "PCIE_RX_P40")
	)
	(arc
		(start 204.900276 -224.713546)
		(mid 204.936644 -224.53071)
		(end 205.04023 -224.375726)
		(width 0.136652)
		(layer "B.Cu")
		(net "PCIE_RX_P40")
	)
	(segment
		(start 248.850912 -62.79007)
		(end 248.829068 -62.807342)
		(width 0.1016)
		(layer "In2.Cu")
		(net "PCIE_RX_P40")
	)
	(segment
		(start 249.59437 -89.58707)
		(end 244.051582 -121.021856)
		(width 0.1397)
		(layer "In2.Cu")
		(net "PCIE_RX_P40")
	)
	(segment
		(start 210.25358 -206.151734)
		(end 208.533492 -215.906096)
		(width 0.1397)
		(layer "In2.Cu")
		(net "PCIE_RX_P40")
	)
	(segment
		(start 248.642378 -62.95771)
		(end 248.641108 -62.958726)
		(width 0.1016)
		(layer "In2.Cu")
		(net "PCIE_RX_P40")
	)
	(segment
		(start 249.209814 -73.646538)
		(end 247.99671 -80.526382)
		(width 0.1397)
		(layer "In2.Cu")
		(net "PCIE_RX_P40")
	)
	(segment
		(start 248.493534 -63.302134)
		(end 248.493534 -67.152266)
		(width 0.1016)
		(layer "In2.Cu")
		(net "PCIE_RX_P40")
	)
	(segment
		(start 248.4374 -67.2084)
		(end 248.4374 -69.26453)
		(width 0.1397)
		(layer "In2.Cu")
		(net "PCIE_RX_P40")
	)
	(segment
		(start 248.85777 -62.784736)
		(end 248.851166 -62.79007)
		(width 0.1016)
		(layer "In2.Cu")
		(net "PCIE_RX_P40")
	)
	(segment
		(start 248.4374 -69.26453)
		(end 249.209814 -73.646538)
		(width 0.1397)
		(layer "In2.Cu")
		(net "PCIE_RX_P40")
	)
	(segment
		(start 244.051582 -121.021856)
		(end 210.412838 -169.063416)
		(width 0.1397)
		(layer "In2.Cu")
		(net "PCIE_RX_P40")
	)
	(segment
		(start 248.754392 -62.866016)
		(end 248.753884 -62.866524)
		(width 0.1016)
		(layer "In2.Cu")
		(net "PCIE_RX_P40")
	)
	(segment
		(start 248.901712 -62.7507)
		(end 248.895616 -62.755272)
		(width 0.1016)
		(layer "In2.Cu")
		(net "PCIE_RX_P40")
	)
	(segment
		(start 248.797572 -62.831726)
		(end 248.754392 -62.866016)
		(width 0.1016)
		(layer "In2.Cu")
		(net "PCIE_RX_P40")
	)
	(segment
		(start 248.818146 -62.815724)
		(end 248.797572 -62.831726)
		(width 0.1016)
		(layer "In2.Cu")
		(net "PCIE_RX_P40")
	)
	(segment
		(start 248.493534 -67.152266)
		(end 248.4374 -67.2084)
		(width 0.1016)
		(layer "In2.Cu")
		(net "PCIE_RX_P40")
	)
	(segment
		(start 205.134972 -221.063566)
		(end 205.134972 -221.712028)
		(width 0.1397)
		(layer "In2.Cu")
		(net "PCIE_RX_P40")
	)
	(segment
		(start 249.025918 -62.652402)
		(end 248.904252 -62.748414)
		(width 0.1016)
		(layer "In2.Cu")
		(net "PCIE_RX_P40")
	)
	(segment
		(start 248.753884 -62.866524)
		(end 248.674636 -62.92977)
		(width 0.1016)
		(layer "In2.Cu")
		(net "PCIE_RX_P40")
	)
	(segment
		(start 248.829068 -62.807342)
		(end 248.823988 -62.811152)
		(width 0.1016)
		(layer "In2.Cu")
		(net "PCIE_RX_P40")
	)
	(segment
		(start 248.823988 -62.811152)
		(end 248.818146 -62.815724)
		(width 0.1016)
		(layer "In2.Cu")
		(net "PCIE_RX_P40")
	)
	(segment
		(start 207.06334 -188.058552)
		(end 210.25358 -206.151734)
		(width 0.1397)
		(layer "In2.Cu")
		(net "PCIE_RX_P40")
	)
	(segment
		(start 248.904252 -62.748414)
		(end 248.901712 -62.7507)
		(width 0.1016)
		(layer "In2.Cu")
		(net "PCIE_RX_P40")
	)
	(segment
		(start 247.99671 -80.526382)
		(end 249.59437 -89.58707)
		(width 0.1397)
		(layer "In2.Cu")
		(net "PCIE_RX_P40")
	)
	(segment
		(start 210.412838 -169.063416)
		(end 207.06334 -188.058552)
		(width 0.1397)
		(layer "In2.Cu")
		(net "PCIE_RX_P40")
	)
	(segment
		(start 208.533492 -215.906096)
		(end 205.30947 -220.5101)
		(width 0.1397)
		(layer "In2.Cu")
		(net "PCIE_RX_P40")
	)
	(segment
		(start 248.851166 -62.79007)
		(end 248.850912 -62.79007)
		(width 0.1016)
		(layer "In2.Cu")
		(net "PCIE_RX_P40")
	)
	(segment
		(start 248.895616 -62.755272)
		(end 248.85777 -62.784736)
		(width 0.1016)
		(layer "In2.Cu")
		(net "PCIE_RX_P40")
	)
	(arc
		(start 249.099832 -62.499748)
		(mid 249.080379 -62.584549)
		(end 249.025918 -62.652402)
		(width 0.1016)
		(layer "In2.Cu")
		(net "PCIE_RX_P40")
	)
	(arc
		(start 205.134972 -221.712028)
		(mid 205.072251 -222.02735)
		(end 204.893672 -222.294704)
		(width 0.1397)
		(layer "In2.Cu")
		(net "PCIE_RX_P40")
	)
	(arc
		(start 248.641108 -62.958726)
		(mid 248.586444 -63.02036)
		(end 248.543318 -63.090552)
		(width 0.1016)
		(layer "In2.Cu")
		(net "PCIE_RX_P40")
	)
	(arc
		(start 248.674636 -62.92977)
		(mid 248.658185 -62.943368)
		(end 248.642378 -62.95771)
		(width 0.1016)
		(layer "In2.Cu")
		(net "PCIE_RX_P40")
	)
	(arc
		(start 205.30947 -220.5101)
		(mid 205.179659 -220.773411)
		(end 205.134972 -221.063566)
		(width 0.1397)
		(layer "In2.Cu")
		(net "PCIE_RX_P40")
	)
	(arc
		(start 248.543318 -63.090552)
		(mid 248.506082 -63.193441)
		(end 248.493534 -63.302134)
		(width 0.1016)
		(layer "In2.Cu")
		(net "PCIE_RX_P40")
	)
	(segment
		(start 246.599964 -30.999938)
		(end 247.099836 -30.500066)
		(width 0.136652)
		(layer "F.Cu")
		(net "PCIE_RX_P4")
	)
	(via
		(at 247.099836 -30.500066)
		(size 0.4572)
		(drill 0.2032)
		(layers "F.Cu" "B.Cu")
		(net "PCIE_RX_P4")
	)
	(via
		(at 283.169868 -21.101812)
		(size 0.508)
		(drill 0.254)
		(layers "F.Cu" "B.Cu")
		(net "PCIE_RX_P4")
	)
	(segment
		(start 299.86224 -13.3985)
		(end 299.929804 -13.716508)
		(width 0.136652)
		(layer "B.Cu")
		(net "PCIE_RX_P4")
	)
	(segment
		(start 299.962316 -14.027658)
		(end 299.96257 -14.027658)
		(width 0.136652)
		(layer "B.Cu")
		(net "PCIE_RX_P4")
	)
	(segment
		(start 299.69841 -14.749018)
		(end 298.006008 -15.108682)
		(width 0.136652)
		(layer "B.Cu")
		(net "PCIE_RX_P4")
	)
	(segment
		(start 297.473878 -15.3289)
		(end 296.829734 -15.747492)
		(width 0.136652)
		(layer "B.Cu")
		(net "PCIE_RX_P4")
	)
	(segment
		(start 296.450258 -16.126968)
		(end 295.266364 -17.949672)
		(width 0.136652)
		(layer "B.Cu")
		(net "PCIE_RX_P4")
	)
	(segment
		(start 294.96893 -18.52168)
		(end 294.154098 -20.544536)
		(width 0.136652)
		(layer "B.Cu")
		(net "PCIE_RX_P4")
	)
	(segment
		(start 299.51934 -13.17625)
		(end 299.519594 -13.17625)
		(width 0.136652)
		(layer "B.Cu")
		(net "PCIE_RX_P4")
	)
	(segment
		(start 282.194 -21.9964)
		(end 282.194 -21.880576)
		(width 0.136652)
		(layer "B.Cu")
		(net "PCIE_RX_P4")
	)
	(segment
		(start 282.321 -21.559012)
		(end 282.668726 -21.211286)
		(width 0.136652)
		(layer "B.Cu")
		(net "PCIE_RX_P4")
	)
	(segment
		(start 299.384466 -13.930122)
		(end 299.296836 -13.518896)
		(width 0.136652)
		(layer "B.Cu")
		(net "PCIE_RX_P4")
	)
	(segment
		(start 299.96257 -14.027658)
		(end 299.96257 -14.422882)
		(width 0.136652)
		(layer "B.Cu")
		(net "PCIE_RX_P4")
	)
	(segment
		(start 293.940738 -20.86737)
		(end 292.338506 -22.469348)
		(width 0.136652)
		(layer "B.Cu")
		(net "PCIE_RX_P4")
	)
	(segment
		(start 291.963856 -22.6314)
		(end 282.829 -22.6314)
		(width 0.136652)
		(layer "B.Cu")
		(net "PCIE_RX_P4")
	)
	(arc
		(start 299.296836 -13.518896)
		(mid 299.337064 -13.301439)
		(end 299.51934 -13.17625)
		(width 0.136652)
		(layer "B.Cu")
		(net "PCIE_RX_P4")
	)
	(arc
		(start 296.829734 -15.747492)
		(mid 296.620063 -15.917297)
		(end 296.450258 -16.126968)
		(width 0.136652)
		(layer "B.Cu")
		(net "PCIE_RX_P4")
	)
	(arc
		(start 282.194 -21.880576)
		(mid 282.226897 -21.707706)
		(end 282.321 -21.559012)
		(width 0.136652)
		(layer "B.Cu")
		(net "PCIE_RX_P4")
	)
	(arc
		(start 282.829 -22.6314)
		(mid 282.379987 -22.445413)
		(end 282.194 -21.9964)
		(width 0.136652)
		(layer "B.Cu")
		(net "PCIE_RX_P4")
	)
	(arc
		(start 299.519594 -13.17625)
		(mid 299.736946 -13.216411)
		(end 299.86224 -13.3985)
		(width 0.136652)
		(layer "B.Cu")
		(net "PCIE_RX_P4")
	)
	(arc
		(start 299.929804 -13.716508)
		(mid 299.945012 -13.800091)
		(end 299.955458 -13.884402)
		(width 0.136652)
		(layer "B.Cu")
		(net "PCIE_RX_P4")
	)
	(arc
		(start 298.006008 -15.108682)
		(mid 297.729824 -15.194334)
		(end 297.473878 -15.3289)
		(width 0.136652)
		(layer "B.Cu")
		(net "PCIE_RX_P4")
	)
	(arc
		(start 299.955458 -13.884402)
		(mid 299.960596 -13.955948)
		(end 299.962316 -14.027658)
		(width 0.136652)
		(layer "B.Cu")
		(net "PCIE_RX_P4")
	)
	(arc
		(start 292.338506 -22.469348)
		(mid 292.166671 -22.586179)
		(end 291.963856 -22.6314)
		(width 0.136652)
		(layer "B.Cu")
		(net "PCIE_RX_P4")
	)
	(arc
		(start 282.668726 -21.211286)
		(mid 282.913387 -21.129492)
		(end 283.169868 -21.101812)
		(width 0.136652)
		(layer "B.Cu")
		(net "PCIE_RX_P4")
	)
	(arc
		(start 294.154098 -20.544536)
		(mid 294.063739 -20.71674)
		(end 293.940738 -20.86737)
		(width 0.136652)
		(layer "B.Cu")
		(net "PCIE_RX_P4")
	)
	(arc
		(start 295.266364 -17.949672)
		(mid 295.103836 -18.228494)
		(end 294.96893 -18.52168)
		(width 0.136652)
		(layer "B.Cu")
		(net "PCIE_RX_P4")
	)
	(arc
		(start 299.96257 -14.422882)
		(mid 299.888254 -14.632754)
		(end 299.69841 -14.749018)
		(width 0.136652)
		(layer "B.Cu")
		(net "PCIE_RX_P4")
	)
	(segment
		(start 272.48866 -21.059648)
		(end 277.109936 -20.244816)
		(width 0.1397)
		(layer "In2.Cu")
		(net "PCIE_RX_P4")
	)
	(segment
		(start 281.086052 -21.519642)
		(end 282.345384 -21.519642)
		(width 0.1397)
		(layer "In2.Cu")
		(net "PCIE_RX_P4")
	)
	(segment
		(start 257.490468 -20.268184)
		(end 260.670548 -20.9042)
		(width 0.1397)
		(layer "In2.Cu")
		(net "PCIE_RX_P4")
	)
	(segment
		(start 247.608344 -27.108404)
		(end 253.834646 -20.882356)
		(width 0.1397)
		(layer "In2.Cu")
		(net "PCIE_RX_P4")
	)
	(segment
		(start 253.834646 -20.882356)
		(end 257.490468 -20.268184)
		(width 0.1397)
		(layer "In2.Cu")
		(net "PCIE_RX_P4")
	)
	(segment
		(start 282.345384 -21.519642)
		(end 282.512516 -21.36902)
		(width 0.1397)
		(layer "In2.Cu")
		(net "PCIE_RX_P4")
	)
	(segment
		(start 277.109936 -20.244816)
		(end 279.325578 -20.635468)
		(width 0.1397)
		(layer "In2.Cu")
		(net "PCIE_RX_P4")
	)
	(segment
		(start 267.020548 -20.9042)
		(end 269.36573 -20.435062)
		(width 0.1397)
		(layer "In2.Cu")
		(net "PCIE_RX_P4")
	)
	(segment
		(start 260.670548 -20.9042)
		(end 263.845548 -20.2692)
		(width 0.1397)
		(layer "In2.Cu")
		(net "PCIE_RX_P4")
	)
	(segment
		(start 279.325578 -20.635468)
		(end 281.086052 -21.519642)
		(width 0.1397)
		(layer "In2.Cu")
		(net "PCIE_RX_P4")
	)
	(segment
		(start 263.845548 -20.2692)
		(end 267.020548 -20.9042)
		(width 0.1397)
		(layer "In2.Cu")
		(net "PCIE_RX_P4")
	)
	(segment
		(start 269.36573 -20.435062)
		(end 272.48866 -21.059648)
		(width 0.1397)
		(layer "In2.Cu")
		(net "PCIE_RX_P4")
	)
	(segment
		(start 247.608344 -29.04363)
		(end 247.608344 -27.108404)
		(width 0.1397)
		(layer "In2.Cu")
		(net "PCIE_RX_P4")
	)
	(arc
		(start 282.512516 -21.36902)
		(mid 282.815071 -21.171149)
		(end 283.169868 -21.101812)
		(width 0.1397)
		(layer "In2.Cu")
		(net "PCIE_RX_P4")
	)
	(arc
		(start 247.099836 -30.500066)
		(mid 247.477582 -29.814962)
		(end 247.608344 -29.04363)
		(width 0.1397)
		(layer "In2.Cu")
		(net "PCIE_RX_P4")
	)
	(segment
		(start 250.599956 -60.999878)
		(end 251.099828 -61.49975)
		(width 0.136652)
		(layer "F.Cu")
		(net "PCIE_RX_P39")
	)
	(via
		(at 251.099828 -61.49975)
		(size 0.4572)
		(drill 0.2032)
		(layers "F.Cu" "B.Cu")
		(net "PCIE_RX_P39")
	)
	(via
		(at 211.29371 -222.294704)
		(size 0.508)
		(drill 0.254)
		(layers "F.Cu" "B.Cu")
		(net "PCIE_RX_P39")
	)
	(segment
		(start 211.54771 -223.5962)
		(end 211.54771 -222.90786)
		(width 0.136652)
		(layer "B.Cu")
		(net "PCIE_RX_P39")
	)
	(segment
		(start 211.30006 -224.7138)
		(end 211.300314 -224.713546)
		(width 0.136652)
		(layer "B.Cu")
		(net "PCIE_RX_P39")
	)
	(segment
		(start 211.547964 -223.596454)
		(end 211.54771 -223.5962)
		(width 0.136652)
		(layer "B.Cu")
		(net "PCIE_RX_P39")
	)
	(segment
		(start 211.30006 -225.92538)
		(end 211.30006 -224.7138)
		(width 0.136652)
		(layer "B.Cu")
		(net "PCIE_RX_P39")
	)
	(segment
		(start 211.547964 -224.187512)
		(end 211.547964 -223.596454)
		(width 0.136652)
		(layer "B.Cu")
		(net "PCIE_RX_P39")
	)
	(segment
		(start 211.440268 -224.375726)
		(end 211.491068 -224.324926)
		(width 0.136652)
		(layer "B.Cu")
		(net "PCIE_RX_P39")
	)
	(arc
		(start 211.491068 -224.324926)
		(mid 211.533194 -224.26188)
		(end 211.547964 -224.187512)
		(width 0.136652)
		(layer "B.Cu")
		(net "PCIE_RX_P39")
	)
	(arc
		(start 211.54771 -222.90786)
		(mid 211.481702 -222.576014)
		(end 211.29371 -222.294704)
		(width 0.136652)
		(layer "B.Cu")
		(net "PCIE_RX_P39")
	)
	(arc
		(start 211.300314 -224.713546)
		(mid 211.336682 -224.53071)
		(end 211.440268 -224.375726)
		(width 0.136652)
		(layer "B.Cu")
		(net "PCIE_RX_P39")
	)
	(segment
		(start 250.823984 -61.811154)
		(end 250.829064 -61.807344)
		(width 0.1016)
		(layer "In2.Cu")
		(net "PCIE_RX_P39")
	)
	(segment
		(start 250.4186 -67.183)
		(end 250.49353 -67.10807)
		(width 0.1016)
		(layer "In2.Cu")
		(net "PCIE_RX_P39")
	)
	(segment
		(start 208.420208 -187.846716)
		(end 211.63788 -169.599102)
		(width 0.1397)
		(layer "In2.Cu")
		(net "PCIE_RX_P39")
	)
	(segment
		(start 250.857766 -61.784738)
		(end 250.895612 -61.755274)
		(width 0.1016)
		(layer "In2.Cu")
		(net "PCIE_RX_P39")
	)
	(segment
		(start 250.641104 -61.958728)
		(end 250.642374 -61.957712)
		(width 0.1016)
		(layer "In2.Cu")
		(net "PCIE_RX_P39")
	)
	(segment
		(start 210.96605 -211.415884)
		(end 210.96605 -211.244434)
		(width 0.1397)
		(layer "In2.Cu")
		(net "PCIE_RX_P39")
	)
	(segment
		(start 250.895612 -61.755274)
		(end 250.901708 -61.750702)
		(width 0.1016)
		(layer "In2.Cu")
		(net "PCIE_RX_P39")
	)
	(segment
		(start 250.818142 -61.815726)
		(end 250.823984 -61.811154)
		(width 0.1016)
		(layer "In2.Cu")
		(net "PCIE_RX_P39")
	)
	(segment
		(start 250.904248 -61.748416)
		(end 251.025914 -61.652404)
		(width 0.1016)
		(layer "In2.Cu")
		(net "PCIE_RX_P39")
	)
	(segment
		(start 250.75388 -61.866526)
		(end 250.754388 -61.866018)
		(width 0.1016)
		(layer "In2.Cu")
		(net "PCIE_RX_P39")
	)
	(segment
		(start 251.124466 -73.533)
		(end 250.4186 -69.528436)
		(width 0.1397)
		(layer "In2.Cu")
		(net "PCIE_RX_P39")
	)
	(segment
		(start 211.53501 -219.59951)
		(end 211.970874 -217.127582)
		(width 0.1397)
		(layer "In2.Cu")
		(net "PCIE_RX_P39")
	)
	(segment
		(start 250.851162 -61.790072)
		(end 250.857766 -61.784738)
		(width 0.1016)
		(layer "In2.Cu")
		(net "PCIE_RX_P39")
	)
	(segment
		(start 210.96351 -211.24164)
		(end 211.754466 -206.756)
		(width 0.1397)
		(layer "In2.Cu")
		(net "PCIE_RX_P39")
	)
	(segment
		(start 211.754466 -206.756)
		(end 208.420208 -187.846716)
		(width 0.1397)
		(layer "In2.Cu")
		(net "PCIE_RX_P39")
	)
	(segment
		(start 249.903996 -80.455008)
		(end 251.124466 -73.533)
		(width 0.1397)
		(layer "In2.Cu")
		(net "PCIE_RX_P39")
	)
	(segment
		(start 210.96605 -211.244434)
		(end 210.96351 -211.241894)
		(width 0.1397)
		(layer "In2.Cu")
		(net "PCIE_RX_P39")
	)
	(segment
		(start 250.901708 -61.750702)
		(end 250.904248 -61.748416)
		(width 0.1016)
		(layer "In2.Cu")
		(net "PCIE_RX_P39")
	)
	(segment
		(start 211.53501 -221.712028)
		(end 211.53501 -219.59951)
		(width 0.1397)
		(layer "In2.Cu")
		(net "PCIE_RX_P39")
	)
	(segment
		(start 250.674632 -61.929772)
		(end 250.75388 -61.866526)
		(width 0.1016)
		(layer "In2.Cu")
		(net "PCIE_RX_P39")
	)
	(segment
		(start 251.124466 -87.376)
		(end 249.903996 -80.455008)
		(width 0.1397)
		(layer "In2.Cu")
		(net "PCIE_RX_P39")
	)
	(segment
		(start 245.037102 -121.89968)
		(end 251.124466 -87.376)
		(width 0.1397)
		(layer "In2.Cu")
		(net "PCIE_RX_P39")
	)
	(segment
		(start 250.850908 -61.790072)
		(end 250.851162 -61.790072)
		(width 0.1016)
		(layer "In2.Cu")
		(net "PCIE_RX_P39")
	)
	(segment
		(start 250.754388 -61.866018)
		(end 250.797568 -61.831728)
		(width 0.1016)
		(layer "In2.Cu")
		(net "PCIE_RX_P39")
	)
	(segment
		(start 250.4186 -69.528436)
		(end 250.4186 -67.183)
		(width 0.1397)
		(layer "In2.Cu")
		(net "PCIE_RX_P39")
	)
	(segment
		(start 250.49353 -67.10807)
		(end 250.49353 -62.302136)
		(width 0.1016)
		(layer "In2.Cu")
		(net "PCIE_RX_P39")
	)
	(segment
		(start 250.829064 -61.807344)
		(end 250.850908 -61.790072)
		(width 0.1016)
		(layer "In2.Cu")
		(net "PCIE_RX_P39")
	)
	(segment
		(start 211.970874 -217.127582)
		(end 210.96605 -211.415884)
		(width 0.1397)
		(layer "In2.Cu")
		(net "PCIE_RX_P39")
	)
	(segment
		(start 211.63788 -169.599102)
		(end 245.037102 -121.89968)
		(width 0.1397)
		(layer "In2.Cu")
		(net "PCIE_RX_P39")
	)
	(segment
		(start 250.797568 -61.831728)
		(end 250.818142 -61.815726)
		(width 0.1016)
		(layer "In2.Cu")
		(net "PCIE_RX_P39")
	)
	(segment
		(start 210.96351 -211.241894)
		(end 210.96351 -211.24164)
		(width 0.1397)
		(layer "In2.Cu")
		(net "PCIE_RX_P39")
	)
	(arc
		(start 251.025914 -61.652404)
		(mid 251.080386 -61.584556)
		(end 251.099828 -61.49975)
		(width 0.1016)
		(layer "In2.Cu")
		(net "PCIE_RX_P39")
	)
	(arc
		(start 250.543314 -62.090554)
		(mid 250.586451 -62.02037)
		(end 250.641104 -61.958728)
		(width 0.1016)
		(layer "In2.Cu")
		(net "PCIE_RX_P39")
	)
	(arc
		(start 250.49353 -62.302136)
		(mid 250.506127 -62.193455)
		(end 250.543314 -62.090554)
		(width 0.1016)
		(layer "In2.Cu")
		(net "PCIE_RX_P39")
	)
	(arc
		(start 211.29371 -222.294704)
		(mid 211.472337 -222.02737)
		(end 211.53501 -221.712028)
		(width 0.1397)
		(layer "In2.Cu")
		(net "PCIE_RX_P39")
	)
	(arc
		(start 250.642374 -61.957712)
		(mid 250.658177 -61.943365)
		(end 250.674632 -61.929772)
		(width 0.1016)
		(layer "In2.Cu")
		(net "PCIE_RX_P39")
	)
	(segment
		(start 251.599954 -61.999876)
		(end 252.099826 -62.499748)
		(width 0.136652)
		(layer "F.Cu")
		(net "PCIE_RX_P38")
	)
	(via
		(at 214.493602 -222.294704)
		(size 0.508)
		(drill 0.254)
		(layers "F.Cu" "B.Cu")
		(net "PCIE_RX_P38")
	)
	(via
		(at 252.099826 -62.499748)
		(size 0.4572)
		(drill 0.2032)
		(layers "F.Cu" "B.Cu")
		(net "PCIE_RX_P38")
	)
	(segment
		(start 214.747856 -223.596454)
		(end 214.747602 -223.5962)
		(width 0.136652)
		(layer "B.Cu")
		(net "PCIE_RX_P38")
	)
	(segment
		(start 214.64016 -224.375726)
		(end 214.69096 -224.324926)
		(width 0.136652)
		(layer "B.Cu")
		(net "PCIE_RX_P38")
	)
	(segment
		(start 214.747602 -223.5962)
		(end 214.747602 -222.90786)
		(width 0.136652)
		(layer "B.Cu")
		(net "PCIE_RX_P38")
	)
	(segment
		(start 214.747856 -224.187512)
		(end 214.747856 -223.596454)
		(width 0.136652)
		(layer "B.Cu")
		(net "PCIE_RX_P38")
	)
	(segment
		(start 214.500206 -225.92538)
		(end 214.500206 -224.713546)
		(width 0.136652)
		(layer "B.Cu")
		(net "PCIE_RX_P38")
	)
	(arc
		(start 214.747602 -222.90786)
		(mid 214.681594 -222.576014)
		(end 214.493602 -222.294704)
		(width 0.136652)
		(layer "B.Cu")
		(net "PCIE_RX_P38")
	)
	(arc
		(start 214.500206 -224.713546)
		(mid 214.536574 -224.53071)
		(end 214.64016 -224.375726)
		(width 0.136652)
		(layer "B.Cu")
		(net "PCIE_RX_P38")
	)
	(arc
		(start 214.69096 -224.324926)
		(mid 214.733086 -224.26188)
		(end 214.747856 -224.187512)
		(width 0.136652)
		(layer "B.Cu")
		(net "PCIE_RX_P38")
	)
	(segment
		(start 214.734902 -220.274642)
		(end 214.734902 -221.712028)
		(width 0.1397)
		(layer "In2.Cu")
		(net "PCIE_RX_P38")
	)
	(segment
		(start 214.372444 -207.577436)
		(end 214.6808 -209.324956)
		(width 0.1397)
		(layer "In2.Cu")
		(net "PCIE_RX_P38")
	)
	(segment
		(start 251.493528 -63.302134)
		(end 251.493528 -67.141344)
		(width 0.1016)
		(layer "In2.Cu")
		(net "PCIE_RX_P38")
	)
	(segment
		(start 251.823982 -62.811152)
		(end 251.81814 -62.815724)
		(width 0.1016)
		(layer "In2.Cu")
		(net "PCIE_RX_P38")
	)
	(segment
		(start 251.829062 -62.807342)
		(end 251.823982 -62.811152)
		(width 0.1016)
		(layer "In2.Cu")
		(net "PCIE_RX_P38")
	)
	(segment
		(start 251.89561 -62.755272)
		(end 251.857764 -62.784736)
		(width 0.1016)
		(layer "In2.Cu")
		(net "PCIE_RX_P38")
	)
	(segment
		(start 251.904246 -62.748414)
		(end 251.901706 -62.7507)
		(width 0.1016)
		(layer "In2.Cu")
		(net "PCIE_RX_P38")
	)
	(segment
		(start 251.797566 -62.831726)
		(end 251.754386 -62.866016)
		(width 0.1016)
		(layer "In2.Cu")
		(net "PCIE_RX_P38")
	)
	(segment
		(start 214.447628 -218.645994)
		(end 214.734902 -220.274642)
		(width 0.1397)
		(layer "In2.Cu")
		(net "PCIE_RX_P38")
	)
	(segment
		(start 251.81814 -62.815724)
		(end 251.797566 -62.831726)
		(width 0.1016)
		(layer "In2.Cu")
		(net "PCIE_RX_P38")
	)
	(segment
		(start 212.824822 -170.414188)
		(end 209.86623 -187.193682)
		(width 0.1397)
		(layer "In2.Cu")
		(net "PCIE_RX_P38")
	)
	(segment
		(start 246.091202 -122.905266)
		(end 212.824822 -170.414188)
		(width 0.1397)
		(layer "In2.Cu")
		(net "PCIE_RX_P38")
	)
	(segment
		(start 251.430536 -67.204336)
		(end 251.430536 -69.26453)
		(width 0.1397)
		(layer "In2.Cu")
		(net "PCIE_RX_P38")
	)
	(segment
		(start 214.6808 -213.592156)
		(end 215.00973 -215.458548)
		(width 0.1397)
		(layer "In2.Cu")
		(net "PCIE_RX_P38")
	)
	(segment
		(start 215.00973 -215.458548)
		(end 214.447628 -218.645994)
		(width 0.1397)
		(layer "In2.Cu")
		(net "PCIE_RX_P38")
	)
	(segment
		(start 251.85116 -62.79007)
		(end 251.850906 -62.79007)
		(width 0.1016)
		(layer "In2.Cu")
		(net "PCIE_RX_P38")
	)
	(segment
		(start 251.493528 -67.141344)
		(end 251.430536 -67.204336)
		(width 0.1016)
		(layer "In2.Cu")
		(net "PCIE_RX_P38")
	)
	(segment
		(start 214.6808 -209.324956)
		(end 214.6808 -213.592156)
		(width 0.1397)
		(layer "In2.Cu")
		(net "PCIE_RX_P38")
	)
	(segment
		(start 251.857764 -62.784736)
		(end 251.85116 -62.79007)
		(width 0.1016)
		(layer "In2.Cu")
		(net "PCIE_RX_P38")
	)
	(segment
		(start 209.86623 -187.193682)
		(end 213.153244 -205.836266)
		(width 0.1397)
		(layer "In2.Cu")
		(net "PCIE_RX_P38")
	)
	(segment
		(start 252.025912 -62.652402)
		(end 251.904246 -62.748414)
		(width 0.1016)
		(layer "In2.Cu")
		(net "PCIE_RX_P38")
	)
	(segment
		(start 251.754386 -62.866016)
		(end 251.753878 -62.866524)
		(width 0.1016)
		(layer "In2.Cu")
		(net "PCIE_RX_P38")
	)
	(segment
		(start 252.167644 -73.445878)
		(end 250.994418 -80.099154)
		(width 0.1397)
		(layer "In2.Cu")
		(net "PCIE_RX_P38")
	)
	(segment
		(start 251.901706 -62.7507)
		(end 251.89561 -62.755272)
		(width 0.1016)
		(layer "In2.Cu")
		(net "PCIE_RX_P38")
	)
	(segment
		(start 251.850906 -62.79007)
		(end 251.829062 -62.807342)
		(width 0.1016)
		(layer "In2.Cu")
		(net "PCIE_RX_P38")
	)
	(segment
		(start 252.316742 -87.598504)
		(end 246.091202 -122.905266)
		(width 0.1397)
		(layer "In2.Cu")
		(net "PCIE_RX_P38")
	)
	(segment
		(start 213.153244 -205.836266)
		(end 214.372444 -207.577436)
		(width 0.1397)
		(layer "In2.Cu")
		(net "PCIE_RX_P38")
	)
	(segment
		(start 251.753878 -62.866524)
		(end 251.67463 -62.92977)
		(width 0.1016)
		(layer "In2.Cu")
		(net "PCIE_RX_P38")
	)
	(segment
		(start 251.642372 -62.95771)
		(end 251.641102 -62.958726)
		(width 0.1016)
		(layer "In2.Cu")
		(net "PCIE_RX_P38")
	)
	(segment
		(start 250.994418 -80.099154)
		(end 252.316742 -87.598504)
		(width 0.1397)
		(layer "In2.Cu")
		(net "PCIE_RX_P38")
	)
	(segment
		(start 251.430536 -69.26453)
		(end 252.167644 -73.445878)
		(width 0.1397)
		(layer "In2.Cu")
		(net "PCIE_RX_P38")
	)
	(arc
		(start 251.641102 -62.958726)
		(mid 251.586438 -63.02036)
		(end 251.543312 -63.090552)
		(width 0.1016)
		(layer "In2.Cu")
		(net "PCIE_RX_P38")
	)
	(arc
		(start 214.734902 -221.712028)
		(mid 214.672181 -222.02735)
		(end 214.493602 -222.294704)
		(width 0.1397)
		(layer "In2.Cu")
		(net "PCIE_RX_P38")
	)
	(arc
		(start 251.543312 -63.090552)
		(mid 251.506076 -63.193441)
		(end 251.493528 -63.302134)
		(width 0.1016)
		(layer "In2.Cu")
		(net "PCIE_RX_P38")
	)
	(arc
		(start 251.67463 -62.92977)
		(mid 251.658179 -62.943368)
		(end 251.642372 -62.95771)
		(width 0.1016)
		(layer "In2.Cu")
		(net "PCIE_RX_P38")
	)
	(arc
		(start 252.099826 -62.499748)
		(mid 252.080373 -62.584549)
		(end 252.025912 -62.652402)
		(width 0.1016)
		(layer "In2.Cu")
		(net "PCIE_RX_P38")
	)
	(segment
		(start 252.599952 -60.999878)
		(end 253.099824 -61.49975)
		(width 0.136652)
		(layer "F.Cu")
		(net "PCIE_RX_P37")
	)
	(via
		(at 253.099824 -61.49975)
		(size 0.4572)
		(drill 0.2032)
		(layers "F.Cu" "B.Cu")
		(net "PCIE_RX_P37")
	)
	(via
		(at 262.893556 -222.294704)
		(size 0.508)
		(drill 0.254)
		(layers "F.Cu" "B.Cu")
		(net "PCIE_RX_P37")
	)
	(segment
		(start 263.147556 -223.5962)
		(end 263.147556 -222.90786)
		(width 0.136652)
		(layer "B.Cu")
		(net "PCIE_RX_P37")
	)
	(segment
		(start 262.90016 -225.92538)
		(end 262.90016 -224.713546)
		(width 0.136652)
		(layer "B.Cu")
		(net "PCIE_RX_P37")
	)
	(segment
		(start 263.14781 -223.596454)
		(end 263.147556 -223.5962)
		(width 0.136652)
		(layer "B.Cu")
		(net "PCIE_RX_P37")
	)
	(segment
		(start 263.14781 -224.187512)
		(end 263.14781 -223.596454)
		(width 0.136652)
		(layer "B.Cu")
		(net "PCIE_RX_P37")
	)
	(segment
		(start 263.040114 -224.375726)
		(end 263.090914 -224.324926)
		(width 0.136652)
		(layer "B.Cu")
		(net "PCIE_RX_P37")
	)
	(arc
		(start 263.147556 -222.90786)
		(mid 263.081548 -222.576014)
		(end 262.893556 -222.294704)
		(width 0.136652)
		(layer "B.Cu")
		(net "PCIE_RX_P37")
	)
	(arc
		(start 262.90016 -224.713546)
		(mid 262.936528 -224.53071)
		(end 263.040114 -224.375726)
		(width 0.136652)
		(layer "B.Cu")
		(net "PCIE_RX_P37")
	)
	(arc
		(start 263.090914 -224.324926)
		(mid 263.13304 -224.26188)
		(end 263.14781 -224.187512)
		(width 0.136652)
		(layer "B.Cu")
		(net "PCIE_RX_P37")
	)
	(segment
		(start 253.696216 -76.29144)
		(end 253.69647 -76.29144)
		(width 0.1397)
		(layer "In2.Cu")
		(net "PCIE_RX_P37")
	)
	(segment
		(start 252.851158 -61.790072)
		(end 252.857762 -61.784738)
		(width 0.1016)
		(layer "In2.Cu")
		(net "PCIE_RX_P37")
	)
	(segment
		(start 252.493526 -67.165982)
		(end 252.493526 -62.302136)
		(width 0.1016)
		(layer "In2.Cu")
		(net "PCIE_RX_P37")
	)
	(segment
		(start 252.850904 -61.790072)
		(end 252.851158 -61.790072)
		(width 0.1016)
		(layer "In2.Cu")
		(net "PCIE_RX_P37")
	)
	(segment
		(start 252.450854 -67.208654)
		(end 252.493526 -67.165982)
		(width 0.1016)
		(layer "In2.Cu")
		(net "PCIE_RX_P37")
	)
	(segment
		(start 252.82398 -61.811154)
		(end 252.82906 -61.807344)
		(width 0.1016)
		(layer "In2.Cu")
		(net "PCIE_RX_P37")
	)
	(segment
		(start 252.797564 -61.831728)
		(end 252.818138 -61.815726)
		(width 0.1016)
		(layer "In2.Cu")
		(net "PCIE_RX_P37")
	)
	(segment
		(start 252.857762 -61.784738)
		(end 252.895608 -61.755274)
		(width 0.1016)
		(layer "In2.Cu")
		(net "PCIE_RX_P37")
	)
	(segment
		(start 252.6411 -61.958728)
		(end 252.64237 -61.957712)
		(width 0.1016)
		(layer "In2.Cu")
		(net "PCIE_RX_P37")
	)
	(segment
		(start 253.692406 -76.282804)
		(end 253.688342 -76.28128)
		(width 0.1397)
		(layer "In2.Cu")
		(net "PCIE_RX_P37")
	)
	(segment
		(start 252.450854 -69.26453)
		(end 252.450854 -67.208654)
		(width 0.1397)
		(layer "In2.Cu")
		(net "PCIE_RX_P37")
	)
	(segment
		(start 253.687834 -76.280518)
		(end 252.450854 -69.26453)
		(width 0.1397)
		(layer "In2.Cu")
		(net "PCIE_RX_P37")
	)
	(segment
		(start 252.82906 -61.807344)
		(end 252.850904 -61.790072)
		(width 0.1016)
		(layer "In2.Cu")
		(net "PCIE_RX_P37")
	)
	(segment
		(start 260.014974 -89.720674)
		(end 253.696216 -76.29144)
		(width 0.1397)
		(layer "In2.Cu")
		(net "PCIE_RX_P37")
	)
	(segment
		(start 262.893556 -222.294704)
		(end 262.950706 -222.237808)
		(width 0.1397)
		(layer "In2.Cu")
		(net "PCIE_RX_P37")
	)
	(segment
		(start 252.901704 -61.750702)
		(end 252.904244 -61.748416)
		(width 0.1016)
		(layer "In2.Cu")
		(net "PCIE_RX_P37")
	)
	(segment
		(start 252.754384 -61.866018)
		(end 252.797564 -61.831728)
		(width 0.1016)
		(layer "In2.Cu")
		(net "PCIE_RX_P37")
	)
	(segment
		(start 253.69647 -76.29144)
		(end 253.692406 -76.282804)
		(width 0.1397)
		(layer "In2.Cu")
		(net "PCIE_RX_P37")
	)
	(segment
		(start 262.000238 -212.711284)
		(end 271.850866 -156.845)
		(width 0.1397)
		(layer "In2.Cu")
		(net "PCIE_RX_P37")
	)
	(segment
		(start 252.753876 -61.866526)
		(end 252.754384 -61.866018)
		(width 0.1016)
		(layer "In2.Cu")
		(net "PCIE_RX_P37")
	)
	(segment
		(start 252.674628 -61.929772)
		(end 252.753876 -61.866526)
		(width 0.1016)
		(layer "In2.Cu")
		(net "PCIE_RX_P37")
	)
	(segment
		(start 271.850866 -156.845)
		(end 260.014974 -89.720674)
		(width 0.1397)
		(layer "In2.Cu")
		(net "PCIE_RX_P37")
	)
	(segment
		(start 253.688342 -76.28128)
		(end 253.687834 -76.280518)
		(width 0.1397)
		(layer "In2.Cu")
		(net "PCIE_RX_P37")
	)
	(segment
		(start 263.134856 -221.7928)
		(end 263.134856 -219.145866)
		(width 0.1397)
		(layer "In2.Cu")
		(net "PCIE_RX_P37")
	)
	(segment
		(start 263.134856 -219.145866)
		(end 262.000238 -212.711284)
		(width 0.1397)
		(layer "In2.Cu")
		(net "PCIE_RX_P37")
	)
	(segment
		(start 252.818138 -61.815726)
		(end 252.82398 -61.811154)
		(width 0.1016)
		(layer "In2.Cu")
		(net "PCIE_RX_P37")
	)
	(segment
		(start 252.895608 -61.755274)
		(end 252.901704 -61.750702)
		(width 0.1016)
		(layer "In2.Cu")
		(net "PCIE_RX_P37")
	)
	(segment
		(start 252.904244 -61.748416)
		(end 253.02591 -61.652404)
		(width 0.1016)
		(layer "In2.Cu")
		(net "PCIE_RX_P37")
	)
	(arc
		(start 252.64237 -61.957712)
		(mid 252.658173 -61.943365)
		(end 252.674628 -61.929772)
		(width 0.1016)
		(layer "In2.Cu")
		(net "PCIE_RX_P37")
	)
	(arc
		(start 252.54331 -62.090554)
		(mid 252.586447 -62.02037)
		(end 252.6411 -61.958728)
		(width 0.1016)
		(layer "In2.Cu")
		(net "PCIE_RX_P37")
	)
	(arc
		(start 252.493526 -62.302136)
		(mid 252.506123 -62.193455)
		(end 252.54331 -62.090554)
		(width 0.1016)
		(layer "In2.Cu")
		(net "PCIE_RX_P37")
	)
	(arc
		(start 262.950706 -222.237808)
		(mid 263.087046 -222.033622)
		(end 263.134856 -221.7928)
		(width 0.1397)
		(layer "In2.Cu")
		(net "PCIE_RX_P37")
	)
	(arc
		(start 253.02591 -61.652404)
		(mid 253.080382 -61.584556)
		(end 253.099824 -61.49975)
		(width 0.1016)
		(layer "In2.Cu")
		(net "PCIE_RX_P37")
	)
	(segment
		(start 253.59995 -61.999876)
		(end 254.099822 -62.499748)
		(width 0.136652)
		(layer "F.Cu")
		(net "PCIE_RX_P36")
	)
	(via
		(at 254.099822 -62.499748)
		(size 0.4572)
		(drill 0.2032)
		(layers "F.Cu" "B.Cu")
		(net "PCIE_RX_P36")
	)
	(via
		(at 266.093702 -222.294704)
		(size 0.508)
		(drill 0.254)
		(layers "F.Cu" "B.Cu")
		(net "PCIE_RX_P36")
	)
	(segment
		(start 266.100052 -224.7138)
		(end 266.100306 -224.713546)
		(width 0.136652)
		(layer "B.Cu")
		(net "PCIE_RX_P36")
	)
	(segment
		(start 266.347956 -223.596454)
		(end 266.347702 -223.5962)
		(width 0.136652)
		(layer "B.Cu")
		(net "PCIE_RX_P36")
	)
	(segment
		(start 266.100052 -225.92538)
		(end 266.100052 -224.7138)
		(width 0.136652)
		(layer "B.Cu")
		(net "PCIE_RX_P36")
	)
	(segment
		(start 266.24026 -224.375726)
		(end 266.29106 -224.324926)
		(width 0.136652)
		(layer "B.Cu")
		(net "PCIE_RX_P36")
	)
	(segment
		(start 266.347956 -224.187512)
		(end 266.347956 -223.596454)
		(width 0.136652)
		(layer "B.Cu")
		(net "PCIE_RX_P36")
	)
	(segment
		(start 266.347702 -223.5962)
		(end 266.347702 -222.90786)
		(width 0.136652)
		(layer "B.Cu")
		(net "PCIE_RX_P36")
	)
	(arc
		(start 266.29106 -224.324926)
		(mid 266.333186 -224.26188)
		(end 266.347956 -224.187512)
		(width 0.136652)
		(layer "B.Cu")
		(net "PCIE_RX_P36")
	)
	(arc
		(start 266.100306 -224.713546)
		(mid 266.136674 -224.53071)
		(end 266.24026 -224.375726)
		(width 0.136652)
		(layer "B.Cu")
		(net "PCIE_RX_P36")
	)
	(arc
		(start 266.347702 -222.90786)
		(mid 266.281694 -222.576014)
		(end 266.093702 -222.294704)
		(width 0.136652)
		(layer "B.Cu")
		(net "PCIE_RX_P36")
	)
	(segment
		(start 253.4539 -67.291204)
		(end 253.4539 -69.350636)
		(width 0.1397)
		(layer "In2.Cu")
		(net "PCIE_RX_P36")
	)
	(segment
		(start 253.753874 -62.866524)
		(end 253.674626 -62.92977)
		(width 0.1016)
		(layer "In2.Cu")
		(net "PCIE_RX_P36")
	)
	(segment
		(start 261.703312 -84.88045)
		(end 273.639534 -152.57526)
		(width 0.1397)
		(layer "In2.Cu")
		(net "PCIE_RX_P36")
	)
	(segment
		(start 253.901702 -62.7507)
		(end 253.895606 -62.755272)
		(width 0.1016)
		(layer "In2.Cu")
		(net "PCIE_RX_P36")
	)
	(segment
		(start 265.739626 -216.878916)
		(end 266.335002 -220.255338)
		(width 0.1397)
		(layer "In2.Cu")
		(net "PCIE_RX_P36")
	)
	(segment
		(start 265.019028 -201.462386)
		(end 266.2936 -208.689956)
		(width 0.1397)
		(layer "In2.Cu")
		(net "PCIE_RX_P36")
	)
	(segment
		(start 253.493524 -67.25158)
		(end 253.4539 -67.291204)
		(width 0.1016)
		(layer "In2.Cu")
		(net "PCIE_RX_P36")
	)
	(segment
		(start 253.829058 -62.807342)
		(end 253.823978 -62.811152)
		(width 0.1016)
		(layer "In2.Cu")
		(net "PCIE_RX_P36")
	)
	(segment
		(start 266.2936 -213.737444)
		(end 265.739626 -216.878916)
		(width 0.1397)
		(layer "In2.Cu")
		(net "PCIE_RX_P36")
	)
	(segment
		(start 253.797562 -62.831726)
		(end 253.754382 -62.866016)
		(width 0.1016)
		(layer "In2.Cu")
		(net "PCIE_RX_P36")
	)
	(segment
		(start 253.851156 -62.79007)
		(end 253.850902 -62.79007)
		(width 0.1016)
		(layer "In2.Cu")
		(net "PCIE_RX_P36")
	)
	(segment
		(start 254.097282 -73.00214)
		(end 254.09779 -73.003156)
		(width 0.1397)
		(layer "In2.Cu")
		(net "PCIE_RX_P36")
	)
	(segment
		(start 266.2936 -208.689956)
		(end 266.2936 -213.737444)
		(width 0.1397)
		(layer "In2.Cu")
		(net "PCIE_RX_P36")
	)
	(segment
		(start 253.895606 -62.755272)
		(end 253.85776 -62.784736)
		(width 0.1016)
		(layer "In2.Cu")
		(net "PCIE_RX_P36")
	)
	(segment
		(start 253.642368 -62.95771)
		(end 253.641098 -62.958726)
		(width 0.1016)
		(layer "In2.Cu")
		(net "PCIE_RX_P36")
	)
	(segment
		(start 255.114806 -75.470004)
		(end 261.703312 -84.88045)
		(width 0.1397)
		(layer "In2.Cu")
		(net "PCIE_RX_P36")
	)
	(segment
		(start 253.904242 -62.748414)
		(end 253.901702 -62.7507)
		(width 0.1016)
		(layer "In2.Cu")
		(net "PCIE_RX_P36")
	)
	(segment
		(start 254.09779 -73.003156)
		(end 254.101854 -73.00468)
		(width 0.1397)
		(layer "In2.Cu")
		(net "PCIE_RX_P36")
	)
	(segment
		(start 266.335002 -220.255338)
		(end 266.335002 -221.7928)
		(width 0.1397)
		(layer "In2.Cu")
		(net "PCIE_RX_P36")
	)
	(segment
		(start 253.818136 -62.815724)
		(end 253.797562 -62.831726)
		(width 0.1016)
		(layer "In2.Cu")
		(net "PCIE_RX_P36")
	)
	(segment
		(start 253.4539 -69.350636)
		(end 254.097282 -73.00214)
		(width 0.1397)
		(layer "In2.Cu")
		(net "PCIE_RX_P36")
	)
	(segment
		(start 254.025908 -62.652402)
		(end 253.904242 -62.748414)
		(width 0.1016)
		(layer "In2.Cu")
		(net "PCIE_RX_P36")
	)
	(segment
		(start 273.639534 -152.57526)
		(end 265.019028 -201.462386)
		(width 0.1397)
		(layer "In2.Cu")
		(net "PCIE_RX_P36")
	)
	(segment
		(start 253.85776 -62.784736)
		(end 253.851156 -62.79007)
		(width 0.1016)
		(layer "In2.Cu")
		(net "PCIE_RX_P36")
	)
	(segment
		(start 254.101854 -73.00468)
		(end 255.114806 -75.470004)
		(width 0.1397)
		(layer "In2.Cu")
		(net "PCIE_RX_P36")
	)
	(segment
		(start 253.754382 -62.866016)
		(end 253.753874 -62.866524)
		(width 0.1016)
		(layer "In2.Cu")
		(net "PCIE_RX_P36")
	)
	(segment
		(start 266.150852 -222.237808)
		(end 266.093702 -222.294704)
		(width 0.1397)
		(layer "In2.Cu")
		(net "PCIE_RX_P36")
	)
	(segment
		(start 253.850902 -62.79007)
		(end 253.829058 -62.807342)
		(width 0.1016)
		(layer "In2.Cu")
		(net "PCIE_RX_P36")
	)
	(segment
		(start 253.493524 -63.302134)
		(end 253.493524 -67.25158)
		(width 0.1016)
		(layer "In2.Cu")
		(net "PCIE_RX_P36")
	)
	(segment
		(start 253.823978 -62.811152)
		(end 253.818136 -62.815724)
		(width 0.1016)
		(layer "In2.Cu")
		(net "PCIE_RX_P36")
	)
	(arc
		(start 253.543308 -63.090552)
		(mid 253.506072 -63.193441)
		(end 253.493524 -63.302134)
		(width 0.1016)
		(layer "In2.Cu")
		(net "PCIE_RX_P36")
	)
	(arc
		(start 253.674626 -62.92977)
		(mid 253.658175 -62.943368)
		(end 253.642368 -62.95771)
		(width 0.1016)
		(layer "In2.Cu")
		(net "PCIE_RX_P36")
	)
	(arc
		(start 266.335002 -221.7928)
		(mid 266.287193 -222.033622)
		(end 266.150852 -222.237808)
		(width 0.1397)
		(layer "In2.Cu")
		(net "PCIE_RX_P36")
	)
	(arc
		(start 253.641098 -62.958726)
		(mid 253.586434 -63.02036)
		(end 253.543308 -63.090552)
		(width 0.1016)
		(layer "In2.Cu")
		(net "PCIE_RX_P36")
	)
	(arc
		(start 254.099822 -62.499748)
		(mid 254.080369 -62.584549)
		(end 254.025908 -62.652402)
		(width 0.1016)
		(layer "In2.Cu")
		(net "PCIE_RX_P36")
	)
	(segment
		(start 254.599948 -60.999878)
		(end 255.09982 -61.49975)
		(width 0.136652)
		(layer "F.Cu")
		(net "PCIE_RX_P35")
	)
	(via
		(at 255.09982 -61.49975)
		(size 0.4572)
		(drill 0.2032)
		(layers "F.Cu" "B.Cu")
		(net "PCIE_RX_P35")
	)
	(via
		(at 272.49374 -222.294704)
		(size 0.508)
		(drill 0.254)
		(layers "F.Cu" "B.Cu")
		(net "PCIE_RX_P35")
	)
	(segment
		(start 272.640298 -224.375726)
		(end 272.691098 -224.324926)
		(width 0.136652)
		(layer "B.Cu")
		(net "PCIE_RX_P35")
	)
	(segment
		(start 272.74774 -223.5962)
		(end 272.74774 -222.90786)
		(width 0.136652)
		(layer "B.Cu")
		(net "PCIE_RX_P35")
	)
	(segment
		(start 272.747994 -223.596454)
		(end 272.74774 -223.5962)
		(width 0.136652)
		(layer "B.Cu")
		(net "PCIE_RX_P35")
	)
	(segment
		(start 272.50009 -225.92538)
		(end 272.50009 -224.7138)
		(width 0.136652)
		(layer "B.Cu")
		(net "PCIE_RX_P35")
	)
	(segment
		(start 272.747994 -224.187512)
		(end 272.747994 -223.596454)
		(width 0.136652)
		(layer "B.Cu")
		(net "PCIE_RX_P35")
	)
	(segment
		(start 272.50009 -224.7138)
		(end 272.500344 -224.713546)
		(width 0.136652)
		(layer "B.Cu")
		(net "PCIE_RX_P35")
	)
	(arc
		(start 272.691098 -224.324926)
		(mid 272.733224 -224.26188)
		(end 272.747994 -224.187512)
		(width 0.136652)
		(layer "B.Cu")
		(net "PCIE_RX_P35")
	)
	(arc
		(start 272.500344 -224.713546)
		(mid 272.536712 -224.53071)
		(end 272.640298 -224.375726)
		(width 0.136652)
		(layer "B.Cu")
		(net "PCIE_RX_P35")
	)
	(arc
		(start 272.74774 -222.90786)
		(mid 272.681732 -222.576014)
		(end 272.49374 -222.294704)
		(width 0.136652)
		(layer "B.Cu")
		(net "PCIE_RX_P35")
	)
	(segment
		(start 255.023112 -72.619362)
		(end 254.4318 -69.26453)
		(width 0.1397)
		(layer "In2.Cu")
		(net "PCIE_RX_P35")
	)
	(segment
		(start 272.708624 -209.178398)
		(end 272.866866 -208.28)
		(width 0.1397)
		(layer "In2.Cu")
		(net "PCIE_RX_P35")
	)
	(segment
		(start 254.895604 -61.755274)
		(end 254.9017 -61.750702)
		(width 0.1016)
		(layer "In2.Cu")
		(net "PCIE_RX_P35")
	)
	(segment
		(start 254.90424 -61.748416)
		(end 255.025906 -61.652404)
		(width 0.1016)
		(layer "In2.Cu")
		(net "PCIE_RX_P35")
	)
	(segment
		(start 254.818134 -61.815726)
		(end 254.823976 -61.811154)
		(width 0.1016)
		(layer "In2.Cu")
		(net "PCIE_RX_P35")
	)
	(segment
		(start 273.000978 -218.30538)
		(end 272.437352 -215.108536)
		(width 0.1397)
		(layer "In2.Cu")
		(net "PCIE_RX_P35")
	)
	(segment
		(start 254.9017 -61.750702)
		(end 254.90424 -61.748416)
		(width 0.1016)
		(layer "In2.Cu")
		(net "PCIE_RX_P35")
	)
	(segment
		(start 272.708624 -213.57082)
		(end 272.708624 -209.178398)
		(width 0.1397)
		(layer "In2.Cu")
		(net "PCIE_RX_P35")
	)
	(segment
		(start 254.829056 -61.807344)
		(end 254.8509 -61.790072)
		(width 0.1016)
		(layer "In2.Cu")
		(net "PCIE_RX_P35")
	)
	(segment
		(start 254.4318 -67.183)
		(end 254.4318 -67.1703)
		(width 0.1016)
		(layer "In2.Cu")
		(net "PCIE_RX_P35")
	)
	(segment
		(start 268.292326 -91.56954)
		(end 255.023112 -72.619362)
		(width 0.1397)
		(layer "In2.Cu")
		(net "PCIE_RX_P35")
	)
	(segment
		(start 254.851154 -61.790072)
		(end 254.857758 -61.784738)
		(width 0.1016)
		(layer "In2.Cu")
		(net "PCIE_RX_P35")
	)
	(segment
		(start 254.79756 -61.831728)
		(end 254.818134 -61.815726)
		(width 0.1016)
		(layer "In2.Cu")
		(net "PCIE_RX_P35")
	)
	(segment
		(start 272.73504 -221.7928)
		(end 272.73504 -219.81414)
		(width 0.1397)
		(layer "In2.Cu")
		(net "PCIE_RX_P35")
	)
	(segment
		(start 254.674624 -61.929772)
		(end 254.753872 -61.866526)
		(width 0.1016)
		(layer "In2.Cu")
		(net "PCIE_RX_P35")
	)
	(segment
		(start 272.437352 -215.108536)
		(end 272.708624 -213.57082)
		(width 0.1397)
		(layer "In2.Cu")
		(net "PCIE_RX_P35")
	)
	(segment
		(start 254.493522 -67.108578)
		(end 254.493522 -62.302136)
		(width 0.1016)
		(layer "In2.Cu")
		(net "PCIE_RX_P35")
	)
	(segment
		(start 279.597866 -155.688284)
		(end 268.292326 -91.56954)
		(width 0.1397)
		(layer "In2.Cu")
		(net "PCIE_RX_P35")
	)
	(segment
		(start 272.49374 -222.294704)
		(end 272.55089 -222.237808)
		(width 0.1397)
		(layer "In2.Cu")
		(net "PCIE_RX_P35")
	)
	(segment
		(start 254.857758 -61.784738)
		(end 254.895604 -61.755274)
		(width 0.1016)
		(layer "In2.Cu")
		(net "PCIE_RX_P35")
	)
	(segment
		(start 272.866866 -208.28)
		(end 271.595596 -201.070464)
		(width 0.1397)
		(layer "In2.Cu")
		(net "PCIE_RX_P35")
	)
	(segment
		(start 272.73504 -219.81414)
		(end 273.000978 -218.30538)
		(width 0.1397)
		(layer "In2.Cu")
		(net "PCIE_RX_P35")
	)
	(segment
		(start 254.8509 -61.790072)
		(end 254.851154 -61.790072)
		(width 0.1016)
		(layer "In2.Cu")
		(net "PCIE_RX_P35")
	)
	(segment
		(start 254.641096 -61.958728)
		(end 254.642366 -61.957712)
		(width 0.1016)
		(layer "In2.Cu")
		(net "PCIE_RX_P35")
	)
	(segment
		(start 254.4318 -69.26453)
		(end 254.4318 -67.183)
		(width 0.1397)
		(layer "In2.Cu")
		(net "PCIE_RX_P35")
	)
	(segment
		(start 271.595596 -201.070464)
		(end 279.597866 -155.688284)
		(width 0.1397)
		(layer "In2.Cu")
		(net "PCIE_RX_P35")
	)
	(segment
		(start 254.823976 -61.811154)
		(end 254.829056 -61.807344)
		(width 0.1016)
		(layer "In2.Cu")
		(net "PCIE_RX_P35")
	)
	(segment
		(start 254.4318 -67.1703)
		(end 254.493522 -67.108578)
		(width 0.1016)
		(layer "In2.Cu")
		(net "PCIE_RX_P35")
	)
	(segment
		(start 254.753872 -61.866526)
		(end 254.75438 -61.866018)
		(width 0.1016)
		(layer "In2.Cu")
		(net "PCIE_RX_P35")
	)
	(segment
		(start 254.75438 -61.866018)
		(end 254.79756 -61.831728)
		(width 0.1016)
		(layer "In2.Cu")
		(net "PCIE_RX_P35")
	)
	(arc
		(start 254.543306 -62.090554)
		(mid 254.586443 -62.02037)
		(end 254.641096 -61.958728)
		(width 0.1016)
		(layer "In2.Cu")
		(net "PCIE_RX_P35")
	)
	(arc
		(start 254.493522 -62.302136)
		(mid 254.506119 -62.193455)
		(end 254.543306 -62.090554)
		(width 0.1016)
		(layer "In2.Cu")
		(net "PCIE_RX_P35")
	)
	(arc
		(start 255.025906 -61.652404)
		(mid 255.080378 -61.584556)
		(end 255.09982 -61.49975)
		(width 0.1016)
		(layer "In2.Cu")
		(net "PCIE_RX_P35")
	)
	(arc
		(start 272.55089 -222.237808)
		(mid 272.68723 -222.033622)
		(end 272.73504 -221.7928)
		(width 0.1397)
		(layer "In2.Cu")
		(net "PCIE_RX_P35")
	)
	(arc
		(start 254.642366 -61.957712)
		(mid 254.658169 -61.943365)
		(end 254.674624 -61.929772)
		(width 0.1016)
		(layer "In2.Cu")
		(net "PCIE_RX_P35")
	)
	(segment
		(start 255.599946 -61.999876)
		(end 256.099818 -62.499748)
		(width 0.136652)
		(layer "F.Cu")
		(net "PCIE_RX_P34")
	)
	(via
		(at 256.099818 -62.499748)
		(size 0.4572)
		(drill 0.2032)
		(layers "F.Cu" "B.Cu")
		(net "PCIE_RX_P34")
	)
	(via
		(at 275.693632 -222.294704)
		(size 0.508)
		(drill 0.254)
		(layers "F.Cu" "B.Cu")
		(net "PCIE_RX_P34")
	)
	(segment
		(start 275.947886 -223.596454)
		(end 275.947632 -223.5962)
		(width 0.136652)
		(layer "B.Cu")
		(net "PCIE_RX_P34")
	)
	(segment
		(start 275.947886 -224.187512)
		(end 275.947886 -223.596454)
		(width 0.136652)
		(layer "B.Cu")
		(net "PCIE_RX_P34")
	)
	(segment
		(start 275.84019 -224.375726)
		(end 275.89099 -224.324926)
		(width 0.136652)
		(layer "B.Cu")
		(net "PCIE_RX_P34")
	)
	(segment
		(start 275.700236 -225.92538)
		(end 275.700236 -224.713546)
		(width 0.136652)
		(layer "B.Cu")
		(net "PCIE_RX_P34")
	)
	(segment
		(start 275.947632 -223.5962)
		(end 275.947632 -222.90786)
		(width 0.136652)
		(layer "B.Cu")
		(net "PCIE_RX_P34")
	)
	(arc
		(start 275.947632 -222.90786)
		(mid 275.881624 -222.576014)
		(end 275.693632 -222.294704)
		(width 0.136652)
		(layer "B.Cu")
		(net "PCIE_RX_P34")
	)
	(arc
		(start 275.89099 -224.324926)
		(mid 275.933116 -224.26188)
		(end 275.947886 -224.187512)
		(width 0.136652)
		(layer "B.Cu")
		(net "PCIE_RX_P34")
	)
	(arc
		(start 275.700236 -224.713546)
		(mid 275.736604 -224.53071)
		(end 275.84019 -224.375726)
		(width 0.136652)
		(layer "B.Cu")
		(net "PCIE_RX_P34")
	)
	(segment
		(start 275.934932 -219.011754)
		(end 275.934932 -221.7928)
		(width 0.1397)
		(layer "In2.Cu")
		(net "PCIE_RX_P34")
	)
	(segment
		(start 255.818132 -62.815724)
		(end 255.797558 -62.831726)
		(width 0.1016)
		(layer "In2.Cu")
		(net "PCIE_RX_P34")
	)
	(segment
		(start 255.49352 -63.302134)
		(end 255.49352 -67.13728)
		(width 0.1016)
		(layer "In2.Cu")
		(net "PCIE_RX_P34")
	)
	(segment
		(start 275.8948 -207.42021)
		(end 275.8948 -213.610444)
		(width 0.1397)
		(layer "In2.Cu")
		(net "PCIE_RX_P34")
	)
	(segment
		(start 255.901698 -62.7507)
		(end 255.895602 -62.755272)
		(width 0.1016)
		(layer "In2.Cu")
		(net "PCIE_RX_P34")
	)
	(segment
		(start 269.562326 -91.31554)
		(end 281.109928 -156.786834)
		(width 0.1397)
		(layer "In2.Cu")
		(net "PCIE_RX_P34")
	)
	(segment
		(start 255.823974 -62.811152)
		(end 255.818132 -62.815724)
		(width 0.1016)
		(layer "In2.Cu")
		(net "PCIE_RX_P34")
	)
	(segment
		(start 255.829054 -62.807342)
		(end 255.823974 -62.811152)
		(width 0.1016)
		(layer "In2.Cu")
		(net "PCIE_RX_P34")
	)
	(segment
		(start 255.642364 -62.95771)
		(end 255.641094 -62.958726)
		(width 0.1016)
		(layer "In2.Cu")
		(net "PCIE_RX_P34")
	)
	(segment
		(start 281.109928 -156.786834)
		(end 274.03806 -196.89191)
		(width 0.1397)
		(layer "In2.Cu")
		(net "PCIE_RX_P34")
	)
	(segment
		(start 275.8948 -213.610444)
		(end 275.438616 -216.196926)
		(width 0.1397)
		(layer "In2.Cu")
		(net "PCIE_RX_P34")
	)
	(segment
		(start 255.851152 -62.79007)
		(end 255.850898 -62.79007)
		(width 0.1016)
		(layer "In2.Cu")
		(net "PCIE_RX_P34")
	)
	(segment
		(start 256.025904 -62.652402)
		(end 255.904238 -62.748414)
		(width 0.1016)
		(layer "In2.Cu")
		(net "PCIE_RX_P34")
	)
	(segment
		(start 255.49352 -67.13728)
		(end 255.4478 -67.183)
		(width 0.1016)
		(layer "In2.Cu")
		(net "PCIE_RX_P34")
	)
	(segment
		(start 255.850898 -62.79007)
		(end 255.829054 -62.807342)
		(width 0.1016)
		(layer "In2.Cu")
		(net "PCIE_RX_P34")
	)
	(segment
		(start 255.754378 -62.866016)
		(end 255.75387 -62.866524)
		(width 0.1016)
		(layer "In2.Cu")
		(net "PCIE_RX_P34")
	)
	(segment
		(start 255.895602 -62.755272)
		(end 255.857756 -62.784736)
		(width 0.1016)
		(layer "In2.Cu")
		(net "PCIE_RX_P34")
	)
	(segment
		(start 255.857756 -62.784736)
		(end 255.851152 -62.79007)
		(width 0.1016)
		(layer "In2.Cu")
		(net "PCIE_RX_P34")
	)
	(segment
		(start 255.4478 -69.26453)
		(end 255.89357 -71.794624)
		(width 0.1397)
		(layer "In2.Cu")
		(net "PCIE_RX_P34")
	)
	(segment
		(start 275.750782 -222.237808)
		(end 275.693632 -222.294704)
		(width 0.1397)
		(layer "In2.Cu")
		(net "PCIE_RX_P34")
	)
	(segment
		(start 275.438616 -216.196926)
		(end 275.934932 -219.011754)
		(width 0.1397)
		(layer "In2.Cu")
		(net "PCIE_RX_P34")
	)
	(segment
		(start 274.03806 -196.89191)
		(end 275.8948 -207.42021)
		(width 0.1397)
		(layer "In2.Cu")
		(net "PCIE_RX_P34")
	)
	(segment
		(start 255.4478 -67.183)
		(end 255.4478 -69.26453)
		(width 0.1397)
		(layer "In2.Cu")
		(net "PCIE_RX_P34")
	)
	(segment
		(start 255.904238 -62.748414)
		(end 255.901698 -62.7507)
		(width 0.1016)
		(layer "In2.Cu")
		(net "PCIE_RX_P34")
	)
	(segment
		(start 255.75387 -62.866524)
		(end 255.674622 -62.92977)
		(width 0.1016)
		(layer "In2.Cu")
		(net "PCIE_RX_P34")
	)
	(segment
		(start 255.797558 -62.831726)
		(end 255.754378 -62.866016)
		(width 0.1016)
		(layer "In2.Cu")
		(net "PCIE_RX_P34")
	)
	(segment
		(start 255.89357 -71.794624)
		(end 269.562326 -91.31554)
		(width 0.1397)
		(layer "In2.Cu")
		(net "PCIE_RX_P34")
	)
	(arc
		(start 255.543304 -63.090552)
		(mid 255.506068 -63.193441)
		(end 255.49352 -63.302134)
		(width 0.1016)
		(layer "In2.Cu")
		(net "PCIE_RX_P34")
	)
	(arc
		(start 256.099818 -62.499748)
		(mid 256.080365 -62.584549)
		(end 256.025904 -62.652402)
		(width 0.1016)
		(layer "In2.Cu")
		(net "PCIE_RX_P34")
	)
	(arc
		(start 275.934932 -221.7928)
		(mid 275.887123 -222.033622)
		(end 275.750782 -222.237808)
		(width 0.1397)
		(layer "In2.Cu")
		(net "PCIE_RX_P34")
	)
	(arc
		(start 255.641094 -62.958726)
		(mid 255.58643 -63.02036)
		(end 255.543304 -63.090552)
		(width 0.1016)
		(layer "In2.Cu")
		(net "PCIE_RX_P34")
	)
	(arc
		(start 255.674622 -62.92977)
		(mid 255.658171 -62.943368)
		(end 255.642364 -62.95771)
		(width 0.1016)
		(layer "In2.Cu")
		(net "PCIE_RX_P34")
	)
	(segment
		(start 256.599944 -60.999878)
		(end 257.099816 -61.49975)
		(width 0.136652)
		(layer "F.Cu")
		(net "PCIE_RX_P33")
	)
	(via
		(at 257.099816 -61.49975)
		(size 0.4572)
		(drill 0.2032)
		(layers "F.Cu" "B.Cu")
		(net "PCIE_RX_P33")
	)
	(via
		(at 278.893778 -222.294704)
		(size 0.508)
		(drill 0.254)
		(layers "F.Cu" "B.Cu")
		(net "PCIE_RX_P33")
	)
	(segment
		(start 279.148032 -223.596454)
		(end 279.147778 -223.5962)
		(width 0.136652)
		(layer "B.Cu")
		(net "PCIE_RX_P33")
	)
	(segment
		(start 278.900128 -225.92538)
		(end 278.900128 -224.7138)
		(width 0.136652)
		(layer "B.Cu")
		(net "PCIE_RX_P33")
	)
	(segment
		(start 279.040336 -224.375726)
		(end 279.091136 -224.324926)
		(width 0.136652)
		(layer "B.Cu")
		(net "PCIE_RX_P33")
	)
	(segment
		(start 278.900128 -224.7138)
		(end 278.900382 -224.713546)
		(width 0.136652)
		(layer "B.Cu")
		(net "PCIE_RX_P33")
	)
	(segment
		(start 279.148032 -224.187512)
		(end 279.148032 -223.596454)
		(width 0.136652)
		(layer "B.Cu")
		(net "PCIE_RX_P33")
	)
	(segment
		(start 279.147778 -223.5962)
		(end 279.147778 -222.90786)
		(width 0.136652)
		(layer "B.Cu")
		(net "PCIE_RX_P33")
	)
	(arc
		(start 279.091136 -224.324926)
		(mid 279.133262 -224.26188)
		(end 279.148032 -224.187512)
		(width 0.136652)
		(layer "B.Cu")
		(net "PCIE_RX_P33")
	)
	(arc
		(start 279.147778 -222.90786)
		(mid 279.08177 -222.576014)
		(end 278.893778 -222.294704)
		(width 0.136652)
		(layer "B.Cu")
		(net "PCIE_RX_P33")
	)
	(arc
		(start 278.900382 -224.713546)
		(mid 278.93675 -224.53071)
		(end 279.040336 -224.375726)
		(width 0.136652)
		(layer "B.Cu")
		(net "PCIE_RX_P33")
	)
	(segment
		(start 278.893778 -222.294704)
		(end 278.950928 -222.237808)
		(width 0.1397)
		(layer "In2.Cu")
		(net "PCIE_RX_P33")
	)
	(segment
		(start 256.901696 -61.750702)
		(end 256.904236 -61.748416)
		(width 0.1016)
		(layer "In2.Cu")
		(net "PCIE_RX_P33")
	)
	(segment
		(start 256.67462 -61.929772)
		(end 256.753868 -61.866526)
		(width 0.1016)
		(layer "In2.Cu")
		(net "PCIE_RX_P33")
	)
	(segment
		(start 279.043384 -213.563708)
		(end 279.043384 -210.06308)
		(width 0.1397)
		(layer "In2.Cu")
		(net "PCIE_RX_P33")
	)
	(segment
		(start 256.4384 -69.26453)
		(end 256.4384 -67.183)
		(width 0.1397)
		(layer "In2.Cu")
		(net "PCIE_RX_P33")
	)
	(segment
		(start 256.857754 -61.784738)
		(end 256.8956 -61.755274)
		(width 0.1016)
		(layer "In2.Cu")
		(net "PCIE_RX_P33")
	)
	(segment
		(start 256.700782 -70.752716)
		(end 256.4384 -69.26453)
		(width 0.1397)
		(layer "In2.Cu")
		(net "PCIE_RX_P33")
	)
	(segment
		(start 278.471122 -206.8195)
		(end 281.67965 -188.621162)
		(width 0.1397)
		(layer "In2.Cu")
		(net "PCIE_RX_P33")
	)
	(segment
		(start 256.493518 -67.127882)
		(end 256.493518 -62.302136)
		(width 0.1016)
		(layer "In2.Cu")
		(net "PCIE_RX_P33")
	)
	(segment
		(start 256.85115 -61.790072)
		(end 256.857754 -61.784738)
		(width 0.1016)
		(layer "In2.Cu")
		(net "PCIE_RX_P33")
	)
	(segment
		(start 279.043384 -210.06308)
		(end 278.471122 -206.8195)
		(width 0.1397)
		(layer "In2.Cu")
		(net "PCIE_RX_P33")
	)
	(segment
		(start 256.8956 -61.755274)
		(end 256.901696 -61.750702)
		(width 0.1016)
		(layer "In2.Cu")
		(net "PCIE_RX_P33")
	)
	(segment
		(start 256.753868 -61.866526)
		(end 256.754376 -61.866018)
		(width 0.1016)
		(layer "In2.Cu")
		(net "PCIE_RX_P33")
	)
	(segment
		(start 256.81813 -61.815726)
		(end 256.823972 -61.811154)
		(width 0.1016)
		(layer "In2.Cu")
		(net "PCIE_RX_P33")
	)
	(segment
		(start 256.850896 -61.790072)
		(end 256.85115 -61.790072)
		(width 0.1016)
		(layer "In2.Cu")
		(net "PCIE_RX_P33")
	)
	(segment
		(start 256.829052 -61.807344)
		(end 256.850896 -61.790072)
		(width 0.1016)
		(layer "In2.Cu")
		(net "PCIE_RX_P33")
	)
	(segment
		(start 256.823972 -61.811154)
		(end 256.829052 -61.807344)
		(width 0.1016)
		(layer "In2.Cu")
		(net "PCIE_RX_P33")
	)
	(segment
		(start 270.832326 -90.93454)
		(end 256.700782 -70.752716)
		(width 0.1397)
		(layer "In2.Cu")
		(net "PCIE_RX_P33")
	)
	(segment
		(start 256.754376 -61.866018)
		(end 256.797556 -61.831728)
		(width 0.1016)
		(layer "In2.Cu")
		(net "PCIE_RX_P33")
	)
	(segment
		(start 256.797556 -61.831728)
		(end 256.81813 -61.815726)
		(width 0.1016)
		(layer "In2.Cu")
		(net "PCIE_RX_P33")
	)
	(segment
		(start 281.67965 -188.621162)
		(end 284.86862 -170.537124)
		(width 0.1397)
		(layer "In2.Cu")
		(net "PCIE_RX_P33")
	)
	(segment
		(start 284.86862 -170.537124)
		(end 270.832326 -90.93454)
		(width 0.1397)
		(layer "In2.Cu")
		(net "PCIE_RX_P33")
	)
	(segment
		(start 256.904236 -61.748416)
		(end 257.025902 -61.652404)
		(width 0.1016)
		(layer "In2.Cu")
		(net "PCIE_RX_P33")
	)
	(segment
		(start 256.4384 -67.183)
		(end 256.493518 -67.127882)
		(width 0.1016)
		(layer "In2.Cu")
		(net "PCIE_RX_P33")
	)
	(segment
		(start 278.500586 -216.640664)
		(end 279.043384 -213.563708)
		(width 0.1397)
		(layer "In2.Cu")
		(net "PCIE_RX_P33")
	)
	(segment
		(start 256.641092 -61.958728)
		(end 256.642362 -61.957712)
		(width 0.1016)
		(layer "In2.Cu")
		(net "PCIE_RX_P33")
	)
	(segment
		(start 279.135078 -221.7928)
		(end 279.135078 -220.236034)
		(width 0.1397)
		(layer "In2.Cu")
		(net "PCIE_RX_P33")
	)
	(segment
		(start 279.135078 -220.236034)
		(end 278.500586 -216.640664)
		(width 0.1397)
		(layer "In2.Cu")
		(net "PCIE_RX_P33")
	)
	(arc
		(start 256.543302 -62.090554)
		(mid 256.586439 -62.02037)
		(end 256.641092 -61.958728)
		(width 0.1016)
		(layer "In2.Cu")
		(net "PCIE_RX_P33")
	)
	(arc
		(start 256.493518 -62.302136)
		(mid 256.506115 -62.193455)
		(end 256.543302 -62.090554)
		(width 0.1016)
		(layer "In2.Cu")
		(net "PCIE_RX_P33")
	)
	(arc
		(start 257.025902 -61.652404)
		(mid 257.080374 -61.584556)
		(end 257.099816 -61.49975)
		(width 0.1016)
		(layer "In2.Cu")
		(net "PCIE_RX_P33")
	)
	(arc
		(start 256.642362 -61.957712)
		(mid 256.658165 -61.943365)
		(end 256.67462 -61.929772)
		(width 0.1016)
		(layer "In2.Cu")
		(net "PCIE_RX_P33")
	)
	(arc
		(start 278.950928 -222.237808)
		(mid 279.087268 -222.033622)
		(end 279.135078 -221.7928)
		(width 0.1397)
		(layer "In2.Cu")
		(net "PCIE_RX_P33")
	)
	(segment
		(start 257.599942 -61.999876)
		(end 258.099814 -62.499748)
		(width 0.136652)
		(layer "F.Cu")
		(net "PCIE_RX_P32")
	)
	(via
		(at 258.099814 -62.499748)
		(size 0.4572)
		(drill 0.2032)
		(layers "F.Cu" "B.Cu")
		(net "PCIE_RX_P32")
	)
	(via
		(at 282.09367 -222.294704)
		(size 0.508)
		(drill 0.254)
		(layers "F.Cu" "B.Cu")
		(net "PCIE_RX_P32")
	)
	(segment
		(start 282.34767 -223.5962)
		(end 282.34767 -222.90786)
		(width 0.136652)
		(layer "B.Cu")
		(net "PCIE_RX_P32")
	)
	(segment
		(start 282.347924 -224.187512)
		(end 282.347924 -223.596454)
		(width 0.136652)
		(layer "B.Cu")
		(net "PCIE_RX_P32")
	)
	(segment
		(start 282.347924 -223.596454)
		(end 282.34767 -223.5962)
		(width 0.136652)
		(layer "B.Cu")
		(net "PCIE_RX_P32")
	)
	(segment
		(start 282.10002 -225.92538)
		(end 282.10002 -224.7138)
		(width 0.136652)
		(layer "B.Cu")
		(net "PCIE_RX_P32")
	)
	(segment
		(start 282.240228 -224.375726)
		(end 282.291028 -224.324926)
		(width 0.136652)
		(layer "B.Cu")
		(net "PCIE_RX_P32")
	)
	(segment
		(start 282.10002 -224.7138)
		(end 282.100274 -224.713546)
		(width 0.136652)
		(layer "B.Cu")
		(net "PCIE_RX_P32")
	)
	(arc
		(start 282.100274 -224.713546)
		(mid 282.136642 -224.53071)
		(end 282.240228 -224.375726)
		(width 0.136652)
		(layer "B.Cu")
		(net "PCIE_RX_P32")
	)
	(arc
		(start 282.291028 -224.324926)
		(mid 282.333154 -224.26188)
		(end 282.347924 -224.187512)
		(width 0.136652)
		(layer "B.Cu")
		(net "PCIE_RX_P32")
	)
	(arc
		(start 282.34767 -222.90786)
		(mid 282.281662 -222.576014)
		(end 282.09367 -222.294704)
		(width 0.136652)
		(layer "B.Cu")
		(net "PCIE_RX_P32")
	)
	(segment
		(start 272.32991 -90.991182)
		(end 257.56743 -69.90715)
		(width 0.1397)
		(layer "In2.Cu")
		(net "PCIE_RX_P32")
	)
	(segment
		(start 282.33497 -219.453206)
		(end 281.79268 -216.378536)
		(width 0.1397)
		(layer "In2.Cu")
		(net "PCIE_RX_P32")
	)
	(segment
		(start 257.674618 -62.92977)
		(end 257.753866 -62.866524)
		(width 0.1016)
		(layer "In2.Cu")
		(net "PCIE_RX_P32")
	)
	(segment
		(start 257.56743 -69.90715)
		(end 257.4544 -69.26453)
		(width 0.1397)
		(layer "In2.Cu")
		(net "PCIE_RX_P32")
	)
	(segment
		(start 257.851148 -62.79007)
		(end 257.857752 -62.784736)
		(width 0.1016)
		(layer "In2.Cu")
		(net "PCIE_RX_P32")
	)
	(segment
		(start 282.09367 -222.294704)
		(end 282.15082 -222.237808)
		(width 0.1397)
		(layer "In2.Cu")
		(net "PCIE_RX_P32")
	)
	(segment
		(start 257.753866 -62.866524)
		(end 257.754374 -62.866016)
		(width 0.1016)
		(layer "In2.Cu")
		(net "PCIE_RX_P32")
	)
	(segment
		(start 281.363674 -204.202284)
		(end 286.827214 -173.216824)
		(width 0.1397)
		(layer "In2.Cu")
		(net "PCIE_RX_P32")
	)
	(segment
		(start 281.79268 -216.378536)
		(end 282.288742 -213.566502)
		(width 0.1397)
		(layer "In2.Cu")
		(net "PCIE_RX_P32")
	)
	(segment
		(start 257.82905 -62.807342)
		(end 257.850894 -62.79007)
		(width 0.1016)
		(layer "In2.Cu")
		(net "PCIE_RX_P32")
	)
	(segment
		(start 257.857752 -62.784736)
		(end 257.895598 -62.755272)
		(width 0.1016)
		(layer "In2.Cu")
		(net "PCIE_RX_P32")
	)
	(segment
		(start 257.797554 -62.831726)
		(end 257.818128 -62.815724)
		(width 0.1016)
		(layer "In2.Cu")
		(net "PCIE_RX_P32")
	)
	(segment
		(start 282.288742 -209.44713)
		(end 281.363674 -204.202284)
		(width 0.1397)
		(layer "In2.Cu")
		(net "PCIE_RX_P32")
	)
	(segment
		(start 286.827214 -173.216824)
		(end 272.32991 -90.991182)
		(width 0.1397)
		(layer "In2.Cu")
		(net "PCIE_RX_P32")
	)
	(segment
		(start 257.4544 -69.26453)
		(end 257.4544 -67.2338)
		(width 0.1397)
		(layer "In2.Cu")
		(net "PCIE_RX_P32")
	)
	(segment
		(start 282.33497 -221.7928)
		(end 282.33497 -219.453206)
		(width 0.1397)
		(layer "In2.Cu")
		(net "PCIE_RX_P32")
	)
	(segment
		(start 257.818128 -62.815724)
		(end 257.82397 -62.811152)
		(width 0.1016)
		(layer "In2.Cu")
		(net "PCIE_RX_P32")
	)
	(segment
		(start 257.493516 -67.194684)
		(end 257.493516 -63.302134)
		(width 0.1016)
		(layer "In2.Cu")
		(net "PCIE_RX_P32")
	)
	(segment
		(start 257.64109 -62.958726)
		(end 257.64236 -62.95771)
		(width 0.1016)
		(layer "In2.Cu")
		(net "PCIE_RX_P32")
	)
	(segment
		(start 257.4544 -67.2338)
		(end 257.493516 -67.194684)
		(width 0.1016)
		(layer "In2.Cu")
		(net "PCIE_RX_P32")
	)
	(segment
		(start 257.895598 -62.755272)
		(end 257.901694 -62.7507)
		(width 0.1016)
		(layer "In2.Cu")
		(net "PCIE_RX_P32")
	)
	(segment
		(start 257.901694 -62.7507)
		(end 257.904234 -62.748414)
		(width 0.1016)
		(layer "In2.Cu")
		(net "PCIE_RX_P32")
	)
	(segment
		(start 257.904234 -62.748414)
		(end 258.0259 -62.652402)
		(width 0.1016)
		(layer "In2.Cu")
		(net "PCIE_RX_P32")
	)
	(segment
		(start 257.82397 -62.811152)
		(end 257.82905 -62.807342)
		(width 0.1016)
		(layer "In2.Cu")
		(net "PCIE_RX_P32")
	)
	(segment
		(start 257.850894 -62.79007)
		(end 257.851148 -62.79007)
		(width 0.1016)
		(layer "In2.Cu")
		(net "PCIE_RX_P32")
	)
	(segment
		(start 282.288742 -213.566502)
		(end 282.288742 -209.44713)
		(width 0.1397)
		(layer "In2.Cu")
		(net "PCIE_RX_P32")
	)
	(segment
		(start 257.754374 -62.866016)
		(end 257.797554 -62.831726)
		(width 0.1016)
		(layer "In2.Cu")
		(net "PCIE_RX_P32")
	)
	(arc
		(start 258.0259 -62.652402)
		(mid 258.080372 -62.584554)
		(end 258.099814 -62.499748)
		(width 0.1016)
		(layer "In2.Cu")
		(net "PCIE_RX_P32")
	)
	(arc
		(start 257.5433 -63.090552)
		(mid 257.586437 -63.020368)
		(end 257.64109 -62.958726)
		(width 0.1016)
		(layer "In2.Cu")
		(net "PCIE_RX_P32")
	)
	(arc
		(start 282.15082 -222.237808)
		(mid 282.28716 -222.033622)
		(end 282.33497 -221.7928)
		(width 0.1397)
		(layer "In2.Cu")
		(net "PCIE_RX_P32")
	)
	(arc
		(start 257.64236 -62.95771)
		(mid 257.658163 -62.943363)
		(end 257.674618 -62.92977)
		(width 0.1016)
		(layer "In2.Cu")
		(net "PCIE_RX_P32")
	)
	(arc
		(start 257.493516 -63.302134)
		(mid 257.506113 -63.193453)
		(end 257.5433 -63.090552)
		(width 0.1016)
		(layer "In2.Cu")
		(net "PCIE_RX_P32")
	)
	(segment
		(start 253.59995 -58.999882)
		(end 254.099822 -59.499754)
		(width 0.136652)
		(layer "F.Cu")
		(net "PCIE_RX_P31")
	)
	(via
		(at 285.293562 -222.294704)
		(size 0.508)
		(drill 0.254)
		(layers "F.Cu" "B.Cu")
		(net "PCIE_RX_P31")
	)
	(via
		(at 254.099822 -59.499754)
		(size 0.4572)
		(drill 0.2032)
		(layers "F.Cu" "B.Cu")
		(net "PCIE_RX_P31")
	)
	(segment
		(start 285.547562 -223.5962)
		(end 285.547562 -222.90786)
		(width 0.136652)
		(layer "B.Cu")
		(net "PCIE_RX_P31")
	)
	(segment
		(start 285.44012 -224.375726)
		(end 285.49092 -224.324926)
		(width 0.136652)
		(layer "B.Cu")
		(net "PCIE_RX_P31")
	)
	(segment
		(start 285.300166 -225.92538)
		(end 285.300166 -224.713546)
		(width 0.136652)
		(layer "B.Cu")
		(net "PCIE_RX_P31")
	)
	(segment
		(start 285.547816 -224.187512)
		(end 285.547816 -223.596454)
		(width 0.136652)
		(layer "B.Cu")
		(net "PCIE_RX_P31")
	)
	(segment
		(start 285.547816 -223.596454)
		(end 285.547562 -223.5962)
		(width 0.136652)
		(layer "B.Cu")
		(net "PCIE_RX_P31")
	)
	(arc
		(start 285.300166 -224.713546)
		(mid 285.336534 -224.53071)
		(end 285.44012 -224.375726)
		(width 0.136652)
		(layer "B.Cu")
		(net "PCIE_RX_P31")
	)
	(arc
		(start 285.547562 -222.90786)
		(mid 285.481554 -222.576014)
		(end 285.293562 -222.294704)
		(width 0.136652)
		(layer "B.Cu")
		(net "PCIE_RX_P31")
	)
	(arc
		(start 285.49092 -224.324926)
		(mid 285.533046 -224.26188)
		(end 285.547816 -224.187512)
		(width 0.136652)
		(layer "B.Cu")
		(net "PCIE_RX_P31")
	)
	(segment
		(start 266.674092 -66.181986)
		(end 271.467326 -73.02754)
		(width 0.1397)
		(layer "In2.Cu")
		(net "PCIE_RX_P31")
	)
	(segment
		(start 285.5214 -210.006438)
		(end 285.5214 -213.432644)
		(width 0.1397)
		(layer "In2.Cu")
		(net "PCIE_RX_P31")
	)
	(segment
		(start 259.893816 -61.433964)
		(end 266.674092 -66.181986)
		(width 0.1397)
		(layer "In2.Cu")
		(net "PCIE_RX_P31")
	)
	(segment
		(start 254.725932 -60.970414)
		(end 254.772414 -61.016642)
		(width 0.1016)
		(layer "In2.Cu")
		(net "PCIE_RX_P31")
	)
	(segment
		(start 254.3683 -59.5503)
		(end 254.4191 -59.6011)
		(width 0.1016)
		(layer "In2.Cu")
		(net "PCIE_RX_P31")
	)
	(segment
		(start 254.9652 -61.096652)
		(end 259.519674 -61.096652)
		(width 0.1016)
		(layer "In2.Cu")
		(net "PCIE_RX_P31")
	)
	(segment
		(start 271.467326 -73.02754)
		(end 289.594036 -175.831246)
		(width 0.1397)
		(layer "In2.Cu")
		(net "PCIE_RX_P31")
	)
	(segment
		(start 285.534862 -218.844876)
		(end 285.534862 -221.7928)
		(width 0.1397)
		(layer "In2.Cu")
		(net "PCIE_RX_P31")
	)
	(segment
		(start 254.585978 -60.830714)
		(end 254.586232 -60.830714)
		(width 0.1016)
		(layer "In2.Cu")
		(net "PCIE_RX_P31")
	)
	(segment
		(start 259.519674 -61.096652)
		(end 259.602732 -61.17971)
		(width 0.1016)
		(layer "In2.Cu")
		(net "PCIE_RX_P31")
	)
	(segment
		(start 254.099822 -59.499754)
		(end 254.24638 -59.499754)
		(width 0.1016)
		(layer "In2.Cu")
		(net "PCIE_RX_P31")
	)
	(segment
		(start 285.5214 -213.432644)
		(end 285.050738 -216.100152)
		(width 0.1397)
		(layer "In2.Cu")
		(net "PCIE_RX_P31")
	)
	(segment
		(start 254.50292 -59.7662)
		(end 254.50292 -60.6298)
		(width 0.1016)
		(layer "In2.Cu")
		(net "PCIE_RX_P31")
	)
	(segment
		(start 285.050738 -216.100152)
		(end 285.534862 -218.844876)
		(width 0.1397)
		(layer "In2.Cu")
		(net "PCIE_RX_P31")
	)
	(segment
		(start 259.774944 -61.330078)
		(end 259.893816 -61.433964)
		(width 0.1397)
		(layer "In2.Cu")
		(net "PCIE_RX_P31")
	)
	(segment
		(start 285.350712 -222.237808)
		(end 285.293562 -222.294704)
		(width 0.1397)
		(layer "In2.Cu")
		(net "PCIE_RX_P31")
	)
	(segment
		(start 286.268922 -205.764892)
		(end 285.5214 -210.006438)
		(width 0.1397)
		(layer "In2.Cu")
		(net "PCIE_RX_P31")
	)
	(segment
		(start 254.4191 -59.6011)
		(end 254.445516 -59.627262)
		(width 0.1016)
		(layer "In2.Cu")
		(net "PCIE_RX_P31")
	)
	(segment
		(start 285.2928 -200.223374)
		(end 286.268922 -205.764892)
		(width 0.1397)
		(layer "In2.Cu")
		(net "PCIE_RX_P31")
	)
	(segment
		(start 254.586232 -60.830714)
		(end 254.725932 -60.970414)
		(width 0.1016)
		(layer "In2.Cu")
		(net "PCIE_RX_P31")
	)
	(segment
		(start 289.594036 -175.831246)
		(end 285.2928 -200.223374)
		(width 0.1397)
		(layer "In2.Cu")
		(net "PCIE_RX_P31")
	)
	(segment
		(start 259.602732 -61.17971)
		(end 259.774944 -61.330078)
		(width 0.1016)
		(layer "In2.Cu")
		(net "PCIE_RX_P31")
	)
	(arc
		(start 254.772414 -61.016642)
		(mid 254.86085 -61.075826)
		(end 254.9652 -61.096652)
		(width 0.1016)
		(layer "In2.Cu")
		(net "PCIE_RX_P31")
	)
	(arc
		(start 254.445516 -59.627262)
		(mid 254.488026 -59.691022)
		(end 254.50292 -59.7662)
		(width 0.1016)
		(layer "In2.Cu")
		(net "PCIE_RX_P31")
	)
	(arc
		(start 254.24638 -59.499754)
		(mid 254.31238 -59.512882)
		(end 254.3683 -59.5503)
		(width 0.1016)
		(layer "In2.Cu")
		(net "PCIE_RX_P31")
	)
	(arc
		(start 285.534862 -221.7928)
		(mid 285.487053 -222.033622)
		(end 285.350712 -222.237808)
		(width 0.1397)
		(layer "In2.Cu")
		(net "PCIE_RX_P31")
	)
	(arc
		(start 254.50292 -60.6298)
		(mid 254.524453 -60.738525)
		(end 254.585978 -60.830714)
		(width 0.1016)
		(layer "In2.Cu")
		(net "PCIE_RX_P31")
	)
	(segment
		(start 254.599948 -57.999884)
		(end 255.09982 -58.499756)
		(width 0.136652)
		(layer "F.Cu")
		(net "PCIE_RX_P30")
	)
	(via
		(at 255.09982 -58.499756)
		(size 0.4572)
		(drill 0.2032)
		(layers "F.Cu" "B.Cu")
		(net "PCIE_RX_P30")
	)
	(via
		(at 288.493708 -222.294704)
		(size 0.508)
		(drill 0.254)
		(layers "F.Cu" "B.Cu")
		(net "PCIE_RX_P30")
	)
	(segment
		(start 288.747962 -223.596454)
		(end 288.747708 -223.5962)
		(width 0.136652)
		(layer "B.Cu")
		(net "PCIE_RX_P30")
	)
	(segment
		(start 288.500058 -224.7138)
		(end 288.500312 -224.713546)
		(width 0.136652)
		(layer "B.Cu")
		(net "PCIE_RX_P30")
	)
	(segment
		(start 288.747708 -223.5962)
		(end 288.747708 -222.90786)
		(width 0.136652)
		(layer "B.Cu")
		(net "PCIE_RX_P30")
	)
	(segment
		(start 288.640266 -224.375726)
		(end 288.691066 -224.324926)
		(width 0.136652)
		(layer "B.Cu")
		(net "PCIE_RX_P30")
	)
	(segment
		(start 288.747962 -224.187512)
		(end 288.747962 -223.596454)
		(width 0.136652)
		(layer "B.Cu")
		(net "PCIE_RX_P30")
	)
	(segment
		(start 288.500058 -225.92538)
		(end 288.500058 -224.7138)
		(width 0.136652)
		(layer "B.Cu")
		(net "PCIE_RX_P30")
	)
	(arc
		(start 288.500312 -224.713546)
		(mid 288.53668 -224.53071)
		(end 288.640266 -224.375726)
		(width 0.136652)
		(layer "B.Cu")
		(net "PCIE_RX_P30")
	)
	(arc
		(start 288.747708 -222.90786)
		(mid 288.6817 -222.576014)
		(end 288.493708 -222.294704)
		(width 0.136652)
		(layer "B.Cu")
		(net "PCIE_RX_P30")
	)
	(arc
		(start 288.691066 -224.324926)
		(mid 288.733192 -224.26188)
		(end 288.747962 -224.187512)
		(width 0.136652)
		(layer "B.Cu")
		(net "PCIE_RX_P30")
	)
	(segment
		(start 268.605 -65.151)
		(end 274.09521 -72.991726)
		(width 0.1397)
		(layer "In2.Cu")
		(net "PCIE_RX_P30")
	)
	(segment
		(start 288.086038 -202.506072)
		(end 289.01263 -207.761078)
		(width 0.1397)
		(layer "In2.Cu")
		(net "PCIE_RX_P30")
	)
	(segment
		(start 274.09521 -72.991726)
		(end 292.50894 -177.422048)
		(width 0.1397)
		(layer "In2.Cu")
		(net "PCIE_RX_P30")
	)
	(segment
		(start 255.09982 -58.499756)
		(end 255.491996 -58.891678)
		(width 0.1016)
		(layer "In2.Cu")
		(net "PCIE_RX_P30")
	)
	(segment
		(start 288.735008 -219.309696)
		(end 288.735008 -221.7928)
		(width 0.1397)
		(layer "In2.Cu")
		(net "PCIE_RX_P30")
	)
	(segment
		(start 288.7472 -209.267044)
		(end 288.7472 -213.712044)
		(width 0.1397)
		(layer "In2.Cu")
		(net "PCIE_RX_P30")
	)
	(segment
		(start 256.00914 -59.106054)
		(end 259.67817 -59.106054)
		(width 0.1016)
		(layer "In2.Cu")
		(net "PCIE_RX_P30")
	)
	(segment
		(start 289.01263 -207.761078)
		(end 288.7472 -209.267044)
		(width 0.1397)
		(layer "In2.Cu")
		(net "PCIE_RX_P30")
	)
	(segment
		(start 288.247582 -216.544906)
		(end 288.735008 -219.309696)
		(width 0.1397)
		(layer "In2.Cu")
		(net "PCIE_RX_P30")
	)
	(segment
		(start 259.877814 -59.305698)
		(end 259.887212 -59.34456)
		(width 0.1016)
		(layer "In2.Cu")
		(net "PCIE_RX_P30")
	)
	(segment
		(start 259.908802 -59.357514)
		(end 263.017254 -61.238384)
		(width 0.1397)
		(layer "In2.Cu")
		(net "PCIE_RX_P30")
	)
	(segment
		(start 259.67817 -59.106054)
		(end 259.877814 -59.305698)
		(width 0.1016)
		(layer "In2.Cu")
		(net "PCIE_RX_P30")
	)
	(segment
		(start 288.550858 -222.237808)
		(end 288.493708 -222.294704)
		(width 0.1397)
		(layer "In2.Cu")
		(net "PCIE_RX_P30")
	)
	(segment
		(start 292.50894 -177.422048)
		(end 288.086038 -202.506072)
		(width 0.1397)
		(layer "In2.Cu")
		(net "PCIE_RX_P30")
	)
	(segment
		(start 263.017254 -61.238384)
		(end 268.605 -65.151)
		(width 0.1397)
		(layer "In2.Cu")
		(net "PCIE_RX_P30")
	)
	(segment
		(start 288.7472 -213.712044)
		(end 288.247582 -216.544906)
		(width 0.1397)
		(layer "In2.Cu")
		(net "PCIE_RX_P30")
	)
	(segment
		(start 259.887212 -59.34456)
		(end 259.908802 -59.357514)
		(width 0.1016)
		(layer "In2.Cu")
		(net "PCIE_RX_P30")
	)
	(arc
		(start 288.735008 -221.7928)
		(mid 288.687199 -222.033622)
		(end 288.550858 -222.237808)
		(width 0.1397)
		(layer "In2.Cu")
		(net "PCIE_RX_P30")
	)
	(arc
		(start 255.491996 -58.891678)
		(mid 255.729249 -59.050298)
		(end 256.00914 -59.106054)
		(width 0.1016)
		(layer "In2.Cu")
		(net "PCIE_RX_P30")
	)
	(segment
		(start 245.599966 -31.999936)
		(end 246.099838 -31.500064)
		(width 0.136652)
		(layer "F.Cu")
		(net "PCIE_RX_P3")
	)
	(via
		(at 246.099838 -31.500064)
		(size 0.4572)
		(drill 0.2032)
		(layers "F.Cu" "B.Cu")
		(net "PCIE_RX_P3")
	)
	(via
		(at 280.250646 -17.9578)
		(size 0.508)
		(drill 0.254)
		(layers "F.Cu" "B.Cu")
		(net "PCIE_RX_P3")
	)
	(segment
		(start 291.079682 -14.5542)
		(end 291.079682 -14.5923)
		(width 0.136652)
		(layer "B.Cu")
		(net "PCIE_RX_P3")
	)
	(segment
		(start 290.95065 -14.903704)
		(end 290.927028 -14.927326)
		(width 0.136652)
		(layer "B.Cu")
		(net "PCIE_RX_P3")
	)
	(segment
		(start 290.63442 -13.930122)
		(end 290.95319 -14.248892)
		(width 0.136652)
		(layer "B.Cu")
		(net "PCIE_RX_P3")
	)
	(segment
		(start 290.6014 -15.0622)
		(end 285.596584 -15.0622)
		(width 0.136652)
		(layer "B.Cu")
		(net "PCIE_RX_P3")
	)
	(segment
		(start 280.280618 -17.987772)
		(end 280.250646 -17.9578)
		(width 0.136652)
		(layer "B.Cu")
		(net "PCIE_RX_P3")
	)
	(segment
		(start 282.268168 -18.0467)
		(end 282.145994 -18.12798)
		(width 0.136652)
		(layer "B.Cu")
		(net "PCIE_RX_P3")
	)
	(segment
		(start 282.016708 -18.181574)
		(end 281.810968 -18.222722)
		(width 0.136652)
		(layer "B.Cu")
		(net "PCIE_RX_P3")
	)
	(segment
		(start 282.145994 -18.12798)
		(end 282.016708 -18.181574)
		(width 0.136652)
		(layer "B.Cu")
		(net "PCIE_RX_P3")
	)
	(segment
		(start 281.810968 -18.222722)
		(end 280.8478 -18.222722)
		(width 0.136652)
		(layer "B.Cu")
		(net "PCIE_RX_P3")
	)
	(segment
		(start 285.009844 -15.305024)
		(end 282.268168 -18.0467)
		(width 0.136652)
		(layer "B.Cu")
		(net "PCIE_RX_P3")
	)
	(arc
		(start 285.596584 -15.0622)
		(mid 285.27907 -15.125264)
		(end 285.009844 -15.305024)
		(width 0.136652)
		(layer "B.Cu")
		(net "PCIE_RX_P3")
	)
	(arc
		(start 291.079682 -14.5923)
		(mid 291.046156 -14.760848)
		(end 290.95065 -14.903704)
		(width 0.136652)
		(layer "B.Cu")
		(net "PCIE_RX_P3")
	)
	(arc
		(start 280.8478 -18.222722)
		(mid 280.540837 -18.161663)
		(end 280.280618 -17.987772)
		(width 0.136652)
		(layer "B.Cu")
		(net "PCIE_RX_P3")
	)
	(arc
		(start 290.95319 -14.248892)
		(mid 291.046786 -14.388969)
		(end 291.079682 -14.5542)
		(width 0.136652)
		(layer "B.Cu")
		(net "PCIE_RX_P3")
	)
	(arc
		(start 290.927028 -14.927326)
		(mid 290.777629 -15.027151)
		(end 290.6014 -15.0622)
		(width 0.136652)
		(layer "B.Cu")
		(net "PCIE_RX_P3")
	)
	(segment
		(start 270.109442 -18.369026)
		(end 266.355068 -19.11985)
		(width 0.1397)
		(layer "In2.Cu")
		(net "PCIE_RX_P3")
	)
	(segment
		(start 266.355068 -19.11985)
		(end 263.560306 -18.560796)
		(width 0.1397)
		(layer "In2.Cu")
		(net "PCIE_RX_P3")
	)
	(segment
		(start 263.560306 -18.560796)
		(end 260.385306 -19.195796)
		(width 0.1397)
		(layer "In2.Cu")
		(net "PCIE_RX_P3")
	)
	(segment
		(start 245.836948 -31.237174)
		(end 246.099838 -31.500064)
		(width 0.1397)
		(layer "In2.Cu")
		(net "PCIE_RX_P3")
	)
	(segment
		(start 245.618 -30.1752)
		(end 245.618 -30.7086)
		(width 0.1397)
		(layer "In2.Cu")
		(net "PCIE_RX_P3")
	)
	(segment
		(start 257.210306 -18.560796)
		(end 253.3904 -19.2024)
		(width 0.1397)
		(layer "In2.Cu")
		(net "PCIE_RX_P3")
	)
	(segment
		(start 279.039574 -18.147538)
		(end 273.705066 -19.0881)
		(width 0.1397)
		(layer "In2.Cu")
		(net "PCIE_RX_P3")
	)
	(segment
		(start 279.71242 -18.146776)
		(end 279.71242 -18.147538)
		(width 0.1397)
		(layer "In2.Cu")
		(net "PCIE_RX_P3")
	)
	(segment
		(start 245.7196 -26.8732)
		(end 245.7196 -30.0736)
		(width 0.1397)
		(layer "In2.Cu")
		(net "PCIE_RX_P3")
	)
	(segment
		(start 279.794462 -18.146776)
		(end 279.71242 -18.146776)
		(width 0.1397)
		(layer "In2.Cu")
		(net "PCIE_RX_P3")
	)
	(segment
		(start 273.705066 -19.0881)
		(end 270.109442 -18.369026)
		(width 0.1397)
		(layer "In2.Cu")
		(net "PCIE_RX_P3")
	)
	(segment
		(start 245.7196 -30.0736)
		(end 245.618 -30.1752)
		(width 0.1397)
		(layer "In2.Cu")
		(net "PCIE_RX_P3")
	)
	(segment
		(start 279.71242 -18.147538)
		(end 279.039574 -18.147538)
		(width 0.1397)
		(layer "In2.Cu")
		(net "PCIE_RX_P3")
	)
	(segment
		(start 253.3904 -19.2024)
		(end 245.7196 -26.8732)
		(width 0.1397)
		(layer "In2.Cu")
		(net "PCIE_RX_P3")
	)
	(segment
		(start 260.385306 -19.195796)
		(end 257.210306 -18.560796)
		(width 0.1397)
		(layer "In2.Cu")
		(net "PCIE_RX_P3")
	)
	(arc
		(start 280.250646 -17.9578)
		(mid 280.041347 -18.097649)
		(end 279.794462 -18.146776)
		(width 0.1397)
		(layer "In2.Cu")
		(net "PCIE_RX_P3")
	)
	(arc
		(start 245.618 -30.7086)
		(mid 245.674902 -30.994664)
		(end 245.836948 -31.237174)
		(width 0.1397)
		(layer "In2.Cu")
		(net "PCIE_RX_P3")
	)
	(segment
		(start 253.59995 -56.999886)
		(end 254.099822 -57.499758)
		(width 0.136652)
		(layer "F.Cu")
		(net "PCIE_RX_P29")
	)
	(via
		(at 291.6936 -222.294704)
		(size 0.508)
		(drill 0.254)
		(layers "F.Cu" "B.Cu")
		(net "PCIE_RX_P29")
	)
	(via
		(at 254.099822 -57.499758)
		(size 0.4572)
		(drill 0.2032)
		(layers "F.Cu" "B.Cu")
		(net "PCIE_RX_P29")
	)
	(segment
		(start 291.840158 -224.375726)
		(end 291.890958 -224.324926)
		(width 0.136652)
		(layer "B.Cu")
		(net "PCIE_RX_P29")
	)
	(segment
		(start 291.700204 -225.92538)
		(end 291.700204 -224.713546)
		(width 0.136652)
		(layer "B.Cu")
		(net "PCIE_RX_P29")
	)
	(segment
		(start 291.9476 -223.5962)
		(end 291.9476 -222.90786)
		(width 0.136652)
		(layer "B.Cu")
		(net "PCIE_RX_P29")
	)
	(segment
		(start 291.947854 -223.596454)
		(end 291.9476 -223.5962)
		(width 0.136652)
		(layer "B.Cu")
		(net "PCIE_RX_P29")
	)
	(segment
		(start 291.947854 -224.187512)
		(end 291.947854 -223.596454)
		(width 0.136652)
		(layer "B.Cu")
		(net "PCIE_RX_P29")
	)
	(arc
		(start 291.700204 -224.713546)
		(mid 291.736572 -224.53071)
		(end 291.840158 -224.375726)
		(width 0.136652)
		(layer "B.Cu")
		(net "PCIE_RX_P29")
	)
	(arc
		(start 291.890958 -224.324926)
		(mid 291.933084 -224.26188)
		(end 291.947854 -224.187512)
		(width 0.136652)
		(layer "B.Cu")
		(net "PCIE_RX_P29")
	)
	(arc
		(start 291.9476 -222.90786)
		(mid 291.881592 -222.576014)
		(end 291.6936 -222.294704)
		(width 0.136652)
		(layer "B.Cu")
		(net "PCIE_RX_P29")
	)
	(segment
		(start 259.588 -58.166)
		(end 260.179566 -58.166)
		(width 0.1397)
		(layer "In2.Cu")
		(net "PCIE_RX_P29")
	)
	(segment
		(start 254.638048 -57.817258)
		(end 254.695452 -57.921144)
		(width 0.1016)
		(layer "In2.Cu")
		(net "PCIE_RX_P29")
	)
	(segment
		(start 291.718746 -215.156542)
		(end 292.125146 -217.461846)
		(width 0.1397)
		(layer "In2.Cu")
		(net "PCIE_RX_P29")
	)
	(segment
		(start 275.454618 -71.722488)
		(end 295.089834 -183.07812)
		(width 0.1397)
		(layer "In2.Cu")
		(net "PCIE_RX_P29")
	)
	(segment
		(start 291.97808 -209.989674)
		(end 291.97808 -213.686644)
		(width 0.1397)
		(layer "In2.Cu")
		(net "PCIE_RX_P29")
	)
	(segment
		(start 291.97808 -213.686644)
		(end 291.718746 -215.156542)
		(width 0.1397)
		(layer "In2.Cu")
		(net "PCIE_RX_P29")
	)
	(segment
		(start 259.528056 -58.106056)
		(end 259.588 -58.166)
		(width 0.1016)
		(layer "In2.Cu")
		(net "PCIE_RX_P29")
	)
	(segment
		(start 291.51834 -203.33081)
		(end 292.335204 -207.96377)
		(width 0.1397)
		(layer "In2.Cu")
		(net "PCIE_RX_P29")
	)
	(segment
		(start 260.179566 -58.166)
		(end 262.471916 -58.570114)
		(width 0.1397)
		(layer "In2.Cu")
		(net "PCIE_RX_P29")
	)
	(segment
		(start 291.75075 -222.237808)
		(end 291.6936 -222.294704)
		(width 0.1397)
		(layer "In2.Cu")
		(net "PCIE_RX_P29")
	)
	(segment
		(start 295.089834 -183.07812)
		(end 291.51834 -203.33081)
		(width 0.1397)
		(layer "In2.Cu")
		(net "PCIE_RX_P29")
	)
	(segment
		(start 292.125146 -217.461846)
		(end 291.9349 -218.540838)
		(width 0.1397)
		(layer "In2.Cu")
		(net "PCIE_RX_P29")
	)
	(segment
		(start 262.471916 -58.570114)
		(end 269.875 -63.754)
		(width 0.1397)
		(layer "In2.Cu")
		(net "PCIE_RX_P29")
	)
	(segment
		(start 269.875 -63.754)
		(end 275.454618 -71.722488)
		(width 0.1397)
		(layer "In2.Cu")
		(net "PCIE_RX_P29")
	)
	(segment
		(start 255.009142 -58.106056)
		(end 259.528056 -58.106056)
		(width 0.1016)
		(layer "In2.Cu")
		(net "PCIE_RX_P29")
	)
	(segment
		(start 292.335204 -207.96377)
		(end 291.97808 -209.989674)
		(width 0.1397)
		(layer "In2.Cu")
		(net "PCIE_RX_P29")
	)
	(segment
		(start 291.9349 -218.540838)
		(end 291.9349 -221.7928)
		(width 0.1397)
		(layer "In2.Cu")
		(net "PCIE_RX_P29")
	)
	(arc
		(start 254.695452 -57.921144)
		(mid 254.827045 -58.056434)
		(end 255.009142 -58.106056)
		(width 0.1016)
		(layer "In2.Cu")
		(net "PCIE_RX_P29")
	)
	(arc
		(start 254.099822 -57.499758)
		(mid 254.412267 -57.585049)
		(end 254.638048 -57.817258)
		(width 0.1016)
		(layer "In2.Cu")
		(net "PCIE_RX_P29")
	)
	(arc
		(start 291.9349 -221.7928)
		(mid 291.887091 -222.033622)
		(end 291.75075 -222.237808)
		(width 0.1397)
		(layer "In2.Cu")
		(net "PCIE_RX_P29")
	)
	(segment
		(start 254.599948 -55.999888)
		(end 255.09982 -56.49976)
		(width 0.136652)
		(layer "F.Cu")
		(net "PCIE_RX_P28")
	)
	(via
		(at 255.09982 -56.49976)
		(size 0.4572)
		(drill 0.2032)
		(layers "F.Cu" "B.Cu")
		(net "PCIE_RX_P28")
	)
	(via
		(at 294.893746 -222.294704)
		(size 0.508)
		(drill 0.254)
		(layers "F.Cu" "B.Cu")
		(net "PCIE_RX_P28")
	)
	(segment
		(start 295.040304 -224.375726)
		(end 295.091104 -224.324926)
		(width 0.136652)
		(layer "B.Cu")
		(net "PCIE_RX_P28")
	)
	(segment
		(start 294.900096 -225.92538)
		(end 294.900096 -224.7138)
		(width 0.136652)
		(layer "B.Cu")
		(net "PCIE_RX_P28")
	)
	(segment
		(start 294.900096 -224.7138)
		(end 294.90035 -224.713546)
		(width 0.136652)
		(layer "B.Cu")
		(net "PCIE_RX_P28")
	)
	(segment
		(start 295.148 -224.187512)
		(end 295.148 -223.596454)
		(width 0.136652)
		(layer "B.Cu")
		(net "PCIE_RX_P28")
	)
	(segment
		(start 295.147746 -223.5962)
		(end 295.147746 -222.90786)
		(width 0.136652)
		(layer "B.Cu")
		(net "PCIE_RX_P28")
	)
	(segment
		(start 295.148 -223.596454)
		(end 295.147746 -223.5962)
		(width 0.136652)
		(layer "B.Cu")
		(net "PCIE_RX_P28")
	)
	(arc
		(start 294.90035 -224.713546)
		(mid 294.936718 -224.53071)
		(end 295.040304 -224.375726)
		(width 0.136652)
		(layer "B.Cu")
		(net "PCIE_RX_P28")
	)
	(arc
		(start 295.091104 -224.324926)
		(mid 295.13323 -224.26188)
		(end 295.148 -224.187512)
		(width 0.136652)
		(layer "B.Cu")
		(net "PCIE_RX_P28")
	)
	(arc
		(start 295.147746 -222.90786)
		(mid 295.081738 -222.576014)
		(end 294.893746 -222.294704)
		(width 0.136652)
		(layer "B.Cu")
		(net "PCIE_RX_P28")
	)
	(segment
		(start 260.3754 -57.15)
		(end 264.328148 -57.846976)
		(width 0.1397)
		(layer "In2.Cu")
		(net "PCIE_RX_P28")
	)
	(segment
		(start 255.638046 -56.81726)
		(end 255.69545 -56.921146)
		(width 0.1016)
		(layer "In2.Cu")
		(net "PCIE_RX_P28")
	)
	(segment
		(start 294.950896 -222.237808)
		(end 294.893746 -222.294704)
		(width 0.1397)
		(layer "In2.Cu")
		(net "PCIE_RX_P28")
	)
	(segment
		(start 298.202604 -186.85891)
		(end 295.152826 -204.15758)
		(width 0.1397)
		(layer "In2.Cu")
		(net "PCIE_RX_P28")
	)
	(segment
		(start 259.815076 -57.15)
		(end 260.3754 -57.15)
		(width 0.1397)
		(layer "In2.Cu")
		(net "PCIE_RX_P28")
	)
	(segment
		(start 259.771134 -57.106058)
		(end 259.815076 -57.15)
		(width 0.1016)
		(layer "In2.Cu")
		(net "PCIE_RX_P28")
	)
	(segment
		(start 296.603166 -212.396578)
		(end 295.135046 -220.723206)
		(width 0.1397)
		(layer "In2.Cu")
		(net "PCIE_RX_P28")
	)
	(segment
		(start 295.152826 -204.15758)
		(end 296.603166 -212.396578)
		(width 0.1397)
		(layer "In2.Cu")
		(net "PCIE_RX_P28")
	)
	(segment
		(start 295.135046 -220.723206)
		(end 295.135046 -221.7928)
		(width 0.1397)
		(layer "In2.Cu")
		(net "PCIE_RX_P28")
	)
	(segment
		(start 271.37106 -62.778386)
		(end 277.991062 -72.233028)
		(width 0.1397)
		(layer "In2.Cu")
		(net "PCIE_RX_P28")
	)
	(segment
		(start 264.328148 -57.846976)
		(end 271.37106 -62.778386)
		(width 0.1397)
		(layer "In2.Cu")
		(net "PCIE_RX_P28")
	)
	(segment
		(start 256.00914 -57.106058)
		(end 259.771134 -57.106058)
		(width 0.1016)
		(layer "In2.Cu")
		(net "PCIE_RX_P28")
	)
	(segment
		(start 277.991062 -72.233028)
		(end 298.202604 -186.85891)
		(width 0.1397)
		(layer "In2.Cu")
		(net "PCIE_RX_P28")
	)
	(arc
		(start 255.09982 -56.49976)
		(mid 255.412265 -56.585051)
		(end 255.638046 -56.81726)
		(width 0.1016)
		(layer "In2.Cu")
		(net "PCIE_RX_P28")
	)
	(arc
		(start 295.135046 -221.7928)
		(mid 295.087237 -222.033622)
		(end 294.950896 -222.237808)
		(width 0.1397)
		(layer "In2.Cu")
		(net "PCIE_RX_P28")
	)
	(arc
		(start 255.69545 -56.921146)
		(mid 255.827043 -57.056436)
		(end 256.00914 -57.106058)
		(width 0.1016)
		(layer "In2.Cu")
		(net "PCIE_RX_P28")
	)
	(segment
		(start 253.59995 -54.99989)
		(end 254.099822 -55.499762)
		(width 0.136652)
		(layer "F.Cu")
		(net "PCIE_RX_P27")
	)
	(via
		(at 254.099822 -55.499762)
		(size 0.4572)
		(drill 0.2032)
		(layers "F.Cu" "B.Cu")
		(net "PCIE_RX_P27")
	)
	(via
		(at 300.493684 -222.294704)
		(size 0.508)
		(drill 0.254)
		(layers "F.Cu" "B.Cu")
		(net "PCIE_RX_P27")
	)
	(segment
		(start 300.500034 -224.7138)
		(end 300.500288 -224.713546)
		(width 0.136652)
		(layer "B.Cu")
		(net "PCIE_RX_P27")
	)
	(segment
		(start 300.747938 -223.596454)
		(end 300.747684 -223.5962)
		(width 0.136652)
		(layer "B.Cu")
		(net "PCIE_RX_P27")
	)
	(segment
		(start 300.500034 -225.92538)
		(end 300.500034 -224.7138)
		(width 0.136652)
		(layer "B.Cu")
		(net "PCIE_RX_P27")
	)
	(segment
		(start 300.640242 -224.375726)
		(end 300.691042 -224.324926)
		(width 0.136652)
		(layer "B.Cu")
		(net "PCIE_RX_P27")
	)
	(segment
		(start 300.747684 -223.5962)
		(end 300.747684 -222.90786)
		(width 0.136652)
		(layer "B.Cu")
		(net "PCIE_RX_P27")
	)
	(segment
		(start 300.747938 -224.187512)
		(end 300.747938 -223.596454)
		(width 0.136652)
		(layer "B.Cu")
		(net "PCIE_RX_P27")
	)
	(arc
		(start 300.747684 -222.90786)
		(mid 300.681676 -222.576014)
		(end 300.493684 -222.294704)
		(width 0.136652)
		(layer "B.Cu")
		(net "PCIE_RX_P27")
	)
	(arc
		(start 300.691042 -224.324926)
		(mid 300.733168 -224.26188)
		(end 300.747938 -224.187512)
		(width 0.136652)
		(layer "B.Cu")
		(net "PCIE_RX_P27")
	)
	(arc
		(start 300.500288 -224.713546)
		(mid 300.536656 -224.53071)
		(end 300.640242 -224.375726)
		(width 0.136652)
		(layer "B.Cu")
		(net "PCIE_RX_P27")
	)
	(segment
		(start 279.684988 -72.063356)
		(end 273.147028 -62.726316)
		(width 0.1397)
		(layer "In2.Cu")
		(net "PCIE_RX_P27")
	)
	(segment
		(start 300.038516 -205.166976)
		(end 301.596552 -196.330824)
		(width 0.1397)
		(layer "In2.Cu")
		(net "PCIE_RX_P27")
	)
	(segment
		(start 273.147028 -62.726316)
		(end 264.857484 -56.921908)
		(width 0.1397)
		(layer "In2.Cu")
		(net "PCIE_RX_P27")
	)
	(segment
		(start 264.857484 -56.921908)
		(end 260.388862 -56.134)
		(width 0.1397)
		(layer "In2.Cu")
		(net "PCIE_RX_P27")
	)
	(segment
		(start 300.734984 -220.575886)
		(end 300.48454 -219.155518)
		(width 0.1397)
		(layer "In2.Cu")
		(net "PCIE_RX_P27")
	)
	(segment
		(start 259.815076 -56.134)
		(end 259.787136 -56.10606)
		(width 0.1016)
		(layer "In2.Cu")
		(net "PCIE_RX_P27")
	)
	(segment
		(start 259.787136 -56.10606)
		(end 255.009142 -56.10606)
		(width 0.1016)
		(layer "In2.Cu")
		(net "PCIE_RX_P27")
	)
	(segment
		(start 300.666658 -213.839044)
		(end 300.666658 -208.727548)
		(width 0.1397)
		(layer "In2.Cu")
		(net "PCIE_RX_P27")
	)
	(segment
		(start 300.38929 -215.410796)
		(end 300.666658 -213.839044)
		(width 0.1397)
		(layer "In2.Cu")
		(net "PCIE_RX_P27")
	)
	(segment
		(start 260.388862 -56.134)
		(end 259.815076 -56.134)
		(width 0.1397)
		(layer "In2.Cu")
		(net "PCIE_RX_P27")
	)
	(segment
		(start 300.734984 -221.7928)
		(end 300.734984 -220.575886)
		(width 0.1397)
		(layer "In2.Cu")
		(net "PCIE_RX_P27")
	)
	(segment
		(start 300.766988 -217.553286)
		(end 300.38929 -215.410796)
		(width 0.1397)
		(layer "In2.Cu")
		(net "PCIE_RX_P27")
	)
	(segment
		(start 254.695452 -55.921148)
		(end 254.638048 -55.817262)
		(width 0.1016)
		(layer "In2.Cu")
		(net "PCIE_RX_P27")
	)
	(segment
		(start 300.666658 -208.727548)
		(end 300.038516 -205.166976)
		(width 0.1397)
		(layer "In2.Cu")
		(net "PCIE_RX_P27")
	)
	(segment
		(start 300.493684 -222.294704)
		(end 300.550834 -222.237808)
		(width 0.1397)
		(layer "In2.Cu")
		(net "PCIE_RX_P27")
	)
	(segment
		(start 300.48454 -219.155518)
		(end 300.766988 -217.553286)
		(width 0.1397)
		(layer "In2.Cu")
		(net "PCIE_RX_P27")
	)
	(segment
		(start 301.596552 -196.330824)
		(end 279.684988 -72.063356)
		(width 0.1397)
		(layer "In2.Cu")
		(net "PCIE_RX_P27")
	)
	(arc
		(start 254.638048 -55.817262)
		(mid 254.412272 -55.585046)
		(end 254.099822 -55.499762)
		(width 0.1016)
		(layer "In2.Cu")
		(net "PCIE_RX_P27")
	)
	(arc
		(start 300.550834 -222.237808)
		(mid 300.687174 -222.033622)
		(end 300.734984 -221.7928)
		(width 0.1397)
		(layer "In2.Cu")
		(net "PCIE_RX_P27")
	)
	(arc
		(start 255.009142 -56.10606)
		(mid 254.827035 -56.056455)
		(end 254.695452 -55.921148)
		(width 0.1016)
		(layer "In2.Cu")
		(net "PCIE_RX_P27")
	)
	(segment
		(start 254.599948 -53.999892)
		(end 255.09982 -54.499764)
		(width 0.136652)
		(layer "F.Cu")
		(net "PCIE_RX_P26")
	)
	(via
		(at 255.09982 -54.499764)
		(size 0.4572)
		(drill 0.2032)
		(layers "F.Cu" "B.Cu")
		(net "PCIE_RX_P26")
	)
	(via
		(at 303.7332 -220.2942)
		(size 0.508)
		(drill 0.254)
		(layers "F.Cu" "B.Cu")
		(net "PCIE_RX_P26")
	)
	(segment
		(start 303.70018 -225.92538)
		(end 303.70018 -224.713546)
		(width 0.136652)
		(layer "B.Cu")
		(net "PCIE_RX_P26")
	)
	(segment
		(start 303.94783 -224.187512)
		(end 303.94783 -220.8276)
		(width 0.136652)
		(layer "B.Cu")
		(net "PCIE_RX_P26")
	)
	(segment
		(start 303.840134 -224.375726)
		(end 303.890934 -224.324926)
		(width 0.136652)
		(layer "B.Cu")
		(net "PCIE_RX_P26")
	)
	(arc
		(start 303.70018 -224.713546)
		(mid 303.736548 -224.53071)
		(end 303.840134 -224.375726)
		(width 0.136652)
		(layer "B.Cu")
		(net "PCIE_RX_P26")
	)
	(arc
		(start 303.890934 -224.324926)
		(mid 303.93306 -224.26188)
		(end 303.94783 -224.187512)
		(width 0.136652)
		(layer "B.Cu")
		(net "PCIE_RX_P26")
	)
	(arc
		(start 303.94783 -220.8276)
		(mid 303.892161 -220.540118)
		(end 303.7332 -220.2942)
		(width 0.136652)
		(layer "B.Cu")
		(net "PCIE_RX_P26")
	)
	(segment
		(start 274.161758 -61.42228)
		(end 266.065 -55.753)
		(width 0.1397)
		(layer "In2.Cu")
		(net "PCIE_RX_P26")
	)
	(segment
		(start 281.366722 -71.71182)
		(end 274.161758 -61.42228)
		(width 0.1397)
		(layer "In2.Cu")
		(net "PCIE_RX_P26")
	)
	(segment
		(start 303.934876 -219.5576)
		(end 303.934876 -215.944196)
		(width 0.1397)
		(layer "In2.Cu")
		(net "PCIE_RX_P26")
	)
	(segment
		(start 303.53508 -213.676992)
		(end 304.967132 -205.556866)
		(width 0.1397)
		(layer "In2.Cu")
		(net "PCIE_RX_P26")
	)
	(segment
		(start 266.065 -55.753)
		(end 262.756142 -55.169562)
		(width 0.1397)
		(layer "In2.Cu")
		(net "PCIE_RX_P26")
	)
	(segment
		(start 259.751576 -55.106062)
		(end 256.00914 -55.106062)
		(width 0.1016)
		(layer "In2.Cu")
		(net "PCIE_RX_P26")
	)
	(segment
		(start 259.815076 -55.169562)
		(end 259.751576 -55.106062)
		(width 0.1016)
		(layer "In2.Cu")
		(net "PCIE_RX_P26")
	)
	(segment
		(start 303.934876 -215.944196)
		(end 303.53508 -213.676992)
		(width 0.1397)
		(layer "In2.Cu")
		(net "PCIE_RX_P26")
	)
	(segment
		(start 262.756142 -55.169562)
		(end 259.815076 -55.169562)
		(width 0.1397)
		(layer "In2.Cu")
		(net "PCIE_RX_P26")
	)
	(segment
		(start 304.967132 -205.556866)
		(end 281.366722 -71.71182)
		(width 0.1397)
		(layer "In2.Cu")
		(net "PCIE_RX_P26")
	)
	(arc
		(start 255.628902 -54.711346)
		(mid 255.506706 -54.560499)
		(end 255.321054 -54.503828)
		(width 0.1016)
		(layer "In2.Cu")
		(net "PCIE_RX_P26")
	)
	(arc
		(start 256.00914 -55.106062)
		(mid 255.827033 -55.056457)
		(end 255.69545 -54.92115)
		(width 0.1016)
		(layer "In2.Cu")
		(net "PCIE_RX_P26")
	)
	(arc
		(start 255.69545 -54.92115)
		(mid 255.651789 -54.819543)
		(end 255.628902 -54.711346)
		(width 0.1016)
		(layer "In2.Cu")
		(net "PCIE_RX_P26")
	)
	(arc
		(start 255.321054 -54.503828)
		(mid 255.210456 -54.500783)
		(end 255.09982 -54.499764)
		(width 0.1016)
		(layer "In2.Cu")
		(net "PCIE_RX_P26")
	)
	(arc
		(start 303.7332 -220.2942)
		(mid 303.883545 -219.939455)
		(end 303.934876 -219.5576)
		(width 0.1397)
		(layer "In2.Cu")
		(net "PCIE_RX_P26")
	)
	(segment
		(start 253.59995 -52.999894)
		(end 254.099822 -53.499766)
		(width 0.136652)
		(layer "F.Cu")
		(net "PCIE_RX_P25")
	)
	(via
		(at 311.69356 -222.294704)
		(size 0.508)
		(drill 0.254)
		(layers "F.Cu" "B.Cu")
		(net "PCIE_RX_P25")
	)
	(via
		(at 254.099822 -53.499766)
		(size 0.4572)
		(drill 0.2032)
		(layers "F.Cu" "B.Cu")
		(net "PCIE_RX_P25")
	)
	(segment
		(start 311.840118 -224.375726)
		(end 311.890918 -224.324926)
		(width 0.136652)
		(layer "B.Cu")
		(net "PCIE_RX_P25")
	)
	(segment
		(start 311.947814 -224.187512)
		(end 311.947814 -223.596454)
		(width 0.136652)
		(layer "B.Cu")
		(net "PCIE_RX_P25")
	)
	(segment
		(start 311.94756 -223.5962)
		(end 311.94756 -222.90786)
		(width 0.136652)
		(layer "B.Cu")
		(net "PCIE_RX_P25")
	)
	(segment
		(start 311.700164 -225.92538)
		(end 311.700164 -224.713546)
		(width 0.136652)
		(layer "B.Cu")
		(net "PCIE_RX_P25")
	)
	(segment
		(start 311.947814 -223.596454)
		(end 311.94756 -223.5962)
		(width 0.136652)
		(layer "B.Cu")
		(net "PCIE_RX_P25")
	)
	(arc
		(start 311.94756 -222.90786)
		(mid 311.881552 -222.576014)
		(end 311.69356 -222.294704)
		(width 0.136652)
		(layer "B.Cu")
		(net "PCIE_RX_P25")
	)
	(arc
		(start 311.890918 -224.324926)
		(mid 311.933044 -224.26188)
		(end 311.947814 -224.187512)
		(width 0.136652)
		(layer "B.Cu")
		(net "PCIE_RX_P25")
	)
	(arc
		(start 311.700164 -224.713546)
		(mid 311.736532 -224.53071)
		(end 311.840118 -224.375726)
		(width 0.136652)
		(layer "B.Cu")
		(net "PCIE_RX_P25")
	)
	(segment
		(start 311.93486 -221.116906)
		(end 307.626004 -214.963756)
		(width 0.1397)
		(layer "In2.Cu")
		(net "PCIE_RX_P25")
	)
	(segment
		(start 282.150312 -70.483222)
		(end 275.411692 -60.859162)
		(width 0.1397)
		(layer "In2.Cu")
		(net "PCIE_RX_P25")
	)
	(segment
		(start 266.57046 -54.668674)
		(end 263.646158 -54.1528)
		(width 0.1397)
		(layer "In2.Cu")
		(net "PCIE_RX_P25")
	)
	(segment
		(start 259.76834 -54.106064)
		(end 255.009142 -54.106064)
		(width 0.1016)
		(layer "In2.Cu")
		(net "PCIE_RX_P25")
	)
	(segment
		(start 307.626004 -214.963756)
		(end 282.150312 -70.483222)
		(width 0.1397)
		(layer "In2.Cu")
		(net "PCIE_RX_P25")
	)
	(segment
		(start 275.411692 -60.859162)
		(end 266.57046 -54.668674)
		(width 0.1397)
		(layer "In2.Cu")
		(net "PCIE_RX_P25")
	)
	(segment
		(start 259.815076 -54.1528)
		(end 259.76834 -54.106064)
		(width 0.1016)
		(layer "In2.Cu")
		(net "PCIE_RX_P25")
	)
	(segment
		(start 311.93486 -221.7928)
		(end 311.93486 -221.116906)
		(width 0.1397)
		(layer "In2.Cu")
		(net "PCIE_RX_P25")
	)
	(segment
		(start 263.646158 -54.1528)
		(end 259.815076 -54.1528)
		(width 0.1397)
		(layer "In2.Cu")
		(net "PCIE_RX_P25")
	)
	(segment
		(start 254.695452 -53.921152)
		(end 254.638048 -53.817266)
		(width 0.1016)
		(layer "In2.Cu")
		(net "PCIE_RX_P25")
	)
	(segment
		(start 311.69356 -222.294704)
		(end 311.75071 -222.237808)
		(width 0.1397)
		(layer "In2.Cu")
		(net "PCIE_RX_P25")
	)
	(arc
		(start 254.638048 -53.817266)
		(mid 254.412272 -53.58505)
		(end 254.099822 -53.499766)
		(width 0.1016)
		(layer "In2.Cu")
		(net "PCIE_RX_P25")
	)
	(arc
		(start 255.009142 -54.106064)
		(mid 254.827035 -54.056459)
		(end 254.695452 -53.921152)
		(width 0.1016)
		(layer "In2.Cu")
		(net "PCIE_RX_P25")
	)
	(arc
		(start 311.75071 -222.237808)
		(mid 311.88705 -222.033622)
		(end 311.93486 -221.7928)
		(width 0.1397)
		(layer "In2.Cu")
		(net "PCIE_RX_P25")
	)
	(segment
		(start 254.599948 -51.999896)
		(end 255.09982 -52.499768)
		(width 0.136652)
		(layer "F.Cu")
		(net "PCIE_RX_P24")
	)
	(via
		(at 255.09982 -52.499768)
		(size 0.4572)
		(drill 0.2032)
		(layers "F.Cu" "B.Cu")
		(net "PCIE_RX_P24")
	)
	(via
		(at 314.893706 -222.294704)
		(size 0.508)
		(drill 0.254)
		(layers "F.Cu" "B.Cu")
		(net "PCIE_RX_P24")
	)
	(segment
		(start 314.900056 -225.92538)
		(end 314.900056 -224.7138)
		(width 0.136652)
		(layer "B.Cu")
		(net "PCIE_RX_P24")
	)
	(segment
		(start 315.040264 -224.375726)
		(end 315.091064 -224.324926)
		(width 0.136652)
		(layer "B.Cu")
		(net "PCIE_RX_P24")
	)
	(segment
		(start 315.147706 -223.5962)
		(end 315.147706 -222.90786)
		(width 0.136652)
		(layer "B.Cu")
		(net "PCIE_RX_P24")
	)
	(segment
		(start 314.900056 -224.7138)
		(end 314.90031 -224.713546)
		(width 0.136652)
		(layer "B.Cu")
		(net "PCIE_RX_P24")
	)
	(segment
		(start 315.14796 -223.596454)
		(end 315.147706 -223.5962)
		(width 0.136652)
		(layer "B.Cu")
		(net "PCIE_RX_P24")
	)
	(segment
		(start 315.14796 -224.187512)
		(end 315.14796 -223.596454)
		(width 0.136652)
		(layer "B.Cu")
		(net "PCIE_RX_P24")
	)
	(arc
		(start 314.90031 -224.713546)
		(mid 314.936678 -224.53071)
		(end 315.040264 -224.375726)
		(width 0.136652)
		(layer "B.Cu")
		(net "PCIE_RX_P24")
	)
	(arc
		(start 315.147706 -222.90786)
		(mid 315.081698 -222.576014)
		(end 314.893706 -222.294704)
		(width 0.136652)
		(layer "B.Cu")
		(net "PCIE_RX_P24")
	)
	(arc
		(start 315.091064 -224.324926)
		(mid 315.13319 -224.26188)
		(end 315.14796 -224.187512)
		(width 0.136652)
		(layer "B.Cu")
		(net "PCIE_RX_P24")
	)
	(segment
		(start 308.580536 -214.276178)
		(end 310.143398 -216.50833)
		(width 0.1397)
		(layer "In2.Cu")
		(net "PCIE_RX_P24")
	)
	(segment
		(start 315.135006 -220.811598)
		(end 315.135006 -221.7928)
		(width 0.1397)
		(layer "In2.Cu")
		(net "PCIE_RX_P24")
	)
	(segment
		(start 259.658866 -53.106066)
		(end 259.7404 -53.1876)
		(width 0.1016)
		(layer "In2.Cu")
		(net "PCIE_RX_P24")
	)
	(segment
		(start 256.00914 -53.106066)
		(end 259.658866 -53.106066)
		(width 0.1016)
		(layer "In2.Cu")
		(net "PCIE_RX_P24")
	)
	(segment
		(start 314.950856 -222.237808)
		(end 314.893706 -222.294704)
		(width 0.1397)
		(layer "In2.Cu")
		(net "PCIE_RX_P24")
	)
	(segment
		(start 267.20546 -53.652674)
		(end 276.344888 -60.052204)
		(width 0.1397)
		(layer "In2.Cu")
		(net "PCIE_RX_P24")
	)
	(segment
		(start 283.506164 -70.279768)
		(end 308.026308 -209.338926)
		(width 0.1397)
		(layer "In2.Cu")
		(net "PCIE_RX_P24")
	)
	(segment
		(start 308.026308 -209.338926)
		(end 307.868066 -210.2358)
		(width 0.1397)
		(layer "In2.Cu")
		(net "PCIE_RX_P24")
	)
	(segment
		(start 276.344888 -60.052204)
		(end 283.506164 -70.279768)
		(width 0.1397)
		(layer "In2.Cu")
		(net "PCIE_RX_P24")
	)
	(segment
		(start 314.021724 -219.22359)
		(end 315.135006 -220.811598)
		(width 0.1397)
		(layer "In2.Cu")
		(net "PCIE_RX_P24")
	)
	(segment
		(start 264.56894 -53.1876)
		(end 267.20546 -53.652674)
		(width 0.1397)
		(layer "In2.Cu")
		(net "PCIE_RX_P24")
	)
	(segment
		(start 310.143398 -216.50833)
		(end 314.021724 -219.22359)
		(width 0.1397)
		(layer "In2.Cu")
		(net "PCIE_RX_P24")
	)
	(segment
		(start 255.638046 -52.817268)
		(end 255.69545 -52.921154)
		(width 0.1016)
		(layer "In2.Cu")
		(net "PCIE_RX_P24")
	)
	(segment
		(start 259.7404 -53.1876)
		(end 264.56894 -53.1876)
		(width 0.1397)
		(layer "In2.Cu")
		(net "PCIE_RX_P24")
	)
	(segment
		(start 307.868066 -210.2358)
		(end 308.580536 -214.276178)
		(width 0.1397)
		(layer "In2.Cu")
		(net "PCIE_RX_P24")
	)
	(arc
		(start 255.09982 -52.499768)
		(mid 255.412265 -52.585059)
		(end 255.638046 -52.817268)
		(width 0.1016)
		(layer "In2.Cu")
		(net "PCIE_RX_P24")
	)
	(arc
		(start 315.135006 -221.7928)
		(mid 315.087197 -222.033622)
		(end 314.950856 -222.237808)
		(width 0.1397)
		(layer "In2.Cu")
		(net "PCIE_RX_P24")
	)
	(arc
		(start 255.69545 -52.921154)
		(mid 255.827043 -53.056444)
		(end 256.00914 -53.106066)
		(width 0.1016)
		(layer "In2.Cu")
		(net "PCIE_RX_P24")
	)
	(segment
		(start 253.59995 -49.9999)
		(end 254.099822 -50.499772)
		(width 0.136652)
		(layer "F.Cu")
		(net "PCIE_RX_P23")
	)
	(via
		(at 318.093598 -222.294704)
		(size 0.508)
		(drill 0.254)
		(layers "F.Cu" "B.Cu")
		(net "PCIE_RX_P23")
	)
	(via
		(at 254.099822 -50.499772)
		(size 0.4572)
		(drill 0.2032)
		(layers "F.Cu" "B.Cu")
		(net "PCIE_RX_P23")
	)
	(segment
		(start 318.100202 -225.92538)
		(end 318.100202 -224.713546)
		(width 0.136652)
		(layer "B.Cu")
		(net "PCIE_RX_P23")
	)
	(segment
		(start 318.347852 -224.187512)
		(end 318.347852 -223.596454)
		(width 0.136652)
		(layer "B.Cu")
		(net "PCIE_RX_P23")
	)
	(segment
		(start 318.347852 -223.596454)
		(end 318.347598 -223.5962)
		(width 0.136652)
		(layer "B.Cu")
		(net "PCIE_RX_P23")
	)
	(segment
		(start 318.347598 -223.5962)
		(end 318.347598 -222.90786)
		(width 0.136652)
		(layer "B.Cu")
		(net "PCIE_RX_P23")
	)
	(segment
		(start 318.240156 -224.375726)
		(end 318.290956 -224.324926)
		(width 0.136652)
		(layer "B.Cu")
		(net "PCIE_RX_P23")
	)
	(arc
		(start 318.290956 -224.324926)
		(mid 318.333082 -224.26188)
		(end 318.347852 -224.187512)
		(width 0.136652)
		(layer "B.Cu")
		(net "PCIE_RX_P23")
	)
	(arc
		(start 318.347598 -222.90786)
		(mid 318.28159 -222.576014)
		(end 318.093598 -222.294704)
		(width 0.136652)
		(layer "B.Cu")
		(net "PCIE_RX_P23")
	)
	(arc
		(start 318.100202 -224.713546)
		(mid 318.13657 -224.53071)
		(end 318.240156 -224.375726)
		(width 0.136652)
		(layer "B.Cu")
		(net "PCIE_RX_P23")
	)
	(segment
		(start 315.158882 -209.78749)
		(end 314.647326 -206.88554)
		(width 0.1397)
		(layer "In2.Cu")
		(net "PCIE_RX_P23")
	)
	(segment
		(start 307.502306 -196.681344)
		(end 285.215838 -70.287388)
		(width 0.1397)
		(layer "In2.Cu")
		(net "PCIE_RX_P23")
	)
	(segment
		(start 277.238714 -58.89498)
		(end 268.136624 -52.521612)
		(width 0.1397)
		(layer "In2.Cu")
		(net "PCIE_RX_P23")
	)
	(segment
		(start 318.334898 -221.7928)
		(end 318.334898 -219.691458)
		(width 0.1397)
		(layer "In2.Cu")
		(net "PCIE_RX_P23")
	)
	(segment
		(start 259.713476 -51.1556)
		(end 259.663946 -51.10607)
		(width 0.1016)
		(layer "In2.Cu")
		(net "PCIE_RX_P23")
	)
	(segment
		(start 315.161422 -214.525098)
		(end 315.161422 -209.92719)
		(width 0.1397)
		(layer "In2.Cu")
		(net "PCIE_RX_P23")
	)
	(segment
		(start 254.695452 -50.921158)
		(end 254.638048 -50.817272)
		(width 0.1016)
		(layer "In2.Cu")
		(net "PCIE_RX_P23")
	)
	(segment
		(start 315.158882 -209.92465)
		(end 315.158882 -209.78749)
		(width 0.1397)
		(layer "In2.Cu")
		(net "PCIE_RX_P23")
	)
	(segment
		(start 260.388862 -51.1556)
		(end 259.713476 -51.1556)
		(width 0.1397)
		(layer "In2.Cu")
		(net "PCIE_RX_P23")
	)
	(segment
		(start 318.334898 -219.691458)
		(end 315.310774 -215.37295)
		(width 0.1397)
		(layer "In2.Cu")
		(net "PCIE_RX_P23")
	)
	(segment
		(start 285.215838 -70.287388)
		(end 277.238714 -58.89498)
		(width 0.1397)
		(layer "In2.Cu")
		(net "PCIE_RX_P23")
	)
	(segment
		(start 318.093598 -222.294704)
		(end 318.150748 -222.237808)
		(width 0.1397)
		(layer "In2.Cu")
		(net "PCIE_RX_P23")
	)
	(segment
		(start 315.310774 -215.37295)
		(end 315.161422 -214.525098)
		(width 0.1397)
		(layer "In2.Cu")
		(net "PCIE_RX_P23")
	)
	(segment
		(start 259.663946 -51.10607)
		(end 255.009142 -51.10607)
		(width 0.1016)
		(layer "In2.Cu")
		(net "PCIE_RX_P23")
	)
	(segment
		(start 268.136624 -52.521612)
		(end 260.388862 -51.1556)
		(width 0.1397)
		(layer "In2.Cu")
		(net "PCIE_RX_P23")
	)
	(segment
		(start 314.647326 -206.88554)
		(end 307.502306 -196.681344)
		(width 0.1397)
		(layer "In2.Cu")
		(net "PCIE_RX_P23")
	)
	(segment
		(start 315.161422 -209.92719)
		(end 315.158882 -209.92465)
		(width 0.1397)
		(layer "In2.Cu")
		(net "PCIE_RX_P23")
	)
	(arc
		(start 254.638048 -50.817272)
		(mid 254.412272 -50.585056)
		(end 254.099822 -50.499772)
		(width 0.1016)
		(layer "In2.Cu")
		(net "PCIE_RX_P23")
	)
	(arc
		(start 255.009142 -51.10607)
		(mid 254.827035 -51.056465)
		(end 254.695452 -50.921158)
		(width 0.1016)
		(layer "In2.Cu")
		(net "PCIE_RX_P23")
	)
	(arc
		(start 318.150748 -222.237808)
		(mid 318.287088 -222.033622)
		(end 318.334898 -221.7928)
		(width 0.1397)
		(layer "In2.Cu")
		(net "PCIE_RX_P23")
	)
	(segment
		(start 254.599948 -48.999902)
		(end 255.09982 -49.499774)
		(width 0.136652)
		(layer "F.Cu")
		(net "PCIE_RX_P22")
	)
	(via
		(at 255.09982 -49.499774)
		(size 0.4572)
		(drill 0.2032)
		(layers "F.Cu" "B.Cu")
		(net "PCIE_RX_P22")
	)
	(via
		(at 321.293744 -222.294704)
		(size 0.508)
		(drill 0.254)
		(layers "F.Cu" "B.Cu")
		(net "PCIE_RX_P22")
	)
	(segment
		(start 321.547998 -223.596454)
		(end 321.547744 -223.5962)
		(width 0.136652)
		(layer "B.Cu")
		(net "PCIE_RX_P22")
	)
	(segment
		(start 321.547744 -223.5962)
		(end 321.547744 -222.90786)
		(width 0.136652)
		(layer "B.Cu")
		(net "PCIE_RX_P22")
	)
	(segment
		(start 321.300094 -225.92538)
		(end 321.300094 -224.7138)
		(width 0.136652)
		(layer "B.Cu")
		(net "PCIE_RX_P22")
	)
	(segment
		(start 321.300094 -224.7138)
		(end 321.300348 -224.713546)
		(width 0.136652)
		(layer "B.Cu")
		(net "PCIE_RX_P22")
	)
	(segment
		(start 321.440302 -224.375726)
		(end 321.491102 -224.324926)
		(width 0.136652)
		(layer "B.Cu")
		(net "PCIE_RX_P22")
	)
	(segment
		(start 321.547998 -224.187512)
		(end 321.547998 -223.596454)
		(width 0.136652)
		(layer "B.Cu")
		(net "PCIE_RX_P22")
	)
	(arc
		(start 321.491102 -224.324926)
		(mid 321.533228 -224.26188)
		(end 321.547998 -224.187512)
		(width 0.136652)
		(layer "B.Cu")
		(net "PCIE_RX_P22")
	)
	(arc
		(start 321.300348 -224.713546)
		(mid 321.336716 -224.53071)
		(end 321.440302 -224.375726)
		(width 0.136652)
		(layer "B.Cu")
		(net "PCIE_RX_P22")
	)
	(arc
		(start 321.547744 -222.90786)
		(mid 321.481736 -222.576014)
		(end 321.293744 -222.294704)
		(width 0.136652)
		(layer "B.Cu")
		(net "PCIE_RX_P22")
	)
	(segment
		(start 318.463676 -209.253074)
		(end 318.210438 -211.455)
		(width 0.1397)
		(layer "In2.Cu")
		(net "PCIE_RX_P22")
	)
	(segment
		(start 286.385 -69.85)
		(end 307.800502 -191.302894)
		(width 0.1397)
		(layer "In2.Cu")
		(net "PCIE_RX_P22")
	)
	(segment
		(start 318.210438 -211.455)
		(end 319.06464 -216.299288)
		(width 0.1397)
		(layer "In2.Cu")
		(net "PCIE_RX_P22")
	)
	(segment
		(start 255.638046 -49.817274)
		(end 255.69545 -49.92116)
		(width 0.1016)
		(layer "In2.Cu")
		(net "PCIE_RX_P22")
	)
	(segment
		(start 259.713476 -50.165)
		(end 260.388862 -50.165)
		(width 0.1397)
		(layer "In2.Cu")
		(net "PCIE_RX_P22")
	)
	(segment
		(start 321.535044 -219.827348)
		(end 321.535044 -221.7928)
		(width 0.1397)
		(layer "In2.Cu")
		(net "PCIE_RX_P22")
	)
	(segment
		(start 268.828774 -51.653186)
		(end 278.27478 -58.267346)
		(width 0.1397)
		(layer "In2.Cu")
		(net "PCIE_RX_P22")
	)
	(segment
		(start 278.27478 -58.267346)
		(end 286.385 -69.85)
		(width 0.1397)
		(layer "In2.Cu")
		(net "PCIE_RX_P22")
	)
	(segment
		(start 317.822326 -205.61554)
		(end 318.463676 -209.253074)
		(width 0.1397)
		(layer "In2.Cu")
		(net "PCIE_RX_P22")
	)
	(segment
		(start 256.00914 -50.106072)
		(end 259.654548 -50.106072)
		(width 0.1016)
		(layer "In2.Cu")
		(net "PCIE_RX_P22")
	)
	(segment
		(start 259.654548 -50.106072)
		(end 259.713476 -50.165)
		(width 0.1016)
		(layer "In2.Cu")
		(net "PCIE_RX_P22")
	)
	(segment
		(start 260.388862 -50.165)
		(end 268.828774 -51.653186)
		(width 0.1397)
		(layer "In2.Cu")
		(net "PCIE_RX_P22")
	)
	(segment
		(start 307.800502 -191.302894)
		(end 317.822326 -205.61554)
		(width 0.1397)
		(layer "In2.Cu")
		(net "PCIE_RX_P22")
	)
	(segment
		(start 319.06464 -216.299288)
		(end 321.535044 -219.827348)
		(width 0.1397)
		(layer "In2.Cu")
		(net "PCIE_RX_P22")
	)
	(segment
		(start 321.350894 -222.237808)
		(end 321.293744 -222.294704)
		(width 0.1397)
		(layer "In2.Cu")
		(net "PCIE_RX_P22")
	)
	(arc
		(start 255.69545 -49.92116)
		(mid 255.827043 -50.05645)
		(end 256.00914 -50.106072)
		(width 0.1016)
		(layer "In2.Cu")
		(net "PCIE_RX_P22")
	)
	(arc
		(start 255.09982 -49.499774)
		(mid 255.412265 -49.585065)
		(end 255.638046 -49.817274)
		(width 0.1016)
		(layer "In2.Cu")
		(net "PCIE_RX_P22")
	)
	(arc
		(start 321.535044 -221.7928)
		(mid 321.487235 -222.033622)
		(end 321.350894 -222.237808)
		(width 0.1397)
		(layer "In2.Cu")
		(net "PCIE_RX_P22")
	)
	(segment
		(start 253.59995 -47.999904)
		(end 254.099822 -48.499776)
		(width 0.136652)
		(layer "F.Cu")
		(net "PCIE_RX_P21")
	)
	(via
		(at 324.493636 -222.294704)
		(size 0.508)
		(drill 0.254)
		(layers "F.Cu" "B.Cu")
		(net "PCIE_RX_P21")
	)
	(via
		(at 254.099822 -48.499776)
		(size 0.4572)
		(drill 0.2032)
		(layers "F.Cu" "B.Cu")
		(net "PCIE_RX_P21")
	)
	(segment
		(start 324.74789 -223.596454)
		(end 324.747636 -223.5962)
		(width 0.136652)
		(layer "B.Cu")
		(net "PCIE_RX_P21")
	)
	(segment
		(start 324.50024 -225.92538)
		(end 324.50024 -224.713546)
		(width 0.136652)
		(layer "B.Cu")
		(net "PCIE_RX_P21")
	)
	(segment
		(start 324.640194 -224.375726)
		(end 324.690994 -224.324926)
		(width 0.136652)
		(layer "B.Cu")
		(net "PCIE_RX_P21")
	)
	(segment
		(start 324.747636 -223.5962)
		(end 324.747636 -222.90786)
		(width 0.136652)
		(layer "B.Cu")
		(net "PCIE_RX_P21")
	)
	(segment
		(start 324.74789 -224.187512)
		(end 324.74789 -223.596454)
		(width 0.136652)
		(layer "B.Cu")
		(net "PCIE_RX_P21")
	)
	(arc
		(start 324.50024 -224.713546)
		(mid 324.536608 -224.53071)
		(end 324.640194 -224.375726)
		(width 0.136652)
		(layer "B.Cu")
		(net "PCIE_RX_P21")
	)
	(arc
		(start 324.690994 -224.324926)
		(mid 324.73312 -224.26188)
		(end 324.74789 -224.187512)
		(width 0.136652)
		(layer "B.Cu")
		(net "PCIE_RX_P21")
	)
	(arc
		(start 324.747636 -222.90786)
		(mid 324.681628 -222.576014)
		(end 324.493636 -222.294704)
		(width 0.136652)
		(layer "B.Cu")
		(net "PCIE_RX_P21")
	)
	(segment
		(start 260.359906 -49.149)
		(end 269.24762 -50.716434)
		(width 0.1397)
		(layer "In2.Cu")
		(net "PCIE_RX_P21")
	)
	(segment
		(start 321.6148 -207.62214)
		(end 321.6148 -213.498938)
		(width 0.1397)
		(layer "In2.Cu")
		(net "PCIE_RX_P21")
	)
	(segment
		(start 314.94603 -198.09841)
		(end 321.6148 -207.62214)
		(width 0.1397)
		(layer "In2.Cu")
		(net "PCIE_RX_P21")
	)
	(segment
		(start 308.277006 -188.574172)
		(end 311.7342 -193.511678)
		(width 0.1397)
		(layer "In2.Cu")
		(net "PCIE_RX_P21")
	)
	(segment
		(start 269.24762 -50.716434)
		(end 278.90724 -57.4802)
		(width 0.1397)
		(layer "In2.Cu")
		(net "PCIE_RX_P21")
	)
	(segment
		(start 324.734936 -220.697806)
		(end 324.734936 -221.7928)
		(width 0.1397)
		(layer "In2.Cu")
		(net "PCIE_RX_P21")
	)
	(segment
		(start 259.545074 -49.106074)
		(end 259.588 -49.149)
		(width 0.1016)
		(layer "In2.Cu")
		(net "PCIE_RX_P21")
	)
	(segment
		(start 322.135754 -216.45499)
		(end 324.47738 -219.799916)
		(width 0.1397)
		(layer "In2.Cu")
		(net "PCIE_RX_P21")
	)
	(segment
		(start 321.6148 -213.498938)
		(end 322.135754 -216.45499)
		(width 0.1397)
		(layer "In2.Cu")
		(net "PCIE_RX_P21")
	)
	(segment
		(start 311.7342 -193.511678)
		(end 314.94603 -198.09841)
		(width 0.1397)
		(layer "In2.Cu")
		(net "PCIE_RX_P21")
	)
	(segment
		(start 324.47738 -219.799916)
		(end 324.734936 -220.697806)
		(width 0.1397)
		(layer "In2.Cu")
		(net "PCIE_RX_P21")
	)
	(segment
		(start 259.588 -49.149)
		(end 260.359906 -49.149)
		(width 0.1397)
		(layer "In2.Cu")
		(net "PCIE_RX_P21")
	)
	(segment
		(start 287.26638 -69.418454)
		(end 308.277006 -188.574172)
		(width 0.1397)
		(layer "In2.Cu")
		(net "PCIE_RX_P21")
	)
	(segment
		(start 278.90724 -57.4802)
		(end 287.26638 -69.418454)
		(width 0.1397)
		(layer "In2.Cu")
		(net "PCIE_RX_P21")
	)
	(segment
		(start 254.638048 -48.817276)
		(end 254.695452 -48.921162)
		(width 0.1016)
		(layer "In2.Cu")
		(net "PCIE_RX_P21")
	)
	(segment
		(start 255.009142 -49.106074)
		(end 259.545074 -49.106074)
		(width 0.1016)
		(layer "In2.Cu")
		(net "PCIE_RX_P21")
	)
	(segment
		(start 324.550786 -222.237808)
		(end 324.493636 -222.294704)
		(width 0.1397)
		(layer "In2.Cu")
		(net "PCIE_RX_P21")
	)
	(arc
		(start 324.734936 -221.7928)
		(mid 324.687127 -222.033622)
		(end 324.550786 -222.237808)
		(width 0.1397)
		(layer "In2.Cu")
		(net "PCIE_RX_P21")
	)
	(arc
		(start 254.099822 -48.499776)
		(mid 254.412267 -48.585067)
		(end 254.638048 -48.817276)
		(width 0.1016)
		(layer "In2.Cu")
		(net "PCIE_RX_P21")
	)
	(arc
		(start 254.695452 -48.921162)
		(mid 254.827045 -49.056452)
		(end 255.009142 -49.106074)
		(width 0.1016)
		(layer "In2.Cu")
		(net "PCIE_RX_P21")
	)
	(segment
		(start 254.599948 -46.999906)
		(end 255.09982 -46.500034)
		(width 0.136652)
		(layer "F.Cu")
		(net "PCIE_RX_P20")
	)
	(via
		(at 327.693782 -222.294704)
		(size 0.508)
		(drill 0.254)
		(layers "F.Cu" "B.Cu")
		(net "PCIE_RX_P20")
	)
	(via
		(at 255.09982 -46.500034)
		(size 0.4572)
		(drill 0.2032)
		(layers "F.Cu" "B.Cu")
		(net "PCIE_RX_P20")
	)
	(segment
		(start 327.700132 -225.92538)
		(end 327.700132 -224.7138)
		(width 0.136652)
		(layer "B.Cu")
		(net "PCIE_RX_P20")
	)
	(segment
		(start 327.700132 -224.7138)
		(end 327.700386 -224.713546)
		(width 0.136652)
		(layer "B.Cu")
		(net "PCIE_RX_P20")
	)
	(segment
		(start 327.947782 -223.5962)
		(end 327.947782 -222.90786)
		(width 0.136652)
		(layer "B.Cu")
		(net "PCIE_RX_P20")
	)
	(segment
		(start 327.84034 -224.375726)
		(end 327.89114 -224.324926)
		(width 0.136652)
		(layer "B.Cu")
		(net "PCIE_RX_P20")
	)
	(segment
		(start 327.948036 -223.596454)
		(end 327.947782 -223.5962)
		(width 0.136652)
		(layer "B.Cu")
		(net "PCIE_RX_P20")
	)
	(segment
		(start 327.948036 -224.187512)
		(end 327.948036 -223.596454)
		(width 0.136652)
		(layer "B.Cu")
		(net "PCIE_RX_P20")
	)
	(arc
		(start 327.700386 -224.713546)
		(mid 327.736754 -224.53071)
		(end 327.84034 -224.375726)
		(width 0.136652)
		(layer "B.Cu")
		(net "PCIE_RX_P20")
	)
	(arc
		(start 327.947782 -222.90786)
		(mid 327.881774 -222.576014)
		(end 327.693782 -222.294704)
		(width 0.136652)
		(layer "B.Cu")
		(net "PCIE_RX_P20")
	)
	(arc
		(start 327.89114 -224.324926)
		(mid 327.933266 -224.26188)
		(end 327.948036 -224.187512)
		(width 0.136652)
		(layer "B.Cu")
		(net "PCIE_RX_P20")
	)
	(segment
		(start 327.693782 -222.294704)
		(end 327.750932 -222.237808)
		(width 0.1397)
		(layer "In2.Cu")
		(net "PCIE_RX_P20")
	)
	(segment
		(start 255.434592 -46.834806)
		(end 255.09982 -46.500034)
		(width 0.1397)
		(layer "In2.Cu")
		(net "PCIE_RX_P20")
	)
	(segment
		(start 255.434592 -47.111666)
		(end 255.434592 -46.834806)
		(width 0.1397)
		(layer "In2.Cu")
		(net "PCIE_RX_P20")
	)
	(segment
		(start 256.026666 -47.70374)
		(end 255.434592 -47.111666)
		(width 0.1397)
		(layer "In2.Cu")
		(net "PCIE_RX_P20")
	)
	(segment
		(start 327.935082 -221.7928)
		(end 327.935082 -219.056712)
		(width 0.1397)
		(layer "In2.Cu")
		(net "PCIE_RX_P20")
	)
	(segment
		(start 324.7898 -213.719156)
		(end 324.7898 -208.90992)
		(width 0.1397)
		(layer "In2.Cu")
		(net "PCIE_RX_P20")
	)
	(segment
		(start 269.915132 -49.388776)
		(end 260.359906 -47.70374)
		(width 0.1397)
		(layer "In2.Cu")
		(net "PCIE_RX_P20")
	)
	(segment
		(start 325.157338 -215.80475)
		(end 324.7898 -213.719156)
		(width 0.1397)
		(layer "In2.Cu")
		(net "PCIE_RX_P20")
	)
	(segment
		(start 326.3138 -217.456258)
		(end 325.157338 -215.80475)
		(width 0.1397)
		(layer "In2.Cu")
		(net "PCIE_RX_P20")
	)
	(segment
		(start 324.7898 -208.90992)
		(end 309.418736 -186.958224)
		(width 0.1397)
		(layer "In2.Cu")
		(net "PCIE_RX_P20")
	)
	(segment
		(start 309.418736 -186.958224)
		(end 288.572448 -68.732654)
		(width 0.1397)
		(layer "In2.Cu")
		(net "PCIE_RX_P20")
	)
	(segment
		(start 288.572448 -68.732654)
		(end 279.946608 -56.412892)
		(width 0.1397)
		(layer "In2.Cu")
		(net "PCIE_RX_P20")
	)
	(segment
		(start 279.946608 -56.412892)
		(end 269.915132 -49.388776)
		(width 0.1397)
		(layer "In2.Cu")
		(net "PCIE_RX_P20")
	)
	(segment
		(start 327.935082 -219.056712)
		(end 327.295764 -218.143836)
		(width 0.1397)
		(layer "In2.Cu")
		(net "PCIE_RX_P20")
	)
	(segment
		(start 260.359906 -47.70374)
		(end 256.026666 -47.70374)
		(width 0.1397)
		(layer "In2.Cu")
		(net "PCIE_RX_P20")
	)
	(segment
		(start 327.295764 -218.143836)
		(end 326.3138 -217.456258)
		(width 0.1397)
		(layer "In2.Cu")
		(net "PCIE_RX_P20")
	)
	(arc
		(start 327.750932 -222.237808)
		(mid 327.887272 -222.033622)
		(end 327.935082 -221.7928)
		(width 0.1397)
		(layer "In2.Cu")
		(net "PCIE_RX_P20")
	)
	(segment
		(start 244.599968 -30.999938)
		(end 245.09984 -30.500066)
		(width 0.136652)
		(layer "F.Cu")
		(net "PCIE_RX_P2")
	)
	(via
		(at 245.09984 -30.500066)
		(size 0.4572)
		(drill 0.2032)
		(layers "F.Cu" "B.Cu")
		(net "PCIE_RX_P2")
	)
	(segment
		(start 280.881074 -15.711424)
		(end 280.823416 -15.721584)
		(width 0.1397)
		(layer "In2.Cu")
		(net "PCIE_RX_P2")
	)
	(segment
		(start 291.053774 -18.227548)
		(end 291.053774 -18.288)
		(width 0.1397)
		(layer "In2.Cu")
		(net "PCIE_RX_P2")
	)
	(segment
		(start 259.996432 -17.900396)
		(end 256.821432 -17.265396)
		(width 0.1397)
		(layer "In2.Cu")
		(net "PCIE_RX_P2")
	)
	(segment
		(start 290.96843 -18.495264)
		(end 290.547552 -18.916142)
		(width 0.1397)
		(layer "In2.Cu")
		(net "PCIE_RX_P2")
	)
	(segment
		(start 269.521432 -17.265396)
		(end 266.346432 -17.900396)
		(width 0.1397)
		(layer "In2.Cu")
		(net "PCIE_RX_P2")
	)
	(segment
		(start 290.227258 -19.05)
		(end 288.260536 -19.05)
		(width 0.1397)
		(layer "In2.Cu")
		(net "PCIE_RX_P2")
	)
	(segment
		(start 280.82367 -15.721584)
		(end 279.42286 -15.968726)
		(width 0.1397)
		(layer "In2.Cu")
		(net "PCIE_RX_P2")
	)
	(segment
		(start 263.171432 -17.265396)
		(end 259.996432 -17.900396)
		(width 0.1397)
		(layer "In2.Cu")
		(net "PCIE_RX_P2")
	)
	(segment
		(start 266.346432 -17.900396)
		(end 263.171432 -17.265396)
		(width 0.1397)
		(layer "In2.Cu")
		(net "PCIE_RX_P2")
	)
	(segment
		(start 290.968176 -18.49501)
		(end 290.96843 -18.495264)
		(width 0.1397)
		(layer "In2.Cu")
		(net "PCIE_RX_P2")
	)
	(segment
		(start 244.6528 -29.23413)
		(end 244.6528 -29.52242)
		(width 0.1397)
		(layer "In2.Cu")
		(net "PCIE_RX_P2")
	)
	(segment
		(start 288.260536 -19.05)
		(end 286.187642 -18.68424)
		(width 0.1397)
		(layer "In2.Cu")
		(net "PCIE_RX_P2")
	)
	(segment
		(start 280.823416 -15.721584)
		(end 280.82367 -15.721584)
		(width 0.1397)
		(layer "In2.Cu")
		(net "PCIE_RX_P2")
	)
	(segment
		(start 273.10588 -17.982184)
		(end 269.521432 -17.265396)
		(width 0.1397)
		(layer "In2.Cu")
		(net "PCIE_RX_P2")
	)
	(segment
		(start 277.706074 -17.170908)
		(end 273.10588 -17.982184)
		(width 0.1397)
		(layer "In2.Cu")
		(net "PCIE_RX_P2")
	)
	(segment
		(start 256.821432 -17.265396)
		(end 253.001526 -17.907)
		(width 0.1397)
		(layer "In2.Cu")
		(net "PCIE_RX_P2")
	)
	(segment
		(start 253.001526 -17.907)
		(end 244.9068 -26.001726)
		(width 0.1397)
		(layer "In2.Cu")
		(net "PCIE_RX_P2")
	)
	(segment
		(start 244.6528 -29.52242)
		(end 245.028212 -30.428438)
		(width 0.1397)
		(layer "In2.Cu")
		(net "PCIE_RX_P2")
	)
	(segment
		(start 244.9068 -26.001726)
		(end 244.9068 -28.702)
		(width 0.1397)
		(layer "In2.Cu")
		(net "PCIE_RX_P2")
	)
	(segment
		(start 245.028212 -30.428438)
		(end 245.09984 -30.500066)
		(width 0.1397)
		(layer "In2.Cu")
		(net "PCIE_RX_P2")
	)
	(segment
		(start 286.187642 -18.68424)
		(end 282.299156 -15.96136)
		(width 0.1397)
		(layer "In2.Cu")
		(net "PCIE_RX_P2")
	)
	(segment
		(start 279.42286 -15.968726)
		(end 277.706074 -17.170908)
		(width 0.1397)
		(layer "In2.Cu")
		(net "PCIE_RX_P2")
	)
	(segment
		(start 244.799104 -28.96235)
		(end 244.7417 -29.0195)
		(width 0.1397)
		(layer "In2.Cu")
		(net "PCIE_RX_P2")
	)
	(segment
		(start 282.299156 -15.96136)
		(end 280.881074 -15.711424)
		(width 0.1397)
		(layer "In2.Cu")
		(net "PCIE_RX_P2")
	)
	(arc
		(start 290.547552 -18.916142)
		(mid 290.516865 -18.944235)
		(end 290.483798 -18.969482)
		(width 0.1397)
		(layer "In2.Cu")
		(net "PCIE_RX_P2")
	)
	(arc
		(start 290.63442 -17.729962)
		(mid 290.934916 -17.902201)
		(end 291.053774 -18.227548)
		(width 0.1397)
		(layer "In2.Cu")
		(net "PCIE_RX_P2")
	)
	(arc
		(start 291.053774 -18.288)
		(mid 291.031531 -18.400005)
		(end 290.968176 -18.49501)
		(width 0.1397)
		(layer "In2.Cu")
		(net "PCIE_RX_P2")
	)
	(arc
		(start 244.9068 -28.702)
		(mid 244.90392 -28.747697)
		(end 244.89537 -28.792678)
		(width 0.1397)
		(layer "In2.Cu")
		(net "PCIE_RX_P2")
	)
	(arc
		(start 290.483798 -18.969482)
		(mid 290.361687 -19.029386)
		(end 290.227258 -19.05)
		(width 0.1397)
		(layer "In2.Cu")
		(net "PCIE_RX_P2")
	)
	(arc
		(start 244.7417 -29.0195)
		(mid 244.675902 -29.117973)
		(end 244.6528 -29.23413)
		(width 0.1397)
		(layer "In2.Cu")
		(net "PCIE_RX_P2")
	)
	(arc
		(start 244.89537 -28.792678)
		(mid 244.858662 -28.883993)
		(end 244.799104 -28.96235)
		(width 0.1397)
		(layer "In2.Cu")
		(net "PCIE_RX_P2")
	)
	(segment
		(start 253.59995 -45.999908)
		(end 254.099822 -45.500036)
		(width 0.136652)
		(layer "F.Cu")
		(net "PCIE_RX_P19")
	)
	(via
		(at 330.893674 -222.294704)
		(size 0.508)
		(drill 0.254)
		(layers "F.Cu" "B.Cu")
		(net "PCIE_RX_P19")
	)
	(via
		(at 254.099822 -45.500036)
		(size 0.4572)
		(drill 0.2032)
		(layers "F.Cu" "B.Cu")
		(net "PCIE_RX_P19")
	)
	(segment
		(start 331.040232 -224.375726)
		(end 331.091032 -224.324926)
		(width 0.136652)
		(layer "B.Cu")
		(net "PCIE_RX_P19")
	)
	(segment
		(start 331.147674 -223.5962)
		(end 331.147674 -222.90786)
		(width 0.136652)
		(layer "B.Cu")
		(net "PCIE_RX_P19")
	)
	(segment
		(start 330.900024 -224.7138)
		(end 330.900278 -224.713546)
		(width 0.136652)
		(layer "B.Cu")
		(net "PCIE_RX_P19")
	)
	(segment
		(start 331.147928 -224.187512)
		(end 331.147928 -223.596454)
		(width 0.136652)
		(layer "B.Cu")
		(net "PCIE_RX_P19")
	)
	(segment
		(start 331.147928 -223.596454)
		(end 331.147674 -223.5962)
		(width 0.136652)
		(layer "B.Cu")
		(net "PCIE_RX_P19")
	)
	(segment
		(start 330.900024 -225.92538)
		(end 330.900024 -224.7138)
		(width 0.136652)
		(layer "B.Cu")
		(net "PCIE_RX_P19")
	)
	(arc
		(start 331.091032 -224.324926)
		(mid 331.133158 -224.26188)
		(end 331.147928 -224.187512)
		(width 0.136652)
		(layer "B.Cu")
		(net "PCIE_RX_P19")
	)
	(arc
		(start 330.900278 -224.713546)
		(mid 330.936646 -224.53071)
		(end 331.040232 -224.375726)
		(width 0.136652)
		(layer "B.Cu")
		(net "PCIE_RX_P19")
	)
	(arc
		(start 331.147674 -222.90786)
		(mid 331.081666 -222.576014)
		(end 330.893674 -222.294704)
		(width 0.136652)
		(layer "B.Cu")
		(net "PCIE_RX_P19")
	)
	(segment
		(start 309.5498 -182.067454)
		(end 289.330384 -67.397884)
		(width 0.1397)
		(layer "In2.Cu")
		(net "PCIE_RX_P19")
	)
	(segment
		(start 329.468226 -210.513676)
		(end 309.5498 -182.067454)
		(width 0.1397)
		(layer "In2.Cu")
		(net "PCIE_RX_P19")
	)
	(segment
		(start 330.893674 -222.294704)
		(end 330.950824 -222.237808)
		(width 0.1397)
		(layer "In2.Cu")
		(net "PCIE_RX_P19")
	)
	(segment
		(start 259.603748 -46.106334)
		(end 255.009142 -46.106334)
		(width 0.1016)
		(layer "In2.Cu")
		(net "PCIE_RX_P19")
	)
	(segment
		(start 331.134974 -221.7928)
		(end 331.134974 -219.966286)
		(width 0.1397)
		(layer "In2.Cu")
		(net "PCIE_RX_P19")
	)
	(segment
		(start 280.644092 -54.99227)
		(end 270.586962 -47.95012)
		(width 0.1397)
		(layer "In2.Cu")
		(net "PCIE_RX_P19")
	)
	(segment
		(start 254.695452 -45.921422)
		(end 254.638048 -45.817536)
		(width 0.1016)
		(layer "In2.Cu")
		(net "PCIE_RX_P19")
	)
	(segment
		(start 260.388862 -46.1518)
		(end 259.713476 -46.1518)
		(width 0.1397)
		(layer "In2.Cu")
		(net "PCIE_RX_P19")
	)
	(segment
		(start 289.330384 -67.397884)
		(end 280.644092 -54.99227)
		(width 0.1397)
		(layer "In2.Cu")
		(net "PCIE_RX_P19")
	)
	(segment
		(start 331.134974 -219.966286)
		(end 329.468226 -210.513676)
		(width 0.1397)
		(layer "In2.Cu")
		(net "PCIE_RX_P19")
	)
	(segment
		(start 270.586962 -47.95012)
		(end 260.388862 -46.1518)
		(width 0.1397)
		(layer "In2.Cu")
		(net "PCIE_RX_P19")
	)
	(arc
		(start 330.950824 -222.237808)
		(mid 331.087164 -222.033622)
		(end 331.134974 -221.7928)
		(width 0.1397)
		(layer "In2.Cu")
		(net "PCIE_RX_P19")
	)
	(arc
		(start 259.713476 -46.1518)
		(mid 259.663132 -46.118161)
		(end 259.603748 -46.106334)
		(width 0.1016)
		(layer "In2.Cu")
		(net "PCIE_RX_P19")
	)
	(arc
		(start 255.009142 -46.106334)
		(mid 254.827035 -46.056729)
		(end 254.695452 -45.921422)
		(width 0.1016)
		(layer "In2.Cu")
		(net "PCIE_RX_P19")
	)
	(arc
		(start 254.638048 -45.817536)
		(mid 254.412272 -45.58532)
		(end 254.099822 -45.500036)
		(width 0.1016)
		(layer "In2.Cu")
		(net "PCIE_RX_P19")
	)
	(segment
		(start 254.599948 -44.99991)
		(end 255.09982 -44.500038)
		(width 0.136652)
		(layer "F.Cu")
		(net "PCIE_RX_P18")
	)
	(via
		(at 334.093566 -222.294704)
		(size 0.508)
		(drill 0.254)
		(layers "F.Cu" "B.Cu")
		(net "PCIE_RX_P18")
	)
	(via
		(at 255.09982 -44.500038)
		(size 0.4572)
		(drill 0.2032)
		(layers "F.Cu" "B.Cu")
		(net "PCIE_RX_P18")
	)
	(segment
		(start 334.347566 -223.5962)
		(end 334.347566 -222.90786)
		(width 0.136652)
		(layer "B.Cu")
		(net "PCIE_RX_P18")
	)
	(segment
		(start 334.240124 -224.375726)
		(end 334.290924 -224.324926)
		(width 0.136652)
		(layer "B.Cu")
		(net "PCIE_RX_P18")
	)
	(segment
		(start 334.34782 -224.187512)
		(end 334.34782 -223.596454)
		(width 0.136652)
		(layer "B.Cu")
		(net "PCIE_RX_P18")
	)
	(segment
		(start 334.34782 -223.596454)
		(end 334.347566 -223.5962)
		(width 0.136652)
		(layer "B.Cu")
		(net "PCIE_RX_P18")
	)
	(segment
		(start 334.10017 -225.92538)
		(end 334.10017 -224.713546)
		(width 0.136652)
		(layer "B.Cu")
		(net "PCIE_RX_P18")
	)
	(arc
		(start 334.290924 -224.324926)
		(mid 334.33305 -224.26188)
		(end 334.34782 -224.187512)
		(width 0.136652)
		(layer "B.Cu")
		(net "PCIE_RX_P18")
	)
	(arc
		(start 334.10017 -224.713546)
		(mid 334.136538 -224.53071)
		(end 334.240124 -224.375726)
		(width 0.136652)
		(layer "B.Cu")
		(net "PCIE_RX_P18")
	)
	(arc
		(start 334.347566 -222.90786)
		(mid 334.281558 -222.576014)
		(end 334.093566 -222.294704)
		(width 0.136652)
		(layer "B.Cu")
		(net "PCIE_RX_P18")
	)
	(segment
		(start 290.065714 -66.505328)
		(end 281.630628 -54.458362)
		(width 0.1397)
		(layer "In2.Cu")
		(net "PCIE_RX_P18")
	)
	(segment
		(start 260.388862 -45.160438)
		(end 259.688838 -45.160438)
		(width 0.1397)
		(layer "In2.Cu")
		(net "PCIE_RX_P18")
	)
	(segment
		(start 255.69545 -44.921424)
		(end 255.638046 -44.817538)
		(width 0.1016)
		(layer "In2.Cu")
		(net "PCIE_RX_P18")
	)
	(segment
		(start 259.634736 -45.106336)
		(end 256.00914 -45.106336)
		(width 0.1016)
		(layer "In2.Cu")
		(net "PCIE_RX_P18")
	)
	(segment
		(start 331.460094 -214.532464)
		(end 330.678536 -210.098132)
		(width 0.1397)
		(layer "In2.Cu")
		(net "PCIE_RX_P18")
	)
	(segment
		(start 281.630628 -54.458362)
		(end 271.031462 -47.036736)
		(width 0.1397)
		(layer "In2.Cu")
		(net "PCIE_RX_P18")
	)
	(segment
		(start 310.248808 -180.921406)
		(end 290.065714 -66.505328)
		(width 0.1397)
		(layer "In2.Cu")
		(net "PCIE_RX_P18")
	)
	(segment
		(start 330.678536 -210.098132)
		(end 310.248808 -180.921406)
		(width 0.1397)
		(layer "In2.Cu")
		(net "PCIE_RX_P18")
	)
	(segment
		(start 271.031462 -47.036736)
		(end 260.388862 -45.160438)
		(width 0.1397)
		(layer "In2.Cu")
		(net "PCIE_RX_P18")
	)
	(segment
		(start 259.688838 -45.160438)
		(end 259.634736 -45.106336)
		(width 0.1016)
		(layer "In2.Cu")
		(net "PCIE_RX_P18")
	)
	(segment
		(start 334.093566 -222.294704)
		(end 334.150716 -222.237808)
		(width 0.1397)
		(layer "In2.Cu")
		(net "PCIE_RX_P18")
	)
	(segment
		(start 334.334866 -221.7928)
		(end 334.334866 -219.303092)
		(width 0.1397)
		(layer "In2.Cu")
		(net "PCIE_RX_P18")
	)
	(segment
		(start 334.334866 -219.303092)
		(end 334.178148 -218.414346)
		(width 0.1397)
		(layer "In2.Cu")
		(net "PCIE_RX_P18")
	)
	(segment
		(start 334.178148 -218.414346)
		(end 331.460094 -214.532464)
		(width 0.1397)
		(layer "In2.Cu")
		(net "PCIE_RX_P18")
	)
	(arc
		(start 334.150716 -222.237808)
		(mid 334.287056 -222.033622)
		(end 334.334866 -221.7928)
		(width 0.1397)
		(layer "In2.Cu")
		(net "PCIE_RX_P18")
	)
	(arc
		(start 255.638046 -44.817538)
		(mid 255.41227 -44.585322)
		(end 255.09982 -44.500038)
		(width 0.1016)
		(layer "In2.Cu")
		(net "PCIE_RX_P18")
	)
	(arc
		(start 256.00914 -45.106336)
		(mid 255.827033 -45.056731)
		(end 255.69545 -44.921424)
		(width 0.1016)
		(layer "In2.Cu")
		(net "PCIE_RX_P18")
	)
	(segment
		(start 253.59995 -43.999912)
		(end 254.099822 -43.50004)
		(width 0.136652)
		(layer "F.Cu")
		(net "PCIE_RX_P17")
	)
	(via
		(at 254.099822 -43.50004)
		(size 0.4572)
		(drill 0.2032)
		(layers "F.Cu" "B.Cu")
		(net "PCIE_RX_P17")
	)
	(via
		(at 337.293712 -222.294704)
		(size 0.508)
		(drill 0.254)
		(layers "F.Cu" "B.Cu")
		(net "PCIE_RX_P17")
	)
	(segment
		(start 337.547712 -223.5962)
		(end 337.547712 -222.90786)
		(width 0.136652)
		(layer "B.Cu")
		(net "PCIE_RX_P17")
	)
	(segment
		(start 337.547966 -223.596454)
		(end 337.547712 -223.5962)
		(width 0.136652)
		(layer "B.Cu")
		(net "PCIE_RX_P17")
	)
	(segment
		(start 337.300062 -225.92538)
		(end 337.300062 -224.7138)
		(width 0.136652)
		(layer "B.Cu")
		(net "PCIE_RX_P17")
	)
	(segment
		(start 337.44027 -224.375726)
		(end 337.49107 -224.324926)
		(width 0.136652)
		(layer "B.Cu")
		(net "PCIE_RX_P17")
	)
	(segment
		(start 337.547966 -224.187512)
		(end 337.547966 -223.596454)
		(width 0.136652)
		(layer "B.Cu")
		(net "PCIE_RX_P17")
	)
	(segment
		(start 337.300062 -224.7138)
		(end 337.300316 -224.713546)
		(width 0.136652)
		(layer "B.Cu")
		(net "PCIE_RX_P17")
	)
	(arc
		(start 337.49107 -224.324926)
		(mid 337.533196 -224.26188)
		(end 337.547966 -224.187512)
		(width 0.136652)
		(layer "B.Cu")
		(net "PCIE_RX_P17")
	)
	(arc
		(start 337.547712 -222.90786)
		(mid 337.481704 -222.576014)
		(end 337.293712 -222.294704)
		(width 0.136652)
		(layer "B.Cu")
		(net "PCIE_RX_P17")
	)
	(arc
		(start 337.300316 -224.713546)
		(mid 337.336684 -224.53071)
		(end 337.44027 -224.375726)
		(width 0.136652)
		(layer "B.Cu")
		(net "PCIE_RX_P17")
	)
	(segment
		(start 334.3402 -214.03183)
		(end 334.3402 -209.757518)
		(width 0.1397)
		(layer "In2.Cu")
		(net "PCIE_RX_P17")
	)
	(segment
		(start 282.194762 -53.91277)
		(end 282.175712 -53.89372)
		(width 0.1397)
		(layer "In2.Cu")
		(net "PCIE_RX_P17")
	)
	(segment
		(start 290.989004 -66.4718)
		(end 282.194762 -53.91277)
		(width 0.1397)
		(layer "In2.Cu")
		(net "PCIE_RX_P17")
	)
	(segment
		(start 260.389116 -44.16044)
		(end 259.772912 -44.16044)
		(width 0.1397)
		(layer "In2.Cu")
		(net "PCIE_RX_P17")
	)
	(segment
		(start 282.175712 -53.89372)
		(end 271.848834 -46.180756)
		(width 0.1397)
		(layer "In2.Cu")
		(net "PCIE_RX_P17")
	)
	(segment
		(start 333.817214 -209.234532)
		(end 329.402948 -206.14386)
		(width 0.1397)
		(layer "In2.Cu")
		(net "PCIE_RX_P17")
	)
	(segment
		(start 334.3402 -209.757518)
		(end 333.817214 -209.234532)
		(width 0.1397)
		(layer "In2.Cu")
		(net "PCIE_RX_P17")
	)
	(segment
		(start 311.338468 -180.352192)
		(end 290.989004 -66.4718)
		(width 0.1397)
		(layer "In2.Cu")
		(net "PCIE_RX_P17")
	)
	(segment
		(start 259.772912 -44.16044)
		(end 259.71881 -44.106338)
		(width 0.1016)
		(layer "In2.Cu")
		(net "PCIE_RX_P17")
	)
	(segment
		(start 334.459326 -214.70874)
		(end 334.3402 -214.03183)
		(width 0.1397)
		(layer "In2.Cu")
		(net "PCIE_RX_P17")
	)
	(segment
		(start 329.402948 -206.14386)
		(end 311.338468 -180.352192)
		(width 0.1397)
		(layer "In2.Cu")
		(net "PCIE_RX_P17")
	)
	(segment
		(start 337.535012 -219.100908)
		(end 334.459326 -214.70874)
		(width 0.1397)
		(layer "In2.Cu")
		(net "PCIE_RX_P17")
	)
	(segment
		(start 337.293712 -222.294704)
		(end 337.350862 -222.237808)
		(width 0.1397)
		(layer "In2.Cu")
		(net "PCIE_RX_P17")
	)
	(segment
		(start 337.535012 -221.7928)
		(end 337.535012 -219.100908)
		(width 0.1397)
		(layer "In2.Cu")
		(net "PCIE_RX_P17")
	)
	(segment
		(start 259.71881 -44.106338)
		(end 255.009142 -44.106338)
		(width 0.1016)
		(layer "In2.Cu")
		(net "PCIE_RX_P17")
	)
	(segment
		(start 254.695452 -43.921426)
		(end 254.638048 -43.81754)
		(width 0.1016)
		(layer "In2.Cu")
		(net "PCIE_RX_P17")
	)
	(segment
		(start 271.848834 -46.180756)
		(end 260.389116 -44.16044)
		(width 0.1397)
		(layer "In2.Cu")
		(net "PCIE_RX_P17")
	)
	(arc
		(start 254.638048 -43.81754)
		(mid 254.412272 -43.585324)
		(end 254.099822 -43.50004)
		(width 0.1016)
		(layer "In2.Cu")
		(net "PCIE_RX_P17")
	)
	(arc
		(start 337.350862 -222.237808)
		(mid 337.487202 -222.033622)
		(end 337.535012 -221.7928)
		(width 0.1397)
		(layer "In2.Cu")
		(net "PCIE_RX_P17")
	)
	(arc
		(start 255.009142 -44.106338)
		(mid 254.827035 -44.056733)
		(end 254.695452 -43.921426)
		(width 0.1016)
		(layer "In2.Cu")
		(net "PCIE_RX_P17")
	)
	(segment
		(start 254.599948 -42.999914)
		(end 255.09982 -42.500042)
		(width 0.136652)
		(layer "F.Cu")
		(net "PCIE_RX_P16")
	)
	(via
		(at 340.493604 -222.294704)
		(size 0.508)
		(drill 0.254)
		(layers "F.Cu" "B.Cu")
		(net "PCIE_RX_P16")
	)
	(via
		(at 255.09982 -42.500042)
		(size 0.4572)
		(drill 0.2032)
		(layers "F.Cu" "B.Cu")
		(net "PCIE_RX_P16")
	)
	(segment
		(start 340.747858 -224.187512)
		(end 340.747858 -223.596454)
		(width 0.136652)
		(layer "B.Cu")
		(net "PCIE_RX_P16")
	)
	(segment
		(start 340.747604 -223.5962)
		(end 340.747604 -222.90786)
		(width 0.136652)
		(layer "B.Cu")
		(net "PCIE_RX_P16")
	)
	(segment
		(start 340.640162 -224.375726)
		(end 340.690962 -224.324926)
		(width 0.136652)
		(layer "B.Cu")
		(net "PCIE_RX_P16")
	)
	(segment
		(start 340.747858 -223.596454)
		(end 340.747604 -223.5962)
		(width 0.136652)
		(layer "B.Cu")
		(net "PCIE_RX_P16")
	)
	(segment
		(start 340.500208 -225.92538)
		(end 340.500208 -224.713546)
		(width 0.136652)
		(layer "B.Cu")
		(net "PCIE_RX_P16")
	)
	(arc
		(start 340.500208 -224.713546)
		(mid 340.536576 -224.53071)
		(end 340.640162 -224.375726)
		(width 0.136652)
		(layer "B.Cu")
		(net "PCIE_RX_P16")
	)
	(arc
		(start 340.747604 -222.90786)
		(mid 340.681596 -222.576014)
		(end 340.493604 -222.294704)
		(width 0.136652)
		(layer "B.Cu")
		(net "PCIE_RX_P16")
	)
	(arc
		(start 340.690962 -224.324926)
		(mid 340.733088 -224.26188)
		(end 340.747858 -224.187512)
		(width 0.136652)
		(layer "B.Cu")
		(net "PCIE_RX_P16")
	)
	(segment
		(start 337.535012 -213.724744)
		(end 338.087462 -216.859358)
		(width 0.1397)
		(layer "In2.Cu")
		(net "PCIE_RX_P16")
	)
	(segment
		(start 337.125818 -208.817464)
		(end 337.535012 -209.40141)
		(width 0.1397)
		(layer "In2.Cu")
		(net "PCIE_RX_P16")
	)
	(segment
		(start 334.59166 -207.043274)
		(end 337.125818 -208.817464)
		(width 0.1397)
		(layer "In2.Cu")
		(net "PCIE_RX_P16")
	)
	(segment
		(start 271.962372 -45.210476)
		(end 281.940254 -52.197)
		(width 0.1397)
		(layer "In2.Cu")
		(net "PCIE_RX_P16")
	)
	(segment
		(start 281.940254 -52.197)
		(end 291.70884 -66.102992)
		(width 0.1397)
		(layer "In2.Cu")
		(net "PCIE_RX_P16")
	)
	(segment
		(start 256.00914 -43.10634)
		(end 259.61086 -43.10634)
		(width 0.1016)
		(layer "In2.Cu")
		(net "PCIE_RX_P16")
	)
	(segment
		(start 260.388862 -43.16984)
		(end 271.962372 -45.210476)
		(width 0.1397)
		(layer "In2.Cu")
		(net "PCIE_RX_P16")
	)
	(segment
		(start 259.61086 -43.10634)
		(end 259.67436 -43.16984)
		(width 0.1016)
		(layer "In2.Cu")
		(net "PCIE_RX_P16")
	)
	(segment
		(start 313.317128 -180.155088)
		(end 330.598018 -204.834236)
		(width 0.1397)
		(layer "In2.Cu")
		(net "PCIE_RX_P16")
	)
	(segment
		(start 340.550754 -222.237808)
		(end 340.493604 -222.294704)
		(width 0.1397)
		(layer "In2.Cu")
		(net "PCIE_RX_P16")
	)
	(segment
		(start 340.734904 -220.645482)
		(end 340.734904 -221.7928)
		(width 0.1397)
		(layer "In2.Cu")
		(net "PCIE_RX_P16")
	)
	(segment
		(start 338.087462 -216.859358)
		(end 340.734904 -220.645482)
		(width 0.1397)
		(layer "In2.Cu")
		(net "PCIE_RX_P16")
	)
	(segment
		(start 330.598018 -204.834236)
		(end 333.470758 -206.845662)
		(width 0.1397)
		(layer "In2.Cu")
		(net "PCIE_RX_P16")
	)
	(segment
		(start 259.67436 -43.16984)
		(end 260.388862 -43.16984)
		(width 0.1397)
		(layer "In2.Cu")
		(net "PCIE_RX_P16")
	)
	(segment
		(start 255.638046 -42.817542)
		(end 255.69545 -42.921428)
		(width 0.1016)
		(layer "In2.Cu")
		(net "PCIE_RX_P16")
	)
	(segment
		(start 337.535012 -209.40141)
		(end 337.535012 -213.724744)
		(width 0.1397)
		(layer "In2.Cu")
		(net "PCIE_RX_P16")
	)
	(segment
		(start 291.70884 -66.102992)
		(end 313.317128 -180.155088)
		(width 0.1397)
		(layer "In2.Cu")
		(net "PCIE_RX_P16")
	)
	(segment
		(start 333.470758 -206.845662)
		(end 334.59166 -207.043274)
		(width 0.1397)
		(layer "In2.Cu")
		(net "PCIE_RX_P16")
	)
	(arc
		(start 255.09982 -42.500042)
		(mid 255.412265 -42.585333)
		(end 255.638046 -42.817542)
		(width 0.1016)
		(layer "In2.Cu")
		(net "PCIE_RX_P16")
	)
	(arc
		(start 255.69545 -42.921428)
		(mid 255.827043 -43.056718)
		(end 256.00914 -43.10634)
		(width 0.1016)
		(layer "In2.Cu")
		(net "PCIE_RX_P16")
	)
	(arc
		(start 340.734904 -221.7928)
		(mid 340.687095 -222.033622)
		(end 340.550754 -222.237808)
		(width 0.1397)
		(layer "In2.Cu")
		(net "PCIE_RX_P16")
	)
	(segment
		(start 253.59995 -40.999918)
		(end 254.099822 -40.500046)
		(width 0.136652)
		(layer "F.Cu")
		(net "PCIE_RX_P15")
	)
	(via
		(at 254.099822 -40.500046)
		(size 0.4572)
		(drill 0.2032)
		(layers "F.Cu" "B.Cu")
		(net "PCIE_RX_P15")
	)
	(segment
		(start 324.3072 -13.970254)
		(end 324.3072 -15.0876)
		(width 0.1397)
		(layer "In2.Cu")
		(net "PCIE_RX_P15")
	)
	(segment
		(start 287.810194 -41.943274)
		(end 287.808416 -41.94302)
		(width 0.1397)
		(layer "In2.Cu")
		(net "PCIE_RX_P15")
	)
	(segment
		(start 325.229982 -39.137844)
		(end 300.534578 -44.386754)
		(width 0.1397)
		(layer "In2.Cu")
		(net "PCIE_RX_P15")
	)
	(segment
		(start 330.36637 -34.514282)
		(end 330.049378 -36.007548)
		(width 0.1397)
		(layer "In2.Cu")
		(net "PCIE_RX_P15")
	)
	(segment
		(start 254.576834 -40.023034)
		(end 254.099822 -40.500046)
		(width 0.1016)
		(layer "In2.Cu")
		(net "PCIE_RX_P15")
	)
	(segment
		(start 278.922734 -42.643806)
		(end 276.014942 -42.105326)
		(width 0.1397)
		(layer "In2.Cu")
		(net "PCIE_RX_P15")
	)
	(segment
		(start 282.665932 -43.33748)
		(end 281.775662 -43.17238)
		(width 0.1397)
		(layer "In2.Cu")
		(net "PCIE_RX_P15")
	)
	(segment
		(start 276.014942 -42.105326)
		(end 269.914878 -43.062652)
		(width 0.1397)
		(layer "In2.Cu")
		(net "PCIE_RX_P15")
	)
	(segment
		(start 323.90461 -13.642086)
		(end 324.015862 -13.642086)
		(width 0.1397)
		(layer "In2.Cu")
		(net "PCIE_RX_P15")
	)
	(segment
		(start 327.920604 -18.70075)
		(end 327.920604 -18.703036)
		(width 0.1397)
		(layer "In2.Cu")
		(net "PCIE_RX_P15")
	)
	(segment
		(start 281.775662 -43.17238)
		(end 278.922734 -42.643806)
		(width 0.1397)
		(layer "In2.Cu")
		(net "PCIE_RX_P15")
	)
	(segment
		(start 328.911966 -27.66822)
		(end 330.36637 -34.514282)
		(width 0.1397)
		(layer "In2.Cu")
		(net "PCIE_RX_P15")
	)
	(segment
		(start 261.822692 -40.386)
		(end 259.2578 -40.386)
		(width 0.1397)
		(layer "In2.Cu")
		(net "PCIE_RX_P15")
	)
	(segment
		(start 324.3072 -15.0876)
		(end 327.920604 -18.70075)
		(width 0.1397)
		(layer "In2.Cu")
		(net "PCIE_RX_P15")
	)
	(segment
		(start 287.808416 -41.94302)
		(end 282.665932 -43.33748)
		(width 0.1397)
		(layer "In2.Cu")
		(net "PCIE_RX_P15")
	)
	(segment
		(start 329.369928 -25.511506)
		(end 328.911966 -27.66822)
		(width 0.1397)
		(layer "In2.Cu")
		(net "PCIE_RX_P15")
	)
	(segment
		(start 258.605274 -39.903146)
		(end 254.866394 -39.903146)
		(width 0.1016)
		(layer "In2.Cu")
		(net "PCIE_RX_P15")
	)
	(segment
		(start 324.171564 -13.706602)
		(end 324.22211 -13.757148)
		(width 0.1397)
		(layer "In2.Cu")
		(net "PCIE_RX_P15")
	)
	(segment
		(start 327.92289 -18.703036)
		(end 329.369928 -25.511506)
		(width 0.1397)
		(layer "In2.Cu")
		(net "PCIE_RX_P15")
	)
	(segment
		(start 300.534578 -44.386754)
		(end 287.810194 -41.943274)
		(width 0.1397)
		(layer "In2.Cu")
		(net "PCIE_RX_P15")
	)
	(segment
		(start 259.088128 -40.386)
		(end 258.605274 -39.903146)
		(width 0.1016)
		(layer "In2.Cu")
		(net "PCIE_RX_P15")
	)
	(segment
		(start 269.914878 -43.062652)
		(end 261.822692 -40.386)
		(width 0.1397)
		(layer "In2.Cu")
		(net "PCIE_RX_P15")
	)
	(segment
		(start 323.634354 -13.930122)
		(end 323.679566 -13.821156)
		(width 0.1397)
		(layer "In2.Cu")
		(net "PCIE_RX_P15")
	)
	(segment
		(start 327.920604 -18.703036)
		(end 327.92289 -18.703036)
		(width 0.1397)
		(layer "In2.Cu")
		(net "PCIE_RX_P15")
	)
	(segment
		(start 259.2578 -40.386)
		(end 259.088128 -40.386)
		(width 0.1016)
		(layer "In2.Cu")
		(net "PCIE_RX_P15")
	)
	(segment
		(start 330.049378 -36.007548)
		(end 325.229982 -39.137844)
		(width 0.1397)
		(layer "In2.Cu")
		(net "PCIE_RX_P15")
	)
	(arc
		(start 324.22211 -13.757148)
		(mid 324.284871 -13.851076)
		(end 324.306946 -13.961872)
		(width 0.1397)
		(layer "In2.Cu")
		(net "PCIE_RX_P15")
	)
	(arc
		(start 323.786246 -13.691108)
		(mid 323.840552 -13.654822)
		(end 323.90461 -13.642086)
		(width 0.1397)
		(layer "In2.Cu")
		(net "PCIE_RX_P15")
	)
	(arc
		(start 323.679566 -13.821156)
		(mid 323.723265 -13.748222)
		(end 323.786246 -13.691108)
		(width 0.1397)
		(layer "In2.Cu")
		(net "PCIE_RX_P15")
	)
	(arc
		(start 324.015862 -13.642086)
		(mid 324.100136 -13.658849)
		(end 324.171564 -13.706602)
		(width 0.1397)
		(layer "In2.Cu")
		(net "PCIE_RX_P15")
	)
	(arc
		(start 254.866394 -39.903146)
		(mid 254.709705 -39.934313)
		(end 254.576834 -40.023034)
		(width 0.1016)
		(layer "In2.Cu")
		(net "PCIE_RX_P15")
	)
	(arc
		(start 324.306946 -13.961872)
		(mid 324.3071 -13.966062)
		(end 324.3072 -13.970254)
		(width 0.1397)
		(layer "In2.Cu")
		(net "PCIE_RX_P15")
	)
	(segment
		(start 254.599948 -39.99992)
		(end 255.09982 -39.500048)
		(width 0.136652)
		(layer "F.Cu")
		(net "PCIE_RX_P14")
	)
	(via
		(at 255.09982 -39.500048)
		(size 0.4572)
		(drill 0.2032)
		(layers "F.Cu" "B.Cu")
		(net "PCIE_RX_P14")
	)
	(segment
		(start 287.39465 -40.749982)
		(end 282.737306 -41.6814)
		(width 0.1397)
		(layer "In2.Cu")
		(net "PCIE_RX_P14")
	)
	(segment
		(start 276.369272 -40.407844)
		(end 270.039846 -41.67378)
		(width 0.1397)
		(layer "In2.Cu")
		(net "PCIE_RX_P14")
	)
	(segment
		(start 320.571114 -38.361112)
		(end 318.91351 -39.43731)
		(width 0.1397)
		(layer "In2.Cu")
		(net "PCIE_RX_P14")
	)
	(segment
		(start 255.567434 -39.032434)
		(end 255.09982 -39.500048)
		(width 0.1016)
		(layer "In2.Cu")
		(net "PCIE_RX_P14")
	)
	(segment
		(start 321.202812 -37.413692)
		(end 320.571114 -38.361112)
		(width 0.1397)
		(layer "In2.Cu")
		(net "PCIE_RX_P14")
	)
	(segment
		(start 324.461886 -18.680684)
		(end 324.461886 -18.680938)
		(width 0.1397)
		(layer "In2.Cu")
		(net "PCIE_RX_P14")
	)
	(segment
		(start 318.91351 -39.43731)
		(end 299.432218 -42.87266)
		(width 0.1397)
		(layer "In2.Cu")
		(net "PCIE_RX_P14")
	)
	(segment
		(start 261.885176 -39.205154)
		(end 260.0198 -39.205154)
		(width 0.1397)
		(layer "In2.Cu")
		(net "PCIE_RX_P14")
	)
	(segment
		(start 322.955666 -30.850586)
		(end 322.424044 -31.668974)
		(width 0.1397)
		(layer "In2.Cu")
		(net "PCIE_RX_P14")
	)
	(segment
		(start 327.411588 -20.931378)
		(end 328.191114 -24.600154)
		(width 0.1397)
		(layer "In2.Cu")
		(net "PCIE_RX_P14")
	)
	(segment
		(start 324.3072 -18.45945)
		(end 324.461886 -18.680684)
		(width 0.1397)
		(layer "In2.Cu")
		(net "PCIE_RX_P14")
	)
	(segment
		(start 324.46214 -18.680938)
		(end 324.588378 -18.861278)
		(width 0.1397)
		(layer "In2.Cu")
		(net "PCIE_RX_P14")
	)
	(segment
		(start 324.461886 -18.680938)
		(end 324.46214 -18.680938)
		(width 0.1397)
		(layer "In2.Cu")
		(net "PCIE_RX_P14")
	)
	(segment
		(start 328.191114 -24.600154)
		(end 327.278238 -28.990036)
		(width 0.1397)
		(layer "In2.Cu")
		(net "PCIE_RX_P14")
	)
	(segment
		(start 327.278238 -28.990036)
		(end 326.85863 -29.634688)
		(width 0.1397)
		(layer "In2.Cu")
		(net "PCIE_RX_P14")
	)
	(segment
		(start 299.432218 -42.87266)
		(end 287.39465 -40.749982)
		(width 0.1397)
		(layer "In2.Cu")
		(net "PCIE_RX_P14")
	)
	(segment
		(start 325.975218 -30.208982)
		(end 322.955666 -30.850586)
		(width 0.1397)
		(layer "In2.Cu")
		(net "PCIE_RX_P14")
	)
	(segment
		(start 322.424044 -31.668974)
		(end 321.202812 -37.413692)
		(width 0.1397)
		(layer "In2.Cu")
		(net "PCIE_RX_P14")
	)
	(segment
		(start 326.85863 -29.634688)
		(end 325.975218 -30.208982)
		(width 0.1397)
		(layer "In2.Cu")
		(net "PCIE_RX_P14")
	)
	(segment
		(start 324.588378 -18.861278)
		(end 327.411588 -20.931378)
		(width 0.1397)
		(layer "In2.Cu")
		(net "PCIE_RX_P14")
	)
	(segment
		(start 323.634354 -17.729962)
		(end 323.679566 -17.620996)
		(width 0.1397)
		(layer "In2.Cu")
		(net "PCIE_RX_P14")
	)
	(segment
		(start 270.039846 -41.67378)
		(end 261.885176 -39.205154)
		(width 0.1397)
		(layer "In2.Cu")
		(net "PCIE_RX_P14")
	)
	(segment
		(start 259.761482 -39.205154)
		(end 259.450078 -38.89375)
		(width 0.1016)
		(layer "In2.Cu")
		(net "PCIE_RX_P14")
	)
	(segment
		(start 324.171564 -17.506442)
		(end 324.22211 -17.556988)
		(width 0.1397)
		(layer "In2.Cu")
		(net "PCIE_RX_P14")
	)
	(segment
		(start 260.0198 -39.205154)
		(end 259.761482 -39.205154)
		(width 0.1016)
		(layer "In2.Cu")
		(net "PCIE_RX_P14")
	)
	(segment
		(start 323.90461 -17.441926)
		(end 324.015862 -17.441926)
		(width 0.1397)
		(layer "In2.Cu")
		(net "PCIE_RX_P14")
	)
	(segment
		(start 259.450078 -38.89375)
		(end 255.902206 -38.89375)
		(width 0.1016)
		(layer "In2.Cu")
		(net "PCIE_RX_P14")
	)
	(segment
		(start 282.737306 -41.6814)
		(end 276.369272 -40.407844)
		(width 0.1397)
		(layer "In2.Cu")
		(net "PCIE_RX_P14")
	)
	(segment
		(start 324.3072 -17.769586)
		(end 324.3072 -18.45945)
		(width 0.1397)
		(layer "In2.Cu")
		(net "PCIE_RX_P14")
	)
	(arc
		(start 323.679566 -17.620996)
		(mid 323.723265 -17.548062)
		(end 323.786246 -17.490948)
		(width 0.1397)
		(layer "In2.Cu")
		(net "PCIE_RX_P14")
	)
	(arc
		(start 324.22211 -17.556988)
		(mid 324.284871 -17.650916)
		(end 324.306946 -17.761712)
		(width 0.1397)
		(layer "In2.Cu")
		(net "PCIE_RX_P14")
	)
	(arc
		(start 255.902206 -38.89375)
		(mid 255.721022 -38.92979)
		(end 255.567434 -39.032434)
		(width 0.1016)
		(layer "In2.Cu")
		(net "PCIE_RX_P14")
	)
	(arc
		(start 324.306946 -17.769078)
		(mid 324.307073 -17.769332)
		(end 324.3072 -17.769586)
		(width 0.1397)
		(layer "In2.Cu")
		(net "PCIE_RX_P14")
	)
	(arc
		(start 323.786246 -17.490948)
		(mid 323.840552 -17.454662)
		(end 323.90461 -17.441926)
		(width 0.1397)
		(layer "In2.Cu")
		(net "PCIE_RX_P14")
	)
	(arc
		(start 324.074536 -17.4498)
		(mid 324.126718 -17.471836)
		(end 324.171564 -17.506442)
		(width 0.1397)
		(layer "In2.Cu")
		(net "PCIE_RX_P14")
	)
	(arc
		(start 324.015862 -17.441926)
		(mid 324.045463 -17.44389)
		(end 324.074536 -17.4498)
		(width 0.1397)
		(layer "In2.Cu")
		(net "PCIE_RX_P14")
	)
	(arc
		(start 324.306946 -17.761712)
		(mid 324.306969 -17.765395)
		(end 324.306946 -17.769078)
		(width 0.1397)
		(layer "In2.Cu")
		(net "PCIE_RX_P14")
	)
	(segment
		(start 253.59995 -38.999922)
		(end 254.099822 -38.50005)
		(width 0.136652)
		(layer "F.Cu")
		(net "PCIE_RX_P13")
	)
	(via
		(at 254.099822 -38.50005)
		(size 0.4572)
		(drill 0.2032)
		(layers "F.Cu" "B.Cu")
		(net "PCIE_RX_P13")
	)
	(segment
		(start 317.855854 -28.184602)
		(end 317.855854 -29.404818)
		(width 0.1397)
		(layer "In2.Cu")
		(net "PCIE_RX_P13")
	)
	(segment
		(start 276.996906 -39.1668)
		(end 270.667734 -40.432482)
		(width 0.1397)
		(layer "In2.Cu")
		(net "PCIE_RX_P13")
	)
	(segment
		(start 270.667734 -40.432482)
		(end 262.82269 -37.837872)
		(width 0.1397)
		(layer "In2.Cu")
		(net "PCIE_RX_P13")
	)
	(segment
		(start 310.062118 -37.724842)
		(end 309.922672 -37.7317)
		(width 0.1397)
		(layer "In2.Cu")
		(net "PCIE_RX_P13")
	)
	(segment
		(start 318.025272 -30.251654)
		(end 318.030098 -30.27553)
		(width 0.1397)
		(layer "In2.Cu")
		(net "PCIE_RX_P13")
	)
	(segment
		(start 301.70501 -40.919146)
		(end 297.867832 -41.73474)
		(width 0.1397)
		(layer "In2.Cu")
		(net "PCIE_RX_P13")
	)
	(segment
		(start 321.393312 -18.633948)
		(end 319.331848 -18.633948)
		(width 0.1397)
		(layer "In2.Cu")
		(net "PCIE_RX_P13")
	)
	(segment
		(start 314.676282 -38.288722)
		(end 313.722004 -38.491414)
		(width 0.1397)
		(layer "In2.Cu")
		(net "PCIE_RX_P13")
	)
	(segment
		(start 309.919624 -37.73043)
		(end 305.448716 -38.5191)
		(width 0.1397)
		(layer "In2.Cu")
		(net "PCIE_RX_P13")
	)
	(segment
		(start 318.030098 -30.27553)
		(end 317.864236 -31.216092)
		(width 0.1397)
		(layer "In2.Cu")
		(net "PCIE_RX_P13")
	)
	(segment
		(start 317.942976 -29.840174)
		(end 318.023748 -30.244288)
		(width 0.1397)
		(layer "In2.Cu")
		(net "PCIE_RX_P13")
	)
	(segment
		(start 317.080138 -33.263332)
		(end 317.405766 -34.794952)
		(width 0.1397)
		(layer "In2.Cu")
		(net "PCIE_RX_P13")
	)
	(segment
		(start 317.6016 -24.33193)
		(end 318.114172 -26.894028)
		(width 0.1397)
		(layer "In2.Cu")
		(net "PCIE_RX_P13")
	)
	(segment
		(start 309.921148 -37.7317)
		(end 309.919878 -37.73043)
		(width 0.1397)
		(layer "In2.Cu")
		(net "PCIE_RX_P13")
	)
	(segment
		(start 316.049152 -37.397182)
		(end 314.676282 -38.288722)
		(width 0.1397)
		(layer "In2.Cu")
		(net "PCIE_RX_P13")
	)
	(segment
		(start 310.113172 -37.724588)
		(end 310.07304 -37.724588)
		(width 0.1397)
		(layer "In2.Cu")
		(net "PCIE_RX_P13")
	)
	(segment
		(start 317.864236 -31.216092)
		(end 317.29807 -32.024574)
		(width 0.1397)
		(layer "In2.Cu")
		(net "PCIE_RX_P13")
	)
	(segment
		(start 322.086732 -17.690592)
		(end 322.086732 -17.940528)
		(width 0.1397)
		(layer "In2.Cu")
		(net "PCIE_RX_P13")
	)
	(segment
		(start 262.82269 -37.837872)
		(end 259.588 -37.837872)
		(width 0.1397)
		(layer "In2.Cu")
		(net "PCIE_RX_P13")
	)
	(segment
		(start 322.052188 -17.499584)
		(end 322.051934 -17.499584)
		(width 0.1397)
		(layer "In2.Cu")
		(net "PCIE_RX_P13")
	)
	(segment
		(start 318.023748 -30.244288)
		(end 318.025272 -30.251654)
		(width 0.1397)
		(layer "In2.Cu")
		(net "PCIE_RX_P13")
	)
	(segment
		(start 322.012564 -17.397984)
		(end 322.012564 -17.398238)
		(width 0.1397)
		(layer "In2.Cu")
		(net "PCIE_RX_P13")
	)
	(segment
		(start 259.3594 -37.8968)
		(end 254.914146 -37.8968)
		(width 0.1016)
		(layer "In2.Cu")
		(net "PCIE_RX_P13")
	)
	(segment
		(start 259.418328 -37.837872)
		(end 259.3594 -37.8968)
		(width 0.1016)
		(layer "In2.Cu")
		(net "PCIE_RX_P13")
	)
	(segment
		(start 305.374548 -38.5191)
		(end 305.326034 -38.567614)
		(width 0.1397)
		(layer "In2.Cu")
		(net "PCIE_RX_P13")
	)
	(segment
		(start 317.6016 -20.364196)
		(end 317.6016 -24.33193)
		(width 0.1397)
		(layer "In2.Cu")
		(net "PCIE_RX_P13")
	)
	(segment
		(start 297.867832 -41.73474)
		(end 287.482534 -39.609522)
		(width 0.1397)
		(layer "In2.Cu")
		(net "PCIE_RX_P13")
	)
	(segment
		(start 287.482534 -39.609522)
		(end 283.346906 -40.4368)
		(width 0.1397)
		(layer "In2.Cu")
		(net "PCIE_RX_P13")
	)
	(segment
		(start 254.333248 -38.50005)
		(end 254.099822 -38.50005)
		(width 0.1016)
		(layer "In2.Cu")
		(net "PCIE_RX_P13")
	)
	(segment
		(start 317.243714 -35.557714)
		(end 316.049152 -37.397182)
		(width 0.1397)
		(layer "In2.Cu")
		(net "PCIE_RX_P13")
	)
	(segment
		(start 309.919878 -37.73043)
		(end 309.919624 -37.73043)
		(width 0.1397)
		(layer "In2.Cu")
		(net "PCIE_RX_P13")
	)
	(segment
		(start 313.722004 -38.491414)
		(end 310.113172 -37.724588)
		(width 0.1397)
		(layer "In2.Cu")
		(net "PCIE_RX_P13")
	)
	(segment
		(start 317.405766 -34.794952)
		(end 317.32474 -35.17646)
		(width 0.1397)
		(layer "In2.Cu")
		(net "PCIE_RX_P13")
	)
	(segment
		(start 321.55892 -17.191736)
		(end 321.559428 -17.191482)
		(width 0.1397)
		(layer "In2.Cu")
		(net "PCIE_RX_P13")
	)
	(segment
		(start 310.07304 -37.724588)
		(end 310.062118 -37.724842)
		(width 0.1397)
		(layer "In2.Cu")
		(net "PCIE_RX_P13")
	)
	(segment
		(start 321.384422 -17.729962)
		(end 321.352672 -17.644872)
		(width 0.1397)
		(layer "In2.Cu")
		(net "PCIE_RX_P13")
	)
	(segment
		(start 305.448716 -38.5191)
		(end 305.374548 -38.5191)
		(width 0.1397)
		(layer "In2.Cu")
		(net "PCIE_RX_P13")
	)
	(segment
		(start 317.29807 -32.024574)
		(end 317.080138 -33.263332)
		(width 0.1397)
		(layer "In2.Cu")
		(net "PCIE_RX_P13")
	)
	(segment
		(start 317.855854 -29.404818)
		(end 317.942976 -29.840174)
		(width 0.1397)
		(layer "In2.Cu")
		(net "PCIE_RX_P13")
	)
	(segment
		(start 318.114172 -26.894028)
		(end 317.855854 -28.184602)
		(width 0.1397)
		(layer "In2.Cu")
		(net "PCIE_RX_P13")
	)
	(segment
		(start 283.346906 -40.4368)
		(end 276.996906 -39.1668)
		(width 0.1397)
		(layer "In2.Cu")
		(net "PCIE_RX_P13")
	)
	(segment
		(start 317.32474 -35.17646)
		(end 317.243714 -35.557714)
		(width 0.1397)
		(layer "In2.Cu")
		(net "PCIE_RX_P13")
	)
	(segment
		(start 305.326034 -38.567614)
		(end 301.70501 -40.919146)
		(width 0.1397)
		(layer "In2.Cu")
		(net "PCIE_RX_P13")
	)
	(segment
		(start 259.588 -37.837872)
		(end 259.418328 -37.837872)
		(width 0.1016)
		(layer "In2.Cu")
		(net "PCIE_RX_P13")
	)
	(segment
		(start 309.922672 -37.7317)
		(end 309.921148 -37.7317)
		(width 0.1397)
		(layer "In2.Cu")
		(net "PCIE_RX_P13")
	)
	(arc
		(start 322.051934 -17.499584)
		(mid 322.077942 -17.593518)
		(end 322.086732 -17.690592)
		(width 0.1397)
		(layer "In2.Cu")
		(net "PCIE_RX_P13")
	)
	(arc
		(start 322.012564 -17.398238)
		(mid 322.0294 -17.442301)
		(end 322.046854 -17.486122)
		(width 0.1397)
		(layer "In2.Cu")
		(net "PCIE_RX_P13")
	)
	(arc
		(start 254.556768 -38.254178)
		(mid 254.492528 -38.42029)
		(end 254.333248 -38.50005)
		(width 0.1016)
		(layer "In2.Cu")
		(net "PCIE_RX_P13")
	)
	(arc
		(start 319.331848 -18.633948)
		(mid 318.108378 -19.140726)
		(end 317.6016 -20.364196)
		(width 0.1397)
		(layer "In2.Cu")
		(net "PCIE_RX_P13")
	)
	(arc
		(start 321.352672 -17.644872)
		(mid 321.361948 -17.375589)
		(end 321.55892 -17.191736)
		(width 0.1397)
		(layer "In2.Cu")
		(net "PCIE_RX_P13")
	)
	(arc
		(start 321.559428 -17.191482)
		(mid 321.82882 -17.200808)
		(end 322.012564 -17.397984)
		(width 0.1397)
		(layer "In2.Cu")
		(net "PCIE_RX_P13")
	)
	(arc
		(start 254.914146 -37.8968)
		(mid 254.661442 -38.001474)
		(end 254.556768 -38.254178)
		(width 0.1016)
		(layer "In2.Cu")
		(net "PCIE_RX_P13")
	)
	(arc
		(start 322.086732 -17.940528)
		(mid 321.883634 -18.43085)
		(end 321.393312 -18.633948)
		(width 0.1397)
		(layer "In2.Cu")
		(net "PCIE_RX_P13")
	)
	(arc
		(start 322.046854 -17.486122)
		(mid 322.049566 -17.492835)
		(end 322.052188 -17.499584)
		(width 0.1397)
		(layer "In2.Cu")
		(net "PCIE_RX_P13")
	)
	(segment
		(start 254.599948 -37.999924)
		(end 255.09982 -37.500052)
		(width 0.136652)
		(layer "F.Cu")
		(net "PCIE_RX_P12")
	)
	(via
		(at 255.09982 -37.500052)
		(size 0.4572)
		(drill 0.2032)
		(layers "F.Cu" "B.Cu")
		(net "PCIE_RX_P12")
	)
	(segment
		(start 259.493512 -36.830254)
		(end 259.423662 -36.900104)
		(width 0.1016)
		(layer "In2.Cu")
		(net "PCIE_RX_P12")
	)
	(segment
		(start 316.615572 -27.17927)
		(end 316.615572 -27.179524)
		(width 0.1397)
		(layer "In2.Cu")
		(net "PCIE_RX_P12")
	)
	(segment
		(start 306.409852 -36.521898)
		(end 301.052738 -40.11676)
		(width 0.1397)
		(layer "In2.Cu")
		(net "PCIE_RX_P12")
	)
	(segment
		(start 311.355232 -31.366968)
		(end 309.559452 -31.74873)
		(width 0.1397)
		(layer "In2.Cu")
		(net "PCIE_RX_P12")
	)
	(segment
		(start 316.220348 -23.784306)
		(end 316.717172 -26.603706)
		(width 0.1397)
		(layer "In2.Cu")
		(net "PCIE_RX_P12")
	)
	(segment
		(start 316.514226 -27.75458)
		(end 311.355232 -31.366968)
		(width 0.1397)
		(layer "In2.Cu")
		(net "PCIE_RX_P12")
	)
	(segment
		(start 283.778706 -39.3192)
		(end 277.428706 -38.0492)
		(width 0.1397)
		(layer "In2.Cu")
		(net "PCIE_RX_P12")
	)
	(segment
		(start 259.423662 -36.900104)
		(end 255.849628 -36.900104)
		(width 0.1016)
		(layer "In2.Cu")
		(net "PCIE_RX_P12")
	)
	(segment
		(start 316.220348 -18.059908)
		(end 316.220348 -23.784306)
		(width 0.1397)
		(layer "In2.Cu")
		(net "PCIE_RX_P12")
	)
	(segment
		(start 322.057014 -13.816076)
		(end 322.057268 -13.815822)
		(width 0.1397)
		(layer "In2.Cu")
		(net "PCIE_RX_P12")
	)
	(segment
		(start 295.524174 -40.186102)
		(end 295.524174 -40.185848)
		(width 0.1397)
		(layer "In2.Cu")
		(net "PCIE_RX_P12")
	)
	(segment
		(start 262.91413 -36.830254)
		(end 259.6642 -36.830254)
		(width 0.1397)
		(layer "In2.Cu")
		(net "PCIE_RX_P12")
	)
	(segment
		(start 292.871398 -39.64432)
		(end 287.565592 -38.561518)
		(width 0.1397)
		(layer "In2.Cu")
		(net "PCIE_RX_P12")
	)
	(segment
		(start 292.871398 -39.644574)
		(end 292.871398 -39.64432)
		(width 0.1397)
		(layer "In2.Cu")
		(net "PCIE_RX_P12")
	)
	(segment
		(start 322.057268 -13.815822)
		(end 322.057268 -14.1732)
		(width 0.1397)
		(layer "In2.Cu")
		(net "PCIE_RX_P12")
	)
	(segment
		(start 301.052738 -40.11676)
		(end 298.177712 -40.727884)
		(width 0.1397)
		(layer "In2.Cu")
		(net "PCIE_RX_P12")
	)
	(segment
		(start 295.524174 -40.185848)
		(end 292.871398 -39.644574)
		(width 0.1397)
		(layer "In2.Cu")
		(net "PCIE_RX_P12")
	)
	(segment
		(start 316.717172 -26.603706)
		(end 316.615572 -27.17927)
		(width 0.1397)
		(layer "In2.Cu")
		(net "PCIE_RX_P12")
	)
	(segment
		(start 321.968368 -13.521944)
		(end 322.014596 -13.626592)
		(width 0.1397)
		(layer "In2.Cu")
		(net "PCIE_RX_P12")
	)
	(segment
		(start 259.6642 -36.830254)
		(end 259.493512 -36.830254)
		(width 0.1016)
		(layer "In2.Cu")
		(net "PCIE_RX_P12")
	)
	(segment
		(start 277.428706 -38.0492)
		(end 271.095724 -39.315644)
		(width 0.1397)
		(layer "In2.Cu")
		(net "PCIE_RX_P12")
	)
	(segment
		(start 316.422278 -16.914622)
		(end 316.220348 -18.059908)
		(width 0.1397)
		(layer "In2.Cu")
		(net "PCIE_RX_P12")
	)
	(segment
		(start 271.095724 -39.315644)
		(end 262.91413 -36.830254)
		(width 0.1397)
		(layer "In2.Cu")
		(net "PCIE_RX_P12")
	)
	(segment
		(start 309.559452 -31.74873)
		(end 306.409852 -36.521898)
		(width 0.1397)
		(layer "In2.Cu")
		(net "PCIE_RX_P12")
	)
	(segment
		(start 317.379858 -15.546832)
		(end 316.422278 -16.914622)
		(width 0.1397)
		(layer "In2.Cu")
		(net "PCIE_RX_P12")
	)
	(segment
		(start 321.384422 -13.930122)
		(end 321.328796 -13.804138)
		(width 0.1397)
		(layer "In2.Cu")
		(net "PCIE_RX_P12")
	)
	(segment
		(start 321.600068 -14.6304)
		(end 319.29451 -14.6304)
		(width 0.1397)
		(layer "In2.Cu")
		(net "PCIE_RX_P12")
	)
	(segment
		(start 316.615572 -27.179524)
		(end 316.514226 -27.75458)
		(width 0.1397)
		(layer "In2.Cu")
		(net "PCIE_RX_P12")
	)
	(segment
		(start 298.177712 -40.727884)
		(end 295.524174 -40.186102)
		(width 0.1397)
		(layer "In2.Cu")
		(net "PCIE_RX_P12")
	)
	(segment
		(start 319.29451 -14.6304)
		(end 317.379858 -15.546832)
		(width 0.1397)
		(layer "In2.Cu")
		(net "PCIE_RX_P12")
	)
	(segment
		(start 287.565592 -38.561518)
		(end 283.778706 -39.3192)
		(width 0.1397)
		(layer "In2.Cu")
		(net "PCIE_RX_P12")
	)
	(arc
		(start 322.057268 -14.1732)
		(mid 321.923357 -14.496489)
		(end 321.600068 -14.6304)
		(width 0.1397)
		(layer "In2.Cu")
		(net "PCIE_RX_P12")
	)
	(arc
		(start 322.014596 -13.626592)
		(mid 322.046311 -13.718985)
		(end 322.057014 -13.816076)
		(width 0.1397)
		(layer "In2.Cu")
		(net "PCIE_RX_P12")
	)
	(arc
		(start 255.849628 -36.900104)
		(mid 255.583453 -37.010357)
		(end 255.4732 -37.276532)
		(width 0.1016)
		(layer "In2.Cu")
		(net "PCIE_RX_P12")
	)
	(arc
		(start 321.328796 -13.804138)
		(mid 321.507506 -13.343429)
		(end 321.968368 -13.521944)
		(width 0.1397)
		(layer "In2.Cu")
		(net "PCIE_RX_P12")
	)
	(arc
		(start 255.4732 -37.276532)
		(mid 255.349872 -37.494053)
		(end 255.09982 -37.500052)
		(width 0.1016)
		(layer "In2.Cu")
		(net "PCIE_RX_P12")
	)
	(segment
		(start 253.59995 -36.999926)
		(end 254.099822 -36.500054)
		(width 0.136652)
		(layer "F.Cu")
		(net "PCIE_RX_P11")
	)
	(via
		(at 254.099822 -36.500054)
		(size 0.4572)
		(drill 0.2032)
		(layers "F.Cu" "B.Cu")
		(net "PCIE_RX_P11")
	)
	(segment
		(start 312.904632 -13.642086)
		(end 313.015884 -13.642086)
		(width 0.1397)
		(layer "In2.Cu")
		(net "PCIE_RX_P11")
	)
	(segment
		(start 309.981092 -30.41015)
		(end 301.151544 -31.966916)
		(width 0.1397)
		(layer "In2.Cu")
		(net "PCIE_RX_P11")
	)
	(segment
		(start 290.037266 -31.450026)
		(end 289.83305 -31.414466)
		(width 0.1397)
		(layer "In2.Cu")
		(net "PCIE_RX_P11")
	)
	(segment
		(start 279.380442 -33.98901)
		(end 266.689078 -36.527486)
		(width 0.1397)
		(layer "In2.Cu")
		(net "PCIE_RX_P11")
	)
	(segment
		(start 289.83305 -31.414466)
		(end 289.351466 -31.330646)
		(width 0.1397)
		(layer "In2.Cu")
		(net "PCIE_RX_P11")
	)
	(segment
		(start 315.009784 -27.158188)
		(end 314.693554 -27.773884)
		(width 0.1397)
		(layer "In2.Cu")
		(net "PCIE_RX_P11")
	)
	(segment
		(start 263.520174 -35.570922)
		(end 259.821172 -35.570922)
		(width 0.1397)
		(layer "In2.Cu")
		(net "PCIE_RX_P11")
	)
	(segment
		(start 258.67868 -35.893756)
		(end 254.93345 -35.893756)
		(width 0.1016)
		(layer "In2.Cu")
		(net "PCIE_RX_P11")
	)
	(segment
		(start 313.624468 -28.522676)
		(end 312.357516 -28.745942)
		(width 0.1397)
		(layer "In2.Cu")
		(net "PCIE_RX_P11")
	)
	(segment
		(start 285.09341 -31.273242)
		(end 282.483052 -31.816802)
		(width 0.1397)
		(layer "In2.Cu")
		(net "PCIE_RX_P11")
	)
	(segment
		(start 291.531548 -31.710376)
		(end 290.946332 -31.608268)
		(width 0.1397)
		(layer "In2.Cu")
		(net "PCIE_RX_P11")
	)
	(segment
		(start 312.357516 -28.745942)
		(end 309.981092 -30.41015)
		(width 0.1397)
		(layer "In2.Cu")
		(net "PCIE_RX_P11")
	)
	(segment
		(start 254.545338 -36.054538)
		(end 254.099822 -36.500054)
		(width 0.1016)
		(layer "In2.Cu")
		(net "PCIE_RX_P11")
	)
	(segment
		(start 280.93162 -32.90316)
		(end 279.380442 -33.98901)
		(width 0.1397)
		(layer "In2.Cu")
		(net "PCIE_RX_P11")
	)
	(segment
		(start 259.465318 -35.926776)
		(end 258.7117 -35.926776)
		(width 0.1397)
		(layer "In2.Cu")
		(net "PCIE_RX_P11")
	)
	(segment
		(start 312.634376 -13.930122)
		(end 312.679588 -13.821156)
		(width 0.1397)
		(layer "In2.Cu")
		(net "PCIE_RX_P11")
	)
	(segment
		(start 313.171586 -13.706602)
		(end 313.222132 -13.757148)
		(width 0.1397)
		(layer "In2.Cu")
		(net "PCIE_RX_P11")
	)
	(segment
		(start 313.562746 -15.290546)
		(end 314.740036 -16.46809)
		(width 0.1397)
		(layer "In2.Cu")
		(net "PCIE_RX_P11")
	)
	(segment
		(start 290.946332 -31.608268)
		(end 290.068508 -31.455614)
		(width 0.1397)
		(layer "In2.Cu")
		(net "PCIE_RX_P11")
	)
	(segment
		(start 314.8838 -23.7998)
		(end 315.272166 -25.741376)
		(width 0.1397)
		(layer "In2.Cu")
		(net "PCIE_RX_P11")
	)
	(segment
		(start 289.351466 -31.330646)
		(end 289.134042 -31.2928)
		(width 0.1397)
		(layer "In2.Cu")
		(net "PCIE_RX_P11")
	)
	(segment
		(start 282.483052 -31.816802)
		(end 280.93162 -32.90316)
		(width 0.1397)
		(layer "In2.Cu")
		(net "PCIE_RX_P11")
	)
	(segment
		(start 315.272166 -25.741376)
		(end 315.009784 -27.158188)
		(width 0.1397)
		(layer "In2.Cu")
		(net "PCIE_RX_P11")
	)
	(segment
		(start 289.134042 -31.2928)
		(end 287.166812 -31.639256)
		(width 0.1397)
		(layer "In2.Cu")
		(net "PCIE_RX_P11")
	)
	(segment
		(start 314.8838 -16.8148)
		(end 314.8838 -23.7998)
		(width 0.1397)
		(layer "In2.Cu")
		(net "PCIE_RX_P11")
	)
	(segment
		(start 287.166812 -31.639256)
		(end 285.09341 -31.273242)
		(width 0.1397)
		(layer "In2.Cu")
		(net "PCIE_RX_P11")
	)
	(segment
		(start 290.068508 -31.455614)
		(end 290.037266 -31.450026)
		(width 0.1397)
		(layer "In2.Cu")
		(net "PCIE_RX_P11")
	)
	(segment
		(start 293.929308 -32.128206)
		(end 291.531548 -31.710376)
		(width 0.1397)
		(layer "In2.Cu")
		(net "PCIE_RX_P11")
	)
	(segment
		(start 301.151544 -31.966916)
		(end 297.99788 -31.41091)
		(width 0.1397)
		(layer "In2.Cu")
		(net "PCIE_RX_P11")
	)
	(segment
		(start 259.821172 -35.570922)
		(end 259.465318 -35.926776)
		(width 0.1397)
		(layer "In2.Cu")
		(net "PCIE_RX_P11")
	)
	(segment
		(start 297.99788 -31.41091)
		(end 293.929308 -32.128206)
		(width 0.1397)
		(layer "In2.Cu")
		(net "PCIE_RX_P11")
	)
	(segment
		(start 313.307222 -13.970254)
		(end 313.307222 -14.67358)
		(width 0.1397)
		(layer "In2.Cu")
		(net "PCIE_RX_P11")
	)
	(segment
		(start 258.7117 -35.926776)
		(end 258.67868 -35.893756)
		(width 0.1016)
		(layer "In2.Cu")
		(net "PCIE_RX_P11")
	)
	(segment
		(start 314.693554 -27.773884)
		(end 313.624468 -28.522676)
		(width 0.1397)
		(layer "In2.Cu")
		(net "PCIE_RX_P11")
	)
	(segment
		(start 266.689078 -36.527486)
		(end 263.520174 -35.570922)
		(width 0.1397)
		(layer "In2.Cu")
		(net "PCIE_RX_P11")
	)
	(arc
		(start 313.015884 -13.642086)
		(mid 313.100158 -13.658849)
		(end 313.171586 -13.706602)
		(width 0.1397)
		(layer "In2.Cu")
		(net "PCIE_RX_P11")
	)
	(arc
		(start 312.786268 -13.691108)
		(mid 312.840574 -13.654822)
		(end 312.904632 -13.642086)
		(width 0.1397)
		(layer "In2.Cu")
		(net "PCIE_RX_P11")
	)
	(arc
		(start 313.222132 -13.757148)
		(mid 313.284893 -13.851076)
		(end 313.306968 -13.961872)
		(width 0.1397)
		(layer "In2.Cu")
		(net "PCIE_RX_P11")
	)
	(arc
		(start 313.306968 -13.961872)
		(mid 313.307122 -13.966062)
		(end 313.307222 -13.970254)
		(width 0.1397)
		(layer "In2.Cu")
		(net "PCIE_RX_P11")
	)
	(arc
		(start 312.679588 -13.821156)
		(mid 312.723287 -13.748222)
		(end 312.786268 -13.691108)
		(width 0.1397)
		(layer "In2.Cu")
		(net "PCIE_RX_P11")
	)
	(arc
		(start 314.740036 -16.46809)
		(mid 314.846407 -16.627147)
		(end 314.8838 -16.8148)
		(width 0.1397)
		(layer "In2.Cu")
		(net "PCIE_RX_P11")
	)
	(arc
		(start 313.307222 -14.67358)
		(mid 313.373689 -15.007442)
		(end 313.562746 -15.290546)
		(width 0.1397)
		(layer "In2.Cu")
		(net "PCIE_RX_P11")
	)
	(arc
		(start 254.93345 -35.893756)
		(mid 254.723397 -35.935538)
		(end 254.545338 -36.054538)
		(width 0.1016)
		(layer "In2.Cu")
		(net "PCIE_RX_P11")
	)
	(segment
		(start 254.599948 -35.999928)
		(end 255.09982 -35.500056)
		(width 0.136652)
		(layer "F.Cu")
		(net "PCIE_RX_P10")
	)
	(via
		(at 255.09982 -35.500056)
		(size 0.4572)
		(drill 0.2032)
		(layers "F.Cu" "B.Cu")
		(net "PCIE_RX_P10")
	)
	(segment
		(start 287.328864 -30.823408)
		(end 284.4292 -30.3276)
		(width 0.1397)
		(layer "In2.Cu")
		(net "PCIE_RX_P10")
	)
	(segment
		(start 306.15382 -24.267414)
		(end 306.055014 -24.827992)
		(width 0.1397)
		(layer "In2.Cu")
		(net "PCIE_RX_P10")
	)
	(segment
		(start 278.08047 -33.120838)
		(end 267.222478 -35.03422)
		(width 0.1397)
		(layer "In2.Cu")
		(net "PCIE_RX_P10")
	)
	(segment
		(start 284.4292 -30.3276)
		(end 280.933652 -31.362142)
		(width 0.1397)
		(layer "In2.Cu")
		(net "PCIE_RX_P10")
	)
	(segment
		(start 313.24042 -17.608296)
		(end 313.275218 -17.692624)
		(width 0.1397)
		(layer "In2.Cu")
		(net "PCIE_RX_P10")
	)
	(segment
		(start 308.311042 -19.1008)
		(end 307.606446 -19.710908)
		(width 0.1397)
		(layer "In2.Cu")
		(net "PCIE_RX_P10")
	)
	(segment
		(start 302.134524 -30.724094)
		(end 298.3357 -30.054296)
		(width 0.1397)
		(layer "In2.Cu")
		(net "PCIE_RX_P10")
	)
	(segment
		(start 287.332166 -30.8229)
		(end 287.328864 -30.823408)
		(width 0.1397)
		(layer "In2.Cu")
		(net "PCIE_RX_P10")
	)
	(segment
		(start 312.634376 -17.729962)
		(end 312.78703 -17.577308)
		(width 0.1397)
		(layer "In2.Cu")
		(net "PCIE_RX_P10")
	)
	(segment
		(start 258.417314 -34.903156)
		(end 255.685798 -34.903156)
		(width 0.1016)
		(layer "In2.Cu")
		(net "PCIE_RX_P10")
	)
	(segment
		(start 307.04917 -21.609304)
		(end 307.102764 -21.914104)
		(width 0.1397)
		(layer "In2.Cu")
		(net "PCIE_RX_P10")
	)
	(segment
		(start 307.0098 -21.3868)
		(end 307.04917 -21.609304)
		(width 0.1397)
		(layer "In2.Cu")
		(net "PCIE_RX_P10")
	)
	(segment
		(start 306.055014 -24.827992)
		(end 306.466748 -27.163776)
		(width 0.1397)
		(layer "In2.Cu")
		(net "PCIE_RX_P10")
	)
	(segment
		(start 296.799254 -30.32506)
		(end 295.825672 -31.006796)
		(width 0.1397)
		(layer "In2.Cu")
		(net "PCIE_RX_P10")
	)
	(segment
		(start 307.102764 -21.914104)
		(end 306.867814 -23.247604)
		(width 0.1397)
		(layer "In2.Cu")
		(net "PCIE_RX_P10")
	)
	(segment
		(start 313.026298 -17.478248)
		(end 313.066176 -17.478248)
		(width 0.1397)
		(layer "In2.Cu")
		(net "PCIE_RX_P10")
	)
	(segment
		(start 307.606446 -19.710908)
		(end 307.203856 -20.28571)
		(width 0.1397)
		(layer "In2.Cu")
		(net "PCIE_RX_P10")
	)
	(segment
		(start 259.08 -34.3916)
		(end 258.675378 -34.796222)
		(width 0.1397)
		(layer "In2.Cu")
		(net "PCIE_RX_P10")
	)
	(segment
		(start 295.825418 -31.006796)
		(end 294.110918 -31.308802)
		(width 0.1397)
		(layer "In2.Cu")
		(net "PCIE_RX_P10")
	)
	(segment
		(start 255.274826 -35.07232)
		(end 255.27381 -35.073336)
		(width 0.1016)
		(layer "In2.Cu")
		(net "PCIE_RX_P10")
	)
	(segment
		(start 298.3357 -30.054296)
		(end 296.799254 -30.32506)
		(width 0.1397)
		(layer "In2.Cu")
		(net "PCIE_RX_P10")
	)
	(segment
		(start 312.532014 -19.1008)
		(end 308.311042 -19.1008)
		(width 0.1397)
		(layer "In2.Cu")
		(net "PCIE_RX_P10")
	)
	(segment
		(start 264.0076 -34.3916)
		(end 259.08 -34.3916)
		(width 0.1397)
		(layer "In2.Cu")
		(net "PCIE_RX_P10")
	)
	(segment
		(start 294.110918 -31.308802)
		(end 289.3441 -30.46857)
		(width 0.1397)
		(layer "In2.Cu")
		(net "PCIE_RX_P10")
	)
	(segment
		(start 305.467258 -29.62783)
		(end 304.49647 -30.307534)
		(width 0.1397)
		(layer "In2.Cu")
		(net "PCIE_RX_P10")
	)
	(segment
		(start 306.466748 -27.163776)
		(end 306.2224 -28.5496)
		(width 0.1397)
		(layer "In2.Cu")
		(net "PCIE_RX_P10")
	)
	(segment
		(start 307.203856 -20.28571)
		(end 307.0098 -21.3868)
		(width 0.1397)
		(layer "In2.Cu")
		(net "PCIE_RX_P10")
	)
	(segment
		(start 306.2224 -28.5496)
		(end 305.467258 -29.62783)
		(width 0.1397)
		(layer "In2.Cu")
		(net "PCIE_RX_P10")
	)
	(segment
		(start 267.222478 -35.03422)
		(end 264.0076 -34.3916)
		(width 0.1397)
		(layer "In2.Cu")
		(net "PCIE_RX_P10")
	)
	(segment
		(start 304.49647 -30.307534)
		(end 302.134524 -30.724094)
		(width 0.1397)
		(layer "In2.Cu")
		(net "PCIE_RX_P10")
	)
	(segment
		(start 280.933652 -31.362142)
		(end 278.08047 -33.120838)
		(width 0.1397)
		(layer "In2.Cu")
		(net "PCIE_RX_P10")
	)
	(segment
		(start 255.09982 -35.490658)
		(end 255.09982 -35.500056)
		(width 0.1016)
		(layer "In2.Cu")
		(net "PCIE_RX_P10")
	)
	(segment
		(start 313.307222 -17.853914)
		(end 313.307222 -18.407634)
		(width 0.1397)
		(layer "In2.Cu")
		(net "PCIE_RX_P10")
	)
	(segment
		(start 295.825672 -31.006796)
		(end 295.825418 -31.006796)
		(width 0.1397)
		(layer "In2.Cu")
		(net "PCIE_RX_P10")
	)
	(segment
		(start 289.3441 -30.46857)
		(end 287.332166 -30.8229)
		(width 0.1397)
		(layer "In2.Cu")
		(net "PCIE_RX_P10")
	)
	(segment
		(start 306.867814 -23.247604)
		(end 306.15382 -24.267414)
		(width 0.1397)
		(layer "In2.Cu")
		(net "PCIE_RX_P10")
	)
	(arc
		(start 313.275218 -17.692624)
		(mid 313.299145 -17.771697)
		(end 313.307222 -17.853914)
		(width 0.1397)
		(layer "In2.Cu")
		(net "PCIE_RX_P10")
	)
	(arc
		(start 313.202066 -17.546828)
		(mid 313.223782 -17.575976)
		(end 313.24042 -17.608296)
		(width 0.1397)
		(layer "In2.Cu")
		(net "PCIE_RX_P10")
	)
	(arc
		(start 312.78703 -17.577308)
		(mid 312.896807 -17.503957)
		(end 313.026298 -17.478248)
		(width 0.1397)
		(layer "In2.Cu")
		(net "PCIE_RX_P10")
	)
	(arc
		(start 313.121294 -18.856706)
		(mid 312.85093 -19.037357)
		(end 312.532014 -19.1008)
		(width 0.1397)
		(layer "In2.Cu")
		(net "PCIE_RX_P10")
	)
	(arc
		(start 255.27381 -35.073336)
		(mid 255.145065 -35.26459)
		(end 255.09982 -35.490658)
		(width 0.1016)
		(layer "In2.Cu")
		(net "PCIE_RX_P10")
	)
	(arc
		(start 313.066176 -17.478248)
		(mid 313.094271 -17.481005)
		(end 313.121294 -17.48917)
		(width 0.1397)
		(layer "In2.Cu")
		(net "PCIE_RX_P10")
	)
	(arc
		(start 258.675378 -34.796222)
		(mid 258.556991 -34.875389)
		(end 258.417314 -34.903156)
		(width 0.1016)
		(layer "In2.Cu")
		(net "PCIE_RX_P10")
	)
	(arc
		(start 255.685798 -34.903156)
		(mid 255.463591 -34.947107)
		(end 255.274826 -35.07232)
		(width 0.1016)
		(layer "In2.Cu")
		(net "PCIE_RX_P10")
	)
	(arc
		(start 313.121294 -17.48917)
		(mid 313.164991 -17.513364)
		(end 313.202066 -17.546828)
		(width 0.1397)
		(layer "In2.Cu")
		(net "PCIE_RX_P10")
	)
	(arc
		(start 313.307222 -18.407634)
		(mid 313.258901 -18.650652)
		(end 313.121294 -18.856706)
		(width 0.1397)
		(layer "In2.Cu")
		(net "PCIE_RX_P10")
	)
	(segment
		(start 243.59997 -31.999936)
		(end 244.099842 -31.500064)
		(width 0.136652)
		(layer "F.Cu")
		(net "PCIE_RX_P1")
	)
	(via
		(at 244.099842 -31.500064)
		(size 0.4572)
		(drill 0.2032)
		(layers "F.Cu" "B.Cu")
		(net "PCIE_RX_P1")
	)
	(segment
		(start 280.97861 -9.06653)
		(end 279.806908 -9.273032)
		(width 0.1397)
		(layer "In2.Cu")
		(net "PCIE_RX_P1")
	)
	(segment
		(start 288.526982 -17.00657)
		(end 286.700722 -15.180564)
		(width 0.1397)
		(layer "In2.Cu")
		(net "PCIE_RX_P1")
	)
	(segment
		(start 283.247846 -10.298176)
		(end 283.03728 -9.997186)
		(width 0.1397)
		(layer "In2.Cu")
		(net "PCIE_RX_P1")
	)
	(segment
		(start 256.466594 -16.280384)
		(end 252.810772 -16.894556)
		(width 0.1397)
		(layer "In2.Cu")
		(net "PCIE_RX_P1")
	)
	(segment
		(start 282.104592 -13.000228)
		(end 283.288486 -11.309604)
		(width 0.1397)
		(layer "In2.Cu")
		(net "PCIE_RX_P1")
	)
	(segment
		(start 252.810772 -16.894556)
		(end 244.4877 -25.217374)
		(width 0.1397)
		(layer "In2.Cu")
		(net "PCIE_RX_P1")
	)
	(segment
		(start 276.82952 -15.548356)
		(end 274.707858 -17.034002)
		(width 0.1397)
		(layer "In2.Cu")
		(net "PCIE_RX_P1")
	)
	(segment
		(start 265.996674 -16.9164)
		(end 262.821674 -16.2814)
		(width 0.1397)
		(layer "In2.Cu")
		(net "PCIE_RX_P1")
	)
	(segment
		(start 244.099842 -31.203138)
		(end 244.099842 -31.500064)
		(width 0.1016)
		(layer "In2.Cu")
		(net "PCIE_RX_P1")
	)
	(segment
		(start 284.361636 -14.767814)
		(end 283.845 -14.859)
		(width 0.1397)
		(layer "In2.Cu")
		(net "PCIE_RX_P1")
	)
	(segment
		(start 274.707858 -17.034002)
		(end 273.369024 -17.270222)
		(width 0.1397)
		(layer "In2.Cu")
		(net "PCIE_RX_P1")
	)
	(segment
		(start 273.369024 -17.270222)
		(end 268.798294 -16.356076)
		(width 0.1397)
		(layer "In2.Cu")
		(net "PCIE_RX_P1")
	)
	(segment
		(start 244.4877 -28.316936)
		(end 244.439948 -28.364688)
		(width 0.1016)
		(layer "In2.Cu")
		(net "PCIE_RX_P1")
	)
	(segment
		(start 262.821674 -16.2814)
		(end 259.646674 -16.9164)
		(width 0.1397)
		(layer "In2.Cu")
		(net "PCIE_RX_P1")
	)
	(segment
		(start 283.845 -14.859)
		(end 282.801822 -14.675104)
		(width 0.1397)
		(layer "In2.Cu")
		(net "PCIE_RX_P1")
	)
	(segment
		(start 279.109932 -9.760966)
		(end 278.362918 -10.828274)
		(width 0.1397)
		(layer "In2.Cu")
		(net "PCIE_RX_P1")
	)
	(segment
		(start 281.99715 -13.60932)
		(end 282.104592 -13.000228)
		(width 0.1397)
		(layer "In2.Cu")
		(net "PCIE_RX_P1")
	)
	(segment
		(start 268.798294 -16.356076)
		(end 265.996674 -16.9164)
		(width 0.1397)
		(layer "In2.Cu")
		(net "PCIE_RX_P1")
	)
	(segment
		(start 277.766526 -14.210538)
		(end 276.82952 -15.548356)
		(width 0.1397)
		(layer "In2.Cu")
		(net "PCIE_RX_P1")
	)
	(segment
		(start 281.953208 -9.238234)
		(end 280.97861 -9.06653)
		(width 0.1397)
		(layer "In2.Cu")
		(net "PCIE_RX_P1")
	)
	(segment
		(start 244.303042 -31.101538)
		(end 244.201442 -31.101538)
		(width 0.1016)
		(layer "In2.Cu")
		(net "PCIE_RX_P1")
	)
	(segment
		(start 244.36578 -29.757878)
		(end 244.466618 -29.858716)
		(width 0.1016)
		(layer "In2.Cu")
		(net "PCIE_RX_P1")
	)
	(segment
		(start 279.806908 -9.273032)
		(end 279.109932 -9.760966)
		(width 0.1397)
		(layer "In2.Cu")
		(net "PCIE_RX_P1")
	)
	(segment
		(start 259.646674 -16.9164)
		(end 256.466594 -16.280384)
		(width 0.1397)
		(layer "In2.Cu")
		(net "PCIE_RX_P1")
	)
	(segment
		(start 283.03728 -9.997186)
		(end 281.953208 -9.238234)
		(width 0.1397)
		(layer "In2.Cu")
		(net "PCIE_RX_P1")
	)
	(segment
		(start 278.362918 -10.828274)
		(end 277.766526 -14.210538)
		(width 0.1397)
		(layer "In2.Cu")
		(net "PCIE_RX_P1")
	)
	(segment
		(start 282.801822 -14.675104)
		(end 282.270962 -14.303248)
		(width 0.1397)
		(layer "In2.Cu")
		(net "PCIE_RX_P1")
	)
	(segment
		(start 244.439948 -28.364688)
		(end 244.439948 -28.890468)
		(width 0.1016)
		(layer "In2.Cu")
		(net "PCIE_RX_P1")
	)
	(segment
		(start 244.439948 -28.890468)
		(end 244.36578 -28.964636)
		(width 0.1016)
		(layer "In2.Cu")
		(net "PCIE_RX_P1")
	)
	(segment
		(start 283.35732 -10.919206)
		(end 283.247846 -10.298176)
		(width 0.1397)
		(layer "In2.Cu")
		(net "PCIE_RX_P1")
	)
	(segment
		(start 286.700722 -15.180564)
		(end 284.361636 -14.767814)
		(width 0.1397)
		(layer "In2.Cu")
		(net "PCIE_RX_P1")
	)
	(segment
		(start 244.4877 -25.217374)
		(end 244.4877 -28.316936)
		(width 0.1397)
		(layer "In2.Cu")
		(net "PCIE_RX_P1")
	)
	(segment
		(start 244.36578 -28.964636)
		(end 244.36578 -29.757878)
		(width 0.1016)
		(layer "In2.Cu")
		(net "PCIE_RX_P1")
	)
	(segment
		(start 282.068524 -14.014704)
		(end 281.99715 -13.60932)
		(width 0.1397)
		(layer "In2.Cu")
		(net "PCIE_RX_P1")
	)
	(segment
		(start 283.288486 -11.309604)
		(end 283.35732 -10.919206)
		(width 0.1397)
		(layer "In2.Cu")
		(net "PCIE_RX_P1")
	)
	(segment
		(start 282.270962 -14.303248)
		(end 282.068524 -14.014704)
		(width 0.1397)
		(layer "In2.Cu")
		(net "PCIE_RX_P1")
	)
	(segment
		(start 244.672358 -30.29204)
		(end 244.717316 -30.62859)
		(width 0.1016)
		(layer "In2.Cu")
		(net "PCIE_RX_P1")
	)
	(arc
		(start 244.466618 -29.858716)
		(mid 244.603422 -30.059272)
		(end 244.672358 -30.29204)
		(width 0.1016)
		(layer "In2.Cu")
		(net "PCIE_RX_P1")
	)
	(arc
		(start 244.201442 -31.101538)
		(mid 244.1296 -31.131296)
		(end 244.099842 -31.203138)
		(width 0.1016)
		(layer "In2.Cu")
		(net "PCIE_RX_P1")
	)
	(arc
		(start 244.717316 -30.62859)
		(mid 244.617443 -30.959049)
		(end 244.303042 -31.101538)
		(width 0.1016)
		(layer "In2.Cu")
		(net "PCIE_RX_P1")
	)
	(arc
		(start 288.384488 -17.729962)
		(mid 288.64857 -17.406275)
		(end 288.526982 -17.00657)
		(width 0.1397)
		(layer "In2.Cu")
		(net "PCIE_RX_P1")
	)
	(segment
		(start 242.599972 -30.999938)
		(end 243.099844 -30.500066)
		(width 0.136652)
		(layer "F.Cu")
		(net "PCIE_RX_P0")
	)
	(via
		(at 243.099844 -30.500066)
		(size 0.4572)
		(drill 0.2032)
		(layers "F.Cu" "B.Cu")
		(net "PCIE_RX_P0")
	)
	(segment
		(start 289.310572 -14.340332)
		(end 289.43046 -14.445488)
		(width 0.1397)
		(layer "In2.Cu")
		(net "PCIE_RX_P0")
	)
	(segment
		(start 279.917652 -7.036308)
		(end 279.857454 -7.078472)
		(width 0.1397)
		(layer "In2.Cu")
		(net "PCIE_RX_P0")
	)
	(segment
		(start 263.97712 -14.447774)
		(end 258.988306 -15.612872)
		(width 0.1397)
		(layer "In2.Cu")
		(net "PCIE_RX_P0")
	)
	(segment
		(start 289.08502 -14.11478)
		(end 289.310572 -14.340332)
		(width 0.1397)
		(layer "In2.Cu")
		(net "PCIE_RX_P0")
	)
	(segment
		(start 293.889176 -8.623554)
		(end 292.847776 -7.13613)
		(width 0.1397)
		(layer "In2.Cu")
		(net "PCIE_RX_P0")
	)
	(segment
		(start 268.34338 -12.501626)
		(end 265.404854 -13.019786)
		(width 0.1397)
		(layer "In2.Cu")
		(net "PCIE_RX_P0")
	)
	(segment
		(start 255.805686 -14.976348)
		(end 251.816362 -15.6464)
		(width 0.1397)
		(layer "In2.Cu")
		(net "PCIE_RX_P0")
	)
	(segment
		(start 279.857708 -7.078472)
		(end 278.90978 -7.742428)
		(width 0.1397)
		(layer "In2.Cu")
		(net "PCIE_RX_P0")
	)
	(segment
		(start 278.538178 -8.002778)
		(end 278.3586 -8.128254)
		(width 0.1397)
		(layer "In2.Cu")
		(net "PCIE_RX_P0")
	)
	(segment
		(start 276.239986 -8.501888)
		(end 274.427696 -8.182102)
		(width 0.1397)
		(layer "In2.Cu")
		(net "PCIE_RX_P0")
	)
	(segment
		(start 274.427696 -8.182102)
		(end 268.34338 -12.501626)
		(width 0.1397)
		(layer "In2.Cu")
		(net "PCIE_RX_P0")
	)
	(segment
		(start 258.988306 -15.612872)
		(end 255.805686 -14.976348)
		(width 0.1397)
		(layer "In2.Cu")
		(net "PCIE_RX_P0")
	)
	(segment
		(start 290.03371 -14.81582)
		(end 290.753038 -15.112746)
		(width 0.1397)
		(layer "In2.Cu")
		(net "PCIE_RX_P0")
	)
	(segment
		(start 290.753038 -15.112746)
		(end 291.333174 -15.112746)
		(width 0.1397)
		(layer "In2.Cu")
		(net "PCIE_RX_P0")
	)
	(segment
		(start 292.090602 -14.798802)
		(end 293.458392 -13.431266)
		(width 0.1397)
		(layer "In2.Cu")
		(net "PCIE_RX_P0")
	)
	(segment
		(start 291.06114 -5.884926)
		(end 288.75482 -5.478272)
		(width 0.1397)
		(layer "In2.Cu")
		(net "PCIE_RX_P0")
	)
	(segment
		(start 278.3586 -8.128254)
		(end 276.239986 -8.501888)
		(width 0.1397)
		(layer "In2.Cu")
		(net "PCIE_RX_P0")
	)
	(segment
		(start 292.847776 -7.13613)
		(end 291.06114 -5.884926)
		(width 0.1397)
		(layer "In2.Cu")
		(net "PCIE_RX_P0")
	)
	(segment
		(start 293.458392 -13.431266)
		(end 293.889176 -12.391136)
		(width 0.1397)
		(layer "In2.Cu")
		(net "PCIE_RX_P0")
	)
	(segment
		(start 242.9764 -24.486362)
		(end 242.9764 -26.654506)
		(width 0.1397)
		(layer "In2.Cu")
		(net "PCIE_RX_P0")
	)
	(segment
		(start 243.40185 -27.079956)
		(end 243.40185 -27.726386)
		(width 0.1397)
		(layer "In2.Cu")
		(net "PCIE_RX_P0")
	)
	(segment
		(start 251.816362 -15.6464)
		(end 242.9764 -24.486362)
		(width 0.1397)
		(layer "In2.Cu")
		(net "PCIE_RX_P0")
	)
	(segment
		(start 288.384488 -13.930122)
		(end 288.63925 -13.930122)
		(width 0.1397)
		(layer "In2.Cu")
		(net "PCIE_RX_P0")
	)
	(segment
		(start 279.857454 -7.078472)
		(end 279.857708 -7.078472)
		(width 0.1397)
		(layer "In2.Cu")
		(net "PCIE_RX_P0")
	)
	(segment
		(start 289.43046 -14.445488)
		(end 290.028376 -14.812264)
		(width 0.1397)
		(layer "In2.Cu")
		(net "PCIE_RX_P0")
	)
	(segment
		(start 290.028376 -14.812264)
		(end 290.03371 -14.81582)
		(width 0.1397)
		(layer "In2.Cu")
		(net "PCIE_RX_P0")
	)
	(segment
		(start 242.9764 -26.654506)
		(end 243.40185 -27.079956)
		(width 0.1397)
		(layer "In2.Cu")
		(net "PCIE_RX_P0")
	)
	(segment
		(start 293.889176 -12.391136)
		(end 293.889176 -8.623554)
		(width 0.1397)
		(layer "In2.Cu")
		(net "PCIE_RX_P0")
	)
	(segment
		(start 243.40185 -27.726386)
		(end 243.069618 -28.058618)
		(width 0.1397)
		(layer "In2.Cu")
		(net "PCIE_RX_P0")
	)
	(segment
		(start 265.404854 -13.019786)
		(end 263.97712 -14.447774)
		(width 0.1397)
		(layer "In2.Cu")
		(net "PCIE_RX_P0")
	)
	(segment
		(start 278.90978 -7.742428)
		(end 278.538178 -8.002778)
		(width 0.1397)
		(layer "In2.Cu")
		(net "PCIE_RX_P0")
	)
	(segment
		(start 243.069618 -28.058618)
		(end 242.508532 -28.619704)
		(width 0.1016)
		(layer "In2.Cu")
		(net "PCIE_RX_P0")
	)
	(segment
		(start 291.333174 -15.112746)
		(end 292.090602 -14.798802)
		(width 0.1397)
		(layer "In2.Cu")
		(net "PCIE_RX_P0")
	)
	(segment
		(start 242.508532 -28.619704)
		(end 242.508532 -29.916628)
		(width 0.1016)
		(layer "In2.Cu")
		(net "PCIE_RX_P0")
	)
	(segment
		(start 288.75482 -5.478272)
		(end 279.917652 -7.036308)
		(width 0.1397)
		(layer "In2.Cu")
		(net "PCIE_RX_P0")
	)
	(arc
		(start 288.777426 -13.945362)
		(mid 288.943247 -14.008236)
		(end 289.08502 -14.11478)
		(width 0.1397)
		(layer "In2.Cu")
		(net "PCIE_RX_P0")
	)
	(arc
		(start 242.508532 -29.916628)
		(mid 242.545135 -30.083243)
		(end 242.648232 -30.219142)
		(width 0.1016)
		(layer "In2.Cu")
		(net "PCIE_RX_P0")
	)
	(arc
		(start 242.648232 -30.219142)
		(mid 242.863537 -30.376484)
		(end 243.099844 -30.500066)
		(width 0.1016)
		(layer "In2.Cu")
		(net "PCIE_RX_P0")
	)
	(arc
		(start 288.63925 -13.930122)
		(mid 288.708761 -13.93391)
		(end 288.777426 -13.945362)
		(width 0.1397)
		(layer "In2.Cu")
		(net "PCIE_RX_P0")
	)
	(segment
		(start 238.59998 -29.99994)
		(end 238.100108 -29.500068)
		(width 0.136652)
		(layer "F.Cu")
		(net "PCIE_RX_N95")
	)
	(via
		(at 238.100108 -29.500068)
		(size 0.4572)
		(drill 0.2032)
		(layers "F.Cu" "B.Cu")
		(net "PCIE_RX_N95")
	)
	(segment
		(start 236.887766 -24.861774)
		(end 238.06277 -26.036778)
		(width 0.1397)
		(layer "In2.Cu")
		(net "PCIE_RX_N95")
	)
	(segment
		(start 232.190544 -19.298412)
		(end 233.761788 -20.39874)
		(width 0.1397)
		(layer "In2.Cu")
		(net "PCIE_RX_N95")
	)
	(segment
		(start 206.657448 -23.341838)
		(end 207.026002 -23.263606)
		(width 0.1397)
		(layer "In2.Cu")
		(net "PCIE_RX_N95")
	)
	(segment
		(start 219.313506 -18.471388)
		(end 223.408748 -17.749266)
		(width 0.1397)
		(layer "In2.Cu")
		(net "PCIE_RX_N95")
	)
	(segment
		(start 171.384468 -12.530074)
		(end 171.384468 -12.766548)
		(width 0.1397)
		(layer "In2.Cu")
		(net "PCIE_RX_N95")
	)
	(segment
		(start 238.06277 -28.279598)
		(end 238.06277 -28.304998)
		(width 0.1016)
		(layer "In2.Cu")
		(net "PCIE_RX_N95")
	)
	(segment
		(start 171.384468 -12.766548)
		(end 171.36491 -12.84859)
		(width 0.1397)
		(layer "In2.Cu")
		(net "PCIE_RX_N95")
	)
	(segment
		(start 237.708948 -29.661866)
		(end 237.945422 -29.89834)
		(width 0.1016)
		(layer "In2.Cu")
		(net "PCIE_RX_N95")
	)
	(segment
		(start 217.495628 -19.743928)
		(end 219.313506 -18.471388)
		(width 0.1397)
		(layer "In2.Cu")
		(net "PCIE_RX_N95")
	)
	(segment
		(start 212.085682 -22.47519)
		(end 213.899496 -20.661376)
		(width 0.1397)
		(layer "In2.Cu")
		(net "PCIE_RX_N95")
	)
	(segment
		(start 188.026802 -15.580614)
		(end 198.339202 -22.802342)
		(width 0.1397)
		(layer "In2.Cu")
		(net "PCIE_RX_N95")
	)
	(segment
		(start 213.899496 -20.661376)
		(end 214.500206 -20.27174)
		(width 0.1397)
		(layer "In2.Cu")
		(net "PCIE_RX_N95")
	)
	(segment
		(start 207.026002 -23.263606)
		(end 207.094582 -23.248874)
		(width 0.1397)
		(layer "In2.Cu")
		(net "PCIE_RX_N95")
	)
	(segment
		(start 181.757828 -14.475206)
		(end 188.026802 -15.580614)
		(width 0.1397)
		(layer "In2.Cu")
		(net "PCIE_RX_N95")
	)
	(segment
		(start 238.06277 -28.304998)
		(end 237.99927 -28.368498)
		(width 0.1016)
		(layer "In2.Cu")
		(net "PCIE_RX_N95")
	)
	(segment
		(start 210.209892 -23.600664)
		(end 212.085682 -22.47519)
		(width 0.1397)
		(layer "In2.Cu")
		(net "PCIE_RX_N95")
	)
	(segment
		(start 209.481166 -23.756112)
		(end 210.209892 -23.600664)
		(width 0.1397)
		(layer "In2.Cu")
		(net "PCIE_RX_N95")
	)
	(segment
		(start 171.414694 -13.147294)
		(end 171.586144 -13.48105)
		(width 0.1397)
		(layer "In2.Cu")
		(net "PCIE_RX_N95")
	)
	(segment
		(start 207.094582 -23.248874)
		(end 209.481166 -23.756112)
		(width 0.1397)
		(layer "In2.Cu")
		(net "PCIE_RX_N95")
	)
	(segment
		(start 237.708948 -29.298392)
		(end 237.708948 -29.661866)
		(width 0.1016)
		(layer "In2.Cu")
		(net "PCIE_RX_N95")
	)
	(segment
		(start 223.408748 -17.749266)
		(end 232.190544 -19.298412)
		(width 0.1397)
		(layer "In2.Cu")
		(net "PCIE_RX_N95")
	)
	(segment
		(start 171.36491 -12.84859)
		(end 171.414694 -13.147294)
		(width 0.1397)
		(layer "In2.Cu")
		(net "PCIE_RX_N95")
	)
	(segment
		(start 198.339202 -22.802342)
		(end 199.084946 -22.960584)
		(width 0.1397)
		(layer "In2.Cu")
		(net "PCIE_RX_N95")
	)
	(segment
		(start 214.500206 -20.27174)
		(end 217.495628 -19.743928)
		(width 0.1397)
		(layer "In2.Cu")
		(net "PCIE_RX_N95")
	)
	(segment
		(start 237.99927 -29.00807)
		(end 237.708948 -29.298392)
		(width 0.1016)
		(layer "In2.Cu")
		(net "PCIE_RX_N95")
	)
	(segment
		(start 238.06277 -26.036778)
		(end 238.06277 -28.279598)
		(width 0.1397)
		(layer "In2.Cu")
		(net "PCIE_RX_N95")
	)
	(segment
		(start 237.99927 -28.368498)
		(end 237.99927 -29.00807)
		(width 0.1016)
		(layer "In2.Cu")
		(net "PCIE_RX_N95")
	)
	(segment
		(start 201.974958 -22.346412)
		(end 206.657448 -23.341838)
		(width 0.1397)
		(layer "In2.Cu")
		(net "PCIE_RX_N95")
	)
	(segment
		(start 237.945422 -29.89834)
		(end 237.998508 -29.89834)
		(width 0.1016)
		(layer "In2.Cu")
		(net "PCIE_RX_N95")
	)
	(segment
		(start 233.761788 -20.39874)
		(end 236.887766 -24.861774)
		(width 0.1397)
		(layer "In2.Cu")
		(net "PCIE_RX_N95")
	)
	(segment
		(start 199.084946 -22.960584)
		(end 201.974958 -22.346412)
		(width 0.1397)
		(layer "In2.Cu")
		(net "PCIE_RX_N95")
	)
	(segment
		(start 176.769522 -15.354046)
		(end 181.757828 -14.475206)
		(width 0.1397)
		(layer "In2.Cu")
		(net "PCIE_RX_N95")
	)
	(segment
		(start 238.100108 -29.79674)
		(end 238.100108 -29.500068)
		(width 0.1016)
		(layer "In2.Cu")
		(net "PCIE_RX_N95")
	)
	(segment
		(start 171.900342 -13.795248)
		(end 176.769522 -15.354046)
		(width 0.1397)
		(layer "In2.Cu")
		(net "PCIE_RX_N95")
	)
	(segment
		(start 171.586144 -13.48105)
		(end 171.900342 -13.795248)
		(width 0.1397)
		(layer "In2.Cu")
		(net "PCIE_RX_N95")
	)
	(arc
		(start 237.998508 -29.89834)
		(mid 238.07035 -29.868582)
		(end 238.100108 -29.79674)
		(width 0.1016)
		(layer "In2.Cu")
		(net "PCIE_RX_N95")
	)
	(segment
		(start 237.599982 -30.999938)
		(end 237.10011 -30.500066)
		(width 0.136652)
		(layer "F.Cu")
		(net "PCIE_RX_N94")
	)
	(via
		(at 237.10011 -30.500066)
		(size 0.4572)
		(drill 0.2032)
		(layers "F.Cu" "B.Cu")
		(net "PCIE_RX_N94")
	)
	(segment
		(start 203.22794 -27.313382)
		(end 204.451458 -27.053286)
		(width 0.1397)
		(layer "In2.Cu")
		(net "PCIE_RX_N94")
	)
	(segment
		(start 236.353096 -28.3845)
		(end 236.7026 -28.734004)
		(width 0.1016)
		(layer "In2.Cu")
		(net "PCIE_RX_N94")
	)
	(segment
		(start 236.353096 -28.294584)
		(end 236.353096 -28.3845)
		(width 0.1016)
		(layer "In2.Cu")
		(net "PCIE_RX_N94")
	)
	(segment
		(start 231.234996 -22.841204)
		(end 233.465878 -24.403812)
		(width 0.1397)
		(layer "In2.Cu")
		(net "PCIE_RX_N94")
	)
	(segment
		(start 205.674214 -26.793444)
		(end 208.032858 -27.208226)
		(width 0.1397)
		(layer "In2.Cu")
		(net "PCIE_RX_N94")
	)
	(segment
		(start 208.947512 -27.046682)
		(end 213.832948 -23.626318)
		(width 0.1397)
		(layer "In2.Cu")
		(net "PCIE_RX_N94")
	)
	(segment
		(start 236.765338 -30.898338)
		(end 236.921548 -30.898338)
		(width 0.1016)
		(layer "In2.Cu")
		(net "PCIE_RX_N94")
	)
	(segment
		(start 235.81233 -27.753818)
		(end 236.335316 -28.276804)
		(width 0.1397)
		(layer "In2.Cu")
		(net "PCIE_RX_N94")
	)
	(segment
		(start 196.459094 -25.874218)
		(end 203.22794 -27.313382)
		(width 0.1397)
		(layer "In2.Cu")
		(net "PCIE_RX_N94")
	)
	(segment
		(start 171.859194 -17.640554)
		(end 174.943516 -18.295874)
		(width 0.1397)
		(layer "In2.Cu")
		(net "PCIE_RX_N94")
	)
	(segment
		(start 233.465878 -24.403812)
		(end 235.81233 -27.753818)
		(width 0.1397)
		(layer "In2.Cu")
		(net "PCIE_RX_N94")
	)
	(segment
		(start 237.047786 -30.846014)
		(end 237.070392 -30.823408)
		(width 0.1016)
		(layer "In2.Cu")
		(net "PCIE_RX_N94")
	)
	(segment
		(start 204.451458 -27.053286)
		(end 205.674214 -26.793444)
		(width 0.1397)
		(layer "In2.Cu")
		(net "PCIE_RX_N94")
	)
	(segment
		(start 220.195394 -20.48764)
		(end 223.419162 -19.842988)
		(width 0.1397)
		(layer "In2.Cu")
		(net "PCIE_RX_N94")
	)
	(segment
		(start 237.10011 -30.751526)
		(end 237.10011 -30.500066)
		(width 0.1016)
		(layer "In2.Cu")
		(net "PCIE_RX_N94")
	)
	(segment
		(start 184.817766 -17.721834)
		(end 196.459094 -25.874218)
		(width 0.1397)
		(layer "In2.Cu")
		(net "PCIE_RX_N94")
	)
	(segment
		(start 229.10546 -20.845018)
		(end 229.550722 -21.15693)
		(width 0.1397)
		(layer "In2.Cu")
		(net "PCIE_RX_N94")
	)
	(segment
		(start 229.550722 -21.15693)
		(end 231.234996 -22.841204)
		(width 0.1397)
		(layer "In2.Cu")
		(net "PCIE_RX_N94")
	)
	(segment
		(start 216.345262 -23.183342)
		(end 220.195394 -20.48764)
		(width 0.1397)
		(layer "In2.Cu")
		(net "PCIE_RX_N94")
	)
	(segment
		(start 180.897022 -17.031462)
		(end 184.817766 -17.721834)
		(width 0.1397)
		(layer "In2.Cu")
		(net "PCIE_RX_N94")
	)
	(segment
		(start 174.943516 -18.295874)
		(end 180.897022 -17.031462)
		(width 0.1397)
		(layer "In2.Cu")
		(net "PCIE_RX_N94")
	)
	(segment
		(start 236.335316 -28.276804)
		(end 236.353096 -28.294584)
		(width 0.1016)
		(layer "In2.Cu")
		(net "PCIE_RX_N94")
	)
	(segment
		(start 208.032858 -27.208226)
		(end 208.947512 -27.046682)
		(width 0.1397)
		(layer "In2.Cu")
		(net "PCIE_RX_N94")
	)
	(segment
		(start 171.856654 -17.639792)
		(end 171.859194 -17.640554)
		(width 0.1397)
		(layer "In2.Cu")
		(net "PCIE_RX_N94")
	)
	(segment
		(start 236.7026 -28.734004)
		(end 236.7026 -30.8356)
		(width 0.1016)
		(layer "In2.Cu")
		(net "PCIE_RX_N94")
	)
	(segment
		(start 223.419162 -19.842988)
		(end 229.10546 -20.845018)
		(width 0.1397)
		(layer "In2.Cu")
		(net "PCIE_RX_N94")
	)
	(segment
		(start 213.832948 -23.626318)
		(end 216.345262 -23.183342)
		(width 0.1397)
		(layer "In2.Cu")
		(net "PCIE_RX_N94")
	)
	(arc
		(start 171.612814 -17.408398)
		(mid 171.622511 -17.422552)
		(end 171.632372 -17.436592)
		(width 0.1397)
		(layer "In2.Cu")
		(net "PCIE_RX_N94")
	)
	(arc
		(start 171.384468 -16.330168)
		(mid 171.393404 -16.891574)
		(end 171.612814 -17.408398)
		(width 0.1397)
		(layer "In2.Cu")
		(net "PCIE_RX_N94")
	)
	(arc
		(start 236.7026 -30.8356)
		(mid 236.720976 -30.879962)
		(end 236.765338 -30.898338)
		(width 0.1016)
		(layer "In2.Cu")
		(net "PCIE_RX_N94")
	)
	(arc
		(start 236.921548 -30.898338)
		(mid 236.989881 -30.884746)
		(end 237.047786 -30.846014)
		(width 0.1016)
		(layer "In2.Cu")
		(net "PCIE_RX_N94")
	)
	(arc
		(start 237.070392 -30.823408)
		(mid 237.092375 -30.790414)
		(end 237.10011 -30.751526)
		(width 0.1016)
		(layer "In2.Cu")
		(net "PCIE_RX_N94")
	)
	(arc
		(start 171.632372 -17.436592)
		(mid 171.675558 -17.494204)
		(end 171.721526 -17.549622)
		(width 0.1397)
		(layer "In2.Cu")
		(net "PCIE_RX_N94")
	)
	(arc
		(start 171.721526 -17.549622)
		(mid 171.782978 -17.603872)
		(end 171.856654 -17.639792)
		(width 0.1397)
		(layer "In2.Cu")
		(net "PCIE_RX_N94")
	)
	(segment
		(start 236.599984 -29.99994)
		(end 236.100112 -29.500068)
		(width 0.136652)
		(layer "F.Cu")
		(net "PCIE_RX_N93")
	)
	(via
		(at 236.100112 -29.500068)
		(size 0.4572)
		(drill 0.2032)
		(layers "F.Cu" "B.Cu")
		(net "PCIE_RX_N93")
	)
	(segment
		(start 234.71505 -27.83078)
		(end 234.813856 -27.929586)
		(width 0.1016)
		(layer "In2.Cu")
		(net "PCIE_RX_N93")
	)
	(segment
		(start 184.913524 -18.992342)
		(end 188.787532 -24.95804)
		(width 0.1397)
		(layer "In2.Cu")
		(net "PCIE_RX_N93")
	)
	(segment
		(start 169.134536 -16.330168)
		(end 168.903396 -16.761206)
		(width 0.1397)
		(layer "In2.Cu")
		(net "PCIE_RX_N93")
	)
	(segment
		(start 188.787532 -24.95804)
		(end 191.40297 -26.789634)
		(width 0.1397)
		(layer "In2.Cu")
		(net "PCIE_RX_N93")
	)
	(segment
		(start 184.531 -18.743676)
		(end 184.913524 -18.992342)
		(width 0.1397)
		(layer "In2.Cu")
		(net "PCIE_RX_N93")
	)
	(segment
		(start 227.59797 -22.20341)
		(end 229.475792 -22.81555)
		(width 0.1397)
		(layer "In2.Cu")
		(net "PCIE_RX_N93")
	)
	(segment
		(start 214.028528 -24.579072)
		(end 220.31325 -23.47087)
		(width 0.1397)
		(layer "In2.Cu")
		(net "PCIE_RX_N93")
	)
	(segment
		(start 170.107102 -18.510504)
		(end 170.631866 -18.88744)
		(width 0.1397)
		(layer "In2.Cu")
		(net "PCIE_RX_N93")
	)
	(segment
		(start 231.21747 -24.03602)
		(end 231.218486 -24.037544)
		(width 0.1397)
		(layer "In2.Cu")
		(net "PCIE_RX_N93")
	)
	(segment
		(start 173.716442 -20.094956)
		(end 182.302658 -18.269966)
		(width 0.1397)
		(layer "In2.Cu")
		(net "PCIE_RX_N93")
	)
	(segment
		(start 232.550208 -25.44064)
		(end 232.856278 -25.882092)
		(width 0.1397)
		(layer "In2.Cu")
		(net "PCIE_RX_N93")
	)
	(segment
		(start 197.057518 -27.786838)
		(end 198.79818 -27.479752)
		(width 0.1397)
		(layer "In2.Cu")
		(net "PCIE_RX_N93")
	)
	(segment
		(start 169.784522 -17.784318)
		(end 170.107102 -18.510504)
		(width 0.1397)
		(layer "In2.Cu")
		(net "PCIE_RX_N93")
	)
	(segment
		(start 169.159174 -17.088104)
		(end 169.784522 -17.784318)
		(width 0.1397)
		(layer "In2.Cu")
		(net "PCIE_RX_N93")
	)
	(segment
		(start 234.71505 -27.740864)
		(end 234.71505 -27.83078)
		(width 0.1016)
		(layer "In2.Cu")
		(net "PCIE_RX_N93")
	)
	(segment
		(start 235.00715 -28.396184)
		(end 235.00715 -29.58973)
		(width 0.1016)
		(layer "In2.Cu")
		(net "PCIE_RX_N93")
	)
	(segment
		(start 226.718114 -22.53361)
		(end 227.59797 -22.20341)
		(width 0.1397)
		(layer "In2.Cu")
		(net "PCIE_RX_N93")
	)
	(segment
		(start 232.856278 -25.882092)
		(end 234.69727 -27.723084)
		(width 0.1397)
		(layer "In2.Cu")
		(net "PCIE_RX_N93")
	)
	(segment
		(start 229.475792 -22.81555)
		(end 231.21747 -24.03602)
		(width 0.1397)
		(layer "In2.Cu")
		(net "PCIE_RX_N93")
	)
	(segment
		(start 172.068744 -19.172936)
		(end 173.241716 -19.994372)
		(width 0.1397)
		(layer "In2.Cu")
		(net "PCIE_RX_N93")
	)
	(segment
		(start 182.302658 -18.269966)
		(end 184.531 -18.743676)
		(width 0.1397)
		(layer "In2.Cu")
		(net "PCIE_RX_N93")
	)
	(segment
		(start 220.31325 -23.47087)
		(end 225.859086 -22.361652)
		(width 0.1397)
		(layer "In2.Cu")
		(net "PCIE_RX_N93")
	)
	(segment
		(start 234.69727 -27.723084)
		(end 234.71505 -27.740864)
		(width 0.1016)
		(layer "In2.Cu")
		(net "PCIE_RX_N93")
	)
	(segment
		(start 204.789532 -28.753308)
		(end 209.168492 -27.981656)
		(width 0.1397)
		(layer "In2.Cu")
		(net "PCIE_RX_N93")
	)
	(segment
		(start 170.631866 -18.88744)
		(end 172.068744 -19.172936)
		(width 0.1397)
		(layer "In2.Cu")
		(net "PCIE_RX_N93")
	)
	(segment
		(start 231.218486 -24.037544)
		(end 231.869996 -24.966168)
		(width 0.1397)
		(layer "In2.Cu")
		(net "PCIE_RX_N93")
	)
	(segment
		(start 198.79818 -27.479752)
		(end 204.789532 -28.753308)
		(width 0.1397)
		(layer "In2.Cu")
		(net "PCIE_RX_N93")
	)
	(segment
		(start 231.869996 -24.966168)
		(end 232.49636 -25.404572)
		(width 0.1397)
		(layer "In2.Cu")
		(net "PCIE_RX_N93")
	)
	(segment
		(start 225.859086 -22.361652)
		(end 226.718114 -22.53361)
		(width 0.1397)
		(layer "In2.Cu")
		(net "PCIE_RX_N93")
	)
	(segment
		(start 232.498392 -25.405842)
		(end 232.550208 -25.44064)
		(width 0.1397)
		(layer "In2.Cu")
		(net "PCIE_RX_N93")
	)
	(segment
		(start 168.960546 -16.950436)
		(end 169.032682 -16.989044)
		(width 0.1397)
		(layer "In2.Cu")
		(net "PCIE_RX_N93")
	)
	(segment
		(start 173.247558 -19.995388)
		(end 173.716442 -20.094956)
		(width 0.1397)
		(layer "In2.Cu")
		(net "PCIE_RX_N93")
	)
	(segment
		(start 209.168492 -27.981656)
		(end 214.028528 -24.579072)
		(width 0.1397)
		(layer "In2.Cu")
		(net "PCIE_RX_N93")
	)
	(segment
		(start 232.49636 -25.404572)
		(end 232.498392 -25.405842)
		(width 0.1397)
		(layer "In2.Cu")
		(net "PCIE_RX_N93")
	)
	(segment
		(start 173.241716 -19.994372)
		(end 173.24197 -19.994372)
		(width 0.1397)
		(layer "In2.Cu")
		(net "PCIE_RX_N93")
	)
	(segment
		(start 235.33227 -29.91485)
		(end 235.982002 -29.91485)
		(width 0.1016)
		(layer "In2.Cu")
		(net "PCIE_RX_N93")
	)
	(segment
		(start 173.24197 -19.994372)
		(end 173.24324 -19.994626)
		(width 0.1397)
		(layer "In2.Cu")
		(net "PCIE_RX_N93")
	)
	(segment
		(start 191.40297 -26.789634)
		(end 197.057518 -27.786838)
		(width 0.1397)
		(layer "In2.Cu")
		(net "PCIE_RX_N93")
	)
	(segment
		(start 173.24324 -19.994626)
		(end 173.247558 -19.995388)
		(width 0.1397)
		(layer "In2.Cu")
		(net "PCIE_RX_N93")
	)
	(segment
		(start 236.100112 -29.79674)
		(end 236.100112 -29.500068)
		(width 0.1016)
		(layer "In2.Cu")
		(net "PCIE_RX_N93")
	)
	(arc
		(start 169.032682 -16.989044)
		(mid 169.100239 -17.033068)
		(end 169.159174 -17.088104)
		(width 0.1397)
		(layer "In2.Cu")
		(net "PCIE_RX_N93")
	)
	(arc
		(start 235.982002 -29.91485)
		(mid 236.065518 -29.880256)
		(end 236.100112 -29.79674)
		(width 0.1016)
		(layer "In2.Cu")
		(net "PCIE_RX_N93")
	)
	(arc
		(start 235.00715 -29.58973)
		(mid 235.102375 -29.819625)
		(end 235.33227 -29.91485)
		(width 0.1016)
		(layer "In2.Cu")
		(net "PCIE_RX_N93")
	)
	(arc
		(start 234.813856 -27.929586)
		(mid 234.956898 -28.143663)
		(end 235.00715 -28.396184)
		(width 0.1016)
		(layer "In2.Cu")
		(net "PCIE_RX_N93")
	)
	(arc
		(start 168.903396 -16.761206)
		(mid 168.89278 -16.867657)
		(end 168.960546 -16.950436)
		(width 0.1397)
		(layer "In2.Cu")
		(net "PCIE_RX_N93")
	)
	(segment
		(start 235.599986 -30.999938)
		(end 235.100114 -30.500066)
		(width 0.136652)
		(layer "F.Cu")
		(net "PCIE_RX_N92")
	)
	(via
		(at 235.100114 -30.500066)
		(size 0.4572)
		(drill 0.2032)
		(layers "F.Cu" "B.Cu")
		(net "PCIE_RX_N92")
	)
	(segment
		(start 234.539282 -31.145988)
		(end 234.554522 -31.11246)
		(width 0.1016)
		(layer "In2.Cu")
		(net "PCIE_RX_N92")
	)
	(segment
		(start 170.022774 -14.394434)
		(end 170.025822 -14.395958)
		(width 0.1397)
		(layer "In2.Cu")
		(net "PCIE_RX_N92")
	)
	(segment
		(start 237.28172 -29.831538)
		(end 237.703614 -30.253432)
		(width 0.1016)
		(layer "In2.Cu")
		(net "PCIE_RX_N92")
	)
	(segment
		(start 232.943146 -21.713698)
		(end 233.03738 -22.155658)
		(width 0.1397)
		(layer "In2.Cu")
		(net "PCIE_RX_N92")
	)
	(segment
		(start 214.091266 -22.49297)
		(end 216.49944 -22.068282)
		(width 0.1397)
		(layer "In2.Cu")
		(net "PCIE_RX_N92")
	)
	(segment
		(start 223.656652 -18.797778)
		(end 231.205532 -20.405344)
		(width 0.1397)
		(layer "In2.Cu")
		(net "PCIE_RX_N92")
	)
	(segment
		(start 181.142894 -15.678658)
		(end 184.982104 -16.355314)
		(width 0.1397)
		(layer "In2.Cu")
		(net "PCIE_RX_N92")
	)
	(segment
		(start 237.34522 -28.47467)
		(end 237.28172 -28.53817)
		(width 0.1016)
		(layer "In2.Cu")
		(net "PCIE_RX_N92")
	)
	(segment
		(start 237.34522 -26.955496)
		(end 237.34522 -28.44927)
		(width 0.1397)
		(layer "In2.Cu")
		(net "PCIE_RX_N92")
	)
	(segment
		(start 231.205532 -20.405344)
		(end 232.740962 -21.402294)
		(width 0.1397)
		(layer "In2.Cu")
		(net "PCIE_RX_N92")
	)
	(segment
		(start 169.307256 -13.422376)
		(end 170.022774 -14.394434)
		(width 0.1397)
		(layer "In2.Cu")
		(net "PCIE_RX_N92")
	)
	(segment
		(start 169.30624 -13.420852)
		(end 169.307256 -13.422376)
		(width 0.1397)
		(layer "In2.Cu")
		(net "PCIE_RX_N92")
	)
	(segment
		(start 195.52285 -23.739094)
		(end 199.300846 -24.54148)
		(width 0.1397)
		(layer "In2.Cu")
		(net "PCIE_RX_N92")
	)
	(segment
		(start 170.45686 -14.643354)
		(end 170.88739 -14.89075)
		(width 0.1397)
		(layer "In2.Cu")
		(net "PCIE_RX_N92")
	)
	(segment
		(start 234.809538 -30.911292)
		(end 234.860846 -30.901386)
		(width 0.1016)
		(layer "In2.Cu")
		(net "PCIE_RX_N92")
	)
	(segment
		(start 236.903768 -26.275792)
		(end 237.34522 -26.955496)
		(width 0.1397)
		(layer "In2.Cu")
		(net "PCIE_RX_N92")
	)
	(segment
		(start 233.03738 -22.155658)
		(end 234.843574 -24.937212)
		(width 0.1397)
		(layer "In2.Cu")
		(net "PCIE_RX_N92")
	)
	(segment
		(start 205.893162 -24.899874)
		(end 206.67726 -26.107898)
		(width 0.1397)
		(layer "In2.Cu")
		(net "PCIE_RX_N92")
	)
	(segment
		(start 237.28172 -28.53817)
		(end 237.28172 -29.831538)
		(width 0.1016)
		(layer "In2.Cu")
		(net "PCIE_RX_N92")
	)
	(segment
		(start 237.087156 -32.1056)
		(end 234.921552 -32.1056)
		(width 0.1016)
		(layer "In2.Cu")
		(net "PCIE_RX_N92")
	)
	(segment
		(start 207.640936 -26.312876)
		(end 208.48447 -26.133806)
		(width 0.1397)
		(layer "In2.Cu")
		(net "PCIE_RX_N92")
	)
	(segment
		(start 170.025822 -14.395958)
		(end 170.299634 -14.553184)
		(width 0.1397)
		(layer "In2.Cu")
		(net "PCIE_RX_N92")
	)
	(segment
		(start 208.48447 -26.133806)
		(end 214.091266 -22.49297)
		(width 0.1397)
		(layer "In2.Cu")
		(net "PCIE_RX_N92")
	)
	(segment
		(start 216.49944 -22.068282)
		(end 220.175328 -19.494246)
		(width 0.1397)
		(layer "In2.Cu")
		(net "PCIE_RX_N92")
	)
	(segment
		(start 234.843574 -24.937212)
		(end 236.903768 -26.275792)
		(width 0.1397)
		(layer "In2.Cu")
		(net "PCIE_RX_N92")
	)
	(segment
		(start 220.175328 -19.494246)
		(end 223.656652 -18.797778)
		(width 0.1397)
		(layer "In2.Cu")
		(net "PCIE_RX_N92")
	)
	(segment
		(start 199.300846 -24.54148)
		(end 201.754486 -24.020018)
		(width 0.1397)
		(layer "In2.Cu")
		(net "PCIE_RX_N92")
	)
	(segment
		(start 234.503976 -31.688024)
		(end 234.503976 -31.308294)
		(width 0.1016)
		(layer "In2.Cu")
		(net "PCIE_RX_N92")
	)
	(segment
		(start 232.740962 -21.402294)
		(end 232.943146 -21.713698)
		(width 0.1397)
		(layer "In2.Cu")
		(net "PCIE_RX_N92")
	)
	(segment
		(start 170.299634 -14.553184)
		(end 170.45686 -14.643354)
		(width 0.1397)
		(layer "In2.Cu")
		(net "PCIE_RX_N92")
	)
	(segment
		(start 177.23739 -16.509238)
		(end 181.142894 -15.678658)
		(width 0.1397)
		(layer "In2.Cu")
		(net "PCIE_RX_N92")
	)
	(segment
		(start 237.703614 -30.253432)
		(end 237.703614 -31.489142)
		(width 0.1016)
		(layer "In2.Cu")
		(net "PCIE_RX_N92")
	)
	(segment
		(start 201.754486 -24.020018)
		(end 205.893162 -24.899874)
		(width 0.1397)
		(layer "In2.Cu")
		(net "PCIE_RX_N92")
	)
	(segment
		(start 170.88739 -14.89075)
		(end 173.802294 -15.778226)
		(width 0.1397)
		(layer "In2.Cu")
		(net "PCIE_RX_N92")
	)
	(segment
		(start 184.982104 -16.355314)
		(end 195.52285 -23.739094)
		(width 0.1397)
		(layer "In2.Cu")
		(net "PCIE_RX_N92")
	)
	(segment
		(start 237.34522 -28.44927)
		(end 237.34522 -28.47467)
		(width 0.1016)
		(layer "In2.Cu")
		(net "PCIE_RX_N92")
	)
	(segment
		(start 206.67726 -26.107898)
		(end 207.640936 -26.312876)
		(width 0.1397)
		(layer "In2.Cu")
		(net "PCIE_RX_N92")
	)
	(segment
		(start 173.802294 -15.778226)
		(end 177.23739 -16.509238)
		(width 0.1397)
		(layer "In2.Cu")
		(net "PCIE_RX_N92")
	)
	(arc
		(start 169.180256 -13.062966)
		(mid 169.228268 -13.24718)
		(end 169.30624 -13.420852)
		(width 0.1397)
		(layer "In2.Cu")
		(net "PCIE_RX_N92")
	)
	(arc
		(start 234.860846 -30.901386)
		(mid 235.035763 -30.733684)
		(end 235.100114 -30.500066)
		(width 0.1016)
		(layer "In2.Cu")
		(net "PCIE_RX_N92")
	)
	(arc
		(start 234.554522 -31.11246)
		(mid 234.65766 -30.980987)
		(end 234.809538 -30.911292)
		(width 0.1016)
		(layer "In2.Cu")
		(net "PCIE_RX_N92")
	)
	(arc
		(start 237.703614 -31.489142)
		(mid 237.523058 -31.925044)
		(end 237.087156 -32.1056)
		(width 0.1016)
		(layer "In2.Cu")
		(net "PCIE_RX_N92")
	)
	(arc
		(start 169.134536 -12.530074)
		(mid 169.145987 -12.797499)
		(end 169.180256 -13.062966)
		(width 0.1397)
		(layer "In2.Cu")
		(net "PCIE_RX_N92")
	)
	(arc
		(start 234.503976 -31.308294)
		(mid 234.512911 -31.225246)
		(end 234.539282 -31.145988)
		(width 0.1016)
		(layer "In2.Cu")
		(net "PCIE_RX_N92")
	)
	(arc
		(start 234.921552 -32.1056)
		(mid 234.626281 -31.983295)
		(end 234.503976 -31.688024)
		(width 0.1016)
		(layer "In2.Cu")
		(net "PCIE_RX_N92")
	)
	(segment
		(start 234.599988 -29.99994)
		(end 234.100116 -29.500068)
		(width 0.136652)
		(layer "F.Cu")
		(net "PCIE_RX_N91")
	)
	(via
		(at 234.100116 -29.500068)
		(size 0.4572)
		(drill 0.2032)
		(layers "F.Cu" "B.Cu")
		(net "PCIE_RX_N91")
	)
	(segment
		(start 185.852308 -28.153614)
		(end 182.515256 -27.565096)
		(width 0.1397)
		(layer "In2.Cu")
		(net "PCIE_RX_N91")
	)
	(segment
		(start 233.813604 -29.193744)
		(end 234.050078 -28.95727)
		(width 0.1016)
		(layer "In2.Cu")
		(net "PCIE_RX_N91")
	)
	(segment
		(start 160.7312 -13.716)
		(end 160.7312 -13.715746)
		(width 0.1397)
		(layer "In2.Cu")
		(net "PCIE_RX_N91")
	)
	(segment
		(start 166.040054 -22.510496)
		(end 165.66007 -22.244558)
		(width 0.1397)
		(layer "In2.Cu")
		(net "PCIE_RX_N91")
	)
	(segment
		(start 209.777076 -28.867862)
		(end 204.587602 -29.782516)
		(width 0.1397)
		(layer "In2.Cu")
		(net "PCIE_RX_N91")
	)
	(segment
		(start 233.892344 -28.203144)
		(end 233.874564 -28.185364)
		(width 0.1016)
		(layer "In2.Cu")
		(net "PCIE_RX_N91")
	)
	(segment
		(start 233.708956 -29.558488)
		(end 233.708956 -29.446474)
		(width 0.1016)
		(layer "In2.Cu")
		(net "PCIE_RX_N91")
	)
	(segment
		(start 179.379372 -27.357324)
		(end 172.780452 -22.828504)
		(width 0.1397)
		(layer "In2.Cu")
		(net "PCIE_RX_N91")
	)
	(segment
		(start 182.515256 -27.565096)
		(end 181.436772 -27.794458)
		(width 0.1397)
		(layer "In2.Cu")
		(net "PCIE_RX_N91")
	)
	(segment
		(start 186.322716 -28.482798)
		(end 185.852308 -28.153614)
		(width 0.1397)
		(layer "In2.Cu")
		(net "PCIE_RX_N91")
	)
	(segment
		(start 160.342072 -12.572492)
		(end 160.38449 -12.530074)
		(width 0.1397)
		(layer "In2.Cu")
		(net "PCIE_RX_N91")
	)
	(segment
		(start 234.100116 -29.500068)
		(end 234.100116 -29.79674)
		(width 0.1016)
		(layer "In2.Cu")
		(net "PCIE_RX_N91")
	)
	(segment
		(start 233.874564 -28.185364)
		(end 231.793542 -26.104342)
		(width 0.1397)
		(layer "In2.Cu")
		(net "PCIE_RX_N91")
	)
	(segment
		(start 204.587602 -29.782516)
		(end 197.994524 -28.620212)
		(width 0.1397)
		(layer "In2.Cu")
		(net "PCIE_RX_N91")
	)
	(segment
		(start 231.793542 -26.104342)
		(end 228.34854 -23.69185)
		(width 0.1397)
		(layer "In2.Cu")
		(net "PCIE_RX_N91")
	)
	(segment
		(start 172.780452 -22.828504)
		(end 169.276268 -22.210776)
		(width 0.1397)
		(layer "In2.Cu")
		(net "PCIE_RX_N91")
	)
	(segment
		(start 225.944176 -23.462488)
		(end 222.39859 -24.171656)
		(width 0.1397)
		(layer "In2.Cu")
		(net "PCIE_RX_N91")
	)
	(segment
		(start 233.907838 -29.860748)
		(end 233.782108 -29.735018)
		(width 0.1016)
		(layer "In2.Cu")
		(net "PCIE_RX_N91")
	)
	(segment
		(start 222.39859 -24.171656)
		(end 214.494872 -25.5651)
		(width 0.1397)
		(layer "In2.Cu")
		(net "PCIE_RX_N91")
	)
	(segment
		(start 165.66007 -22.244558)
		(end 165.45687 -21.954236)
		(width 0.1397)
		(layer "In2.Cu")
		(net "PCIE_RX_N91")
	)
	(segment
		(start 163.435538 -15.68577)
		(end 160.9852 -13.97)
		(width 0.1397)
		(layer "In2.Cu")
		(net "PCIE_RX_N91")
	)
	(segment
		(start 164.659818 -17.43456)
		(end 163.435538 -15.68577)
		(width 0.1397)
		(layer "In2.Cu")
		(net "PCIE_RX_N91")
	)
	(segment
		(start 160.185862 -13.00734)
		(end 160.185862 -12.949428)
		(width 0.1397)
		(layer "In2.Cu")
		(net "PCIE_RX_N91")
	)
	(segment
		(start 228.34854 -23.69185)
		(end 227.63988 -23.472902)
		(width 0.1397)
		(layer "In2.Cu")
		(net "PCIE_RX_N91")
	)
	(segment
		(start 227.63988 -23.472902)
		(end 227.072444 -23.68804)
		(width 0.1397)
		(layer "In2.Cu")
		(net "PCIE_RX_N91")
	)
	(segment
		(start 233.892344 -28.29306)
		(end 233.892344 -28.203144)
		(width 0.1016)
		(layer "In2.Cu")
		(net "PCIE_RX_N91")
	)
	(segment
		(start 160.9852 -13.97)
		(end 160.7312 -13.716)
		(width 0.1397)
		(layer "In2.Cu")
		(net "PCIE_RX_N91")
	)
	(segment
		(start 169.276268 -22.210776)
		(end 166.7256 -22.6314)
		(width 0.1397)
		(layer "In2.Cu")
		(net "PCIE_RX_N91")
	)
	(segment
		(start 234.09021 -28.490926)
		(end 233.892344 -28.29306)
		(width 0.1016)
		(layer "In2.Cu")
		(net "PCIE_RX_N91")
	)
	(segment
		(start 165.45687 -21.954236)
		(end 164.659818 -17.43456)
		(width 0.1397)
		(layer "In2.Cu")
		(net "PCIE_RX_N91")
	)
	(segment
		(start 166.7256 -22.6314)
		(end 166.040054 -22.510496)
		(width 0.1397)
		(layer "In2.Cu")
		(net "PCIE_RX_N91")
	)
	(segment
		(start 197.994524 -28.620212)
		(end 192.548002 -29.580586)
		(width 0.1397)
		(layer "In2.Cu")
		(net "PCIE_RX_N91")
	)
	(segment
		(start 227.072444 -23.68804)
		(end 225.944176 -23.462488)
		(width 0.1397)
		(layer "In2.Cu")
		(net "PCIE_RX_N91")
	)
	(segment
		(start 181.436772 -27.794458)
		(end 179.379372 -27.357324)
		(width 0.1397)
		(layer "In2.Cu")
		(net "PCIE_RX_N91")
	)
	(segment
		(start 192.548002 -29.580586)
		(end 186.322716 -28.482798)
		(width 0.1397)
		(layer "In2.Cu")
		(net "PCIE_RX_N91")
	)
	(segment
		(start 214.494872 -25.5651)
		(end 209.777076 -28.867862)
		(width 0.1397)
		(layer "In2.Cu")
		(net "PCIE_RX_N91")
	)
	(segment
		(start 160.7312 -13.715746)
		(end 160.301178 -13.285724)
		(width 0.1397)
		(layer "In2.Cu")
		(net "PCIE_RX_N91")
	)
	(arc
		(start 234.050078 -28.95727)
		(mid 234.135613 -28.72972)
		(end 234.09021 -28.490926)
		(width 0.1016)
		(layer "In2.Cu")
		(net "PCIE_RX_N91")
	)
	(arc
		(start 234.100116 -29.79674)
		(mid 234.070358 -29.868582)
		(end 233.998516 -29.89834)
		(width 0.1016)
		(layer "In2.Cu")
		(net "PCIE_RX_N91")
	)
	(arc
		(start 233.998516 -29.89834)
		(mid 233.949429 -29.888576)
		(end 233.907838 -29.860748)
		(width 0.1016)
		(layer "In2.Cu")
		(net "PCIE_RX_N91")
	)
	(arc
		(start 233.708956 -29.446474)
		(mid 233.73616 -29.309711)
		(end 233.813604 -29.193744)
		(width 0.1016)
		(layer "In2.Cu")
		(net "PCIE_RX_N91")
	)
	(arc
		(start 160.301178 -13.285724)
		(mid 160.215836 -13.158)
		(end 160.185862 -13.00734)
		(width 0.1397)
		(layer "In2.Cu")
		(net "PCIE_RX_N91")
	)
	(arc
		(start 233.782108 -29.735018)
		(mid 233.72799 -29.654025)
		(end 233.708956 -29.558488)
		(width 0.1016)
		(layer "In2.Cu")
		(net "PCIE_RX_N91")
	)
	(arc
		(start 160.185862 -12.949428)
		(mid 160.226528 -12.745456)
		(end 160.342072 -12.572492)
		(width 0.1397)
		(layer "In2.Cu")
		(net "PCIE_RX_N91")
	)
	(segment
		(start 233.59999 -30.999938)
		(end 233.100118 -30.500066)
		(width 0.136652)
		(layer "F.Cu")
		(net "PCIE_RX_N90")
	)
	(via
		(at 233.100118 -30.500066)
		(size 0.4572)
		(drill 0.2032)
		(layers "F.Cu" "B.Cu")
		(net "PCIE_RX_N90")
	)
	(segment
		(start 221.877382 -26.471118)
		(end 225.758502 -27.155394)
		(width 0.1397)
		(layer "In2.Cu")
		(net "PCIE_RX_N90")
	)
	(segment
		(start 160.541462 -17.310608)
		(end 160.541462 -17.310862)
		(width 0.1397)
		(layer "In2.Cu")
		(net "PCIE_RX_N90")
	)
	(segment
		(start 183.577992 -31.712662)
		(end 187.882784 -30.7975)
		(width 0.1397)
		(layer "In2.Cu")
		(net "PCIE_RX_N90")
	)
	(segment
		(start 233.100118 -30.751526)
		(end 233.100118 -30.500066)
		(width 0.1016)
		(layer "In2.Cu")
		(net "PCIE_RX_N90")
	)
	(segment
		(start 192.30975 -31.73857)
		(end 198.880476 -30.568392)
		(width 0.1397)
		(layer "In2.Cu")
		(net "PCIE_RX_N90")
	)
	(segment
		(start 227.1014 -26.918666)
		(end 230.579168 -27.532076)
		(width 0.1397)
		(layer "In2.Cu")
		(net "PCIE_RX_N90")
	)
	(segment
		(start 232.420414 -28.816046)
		(end 232.702608 -29.254958)
		(width 0.1016)
		(layer "In2.Cu")
		(net "PCIE_RX_N90")
	)
	(segment
		(start 162.922204 -19.693382)
		(end 163.88588 -25.164542)
		(width 0.1397)
		(layer "In2.Cu")
		(net "PCIE_RX_N90")
	)
	(segment
		(start 179.324 -32.188404)
		(end 182.872634 -31.562548)
		(width 0.1397)
		(layer "In2.Cu")
		(net "PCIE_RX_N90")
	)
	(segment
		(start 232.702608 -29.254958)
		(end 232.702608 -30.763972)
		(width 0.1016)
		(layer "In2.Cu")
		(net "PCIE_RX_N90")
	)
	(segment
		(start 225.758502 -27.155394)
		(end 227.04425 -26.928826)
		(width 0.1397)
		(layer "In2.Cu")
		(net "PCIE_RX_N90")
	)
	(segment
		(start 182.872634 -31.562548)
		(end 183.577992 -31.712662)
		(width 0.1397)
		(layer "In2.Cu")
		(net "PCIE_RX_N90")
	)
	(segment
		(start 230.579168 -27.532076)
		(end 232.017062 -28.486862)
		(width 0.1397)
		(layer "In2.Cu")
		(net "PCIE_RX_N90")
	)
	(segment
		(start 214.620348 -27.763978)
		(end 221.877382 -26.471118)
		(width 0.1397)
		(layer "In2.Cu")
		(net "PCIE_RX_N90")
	)
	(segment
		(start 163.88588 -25.164542)
		(end 165.518846 -27.49677)
		(width 0.1397)
		(layer "In2.Cu")
		(net "PCIE_RX_N90")
	)
	(segment
		(start 233.047794 -30.846014)
		(end 233.0704 -30.823408)
		(width 0.1016)
		(layer "In2.Cu")
		(net "PCIE_RX_N90")
	)
	(segment
		(start 232.056686 -28.583636)
		(end 232.420414 -28.816046)
		(width 0.1016)
		(layer "In2.Cu")
		(net "PCIE_RX_N90")
	)
	(segment
		(start 198.880476 -30.568392)
		(end 204.025754 -31.475934)
		(width 0.1397)
		(layer "In2.Cu")
		(net "PCIE_RX_N90")
	)
	(segment
		(start 165.518846 -27.49677)
		(end 169.828464 -30.514036)
		(width 0.1397)
		(layer "In2.Cu")
		(net "PCIE_RX_N90")
	)
	(segment
		(start 160.57753 -17.349216)
		(end 162.922204 -19.693382)
		(width 0.1397)
		(layer "In2.Cu")
		(net "PCIE_RX_N90")
	)
	(segment
		(start 227.04425 -26.928826)
		(end 227.04425 -26.928572)
		(width 0.1397)
		(layer "In2.Cu")
		(net "PCIE_RX_N90")
	)
	(segment
		(start 232.038398 -28.500324)
		(end 232.056686 -28.583636)
		(width 0.1016)
		(layer "In2.Cu")
		(net "PCIE_RX_N90")
	)
	(segment
		(start 169.828464 -30.514036)
		(end 179.324 -32.188404)
		(width 0.1397)
		(layer "In2.Cu")
		(net "PCIE_RX_N90")
	)
	(segment
		(start 232.017062 -28.486862)
		(end 232.038398 -28.500324)
		(width 0.1016)
		(layer "In2.Cu")
		(net "PCIE_RX_N90")
	)
	(segment
		(start 227.04425 -26.928572)
		(end 227.1014 -26.918666)
		(width 0.1397)
		(layer "In2.Cu")
		(net "PCIE_RX_N90")
	)
	(segment
		(start 204.025754 -31.475934)
		(end 211.100924 -30.228286)
		(width 0.1397)
		(layer "In2.Cu")
		(net "PCIE_RX_N90")
	)
	(segment
		(start 232.836974 -30.898338)
		(end 232.921556 -30.898338)
		(width 0.1016)
		(layer "In2.Cu")
		(net "PCIE_RX_N90")
	)
	(segment
		(start 211.100924 -30.228286)
		(end 214.620348 -27.763978)
		(width 0.1397)
		(layer "In2.Cu")
		(net "PCIE_RX_N90")
	)
	(segment
		(start 187.882784 -30.7975)
		(end 192.30975 -31.73857)
		(width 0.1397)
		(layer "In2.Cu")
		(net "PCIE_RX_N90")
	)
	(arc
		(start 232.921556 -30.898338)
		(mid 232.989889 -30.884746)
		(end 233.047794 -30.846014)
		(width 0.1016)
		(layer "In2.Cu")
		(net "PCIE_RX_N90")
	)
	(arc
		(start 160.38449 -16.330168)
		(mid 160.319587 -16.843346)
		(end 160.541462 -17.310608)
		(width 0.1397)
		(layer "In2.Cu")
		(net "PCIE_RX_N90")
	)
	(arc
		(start 233.0704 -30.823408)
		(mid 233.092383 -30.790414)
		(end 233.100118 -30.751526)
		(width 0.1016)
		(layer "In2.Cu")
		(net "PCIE_RX_N90")
	)
	(arc
		(start 232.702608 -30.763972)
		(mid 232.741963 -30.858983)
		(end 232.836974 -30.898338)
		(width 0.1016)
		(layer "In2.Cu")
		(net "PCIE_RX_N90")
	)
	(arc
		(start 160.541462 -17.310862)
		(mid 160.559222 -17.330297)
		(end 160.57753 -17.349216)
		(width 0.1397)
		(layer "In2.Cu")
		(net "PCIE_RX_N90")
	)
	(segment
		(start 254.599948 -34.99993)
		(end 255.09982 -34.500058)
		(width 0.136652)
		(layer "F.Cu")
		(net "PCIE_RX_N9")
	)
	(via
		(at 255.09982 -34.500058)
		(size 0.4572)
		(drill 0.2032)
		(layers "F.Cu" "B.Cu")
		(net "PCIE_RX_N9")
	)
	(segment
		(start 304.515266 -29.21381)
		(end 304.049176 -29.539946)
		(width 0.1397)
		(layer "In2.Cu")
		(net "PCIE_RX_N9")
	)
	(segment
		(start 305.424586 -28.118562)
		(end 304.977038 -28.757372)
		(width 0.1397)
		(layer "In2.Cu")
		(net "PCIE_RX_N9")
	)
	(segment
		(start 309.503826 -18.46072)
		(end 309.479188 -18.436082)
		(width 0.1397)
		(layer "In2.Cu")
		(net "PCIE_RX_N9")
	)
	(segment
		(start 295.315894 -30.55493)
		(end 294.893238 -30.629606)
		(width 0.1397)
		(layer "In2.Cu")
		(net "PCIE_RX_N9")
	)
	(segment
		(start 280.28773 -30.52572)
		(end 280.020776 -30.712664)
		(width 0.1397)
		(layer "In2.Cu")
		(net "PCIE_RX_N9")
	)
	(segment
		(start 257.700018 -33.272984)
		(end 257.700018 -33.693862)
		(width 0.1016)
		(layer "In2.Cu")
		(net "PCIE_RX_N9")
	)
	(segment
		(start 294.03548 -30.780736)
		(end 289.51682 -29.984446)
		(width 0.1397)
		(layer "In2.Cu")
		(net "PCIE_RX_N9")
	)
	(segment
		(start 306.451 -22.014434)
		(end 305.66614 -23.135844)
		(width 0.1397)
		(layer "In2.Cu")
		(net "PCIE_RX_N9")
	)
	(segment
		(start 305.66614 -23.135844)
		(end 305.354228 -24.9047)
		(width 0.1397)
		(layer "In2.Cu")
		(net "PCIE_RX_N9")
	)
	(segment
		(start 294.668194 -30.66923)
		(end 294.03548 -30.780736)
		(width 0.1397)
		(layer "In2.Cu")
		(net "PCIE_RX_N9")
	)
	(segment
		(start 309.58028 -18.53692)
		(end 309.50408 -18.46072)
		(width 0.1397)
		(layer "In2.Cu")
		(net "PCIE_RX_N9")
	)
	(segment
		(start 289.51682 -29.984446)
		(end 287.411922 -30.343602)
		(width 0.1397)
		(layer "In2.Cu")
		(net "PCIE_RX_N9")
	)
	(segment
		(start 266.03071 -33.785302)
		(end 262.959088 -33.170876)
		(width 0.1397)
		(layer "In2.Cu")
		(net "PCIE_RX_N9")
	)
	(segment
		(start 287.411922 -30.343602)
		(end 284.367986 -29.806646)
		(width 0.1397)
		(layer "In2.Cu")
		(net "PCIE_RX_N9")
	)
	(segment
		(start 259.71119 -33.096962)
		(end 257.87604 -33.096962)
		(width 0.1016)
		(layer "In2.Cu")
		(net "PCIE_RX_N9")
	)
	(segment
		(start 310.584088 -18.77314)
		(end 310.107838 -18.77314)
		(width 0.1397)
		(layer "In2.Cu")
		(net "PCIE_RX_N9")
	)
	(segment
		(start 305.67249 -26.710386)
		(end 305.424586 -28.118562)
		(width 0.1397)
		(layer "In2.Cu")
		(net "PCIE_RX_N9")
	)
	(segment
		(start 301.188882 -30.044136)
		(end 298.274486 -29.530548)
		(width 0.1397)
		(layer "In2.Cu")
		(net "PCIE_RX_N9")
	)
	(segment
		(start 255.049274 -34.500058)
		(end 255.09982 -34.500058)
		(width 0.1016)
		(layer "In2.Cu")
		(net "PCIE_RX_N9")
	)
	(segment
		(start 259.785104 -33.170876)
		(end 259.71119 -33.096962)
		(width 0.1016)
		(layer "In2.Cu")
		(net "PCIE_RX_N9")
	)
	(segment
		(start 306.451 -18.5166)
		(end 306.451 -22.014434)
		(width 0.1397)
		(layer "In2.Cu")
		(net "PCIE_RX_N9")
	)
	(segment
		(start 309.22595 -17.974056)
		(end 308.356 -17.104106)
		(width 0.1397)
		(layer "In2.Cu")
		(net "PCIE_RX_N9")
	)
	(segment
		(start 309.50408 -18.46072)
		(end 309.503826 -18.46072)
		(width 0.1397)
		(layer "In2.Cu")
		(net "PCIE_RX_N9")
	)
	(segment
		(start 278.864568 -31.522162)
		(end 266.03071 -33.785302)
		(width 0.1397)
		(layer "In2.Cu")
		(net "PCIE_RX_N9")
	)
	(segment
		(start 294.893238 -30.629606)
		(end 294.668194 -30.66923)
		(width 0.1397)
		(layer "In2.Cu")
		(net "PCIE_RX_N9")
	)
	(segment
		(start 262.959088 -33.170876)
		(end 259.785104 -33.170876)
		(width 0.1397)
		(layer "In2.Cu")
		(net "PCIE_RX_N9")
	)
	(segment
		(start 308.356 -17.104106)
		(end 307.863494 -17.104106)
		(width 0.1397)
		(layer "In2.Cu")
		(net "PCIE_RX_N9")
	)
	(segment
		(start 298.274486 -29.530548)
		(end 296.27703 -29.882592)
		(width 0.1397)
		(layer "In2.Cu")
		(net "PCIE_RX_N9")
	)
	(segment
		(start 284.367986 -29.806646)
		(end 280.28773 -30.52572)
		(width 0.1397)
		(layer "In2.Cu")
		(net "PCIE_RX_N9")
	)
	(segment
		(start 257.291078 -34.102802)
		(end 255.049274 -34.102802)
		(width 0.1016)
		(layer "In2.Cu")
		(net "PCIE_RX_N9")
	)
	(segment
		(start 309.33263 -18.198084)
		(end 309.297324 -18.090134)
		(width 0.1397)
		(layer "In2.Cu")
		(net "PCIE_RX_N9")
	)
	(segment
		(start 280.020776 -30.712664)
		(end 278.864568 -31.522162)
		(width 0.1397)
		(layer "In2.Cu")
		(net "PCIE_RX_N9")
	)
	(segment
		(start 305.354228 -24.9047)
		(end 305.67249 -26.710386)
		(width 0.1397)
		(layer "In2.Cu")
		(net "PCIE_RX_N9")
	)
	(segment
		(start 304.977038 -28.757372)
		(end 304.515266 -29.21381)
		(width 0.1397)
		(layer "In2.Cu")
		(net "PCIE_RX_N9")
	)
	(segment
		(start 304.049176 -29.539946)
		(end 301.188882 -30.044136)
		(width 0.1397)
		(layer "In2.Cu")
		(net "PCIE_RX_N9")
	)
	(segment
		(start 307.863494 -17.104106)
		(end 306.451 -18.5166)
		(width 0.1397)
		(layer "In2.Cu")
		(net "PCIE_RX_N9")
	)
	(segment
		(start 309.609998 -18.566892)
		(end 309.58028 -18.53692)
		(width 0.1397)
		(layer "In2.Cu")
		(net "PCIE_RX_N9")
	)
	(segment
		(start 296.27703 -29.882592)
		(end 295.315894 -30.55493)
		(width 0.1397)
		(layer "In2.Cu")
		(net "PCIE_RX_N9")
	)
	(arc
		(start 311.134506 -16.330168)
		(mid 311.15084 -16.817169)
		(end 311.322974 -17.273016)
		(width 0.1397)
		(layer "In2.Cu")
		(net "PCIE_RX_N9")
	)
	(arc
		(start 257.87604 -33.096962)
		(mid 257.751574 -33.148518)
		(end 257.700018 -33.272984)
		(width 0.1016)
		(layer "In2.Cu")
		(net "PCIE_RX_N9")
	)
	(arc
		(start 309.297324 -18.090134)
		(mid 309.268477 -18.027888)
		(end 309.22595 -17.974056)
		(width 0.1397)
		(layer "In2.Cu")
		(net "PCIE_RX_N9")
	)
	(arc
		(start 311.339992 -18.25117)
		(mid 311.043435 -18.630026)
		(end 310.584088 -18.77314)
		(width 0.1397)
		(layer "In2.Cu")
		(net "PCIE_RX_N9")
	)
	(arc
		(start 309.45455 -18.40992)
		(mid 309.38268 -18.310284)
		(end 309.33263 -18.198084)
		(width 0.1397)
		(layer "In2.Cu")
		(net "PCIE_RX_N9")
	)
	(arc
		(start 255.049274 -34.102802)
		(mid 254.850646 -34.30143)
		(end 255.049274 -34.500058)
		(width 0.1016)
		(layer "In2.Cu")
		(net "PCIE_RX_N9")
	)
	(arc
		(start 310.107838 -18.77314)
		(mid 309.954822 -18.756306)
		(end 309.809134 -18.706592)
		(width 0.1397)
		(layer "In2.Cu")
		(net "PCIE_RX_N9")
	)
	(arc
		(start 257.700018 -33.693862)
		(mid 257.580242 -33.983026)
		(end 257.291078 -34.102802)
		(width 0.1016)
		(layer "In2.Cu")
		(net "PCIE_RX_N9")
	)
	(arc
		(start 311.434988 -17.657826)
		(mid 311.417537 -17.959311)
		(end 311.339992 -18.25117)
		(width 0.1397)
		(layer "In2.Cu")
		(net "PCIE_RX_N9")
	)
	(arc
		(start 309.809134 -18.706592)
		(mid 309.703494 -18.645397)
		(end 309.609998 -18.566892)
		(width 0.1397)
		(layer "In2.Cu")
		(net "PCIE_RX_N9")
	)
	(arc
		(start 311.322974 -17.273016)
		(mid 311.402318 -17.458628)
		(end 311.434988 -17.657826)
		(width 0.1397)
		(layer "In2.Cu")
		(net "PCIE_RX_N9")
	)
	(arc
		(start 309.479188 -18.436082)
		(mid 309.466673 -18.423186)
		(end 309.45455 -18.40992)
		(width 0.1397)
		(layer "In2.Cu")
		(net "PCIE_RX_N9")
	)
	(segment
		(start 232.599992 -29.99994)
		(end 232.10012 -29.500068)
		(width 0.136652)
		(layer "F.Cu")
		(net "PCIE_RX_N89")
	)
	(via
		(at 232.10012 -29.500068)
		(size 0.4572)
		(drill 0.2032)
		(layers "F.Cu" "B.Cu")
		(net "PCIE_RX_N89")
	)
	(segment
		(start 162.16757 -20.473416)
		(end 162.492436 -22.183344)
		(width 0.1397)
		(layer "In2.Cu")
		(net "PCIE_RX_N89")
	)
	(segment
		(start 211.317332 -31.08198)
		(end 214.387938 -28.932124)
		(width 0.1397)
		(layer "In2.Cu")
		(net "PCIE_RX_N89")
	)
	(segment
		(start 161.671 -19.6342)
		(end 162.16757 -20.473416)
		(width 0.1397)
		(layer "In2.Cu")
		(net "PCIE_RX_N89")
	)
	(segment
		(start 162.492436 -22.183344)
		(end 162.03168 -24.510238)
		(width 0.1397)
		(layer "In2.Cu")
		(net "PCIE_RX_N89")
	)
	(segment
		(start 179.30622 -33.173924)
		(end 182.614824 -32.512508)
		(width 0.1397)
		(layer "In2.Cu")
		(net "PCIE_RX_N89")
	)
	(segment
		(start 159.197548 -18.51406)
		(end 159.646366 -18.83791)
		(width 0.1397)
		(layer "In2.Cu")
		(net "PCIE_RX_N89")
	)
	(segment
		(start 159.646366 -18.83791)
		(end 161.0614 -19.1262)
		(width 0.1397)
		(layer "In2.Cu")
		(net "PCIE_RX_N89")
	)
	(segment
		(start 232.10012 -29.79674)
		(end 232.10012 -29.500068)
		(width 0.1016)
		(layer "In2.Cu")
		(net "PCIE_RX_N89")
	)
	(segment
		(start 177.09388 -32.78378)
		(end 179.30622 -33.173924)
		(width 0.1397)
		(layer "In2.Cu")
		(net "PCIE_RX_N89")
	)
	(segment
		(start 162.03168 -24.510238)
		(end 162.525456 -26.502868)
		(width 0.1397)
		(layer "In2.Cu")
		(net "PCIE_RX_N89")
	)
	(segment
		(start 158.365698 -17.405858)
		(end 158.707328 -17.747488)
		(width 0.1397)
		(layer "In2.Cu")
		(net "PCIE_RX_N89")
	)
	(segment
		(start 161.0614 -19.1262)
		(end 161.671 -19.6342)
		(width 0.1397)
		(layer "In2.Cu")
		(net "PCIE_RX_N89")
	)
	(segment
		(start 230.152448 -28.318968)
		(end 230.421688 -28.459176)
		(width 0.1397)
		(layer "In2.Cu")
		(net "PCIE_RX_N89")
	)
	(segment
		(start 230.468424 -28.548584)
		(end 230.70058 -28.669742)
		(width 0.1016)
		(layer "In2.Cu")
		(net "PCIE_RX_N89")
	)
	(segment
		(start 230.44404 -28.47086)
		(end 230.468424 -28.548584)
		(width 0.1016)
		(layer "In2.Cu")
		(net "PCIE_RX_N89")
	)
	(segment
		(start 162.84448 -26.95829)
		(end 169.553128 -31.430722)
		(width 0.1397)
		(layer "In2.Cu")
		(net "PCIE_RX_N89")
	)
	(segment
		(start 225.560382 -28.10637)
		(end 227.253292 -27.80792)
		(width 0.1397)
		(layer "In2.Cu")
		(net "PCIE_RX_N89")
	)
	(segment
		(start 187.809886 -31.724092)
		(end 193.65849 -32.967676)
		(width 0.1397)
		(layer "In2.Cu")
		(net "PCIE_RX_N89")
	)
	(segment
		(start 176.0982 -32.584898)
		(end 177.09388 -32.78378)
		(width 0.1397)
		(layer "In2.Cu")
		(net "PCIE_RX_N89")
	)
	(segment
		(start 193.65849 -32.967676)
		(end 198.232268 -31.99511)
		(width 0.1397)
		(layer "In2.Cu")
		(net "PCIE_RX_N89")
	)
	(segment
		(start 162.525456 -26.502868)
		(end 162.84448 -26.95829)
		(width 0.1397)
		(layer "In2.Cu")
		(net "PCIE_RX_N89")
	)
	(segment
		(start 231.007158 -28.976574)
		(end 231.007158 -29.36367)
		(width 0.1016)
		(layer "In2.Cu")
		(net "PCIE_RX_N89")
	)
	(segment
		(start 231.574594 -29.89834)
		(end 231.99852 -29.89834)
		(width 0.1016)
		(layer "In2.Cu")
		(net "PCIE_RX_N89")
	)
	(segment
		(start 169.553128 -31.430722)
		(end 176.0982 -32.584898)
		(width 0.1397)
		(layer "In2.Cu")
		(net "PCIE_RX_N89")
	)
	(segment
		(start 214.387938 -28.932124)
		(end 222.189548 -27.512264)
		(width 0.1397)
		(layer "In2.Cu")
		(net "PCIE_RX_N89")
	)
	(segment
		(start 230.421688 -28.459176)
		(end 230.44404 -28.47086)
		(width 0.1016)
		(layer "In2.Cu")
		(net "PCIE_RX_N89")
	)
	(segment
		(start 222.189548 -27.512264)
		(end 225.560382 -28.10637)
		(width 0.1397)
		(layer "In2.Cu")
		(net "PCIE_RX_N89")
	)
	(segment
		(start 230.70058 -28.669742)
		(end 231.007158 -28.976574)
		(width 0.1016)
		(layer "In2.Cu")
		(net "PCIE_RX_N89")
	)
	(segment
		(start 198.232268 -31.99511)
		(end 201.817224 -32.75711)
		(width 0.1397)
		(layer "In2.Cu")
		(net "PCIE_RX_N89")
	)
	(segment
		(start 201.817224 -32.75711)
		(end 211.317332 -31.08198)
		(width 0.1397)
		(layer "In2.Cu")
		(net "PCIE_RX_N89")
	)
	(segment
		(start 182.614824 -32.512508)
		(end 183.377078 -32.666178)
		(width 0.1397)
		(layer "In2.Cu")
		(net "PCIE_RX_N89")
	)
	(segment
		(start 158.707328 -17.747488)
		(end 159.197548 -18.51406)
		(width 0.1397)
		(layer "In2.Cu")
		(net "PCIE_RX_N89")
	)
	(segment
		(start 183.377078 -32.666178)
		(end 187.809886 -31.724092)
		(width 0.1397)
		(layer "In2.Cu")
		(net "PCIE_RX_N89")
	)
	(segment
		(start 227.253292 -27.80792)
		(end 230.152448 -28.318968)
		(width 0.1397)
		(layer "In2.Cu")
		(net "PCIE_RX_N89")
	)
	(arc
		(start 231.007158 -29.36367)
		(mid 231.046113 -29.55942)
		(end 231.157018 -29.725366)
		(width 0.1016)
		(layer "In2.Cu")
		(net "PCIE_RX_N89")
	)
	(arc
		(start 231.99852 -29.89834)
		(mid 232.070362 -29.868582)
		(end 232.10012 -29.79674)
		(width 0.1016)
		(layer "In2.Cu")
		(net "PCIE_RX_N89")
	)
	(arc
		(start 231.157018 -29.725366)
		(mid 231.348589 -29.853433)
		(end 231.574594 -29.89834)
		(width 0.1016)
		(layer "In2.Cu")
		(net "PCIE_RX_N89")
	)
	(arc
		(start 158.134558 -16.330168)
		(mid 158.091524 -16.902079)
		(end 158.365698 -17.405858)
		(width 0.1397)
		(layer "In2.Cu")
		(net "PCIE_RX_N89")
	)
	(segment
		(start 231.599994 -30.999938)
		(end 231.100122 -30.500066)
		(width 0.136652)
		(layer "F.Cu")
		(net "PCIE_RX_N88")
	)
	(via
		(at 231.100122 -30.500066)
		(size 0.4572)
		(drill 0.2032)
		(layers "F.Cu" "B.Cu")
		(net "PCIE_RX_N88")
	)
	(segment
		(start 232.588562 -27.912568)
		(end 232.582466 -28.001976)
		(width 0.1016)
		(layer "In2.Cu")
		(net "PCIE_RX_N88")
	)
	(segment
		(start 226.910392 -25.89149)
		(end 230.66883 -26.55443)
		(width 0.1397)
		(layer "In2.Cu")
		(net "PCIE_RX_N88")
	)
	(segment
		(start 158.858966 -14.573758)
		(end 159.042862 -14.662404)
		(width 0.1397)
		(layer "In2.Cu")
		(net "PCIE_RX_N88")
	)
	(segment
		(start 221.56674 -25.415748)
		(end 225.58756 -26.124662)
		(width 0.1397)
		(layer "In2.Cu")
		(net "PCIE_RX_N88")
	)
	(segment
		(start 159.414972 -14.80693)
		(end 161.074608 -15.305278)
		(width 0.1397)
		(layer "In2.Cu")
		(net "PCIE_RX_N88")
	)
	(segment
		(start 179.180998 -31.20009)
		(end 182.593742 -30.59811)
		(width 0.1397)
		(layer "In2.Cu")
		(net "PCIE_RX_N88")
	)
	(segment
		(start 231.100122 -30.661864)
		(end 231.100122 -30.500066)
		(width 0.1016)
		(layer "In2.Cu")
		(net "PCIE_RX_N88")
	)
	(segment
		(start 233.281728 -29.831538)
		(end 233.703622 -30.253432)
		(width 0.1016)
		(layer "In2.Cu")
		(net "PCIE_RX_N88")
	)
	(segment
		(start 233.058208 -28.544266)
		(end 233.281728 -29.10332)
		(width 0.1016)
		(layer "In2.Cu")
		(net "PCIE_RX_N88")
	)
	(segment
		(start 233.281728 -29.10332)
		(end 233.281728 -29.831538)
		(width 0.1016)
		(layer "In2.Cu")
		(net "PCIE_RX_N88")
	)
	(segment
		(start 225.58756 -26.124662)
		(end 226.910392 -25.89149)
		(width 0.1397)
		(layer "In2.Cu")
		(net "PCIE_RX_N88")
	)
	(segment
		(start 232.571544 -27.893264)
		(end 232.572052 -27.893518)
		(width 0.1397)
		(layer "In2.Cu")
		(net "PCIE_RX_N88")
	)
	(segment
		(start 187.420758 -29.975048)
		(end 188.462666 -29.791406)
		(width 0.1397)
		(layer "In2.Cu")
		(net "PCIE_RX_N88")
	)
	(segment
		(start 163.672774 -18.059908)
		(end 164.90696 -25.059132)
		(width 0.1397)
		(layer "In2.Cu")
		(net "PCIE_RX_N88")
	)
	(segment
		(start 233.703622 -30.253432)
		(end 233.703622 -31.572962)
		(width 0.1016)
		(layer "In2.Cu")
		(net "PCIE_RX_N88")
	)
	(segment
		(start 214.548212 -26.653236)
		(end 221.56674 -25.415748)
		(width 0.1397)
		(layer "In2.Cu")
		(net "PCIE_RX_N88")
	)
	(segment
		(start 166.21506 -26.927048)
		(end 170.006772 -29.582364)
		(width 0.1397)
		(layer "In2.Cu")
		(net "PCIE_RX_N88")
	)
	(segment
		(start 161.074608 -15.305278)
		(end 162.733736 -16.719296)
		(width 0.1397)
		(layer "In2.Cu")
		(net "PCIE_RX_N88")
	)
	(segment
		(start 232.461816 -27.768296)
		(end 232.571544 -27.893264)
		(width 0.1397)
		(layer "In2.Cu")
		(net "PCIE_RX_N88")
	)
	(segment
		(start 233.170984 -32.1056)
		(end 230.92156 -32.1056)
		(width 0.1016)
		(layer "In2.Cu")
		(net "PCIE_RX_N88")
	)
	(segment
		(start 162.757866 -16.753586)
		(end 162.757866 -16.75384)
		(width 0.1397)
		(layer "In2.Cu")
		(net "PCIE_RX_N88")
	)
	(segment
		(start 230.503984 -31.688024)
		(end 230.503984 -31.308294)
		(width 0.1016)
		(layer "In2.Cu")
		(net "PCIE_RX_N88")
	)
	(segment
		(start 192.63106 -30.526482)
		(end 198.40829 -29.507688)
		(width 0.1397)
		(layer "In2.Cu")
		(net "PCIE_RX_N88")
	)
	(segment
		(start 230.53929 -31.145988)
		(end 230.55453 -31.11246)
		(width 0.1016)
		(layer "In2.Cu")
		(net "PCIE_RX_N88")
	)
	(segment
		(start 170.006772 -29.582364)
		(end 179.180998 -31.20009)
		(width 0.1397)
		(layer "In2.Cu")
		(net "PCIE_RX_N88")
	)
	(segment
		(start 164.90696 -25.059132)
		(end 166.21506 -26.927048)
		(width 0.1397)
		(layer "In2.Cu")
		(net "PCIE_RX_N88")
	)
	(segment
		(start 162.733736 -16.719296)
		(end 162.757866 -16.753586)
		(width 0.1397)
		(layer "In2.Cu")
		(net "PCIE_RX_N88")
	)
	(segment
		(start 182.593742 -30.59811)
		(end 183.541416 -30.799532)
		(width 0.1397)
		(layer "In2.Cu")
		(net "PCIE_RX_N88")
	)
	(segment
		(start 198.40829 -29.507688)
		(end 204.507592 -30.583886)
		(width 0.1397)
		(layer "In2.Cu")
		(net "PCIE_RX_N88")
	)
	(segment
		(start 210.426554 -29.540454)
		(end 214.548212 -26.653236)
		(width 0.1397)
		(layer "In2.Cu")
		(net "PCIE_RX_N88")
	)
	(segment
		(start 204.507592 -30.583886)
		(end 210.426554 -29.540454)
		(width 0.1397)
		(layer "In2.Cu")
		(net "PCIE_RX_N88")
	)
	(segment
		(start 158.116524 -13.085064)
		(end 158.188406 -13.229082)
		(width 0.1397)
		(layer "In2.Cu")
		(net "PCIE_RX_N88")
	)
	(segment
		(start 232.572052 -27.893518)
		(end 232.588562 -27.912568)
		(width 0.1016)
		(layer "In2.Cu")
		(net "PCIE_RX_N88")
	)
	(segment
		(start 230.66883 -26.55443)
		(end 232.461816 -27.768296)
		(width 0.1397)
		(layer "In2.Cu")
		(net "PCIE_RX_N88")
	)
	(segment
		(start 162.757866 -16.75384)
		(end 163.672774 -18.059908)
		(width 0.1397)
		(layer "In2.Cu")
		(net "PCIE_RX_N88")
	)
	(segment
		(start 230.809546 -30.911292)
		(end 230.909876 -30.891988)
		(width 0.1016)
		(layer "In2.Cu")
		(net "PCIE_RX_N88")
	)
	(segment
		(start 188.462666 -29.791406)
		(end 192.63106 -30.526482)
		(width 0.1397)
		(layer "In2.Cu")
		(net "PCIE_RX_N88")
	)
	(segment
		(start 232.582466 -28.001976)
		(end 233.058208 -28.544266)
		(width 0.1016)
		(layer "In2.Cu")
		(net "PCIE_RX_N88")
	)
	(segment
		(start 183.541416 -30.799532)
		(end 187.420758 -29.975048)
		(width 0.1397)
		(layer "In2.Cu")
		(net "PCIE_RX_N88")
	)
	(arc
		(start 159.042862 -14.662404)
		(mid 159.226071 -14.741994)
		(end 159.414972 -14.80693)
		(width 0.1397)
		(layer "In2.Cu")
		(net "PCIE_RX_N88")
	)
	(arc
		(start 230.503984 -31.308294)
		(mid 230.512919 -31.225246)
		(end 230.53929 -31.145988)
		(width 0.1016)
		(layer "In2.Cu")
		(net "PCIE_RX_N88")
	)
	(arc
		(start 158.430976 -13.84681)
		(mid 158.531677 -14.276968)
		(end 158.858966 -14.573758)
		(width 0.1397)
		(layer "In2.Cu")
		(net "PCIE_RX_N88")
	)
	(arc
		(start 230.92156 -32.1056)
		(mid 230.626289 -31.983295)
		(end 230.503984 -31.688024)
		(width 0.1016)
		(layer "In2.Cu")
		(net "PCIE_RX_N88")
	)
	(arc
		(start 158.188406 -13.229082)
		(mid 158.235225 -13.31183)
		(end 158.29026 -13.389356)
		(width 0.1397)
		(layer "In2.Cu")
		(net "PCIE_RX_N88")
	)
	(arc
		(start 158.29026 -13.389356)
		(mid 158.403525 -13.604893)
		(end 158.430976 -13.84681)
		(width 0.1397)
		(layer "In2.Cu")
		(net "PCIE_RX_N88")
	)
	(arc
		(start 230.55453 -31.11246)
		(mid 230.657668 -30.980987)
		(end 230.809546 -30.911292)
		(width 0.1016)
		(layer "In2.Cu")
		(net "PCIE_RX_N88")
	)
	(arc
		(start 158.134558 -12.530074)
		(mid 158.055376 -12.805283)
		(end 158.116524 -13.085064)
		(width 0.1397)
		(layer "In2.Cu")
		(net "PCIE_RX_N88")
	)
	(arc
		(start 230.909876 -30.891988)
		(mid 231.046423 -30.81114)
		(end 231.100122 -30.661864)
		(width 0.1016)
		(layer "In2.Cu")
		(net "PCIE_RX_N88")
	)
	(arc
		(start 233.703622 -31.572962)
		(mid 233.547616 -31.949594)
		(end 233.170984 -32.1056)
		(width 0.1016)
		(layer "In2.Cu")
		(net "PCIE_RX_N88")
	)
	(segment
		(start 225.600006 -33.999932)
		(end 225.100134 -33.50006)
		(width 0.136652)
		(layer "F.Cu")
		(net "PCIE_RX_N87")
	)
	(via
		(at 225.100134 -33.50006)
		(size 0.4572)
		(drill 0.2032)
		(layers "F.Cu" "B.Cu")
		(net "PCIE_RX_N87")
	)
	(segment
		(start 154.28849 -26.518616)
		(end 155.03779 -27.588972)
		(width 0.1397)
		(layer "In2.Cu")
		(net "PCIE_RX_N87")
	)
	(segment
		(start 221.408752 -33.10636)
		(end 225.080068 -33.10636)
		(width 0.1016)
		(layer "In2.Cu")
		(net "PCIE_RX_N87")
	)
	(segment
		(start 221.319852 -33.16986)
		(end 221.345252 -33.16986)
		(width 0.1016)
		(layer "In2.Cu")
		(net "PCIE_RX_N87")
	)
	(segment
		(start 198.589392 -33.593786)
		(end 201.478388 -34.18205)
		(width 0.1397)
		(layer "In2.Cu")
		(net "PCIE_RX_N87")
	)
	(segment
		(start 165.431978 -30.470094)
		(end 168.739058 -32.617664)
		(width 0.1397)
		(layer "In2.Cu")
		(net "PCIE_RX_N87")
	)
	(segment
		(start 219.206064 -33.165034)
		(end 219.21089 -33.16986)
		(width 0.1397)
		(layer "In2.Cu")
		(net "PCIE_RX_N87")
	)
	(segment
		(start 155.03779 -27.588972)
		(end 156.012134 -28.270962)
		(width 0.1397)
		(layer "In2.Cu")
		(net "PCIE_RX_N87")
	)
	(segment
		(start 213.226396 -32.110172)
		(end 219.206064 -33.165034)
		(width 0.1397)
		(layer "In2.Cu")
		(net "PCIE_RX_N87")
	)
	(segment
		(start 201.478388 -34.18205)
		(end 213.226396 -32.110172)
		(width 0.1397)
		(layer "In2.Cu")
		(net "PCIE_RX_N87")
	)
	(segment
		(start 182.499254 -33.870138)
		(end 183.237378 -34.02711)
		(width 0.1397)
		(layer "In2.Cu")
		(net "PCIE_RX_N87")
	)
	(segment
		(start 148.622004 -12.343638)
		(end 149.827742 -10.964672)
		(width 0.1397)
		(layer "In2.Cu")
		(net "PCIE_RX_N87")
	)
	(segment
		(start 149.384512 -12.530074)
		(end 149.468332 -12.765532)
		(width 0.1397)
		(layer "In2.Cu")
		(net "PCIE_RX_N87")
	)
	(segment
		(start 153.4541 -17.897094)
		(end 154.1145 -21.6408)
		(width 0.1397)
		(layer "In2.Cu")
		(net "PCIE_RX_N87")
	)
	(segment
		(start 225.408236 -33.163764)
		(end 225.467164 -33.187386)
		(width 0.1016)
		(layer "In2.Cu")
		(net "PCIE_RX_N87")
	)
	(segment
		(start 153.8478 -25.1714)
		(end 154.28849 -26.518616)
		(width 0.1397)
		(layer "In2.Cu")
		(net "PCIE_RX_N87")
	)
	(segment
		(start 183.237378 -34.02711)
		(end 185.374534 -33.650174)
		(width 0.1397)
		(layer "In2.Cu")
		(net "PCIE_RX_N87")
	)
	(segment
		(start 154.1145 -21.6408)
		(end 154.1145 -22.0726)
		(width 0.1397)
		(layer "In2.Cu")
		(net "PCIE_RX_N87")
	)
	(segment
		(start 153.879296 -23.405846)
		(end 153.8478 -25.1714)
		(width 0.1397)
		(layer "In2.Cu")
		(net "PCIE_RX_N87")
	)
	(segment
		(start 193.838068 -34.43097)
		(end 198.589392 -33.593786)
		(width 0.1397)
		(layer "In2.Cu")
		(net "PCIE_RX_N87")
	)
	(segment
		(start 185.374534 -33.650174)
		(end 187.39104 -33.294574)
		(width 0.1397)
		(layer "In2.Cu")
		(net "PCIE_RX_N87")
	)
	(segment
		(start 152.284684 -16.023336)
		(end 153.4541 -17.897094)
		(width 0.1397)
		(layer "In2.Cu")
		(net "PCIE_RX_N87")
	)
	(segment
		(start 154.1145 -22.0726)
		(end 153.879296 -23.405846)
		(width 0.1397)
		(layer "In2.Cu")
		(net "PCIE_RX_N87")
	)
	(segment
		(start 221.345252 -33.16986)
		(end 221.408752 -33.10636)
		(width 0.1016)
		(layer "In2.Cu")
		(net "PCIE_RX_N87")
	)
	(segment
		(start 168.739058 -32.617664)
		(end 175.939704 -33.88741)
		(width 0.1397)
		(layer "In2.Cu")
		(net "PCIE_RX_N87")
	)
	(segment
		(start 225.309684 -33.583372)
		(end 225.100134 -33.50006)
		(width 0.1016)
		(layer "In2.Cu")
		(net "PCIE_RX_N87")
	)
	(segment
		(start 156.012134 -28.270962)
		(end 156.984446 -28.67406)
		(width 0.1397)
		(layer "In2.Cu")
		(net "PCIE_RX_N87")
	)
	(segment
		(start 175.939704 -33.88741)
		(end 179.175664 -34.534602)
		(width 0.1397)
		(layer "In2.Cu")
		(net "PCIE_RX_N87")
	)
	(segment
		(start 187.39104 -33.294574)
		(end 193.838068 -34.43097)
		(width 0.1397)
		(layer "In2.Cu")
		(net "PCIE_RX_N87")
	)
	(segment
		(start 151.41575 -13.977874)
		(end 151.669496 -14.794484)
		(width 0.1397)
		(layer "In2.Cu")
		(net "PCIE_RX_N87")
	)
	(segment
		(start 148.76653 -13.015214)
		(end 148.76653 -13.01496)
		(width 0.1397)
		(layer "In2.Cu")
		(net "PCIE_RX_N87")
	)
	(segment
		(start 219.21089 -33.16986)
		(end 221.319852 -33.16986)
		(width 0.1397)
		(layer "In2.Cu")
		(net "PCIE_RX_N87")
	)
	(segment
		(start 179.175664 -34.534602)
		(end 182.499254 -33.870138)
		(width 0.1397)
		(layer "In2.Cu")
		(net "PCIE_RX_N87")
	)
	(segment
		(start 156.984446 -28.67406)
		(end 165.431978 -30.470094)
		(width 0.1397)
		(layer "In2.Cu")
		(net "PCIE_RX_N87")
	)
	(arc
		(start 225.080068 -33.10636)
		(mid 225.246643 -33.120819)
		(end 225.408236 -33.163764)
		(width 0.1016)
		(layer "In2.Cu")
		(net "PCIE_RX_N87")
	)
	(arc
		(start 149.468332 -12.765532)
		(mid 149.242373 -13.241328)
		(end 148.76653 -13.015214)
		(width 0.1397)
		(layer "In2.Cu")
		(net "PCIE_RX_N87")
	)
	(arc
		(start 148.76653 -13.01496)
		(mid 148.696193 -12.840225)
		(end 148.611844 -12.671806)
		(width 0.1397)
		(layer "In2.Cu")
		(net "PCIE_RX_N87")
	)
	(arc
		(start 150.740364 -11.310874)
		(mid 151.042179 -12.65346)
		(end 151.41575 -13.977874)
		(width 0.1397)
		(layer "In2.Cu")
		(net "PCIE_RX_N87")
	)
	(arc
		(start 149.827742 -10.964672)
		(mid 150.380151 -10.884385)
		(end 150.740364 -11.310874)
		(width 0.1397)
		(layer "In2.Cu")
		(net "PCIE_RX_N87")
	)
	(arc
		(start 151.669496 -14.794484)
		(mid 151.926709 -15.434134)
		(end 152.284684 -16.023336)
		(width 0.1397)
		(layer "In2.Cu")
		(net "PCIE_RX_N87")
	)
	(arc
		(start 225.467164 -33.187386)
		(mid 225.586527 -33.46429)
		(end 225.309684 -33.583372)
		(width 0.1016)
		(layer "In2.Cu")
		(net "PCIE_RX_N87")
	)
	(arc
		(start 148.611844 -12.671806)
		(mid 148.571892 -12.50634)
		(end 148.622004 -12.343638)
		(width 0.1397)
		(layer "In2.Cu")
		(net "PCIE_RX_N87")
	)
	(segment
		(start 226.600004 -34.99993)
		(end 226.100132 -34.500058)
		(width 0.136652)
		(layer "F.Cu")
		(net "PCIE_RX_N86")
	)
	(via
		(at 226.100132 -34.500058)
		(size 0.4572)
		(drill 0.2032)
		(layers "F.Cu" "B.Cu")
		(net "PCIE_RX_N86")
	)
	(segment
		(start 164.629338 -31.774638)
		(end 168.38803 -34.215324)
		(width 0.1397)
		(layer "In2.Cu")
		(net "PCIE_RX_N86")
	)
	(segment
		(start 183.255158 -35.738308)
		(end 187.329826 -35.019996)
		(width 0.1397)
		(layer "In2.Cu")
		(net "PCIE_RX_N86")
	)
	(segment
		(start 149.219666 -16.728186)
		(end 149.219666 -16.903446)
		(width 0.1397)
		(layer "In2.Cu")
		(net "PCIE_RX_N86")
	)
	(segment
		(start 221.35592 -34.836354)
		(end 221.38132 -34.836354)
		(width 0.1016)
		(layer "In2.Cu")
		(net "PCIE_RX_N86")
	)
	(segment
		(start 196.15531 -36.781994)
		(end 212.977476 -33.81502)
		(width 0.1397)
		(layer "In2.Cu")
		(net "PCIE_RX_N86")
	)
	(segment
		(start 152.433274 -22.604222)
		(end 152.203912 -23.902924)
		(width 0.1397)
		(layer "In2.Cu")
		(net "PCIE_RX_N86")
	)
	(segment
		(start 149.79396 -17.59204)
		(end 151.92502 -19.722846)
		(width 0.1397)
		(layer "In2.Cu")
		(net "PCIE_RX_N86")
	)
	(segment
		(start 149.358096 -17.23771)
		(end 149.563328 -17.442688)
		(width 0.1397)
		(layer "In2.Cu")
		(net "PCIE_RX_N86")
	)
	(segment
		(start 153.721054 -28.598114)
		(end 155.479496 -29.828998)
		(width 0.1397)
		(layer "In2.Cu")
		(net "PCIE_RX_N86")
	)
	(segment
		(start 155.479496 -29.828998)
		(end 164.629338 -31.774638)
		(width 0.1397)
		(layer "In2.Cu")
		(net "PCIE_RX_N86")
	)
	(segment
		(start 226.496626 -34.77895)
		(end 226.496626 -34.67735)
		(width 0.1016)
		(layer "In2.Cu")
		(net "PCIE_RX_N86")
	)
	(segment
		(start 221.44482 -34.899854)
		(end 226.375722 -34.899854)
		(width 0.1016)
		(layer "In2.Cu")
		(net "PCIE_RX_N86")
	)
	(segment
		(start 151.92502 -19.722846)
		(end 152.433274 -22.604222)
		(width 0.1397)
		(layer "In2.Cu")
		(net "PCIE_RX_N86")
	)
	(segment
		(start 168.38803 -34.215324)
		(end 176.000664 -35.55746)
		(width 0.1397)
		(layer "In2.Cu")
		(net "PCIE_RX_N86")
	)
	(segment
		(start 226.283012 -34.500058)
		(end 226.100132 -34.500058)
		(width 0.1016)
		(layer "In2.Cu")
		(net "PCIE_RX_N86")
	)
	(segment
		(start 221.38132 -34.836354)
		(end 221.44482 -34.899854)
		(width 0.1016)
		(layer "In2.Cu")
		(net "PCIE_RX_N86")
	)
	(segment
		(start 218.770708 -34.836354)
		(end 221.35592 -34.836354)
		(width 0.1397)
		(layer "In2.Cu")
		(net "PCIE_RX_N86")
	)
	(segment
		(start 152.799542 -27.281378)
		(end 153.721054 -28.598114)
		(width 0.1397)
		(layer "In2.Cu")
		(net "PCIE_RX_N86")
	)
	(segment
		(start 179.175664 -36.19246)
		(end 182.350664 -35.55746)
		(width 0.1397)
		(layer "In2.Cu")
		(net "PCIE_RX_N86")
	)
	(segment
		(start 212.977476 -33.81502)
		(end 218.770708 -34.836354)
		(width 0.1397)
		(layer "In2.Cu")
		(net "PCIE_RX_N86")
	)
	(segment
		(start 182.350664 -35.55746)
		(end 183.255158 -35.738308)
		(width 0.1397)
		(layer "In2.Cu")
		(net "PCIE_RX_N86")
	)
	(segment
		(start 176.000664 -35.55746)
		(end 179.175664 -36.19246)
		(width 0.1397)
		(layer "In2.Cu")
		(net "PCIE_RX_N86")
	)
	(segment
		(start 152.203912 -23.902924)
		(end 152.799542 -27.281378)
		(width 0.1397)
		(layer "In2.Cu")
		(net "PCIE_RX_N86")
	)
	(segment
		(start 187.329826 -35.019996)
		(end 196.15531 -36.781994)
		(width 0.1397)
		(layer "In2.Cu")
		(net "PCIE_RX_N86")
	)
	(arc
		(start 226.496626 -34.67735)
		(mid 226.474279 -34.615692)
		(end 226.435158 -34.56305)
		(width 0.1016)
		(layer "In2.Cu")
		(net "PCIE_RX_N86")
	)
	(arc
		(start 149.219666 -16.903446)
		(mid 149.255648 -17.084338)
		(end 149.358096 -17.23771)
		(width 0.1397)
		(layer "In2.Cu")
		(net "PCIE_RX_N86")
	)
	(arc
		(start 226.435158 -34.56305)
		(mid 226.365353 -34.516408)
		(end 226.283012 -34.500058)
		(width 0.1016)
		(layer "In2.Cu")
		(net "PCIE_RX_N86")
	)
	(arc
		(start 226.375722 -34.899854)
		(mid 226.461214 -34.864442)
		(end 226.496626 -34.77895)
		(width 0.1016)
		(layer "In2.Cu")
		(net "PCIE_RX_N86")
	)
	(arc
		(start 149.384512 -16.330168)
		(mid 149.262494 -16.51278)
		(end 149.219666 -16.728186)
		(width 0.1397)
		(layer "In2.Cu")
		(net "PCIE_RX_N86")
	)
	(arc
		(start 149.563328 -17.442688)
		(mid 149.563582 -17.442815)
		(end 149.563836 -17.442942)
		(width 0.1397)
		(layer "In2.Cu")
		(net "PCIE_RX_N86")
	)
	(arc
		(start 149.563836 -17.442942)
		(mid 149.686756 -17.505361)
		(end 149.79396 -17.59204)
		(width 0.1397)
		(layer "In2.Cu")
		(net "PCIE_RX_N86")
	)
	(segment
		(start 225.600006 -35.999928)
		(end 225.100134 -35.500056)
		(width 0.136652)
		(layer "F.Cu")
		(net "PCIE_RX_N85")
	)
	(via
		(at 225.100134 -35.500056)
		(size 0.4572)
		(drill 0.2032)
		(layers "F.Cu" "B.Cu")
		(net "PCIE_RX_N85")
	)
	(segment
		(start 164.475922 -38.069012)
		(end 163.817046 -39.083488)
		(width 0.1397)
		(layer "In2.Cu")
		(net "PCIE_RX_N85")
	)
	(segment
		(start 179.198524 -37.185346)
		(end 167.642794 -34.873184)
		(width 0.1397)
		(layer "In2.Cu")
		(net "PCIE_RX_N85")
	)
	(segment
		(start 167.642794 -34.873184)
		(end 166.128192 -35.195256)
		(width 0.1397)
		(layer "In2.Cu")
		(net "PCIE_RX_N85")
	)
	(segment
		(start 225.498406 -35.601656)
		(end 225.498406 -35.703256)
		(width 0.1016)
		(layer "In2.Cu")
		(net "PCIE_RX_N85")
	)
	(segment
		(start 225.100134 -35.500056)
		(end 225.396806 -35.500056)
		(width 0.1016)
		(layer "In2.Cu")
		(net "PCIE_RX_N85")
	)
	(segment
		(start 225.306636 -35.895026)
		(end 221.392496 -35.895026)
		(width 0.1016)
		(layer "In2.Cu")
		(net "PCIE_RX_N85")
	)
	(segment
		(start 204.30109 -36.283392)
		(end 195.961508 -37.95141)
		(width 0.1397)
		(layer "In2.Cu")
		(net "PCIE_RX_N85")
	)
	(segment
		(start 151.86914 -28.14447)
		(end 151.152606 -24.074628)
		(width 0.1397)
		(layer "In2.Cu")
		(net "PCIE_RX_N85")
	)
	(segment
		(start 161.37128 -39.38778)
		(end 158.06928 -37.244274)
		(width 0.1397)
		(layer "In2.Cu")
		(net "PCIE_RX_N85")
	)
	(segment
		(start 195.961508 -37.95141)
		(end 186.782964 -36.115498)
		(width 0.1397)
		(layer "In2.Cu")
		(net "PCIE_RX_N85")
	)
	(segment
		(start 221.303596 -35.831526)
		(end 218.504262 -35.831526)
		(width 0.1397)
		(layer "In2.Cu")
		(net "PCIE_RX_N85")
	)
	(segment
		(start 158.06928 -37.244274)
		(end 157.656784 -36.60902)
		(width 0.1397)
		(layer "In2.Cu")
		(net "PCIE_RX_N85")
	)
	(segment
		(start 165.247574 -35.76701)
		(end 164.827966 -36.412932)
		(width 0.1397)
		(layer "In2.Cu")
		(net "PCIE_RX_N85")
	)
	(segment
		(start 156.76626 -32.419544)
		(end 155.914598 -31.107888)
		(width 0.1397)
		(layer "In2.Cu")
		(net "PCIE_RX_N85")
	)
	(segment
		(start 163.817046 -39.083488)
		(end 163.469066 -39.309548)
		(width 0.1397)
		(layer "In2.Cu")
		(net "PCIE_RX_N85")
	)
	(segment
		(start 186.782964 -36.115498)
		(end 183.467756 -36.778438)
		(width 0.1397)
		(layer "In2.Cu")
		(net "PCIE_RX_N85")
	)
	(segment
		(start 166.128192 -35.195256)
		(end 165.247574 -35.76701)
		(width 0.1397)
		(layer "In2.Cu")
		(net "PCIE_RX_N85")
	)
	(segment
		(start 221.392496 -35.895026)
		(end 221.328996 -35.831526)
		(width 0.1016)
		(layer "In2.Cu")
		(net "PCIE_RX_N85")
	)
	(segment
		(start 218.504262 -35.831526)
		(end 212.68309 -34.805112)
		(width 0.1397)
		(layer "In2.Cu")
		(net "PCIE_RX_N85")
	)
	(segment
		(start 212.68309 -34.805112)
		(end 204.30109 -36.283392)
		(width 0.1397)
		(layer "In2.Cu")
		(net "PCIE_RX_N85")
	)
	(segment
		(start 182.350664 -36.554918)
		(end 179.198524 -37.185346)
		(width 0.1397)
		(layer "In2.Cu")
		(net "PCIE_RX_N85")
	)
	(segment
		(start 151.423624 -22.538182)
		(end 151.039576 -20.360132)
		(width 0.1397)
		(layer "In2.Cu")
		(net "PCIE_RX_N85")
	)
	(segment
		(start 163.469066 -39.309548)
		(end 162.235642 -39.571676)
		(width 0.1397)
		(layer "In2.Cu")
		(net "PCIE_RX_N85")
	)
	(segment
		(start 148.535898 -18.573242)
		(end 147.995894 -18.222722)
		(width 0.1397)
		(layer "In2.Cu")
		(net "PCIE_RX_N85")
	)
	(segment
		(start 147.618704 -17.633696)
		(end 147.466558 -17.48155)
		(width 0.1397)
		(layer "In2.Cu")
		(net "PCIE_RX_N85")
	)
	(segment
		(start 151.039576 -20.360132)
		(end 150.855934 -19.868642)
		(width 0.1397)
		(layer "In2.Cu")
		(net "PCIE_RX_N85")
	)
	(segment
		(start 147.466558 -17.48155)
		(end 147.466812 -17.481296)
		(width 0.1397)
		(layer "In2.Cu")
		(net "PCIE_RX_N85")
	)
	(segment
		(start 147.995894 -18.222722)
		(end 147.618704 -17.633696)
		(width 0.1397)
		(layer "In2.Cu")
		(net "PCIE_RX_N85")
	)
	(segment
		(start 151.152606 -24.074628)
		(end 151.423624 -22.538182)
		(width 0.1397)
		(layer "In2.Cu")
		(net "PCIE_RX_N85")
	)
	(segment
		(start 183.467756 -36.778438)
		(end 182.350664 -36.554918)
		(width 0.1397)
		(layer "In2.Cu")
		(net "PCIE_RX_N85")
	)
	(segment
		(start 155.914598 -31.107888)
		(end 152.21839 -28.645358)
		(width 0.1397)
		(layer "In2.Cu")
		(net "PCIE_RX_N85")
	)
	(segment
		(start 221.328996 -35.831526)
		(end 221.303596 -35.831526)
		(width 0.1016)
		(layer "In2.Cu")
		(net "PCIE_RX_N85")
	)
	(segment
		(start 150.855934 -19.868642)
		(end 150.1902 -19.1262)
		(width 0.1397)
		(layer "In2.Cu")
		(net "PCIE_RX_N85")
	)
	(segment
		(start 150.1902 -19.1262)
		(end 148.535898 -18.573242)
		(width 0.1397)
		(layer "In2.Cu")
		(net "PCIE_RX_N85")
	)
	(segment
		(start 162.235642 -39.571676)
		(end 161.37128 -39.38778)
		(width 0.1397)
		(layer "In2.Cu")
		(net "PCIE_RX_N85")
	)
	(segment
		(start 164.827966 -36.412932)
		(end 164.475922 -38.069012)
		(width 0.1397)
		(layer "In2.Cu")
		(net "PCIE_RX_N85")
	)
	(segment
		(start 152.21839 -28.645358)
		(end 151.86914 -28.14447)
		(width 0.1397)
		(layer "In2.Cu")
		(net "PCIE_RX_N85")
	)
	(segment
		(start 157.656784 -36.60902)
		(end 156.76626 -32.419544)
		(width 0.1397)
		(layer "In2.Cu")
		(net "PCIE_RX_N85")
	)
	(segment
		(start 147.466812 -17.481296)
		(end 146.969988 -16.984472)
		(width 0.1397)
		(layer "In2.Cu")
		(net "PCIE_RX_N85")
	)
	(arc
		(start 146.969988 -16.984472)
		(mid 146.866741 -16.610809)
		(end 147.134326 -16.330168)
		(width 0.1397)
		(layer "In2.Cu")
		(net "PCIE_RX_N85")
	)
	(arc
		(start 225.498406 -35.703256)
		(mid 225.442238 -35.838858)
		(end 225.306636 -35.895026)
		(width 0.1016)
		(layer "In2.Cu")
		(net "PCIE_RX_N85")
	)
	(arc
		(start 225.396806 -35.500056)
		(mid 225.468648 -35.529814)
		(end 225.498406 -35.601656)
		(width 0.1016)
		(layer "In2.Cu")
		(net "PCIE_RX_N85")
	)
	(segment
		(start 226.600004 -36.999926)
		(end 226.100132 -36.500054)
		(width 0.136652)
		(layer "F.Cu")
		(net "PCIE_RX_N84")
	)
	(via
		(at 226.100132 -36.500054)
		(size 0.4572)
		(drill 0.2032)
		(layers "F.Cu" "B.Cu")
		(net "PCIE_RX_N84")
	)
	(segment
		(start 227.277422 -34.106358)
		(end 227.500942 -34.329878)
		(width 0.1016)
		(layer "In2.Cu")
		(net "PCIE_RX_N84")
	)
	(segment
		(start 213.058502 -33.12287)
		(end 219.05595 -34.180526)
		(width 0.1397)
		(layer "In2.Cu")
		(net "PCIE_RX_N84")
	)
	(segment
		(start 165.208204 -31.364174)
		(end 168.65092 -33.599628)
		(width 0.1397)
		(layer "In2.Cu")
		(net "PCIE_RX_N84")
	)
	(segment
		(start 227.500942 -35.764978)
		(end 227.366068 -35.899852)
		(width 0.1016)
		(layer "In2.Cu")
		(net "PCIE_RX_N84")
	)
	(segment
		(start 196.385688 -36.06292)
		(end 213.058502 -33.12287)
		(width 0.1397)
		(layer "In2.Cu")
		(net "PCIE_RX_N84")
	)
	(segment
		(start 168.65092 -33.599628)
		(end 175.939704 -34.884868)
		(width 0.1397)
		(layer "In2.Cu")
		(net "PCIE_RX_N84")
	)
	(segment
		(start 154.494484 -28.401518)
		(end 156.063442 -29.420566)
		(width 0.1397)
		(layer "In2.Cu")
		(net "PCIE_RX_N84")
	)
	(segment
		(start 153.0096 -21.540724)
		(end 153.0096 -25.276556)
		(width 0.1397)
		(layer "In2.Cu")
		(net "PCIE_RX_N84")
	)
	(segment
		(start 156.063442 -29.420566)
		(end 165.208204 -31.364174)
		(width 0.1397)
		(layer "In2.Cu")
		(net "PCIE_RX_N84")
	)
	(segment
		(start 175.939704 -34.884868)
		(end 179.175664 -35.53206)
		(width 0.1397)
		(layer "In2.Cu")
		(net "PCIE_RX_N84")
	)
	(segment
		(start 143.602202 -11.540998)
		(end 143.24584 -11.89736)
		(width 0.1397)
		(layer "In2.Cu")
		(net "PCIE_RX_N84")
	)
	(segment
		(start 226.396804 -36.500054)
		(end 226.100132 -36.500054)
		(width 0.1016)
		(layer "In2.Cu")
		(net "PCIE_RX_N84")
	)
	(segment
		(start 153.0096 -25.276556)
		(end 153.246074 -26.618946)
		(width 0.1397)
		(layer "In2.Cu")
		(net "PCIE_RX_N84")
	)
	(segment
		(start 149.873716 -15.71498)
		(end 150.699216 -16.54048)
		(width 0.1397)
		(layer "In2.Cu")
		(net "PCIE_RX_N84")
	)
	(segment
		(start 227.500942 -34.329878)
		(end 227.500942 -35.764978)
		(width 0.1016)
		(layer "In2.Cu")
		(net "PCIE_RX_N84")
	)
	(segment
		(start 142.6718 -13.283946)
		(end 142.6718 -13.847826)
		(width 0.1397)
		(layer "In2.Cu")
		(net "PCIE_RX_N84")
	)
	(segment
		(start 221.323154 -34.106358)
		(end 227.277422 -34.106358)
		(width 0.1016)
		(layer "In2.Cu")
		(net "PCIE_RX_N84")
	)
	(segment
		(start 153.246074 -26.618946)
		(end 154.494484 -28.401518)
		(width 0.1397)
		(layer "In2.Cu")
		(net "PCIE_RX_N84")
	)
	(segment
		(start 144.627854 -11.2014)
		(end 144.4244 -11.2014)
		(width 0.1397)
		(layer "In2.Cu")
		(net "PCIE_RX_N84")
	)
	(segment
		(start 150.699216 -16.54048)
		(end 150.71852 -16.567912)
		(width 0.1397)
		(layer "In2.Cu")
		(net "PCIE_RX_N84")
	)
	(segment
		(start 182.350664 -34.89706)
		(end 183.147716 -35.056572)
		(width 0.1397)
		(layer "In2.Cu")
		(net "PCIE_RX_N84")
	)
	(segment
		(start 227.366068 -35.899852)
		(end 226.839018 -35.899852)
		(width 0.1016)
		(layer "In2.Cu")
		(net "PCIE_RX_N84")
	)
	(segment
		(start 179.175664 -35.53206)
		(end 182.350664 -34.89706)
		(width 0.1397)
		(layer "In2.Cu")
		(net "PCIE_RX_N84")
	)
	(segment
		(start 226.498404 -36.240466)
		(end 226.498404 -36.398454)
		(width 0.1016)
		(layer "In2.Cu")
		(net "PCIE_RX_N84")
	)
	(segment
		(start 144.27708 -15.4178)
		(end 149.09546 -15.392654)
		(width 0.1397)
		(layer "In2.Cu")
		(net "PCIE_RX_N84")
	)
	(segment
		(start 151.264874 -17.01546)
		(end 152.530302 -18.822416)
		(width 0.1397)
		(layer "In2.Cu")
		(net "PCIE_RX_N84")
	)
	(segment
		(start 152.530302 -18.822416)
		(end 153.0096 -21.540724)
		(width 0.1397)
		(layer "In2.Cu")
		(net "PCIE_RX_N84")
	)
	(segment
		(start 150.71852 -16.567912)
		(end 151.264874 -17.01546)
		(width 0.1397)
		(layer "In2.Cu")
		(net "PCIE_RX_N84")
	)
	(segment
		(start 219.05595 -34.180526)
		(end 221.248986 -34.180526)
		(width 0.1397)
		(layer "In2.Cu")
		(net "PCIE_RX_N84")
	)
	(segment
		(start 221.248986 -34.180526)
		(end 221.323154 -34.106358)
		(width 0.1016)
		(layer "In2.Cu")
		(net "PCIE_RX_N84")
	)
	(segment
		(start 187.508388 -34.287714)
		(end 196.385688 -36.06292)
		(width 0.1397)
		(layer "In2.Cu")
		(net "PCIE_RX_N84")
	)
	(segment
		(start 183.147716 -35.056572)
		(end 187.508388 -34.287714)
		(width 0.1397)
		(layer "In2.Cu")
		(net "PCIE_RX_N84")
	)
	(segment
		(start 146.252438 -12.44092)
		(end 145.28546 -11.473942)
		(width 0.1397)
		(layer "In2.Cu")
		(net "PCIE_RX_N84")
	)
	(arc
		(start 145.28546 -11.473942)
		(mid 145.16744 -11.374068)
		(end 145.034508 -11.295126)
		(width 0.1397)
		(layer "In2.Cu")
		(net "PCIE_RX_N84")
	)
	(arc
		(start 144.4244 -11.2014)
		(mid 144.24801 -11.214674)
		(end 144.075658 -11.254486)
		(width 0.1397)
		(layer "In2.Cu")
		(net "PCIE_RX_N84")
	)
	(arc
		(start 147.134326 -12.530074)
		(mid 146.797831 -12.646688)
		(end 146.448018 -12.579858)
		(width 0.1397)
		(layer "In2.Cu")
		(net "PCIE_RX_N84")
	)
	(arc
		(start 149.09546 -15.392654)
		(mid 149.516634 -15.476431)
		(end 149.873716 -15.71498)
		(width 0.1397)
		(layer "In2.Cu")
		(net "PCIE_RX_N84")
	)
	(arc
		(start 143.24584 -11.89736)
		(mid 142.974235 -12.237348)
		(end 142.784322 -12.62888)
		(width 0.1397)
		(layer "In2.Cu")
		(net "PCIE_RX_N84")
	)
	(arc
		(start 146.448018 -12.579858)
		(mid 146.344386 -12.51861)
		(end 146.252438 -12.44092)
		(width 0.1397)
		(layer "In2.Cu")
		(net "PCIE_RX_N84")
	)
	(arc
		(start 142.6718 -13.847826)
		(mid 142.789208 -14.439016)
		(end 143.12392 -14.94028)
		(width 0.1397)
		(layer "In2.Cu")
		(net "PCIE_RX_N84")
	)
	(arc
		(start 143.12392 -14.94028)
		(mid 143.653023 -15.293689)
		(end 144.27708 -15.4178)
		(width 0.1397)
		(layer "In2.Cu")
		(net "PCIE_RX_N84")
	)
	(arc
		(start 145.034508 -11.295126)
		(mid 144.836508 -11.225144)
		(end 144.627854 -11.2014)
		(width 0.1397)
		(layer "In2.Cu")
		(net "PCIE_RX_N84")
	)
	(arc
		(start 144.075658 -11.254486)
		(mid 143.821591 -11.369084)
		(end 143.602202 -11.540998)
		(width 0.1397)
		(layer "In2.Cu")
		(net "PCIE_RX_N84")
	)
	(arc
		(start 226.498404 -36.398454)
		(mid 226.468646 -36.470296)
		(end 226.396804 -36.500054)
		(width 0.1016)
		(layer "In2.Cu")
		(net "PCIE_RX_N84")
	)
	(arc
		(start 226.839018 -35.899852)
		(mid 226.598168 -35.999616)
		(end 226.498404 -36.240466)
		(width 0.1016)
		(layer "In2.Cu")
		(net "PCIE_RX_N84")
	)
	(arc
		(start 142.784322 -12.62888)
		(mid 142.700127 -12.951614)
		(end 142.6718 -13.283946)
		(width 0.1397)
		(layer "In2.Cu")
		(net "PCIE_RX_N84")
	)
	(segment
		(start 225.600006 -37.999924)
		(end 225.100134 -37.500052)
		(width 0.136652)
		(layer "F.Cu")
		(net "PCIE_RX_N83")
	)
	(via
		(at 225.100134 -37.500052)
		(size 0.4572)
		(drill 0.2032)
		(layers "F.Cu" "B.Cu")
		(net "PCIE_RX_N83")
	)
	(segment
		(start 142.671546 -25.557734)
		(end 143.07566 -23.266908)
		(width 0.1397)
		(layer "In2.Cu")
		(net "PCIE_RX_N83")
	)
	(segment
		(start 221.205806 -37.106352)
		(end 221.142306 -37.169852)
		(width 0.1016)
		(layer "In2.Cu")
		(net "PCIE_RX_N83")
	)
	(segment
		(start 152.631648 -30.574234)
		(end 145.835116 -28.958794)
		(width 0.1397)
		(layer "In2.Cu")
		(net "PCIE_RX_N83")
	)
	(segment
		(start 142.855188 -26.599642)
		(end 142.671546 -25.557734)
		(width 0.1397)
		(layer "In2.Cu")
		(net "PCIE_RX_N83")
	)
	(segment
		(start 137.805922 -13.050774)
		(end 137.805922 -13.051028)
		(width 0.1397)
		(layer "In2.Cu")
		(net "PCIE_RX_N83")
	)
	(segment
		(start 138.621262 -11.08329)
		(end 138.62177 -11.082528)
		(width 0.1397)
		(layer "In2.Cu")
		(net "PCIE_RX_N83")
	)
	(segment
		(start 221.116906 -37.169852)
		(end 218.283282 -37.169852)
		(width 0.1397)
		(layer "In2.Cu")
		(net "PCIE_RX_N83")
	)
	(segment
		(start 182.353966 -37.890196)
		(end 165.10127 -41.527222)
		(width 0.1397)
		(layer "In2.Cu")
		(net "PCIE_RX_N83")
	)
	(segment
		(start 225.183954 -37.106352)
		(end 221.205806 -37.106352)
		(width 0.1016)
		(layer "In2.Cu")
		(net "PCIE_RX_N83")
	)
	(segment
		(start 160.431734 -40.535352)
		(end 156.529786 -38.000686)
		(width 0.1397)
		(layer "In2.Cu")
		(net "PCIE_RX_N83")
	)
	(segment
		(start 218.283282 -37.169852)
		(end 212.823552 -36.207192)
		(width 0.1397)
		(layer "In2.Cu")
		(net "PCIE_RX_N83")
	)
	(segment
		(start 204.64526 -37.649404)
		(end 196.073522 -39.36365)
		(width 0.1397)
		(layer "In2.Cu")
		(net "PCIE_RX_N83")
	)
	(segment
		(start 143.07566 -23.266908)
		(end 141.773656 -15.882366)
		(width 0.1397)
		(layer "In2.Cu")
		(net "PCIE_RX_N83")
	)
	(segment
		(start 143.839692 -28.115768)
		(end 142.855188 -26.599642)
		(width 0.1397)
		(layer "In2.Cu")
		(net "PCIE_RX_N83")
	)
	(segment
		(start 187.11672 -37.572696)
		(end 183.941212 -38.207442)
		(width 0.1397)
		(layer "In2.Cu")
		(net "PCIE_RX_N83")
	)
	(segment
		(start 196.073522 -39.36365)
		(end 187.11672 -37.572696)
		(width 0.1397)
		(layer "In2.Cu")
		(net "PCIE_RX_N83")
	)
	(segment
		(start 221.142306 -37.169852)
		(end 221.116906 -37.169852)
		(width 0.1016)
		(layer "In2.Cu")
		(net "PCIE_RX_N83")
	)
	(segment
		(start 138.62177 -11.082528)
		(end 137.76579 -12.174728)
		(width 0.1397)
		(layer "In2.Cu")
		(net "PCIE_RX_N83")
	)
	(segment
		(start 138.282426 -13.252196)
		(end 138.28268 -13.251942)
		(width 0.1397)
		(layer "In2.Cu")
		(net "PCIE_RX_N83")
	)
	(segment
		(start 183.941212 -38.207442)
		(end 182.353966 -37.890196)
		(width 0.1397)
		(layer "In2.Cu")
		(net "PCIE_RX_N83")
	)
	(segment
		(start 165.10127 -41.527222)
		(end 160.431734 -40.535352)
		(width 0.1397)
		(layer "In2.Cu")
		(net "PCIE_RX_N83")
	)
	(segment
		(start 225.100134 -37.500052)
		(end 225.149918 -37.551868)
		(width 0.1016)
		(layer "In2.Cu")
		(net "PCIE_RX_N83")
	)
	(segment
		(start 155.104338 -32.512)
		(end 154.731212 -31.937452)
		(width 0.1397)
		(layer "In2.Cu")
		(net "PCIE_RX_N83")
	)
	(segment
		(start 140.302742 -13.781532)
		(end 139.414758 -11.525758)
		(width 0.1397)
		(layer "In2.Cu")
		(net "PCIE_RX_N83")
	)
	(segment
		(start 145.835116 -28.958794)
		(end 143.839692 -28.115768)
		(width 0.1397)
		(layer "In2.Cu")
		(net "PCIE_RX_N83")
	)
	(segment
		(start 212.823552 -36.207192)
		(end 204.64526 -37.649404)
		(width 0.1397)
		(layer "In2.Cu")
		(net "PCIE_RX_N83")
	)
	(segment
		(start 155.25369 -35.104324)
		(end 155.45435 -34.159698)
		(width 0.1397)
		(layer "In2.Cu")
		(net "PCIE_RX_N83")
	)
	(segment
		(start 156.529786 -38.000686)
		(end 155.547568 -36.48837)
		(width 0.1397)
		(layer "In2.Cu")
		(net "PCIE_RX_N83")
	)
	(segment
		(start 141.773656 -15.882366)
		(end 140.302742 -13.781532)
		(width 0.1397)
		(layer "In2.Cu")
		(net "PCIE_RX_N83")
	)
	(segment
		(start 138.484102 -12.775438)
		(end 138.384534 -12.530074)
		(width 0.1397)
		(layer "In2.Cu")
		(net "PCIE_RX_N83")
	)
	(segment
		(start 154.731212 -31.937452)
		(end 152.631648 -30.574234)
		(width 0.1397)
		(layer "In2.Cu")
		(net "PCIE_RX_N83")
	)
	(segment
		(start 139.414758 -11.525758)
		(end 139.399772 -11.316716)
		(width 0.1397)
		(layer "In2.Cu")
		(net "PCIE_RX_N83")
	)
	(segment
		(start 155.547568 -36.48837)
		(end 155.25369 -35.104324)
		(width 0.1397)
		(layer "In2.Cu")
		(net "PCIE_RX_N83")
	)
	(segment
		(start 155.45435 -34.159698)
		(end 155.104338 -32.512)
		(width 0.1397)
		(layer "In2.Cu")
		(net "PCIE_RX_N83")
	)
	(arc
		(start 137.805922 -13.051028)
		(mid 138.002511 -13.250299)
		(end 138.282426 -13.252196)
		(width 0.1397)
		(layer "In2.Cu")
		(net "PCIE_RX_N83")
	)
	(arc
		(start 137.76579 -12.174728)
		(mid 137.640872 -12.458815)
		(end 137.66673 -12.768072)
		(width 0.1397)
		(layer "In2.Cu")
		(net "PCIE_RX_N83")
	)
	(arc
		(start 138.28268 -13.251942)
		(mid 138.482071 -13.055424)
		(end 138.484102 -12.775438)
		(width 0.1397)
		(layer "In2.Cu")
		(net "PCIE_RX_N83")
	)
	(arc
		(start 137.66673 -12.768072)
		(mid 137.695615 -12.819128)
		(end 137.723118 -12.870942)
		(width 0.1397)
		(layer "In2.Cu")
		(net "PCIE_RX_N83")
	)
	(arc
		(start 139.399772 -11.316716)
		(mid 139.09103 -10.931566)
		(end 138.621262 -11.08329)
		(width 0.1397)
		(layer "In2.Cu")
		(net "PCIE_RX_N83")
	)
	(arc
		(start 137.723118 -12.870942)
		(mid 137.753816 -12.932704)
		(end 137.782554 -12.995402)
		(width 0.1397)
		(layer "In2.Cu")
		(net "PCIE_RX_N83")
	)
	(arc
		(start 225.149918 -37.551868)
		(mid 225.475355 -37.558157)
		(end 225.481388 -37.232844)
		(width 0.1016)
		(layer "In2.Cu")
		(net "PCIE_RX_N83")
	)
	(arc
		(start 225.481388 -37.232844)
		(mid 225.345557 -37.139303)
		(end 225.183954 -37.106352)
		(width 0.1016)
		(layer "In2.Cu")
		(net "PCIE_RX_N83")
	)
	(arc
		(start 137.782554 -12.995402)
		(mid 137.794428 -13.023008)
		(end 137.805922 -13.050774)
		(width 0.1397)
		(layer "In2.Cu")
		(net "PCIE_RX_N83")
	)
	(segment
		(start 226.600004 -38.999922)
		(end 226.100132 -38.50005)
		(width 0.136652)
		(layer "F.Cu")
		(net "PCIE_RX_N82")
	)
	(via
		(at 226.100132 -38.50005)
		(size 0.4572)
		(drill 0.2032)
		(layers "F.Cu" "B.Cu")
		(net "PCIE_RX_N82")
	)
	(segment
		(start 226.302062 -38.899846)
		(end 220.613986 -38.899846)
		(width 0.1016)
		(layer "In2.Cu")
		(net "PCIE_RX_N82")
	)
	(segment
		(start 226.498658 -38.60165)
		(end 226.498658 -38.70325)
		(width 0.1016)
		(layer "In2.Cu")
		(net "PCIE_RX_N82")
	)
	(segment
		(start 197.247256 -41.256204)
		(end 187.100464 -39.226998)
		(width 0.1397)
		(layer "In2.Cu")
		(net "PCIE_RX_N82")
	)
	(segment
		(start 164.629338 -43.0911)
		(end 146.973544 -39.529766)
		(width 0.1397)
		(layer "In2.Cu")
		(net "PCIE_RX_N82")
	)
	(segment
		(start 183.925464 -39.861998)
		(end 182.350664 -39.547038)
		(width 0.1397)
		(layer "In2.Cu")
		(net "PCIE_RX_N82")
	)
	(segment
		(start 140.339826 -24.284178)
		(end 140.69441 -22.269704)
		(width 0.1397)
		(layer "In2.Cu")
		(net "PCIE_RX_N82")
	)
	(segment
		(start 226.100132 -38.50005)
		(end 226.397058 -38.50005)
		(width 0.1016)
		(layer "In2.Cu")
		(net "PCIE_RX_N82")
	)
	(segment
		(start 140.69441 -22.269704)
		(end 140.10386 -18.920206)
		(width 0.1397)
		(layer "In2.Cu")
		(net "PCIE_RX_N82")
	)
	(segment
		(start 143.152368 -37.049964)
		(end 142.381732 -35.863276)
		(width 0.1397)
		(layer "In2.Cu")
		(net "PCIE_RX_N82")
	)
	(segment
		(start 139.010644 -17.827244)
		(end 138.4427 -17.2593)
		(width 0.1397)
		(layer "In2.Cu")
		(net "PCIE_RX_N82")
	)
	(segment
		(start 212.795866 -37.950902)
		(end 197.247256 -41.256204)
		(width 0.1397)
		(layer "In2.Cu")
		(net "PCIE_RX_N82")
	)
	(segment
		(start 142.381732 -35.863276)
		(end 140.339826 -24.284178)
		(width 0.1397)
		(layer "In2.Cu")
		(net "PCIE_RX_N82")
	)
	(segment
		(start 220.550486 -38.836346)
		(end 220.525086 -38.836346)
		(width 0.1016)
		(layer "In2.Cu")
		(net "PCIE_RX_N82")
	)
	(segment
		(start 146.973544 -39.529766)
		(end 143.152368 -37.049964)
		(width 0.1397)
		(layer "In2.Cu")
		(net "PCIE_RX_N82")
	)
	(segment
		(start 182.350664 -39.547038)
		(end 164.629338 -43.0911)
		(width 0.1397)
		(layer "In2.Cu")
		(net "PCIE_RX_N82")
	)
	(segment
		(start 138.237214 -16.835882)
		(end 138.237214 -16.685768)
		(width 0.1397)
		(layer "In2.Cu")
		(net "PCIE_RX_N82")
	)
	(segment
		(start 140.10386 -18.920206)
		(end 139.0269 -17.843246)
		(width 0.1397)
		(layer "In2.Cu")
		(net "PCIE_RX_N82")
	)
	(segment
		(start 187.100464 -39.226998)
		(end 183.925464 -39.861998)
		(width 0.1397)
		(layer "In2.Cu")
		(net "PCIE_RX_N82")
	)
	(segment
		(start 220.525086 -38.836346)
		(end 217.816176 -38.836346)
		(width 0.1397)
		(layer "In2.Cu")
		(net "PCIE_RX_N82")
	)
	(segment
		(start 220.613986 -38.899846)
		(end 220.550486 -38.836346)
		(width 0.1016)
		(layer "In2.Cu")
		(net "PCIE_RX_N82")
	)
	(segment
		(start 217.816176 -38.836346)
		(end 212.795866 -37.950902)
		(width 0.1397)
		(layer "In2.Cu")
		(net "PCIE_RX_N82")
	)
	(arc
		(start 138.237214 -16.685768)
		(mid 138.275497 -16.493309)
		(end 138.384534 -16.330168)
		(width 0.1397)
		(layer "In2.Cu")
		(net "PCIE_RX_N82")
	)
	(arc
		(start 138.4427 -17.2593)
		(mid 138.304311 -17.064889)
		(end 138.237214 -16.835882)
		(width 0.1397)
		(layer "In2.Cu")
		(net "PCIE_RX_N82")
	)
	(arc
		(start 226.498658 -38.70325)
		(mid 226.441076 -38.842264)
		(end 226.302062 -38.899846)
		(width 0.1016)
		(layer "In2.Cu")
		(net "PCIE_RX_N82")
	)
	(arc
		(start 139.0269 -17.843246)
		(mid 139.018802 -17.835214)
		(end 139.010644 -17.827244)
		(width 0.1397)
		(layer "In2.Cu")
		(net "PCIE_RX_N82")
	)
	(arc
		(start 226.397058 -38.50005)
		(mid 226.4689 -38.529808)
		(end 226.498658 -38.60165)
		(width 0.1016)
		(layer "In2.Cu")
		(net "PCIE_RX_N82")
	)
	(segment
		(start 225.600006 -39.99992)
		(end 225.100134 -39.500048)
		(width 0.136652)
		(layer "F.Cu")
		(net "PCIE_RX_N81")
	)
	(via
		(at 225.100134 -39.500048)
		(size 0.4572)
		(drill 0.2032)
		(layers "F.Cu" "B.Cu")
		(net "PCIE_RX_N81")
	)
	(segment
		(start 212.662516 -38.976554)
		(end 196.942202 -42.31767)
		(width 0.1397)
		(layer "In2.Cu")
		(net "PCIE_RX_N81")
	)
	(segment
		(start 135.789416 -28.772104)
		(end 135.318754 -28.672028)
		(width 0.1397)
		(layer "In2.Cu")
		(net "PCIE_RX_N81")
	)
	(segment
		(start 186.93257 -40.190166)
		(end 183.755538 -40.82542)
		(width 0.1397)
		(layer "In2.Cu")
		(net "PCIE_RX_N81")
	)
	(segment
		(start 136.255506 -19.1262)
		(end 136.768332 -18.613374)
		(width 0.1397)
		(layer "In2.Cu")
		(net "PCIE_RX_N81")
	)
	(segment
		(start 131.9784 -22.1488)
		(end 131.9784 -21.6154)
		(width 0.1397)
		(layer "In2.Cu")
		(net "PCIE_RX_N81")
	)
	(segment
		(start 217.511884 -39.831518)
		(end 212.662516 -38.976554)
		(width 0.1397)
		(layer "In2.Cu")
		(net "PCIE_RX_N81")
	)
	(segment
		(start 142.28445 -37.549582)
		(end 141.514322 -36.363402)
		(width 0.1397)
		(layer "In2.Cu")
		(net "PCIE_RX_N81")
	)
	(segment
		(start 136.109202 -16.355568)
		(end 136.134348 -16.330168)
		(width 0.1397)
		(layer "In2.Cu")
		(net "PCIE_RX_N81")
	)
	(segment
		(start 132.216398 -26.302716)
		(end 132.14858 -25.983946)
		(width 0.1397)
		(layer "In2.Cu")
		(net "PCIE_RX_N81")
	)
	(segment
		(start 220.717618 -39.831518)
		(end 220.692218 -39.831518)
		(width 0.1016)
		(layer "In2.Cu")
		(net "PCIE_RX_N81")
	)
	(segment
		(start 140.032486 -31.526988)
		(end 135.789416 -28.772104)
		(width 0.1397)
		(layer "In2.Cu")
		(net "PCIE_RX_N81")
	)
	(segment
		(start 135.318754 -28.672028)
		(end 132.616448 -26.919174)
		(width 0.1397)
		(layer "In2.Cu")
		(net "PCIE_RX_N81")
	)
	(segment
		(start 196.942202 -42.31767)
		(end 186.93257 -40.190166)
		(width 0.1397)
		(layer "In2.Cu")
		(net "PCIE_RX_N81")
	)
	(segment
		(start 131.9784 -21.6154)
		(end 132.139436 -20.70227)
		(width 0.1397)
		(layer "In2.Cu")
		(net "PCIE_RX_N81")
	)
	(segment
		(start 135.981948 -16.79702)
		(end 135.981948 -16.6624)
		(width 0.1397)
		(layer "In2.Cu")
		(net "PCIE_RX_N81")
	)
	(segment
		(start 133.656324 -19.202654)
		(end 134.739126 -19.393662)
		(width 0.1397)
		(layer "In2.Cu")
		(net "PCIE_RX_N81")
	)
	(segment
		(start 220.692218 -39.831518)
		(end 217.511884 -39.831518)
		(width 0.1397)
		(layer "In2.Cu")
		(net "PCIE_RX_N81")
	)
	(segment
		(start 146.453606 -40.256968)
		(end 142.28445 -37.549582)
		(width 0.1397)
		(layer "In2.Cu")
		(net "PCIE_RX_N81")
	)
	(segment
		(start 136.768332 -17.794732)
		(end 136.1313 -17.1577)
		(width 0.1397)
		(layer "In2.Cu")
		(net "PCIE_RX_N81")
	)
	(segment
		(start 132.616448 -26.919174)
		(end 132.216398 -26.302716)
		(width 0.1397)
		(layer "In2.Cu")
		(net "PCIE_RX_N81")
	)
	(segment
		(start 132.740146 -19.844258)
		(end 133.656324 -19.202654)
		(width 0.1397)
		(layer "In2.Cu")
		(net "PCIE_RX_N81")
	)
	(segment
		(start 225.306636 -39.895018)
		(end 220.781118 -39.895018)
		(width 0.1016)
		(layer "In2.Cu")
		(net "PCIE_RX_N81")
	)
	(segment
		(start 132.14858 -25.983946)
		(end 132.401564 -24.549354)
		(width 0.1397)
		(layer "In2.Cu")
		(net "PCIE_RX_N81")
	)
	(segment
		(start 141.514322 -36.363402)
		(end 140.719048 -32.624268)
		(width 0.1397)
		(layer "In2.Cu")
		(net "PCIE_RX_N81")
	)
	(segment
		(start 164.76091 -44.061888)
		(end 146.453606 -40.256968)
		(width 0.1397)
		(layer "In2.Cu")
		(net "PCIE_RX_N81")
	)
	(segment
		(start 225.100134 -39.500048)
		(end 225.396806 -39.500048)
		(width 0.1016)
		(layer "In2.Cu")
		(net "PCIE_RX_N81")
	)
	(segment
		(start 132.139436 -20.70227)
		(end 132.740146 -19.844258)
		(width 0.1397)
		(layer "In2.Cu")
		(net "PCIE_RX_N81")
	)
	(segment
		(start 140.719048 -32.624268)
		(end 140.719048 -32.559244)
		(width 0.1397)
		(layer "In2.Cu")
		(net "PCIE_RX_N81")
	)
	(segment
		(start 182.350664 -40.544496)
		(end 164.76091 -44.061888)
		(width 0.1397)
		(layer "In2.Cu")
		(net "PCIE_RX_N81")
	)
	(segment
		(start 225.498406 -39.601648)
		(end 225.498406 -39.703248)
		(width 0.1016)
		(layer "In2.Cu")
		(net "PCIE_RX_N81")
	)
	(segment
		(start 134.739126 -19.393662)
		(end 136.255506 -19.1262)
		(width 0.1397)
		(layer "In2.Cu")
		(net "PCIE_RX_N81")
	)
	(segment
		(start 140.67282 -32.513016)
		(end 140.032486 -31.526988)
		(width 0.1397)
		(layer "In2.Cu")
		(net "PCIE_RX_N81")
	)
	(segment
		(start 140.719048 -32.559244)
		(end 140.67282 -32.513016)
		(width 0.1397)
		(layer "In2.Cu")
		(net "PCIE_RX_N81")
	)
	(segment
		(start 183.755538 -40.82542)
		(end 182.350664 -40.544496)
		(width 0.1397)
		(layer "In2.Cu")
		(net "PCIE_RX_N81")
	)
	(segment
		(start 220.781118 -39.895018)
		(end 220.717618 -39.831518)
		(width 0.1016)
		(layer "In2.Cu")
		(net "PCIE_RX_N81")
	)
	(segment
		(start 132.401564 -24.549354)
		(end 131.9784 -22.1488)
		(width 0.1397)
		(layer "In2.Cu")
		(net "PCIE_RX_N81")
	)
	(arc
		(start 135.981948 -16.6624)
		(mid 136.015074 -16.496336)
		(end 136.109202 -16.355568)
		(width 0.1397)
		(layer "In2.Cu")
		(net "PCIE_RX_N81")
	)
	(arc
		(start 225.498406 -39.703248)
		(mid 225.442238 -39.83885)
		(end 225.306636 -39.895018)
		(width 0.1016)
		(layer "In2.Cu")
		(net "PCIE_RX_N81")
	)
	(arc
		(start 225.396806 -39.500048)
		(mid 225.468648 -39.529806)
		(end 225.498406 -39.601648)
		(width 0.1016)
		(layer "In2.Cu")
		(net "PCIE_RX_N81")
	)
	(arc
		(start 136.768332 -18.613374)
		(mid 136.937826 -18.20409)
		(end 136.768332 -17.794732)
		(width 0.1397)
		(layer "In2.Cu")
		(net "PCIE_RX_N81")
	)
	(arc
		(start 136.1313 -17.1577)
		(mid 136.020729 -16.992219)
		(end 135.981948 -16.79702)
		(width 0.1397)
		(layer "In2.Cu")
		(net "PCIE_RX_N81")
	)
	(segment
		(start 226.600004 -40.999918)
		(end 226.100132 -40.500046)
		(width 0.136652)
		(layer "F.Cu")
		(net "PCIE_RX_N80")
	)
	(via
		(at 226.100132 -40.500046)
		(size 0.4572)
		(drill 0.2032)
		(layers "F.Cu" "B.Cu")
		(net "PCIE_RX_N80")
	)
	(segment
		(start 141.108938 -18.453862)
		(end 141.108938 -18.454878)
		(width 0.1397)
		(layer "In2.Cu")
		(net "PCIE_RX_N80")
	)
	(segment
		(start 133.5278 -15.306548)
		(end 137.5664 -15.306548)
		(width 0.1397)
		(layer "In2.Cu")
		(net "PCIE_RX_N80")
	)
	(segment
		(start 135.771382 -12.611354)
		(end 135.624824 -12.593574)
		(width 0.1397)
		(layer "In2.Cu")
		(net "PCIE_RX_N80")
	)
	(segment
		(start 135.624824 -12.593574)
		(end 135.616188 -12.587986)
		(width 0.1397)
		(layer "In2.Cu")
		(net "PCIE_RX_N80")
	)
	(segment
		(start 134.0104 -11.4554)
		(end 133.7818 -11.4554)
		(width 0.1397)
		(layer "In2.Cu")
		(net "PCIE_RX_N80")
	)
	(segment
		(start 197.210934 -40.588184)
		(end 210.880452 -37.682932)
		(width 0.1397)
		(layer "In2.Cu")
		(net "PCIE_RX_N80")
	)
	(segment
		(start 153.552398 -37.272976)
		(end 159.975296 -41.44391)
		(width 0.1397)
		(layer "In2.Cu")
		(net "PCIE_RX_N80")
	)
	(segment
		(start 135.531352 -12.55141)
		(end 135.480552 -12.528042)
		(width 0.1397)
		(layer "In2.Cu")
		(net "PCIE_RX_N80")
	)
	(segment
		(start 210.880452 -37.682932)
		(end 213.310216 -37.16655)
		(width 0.1397)
		(layer "In2.Cu")
		(net "PCIE_RX_N80")
	)
	(segment
		(start 226.396804 -40.500046)
		(end 226.100132 -40.500046)
		(width 0.1016)
		(layer "In2.Cu")
		(net "PCIE_RX_N80")
	)
	(segment
		(start 145.855182 -37.22116)
		(end 147.476972 -37.565838)
		(width 0.1397)
		(layer "In2.Cu")
		(net "PCIE_RX_N80")
	)
	(segment
		(start 220.490034 -38.16223)
		(end 220.553534 -38.09873)
		(width 0.1016)
		(layer "In2.Cu")
		(net "PCIE_RX_N80")
	)
	(segment
		(start 220.464634 -38.16223)
		(end 220.490034 -38.16223)
		(width 0.1016)
		(layer "In2.Cu")
		(net "PCIE_RX_N80")
	)
	(segment
		(start 139.063984 -15.833344)
		(end 139.91971 -16.68907)
		(width 0.1397)
		(layer "In2.Cu")
		(net "PCIE_RX_N80")
	)
	(segment
		(start 141.969236 -28.052014)
		(end 142.89532 -29.478224)
		(width 0.1397)
		(layer "In2.Cu")
		(net "PCIE_RX_N80")
	)
	(segment
		(start 226.676204 -39.899844)
		(end 226.498404 -40.077644)
		(width 0.1016)
		(layer "In2.Cu")
		(net "PCIE_RX_N80")
	)
	(segment
		(start 139.91971 -16.68907)
		(end 141.108938 -18.453862)
		(width 0.1397)
		(layer "In2.Cu")
		(net "PCIE_RX_N80")
	)
	(segment
		(start 135.616188 -12.587986)
		(end 135.531352 -12.55141)
		(width 0.1397)
		(layer "In2.Cu")
		(net "PCIE_RX_N80")
	)
	(segment
		(start 147.476972 -37.565838)
		(end 151.203914 -36.773612)
		(width 0.1397)
		(layer "In2.Cu")
		(net "PCIE_RX_N80")
	)
	(segment
		(start 183.980328 -39.212266)
		(end 187.155328 -38.577266)
		(width 0.1397)
		(layer "In2.Cu")
		(net "PCIE_RX_N80")
	)
	(segment
		(start 132.0292 -13.3096)
		(end 132.0292 -14.08811)
		(width 0.1397)
		(layer "In2.Cu")
		(net "PCIE_RX_N80")
	)
	(segment
		(start 151.203914 -36.773612)
		(end 153.552398 -37.272976)
		(width 0.1397)
		(layer "In2.Cu")
		(net "PCIE_RX_N80")
	)
	(segment
		(start 135.43534 -12.503658)
		(end 135.414766 -12.491212)
		(width 0.1397)
		(layer "In2.Cu")
		(net "PCIE_RX_N80")
	)
	(segment
		(start 227.500942 -38.32987)
		(end 227.500942 -39.76497)
		(width 0.1016)
		(layer "In2.Cu")
		(net "PCIE_RX_N80")
	)
	(segment
		(start 226.498404 -40.077644)
		(end 226.498404 -40.398446)
		(width 0.1016)
		(layer "In2.Cu")
		(net "PCIE_RX_N80")
	)
	(segment
		(start 135.349234 -12.439396)
		(end 134.632192 -11.722354)
		(width 0.1397)
		(layer "In2.Cu")
		(net "PCIE_RX_N80")
	)
	(segment
		(start 135.967724 -12.611354)
		(end 135.771382 -12.611354)
		(width 0.1397)
		(layer "In2.Cu")
		(net "PCIE_RX_N80")
	)
	(segment
		(start 187.155328 -38.577266)
		(end 197.210934 -40.588184)
		(width 0.1397)
		(layer "In2.Cu")
		(net "PCIE_RX_N80")
	)
	(segment
		(start 132.90042 -11.818874)
		(end 132.49402 -12.225274)
		(width 0.1397)
		(layer "In2.Cu")
		(net "PCIE_RX_N80")
	)
	(segment
		(start 227.269802 -38.09873)
		(end 227.500942 -38.32987)
		(width 0.1016)
		(layer "In2.Cu")
		(net "PCIE_RX_N80")
	)
	(segment
		(start 164.621718 -42.431716)
		(end 182.350664 -38.886384)
		(width 0.1397)
		(layer "In2.Cu")
		(net "PCIE_RX_N80")
	)
	(segment
		(start 142.89532 -29.478224)
		(end 144.15643 -35.413442)
		(width 0.1397)
		(layer "In2.Cu")
		(net "PCIE_RX_N80")
	)
	(segment
		(start 141.108938 -18.454878)
		(end 141.77645 -22.241002)
		(width 0.1397)
		(layer "In2.Cu")
		(net "PCIE_RX_N80")
	)
	(segment
		(start 141.77645 -22.241002)
		(end 141.255242 -24.693372)
		(width 0.1397)
		(layer "In2.Cu")
		(net "PCIE_RX_N80")
	)
	(segment
		(start 213.310216 -37.16655)
		(end 217.9955 -38.16223)
		(width 0.1397)
		(layer "In2.Cu")
		(net "PCIE_RX_N80")
	)
	(segment
		(start 144.94764 -36.63188)
		(end 145.855182 -37.22116)
		(width 0.1397)
		(layer "In2.Cu")
		(net "PCIE_RX_N80")
	)
	(segment
		(start 141.255242 -24.693372)
		(end 141.969236 -28.052014)
		(width 0.1397)
		(layer "In2.Cu")
		(net "PCIE_RX_N80")
	)
	(segment
		(start 144.15643 -35.413442)
		(end 144.94764 -36.63188)
		(width 0.1397)
		(layer "In2.Cu")
		(net "PCIE_RX_N80")
	)
	(segment
		(start 135.436102 -12.504166)
		(end 135.43534 -12.503658)
		(width 0.1397)
		(layer "In2.Cu")
		(net "PCIE_RX_N80")
	)
	(segment
		(start 227.500942 -39.76497)
		(end 227.366068 -39.899844)
		(width 0.1016)
		(layer "In2.Cu")
		(net "PCIE_RX_N80")
	)
	(segment
		(start 220.553534 -38.09873)
		(end 227.269802 -38.09873)
		(width 0.1016)
		(layer "In2.Cu")
		(net "PCIE_RX_N80")
	)
	(segment
		(start 182.350664 -38.886384)
		(end 183.980328 -39.212266)
		(width 0.1397)
		(layer "In2.Cu")
		(net "PCIE_RX_N80")
	)
	(segment
		(start 217.9955 -38.16223)
		(end 220.464634 -38.16223)
		(width 0.1397)
		(layer "In2.Cu")
		(net "PCIE_RX_N80")
	)
	(segment
		(start 227.366068 -39.899844)
		(end 226.676204 -39.899844)
		(width 0.1016)
		(layer "In2.Cu")
		(net "PCIE_RX_N80")
	)
	(segment
		(start 159.975296 -41.44391)
		(end 164.621718 -42.431716)
		(width 0.1397)
		(layer "In2.Cu")
		(net "PCIE_RX_N80")
	)
	(arc
		(start 132.49402 -12.225274)
		(mid 132.226086 -12.566537)
		(end 132.067808 -12.97051)
		(width 0.1397)
		(layer "In2.Cu")
		(net "PCIE_RX_N80")
	)
	(arc
		(start 137.5664 -15.306548)
		(mid 138.30446 -15.423252)
		(end 138.970512 -15.76197)
		(width 0.1397)
		(layer "In2.Cu")
		(net "PCIE_RX_N80")
	)
	(arc
		(start 136.134348 -12.530074)
		(mid 136.057833 -12.584638)
		(end 135.967724 -12.611354)
		(width 0.1397)
		(layer "In2.Cu")
		(net "PCIE_RX_N80")
	)
	(arc
		(start 135.480552 -12.528042)
		(mid 135.457987 -12.516737)
		(end 135.436102 -12.504166)
		(width 0.1397)
		(layer "In2.Cu")
		(net "PCIE_RX_N80")
	)
	(arc
		(start 135.414766 -12.491212)
		(mid 135.380497 -12.467205)
		(end 135.349234 -12.439396)
		(width 0.1397)
		(layer "In2.Cu")
		(net "PCIE_RX_N80")
	)
	(arc
		(start 132.25018 -14.70279)
		(mid 132.280231 -14.737436)
		(end 132.311902 -14.770608)
		(width 0.1397)
		(layer "In2.Cu")
		(net "PCIE_RX_N80")
	)
	(arc
		(start 132.0292 -14.08811)
		(mid 132.086132 -14.4147)
		(end 132.25018 -14.70279)
		(width 0.1397)
		(layer "In2.Cu")
		(net "PCIE_RX_N80")
	)
	(arc
		(start 134.279894 -11.49858)
		(mid 134.14688 -11.466174)
		(end 134.0104 -11.4554)
		(width 0.1397)
		(layer "In2.Cu")
		(net "PCIE_RX_N80")
	)
	(arc
		(start 133.425184 -11.507216)
		(mid 133.143441 -11.63045)
		(end 132.90042 -11.818874)
		(width 0.1397)
		(layer "In2.Cu")
		(net "PCIE_RX_N80")
	)
	(arc
		(start 133.7818 -11.4554)
		(mid 133.601613 -11.468379)
		(end 133.425184 -11.507216)
		(width 0.1397)
		(layer "In2.Cu")
		(net "PCIE_RX_N80")
	)
	(arc
		(start 132.311902 -14.770608)
		(mid 132.408288 -14.869463)
		(end 132.513324 -14.959076)
		(width 0.1397)
		(layer "In2.Cu")
		(net "PCIE_RX_N80")
	)
	(arc
		(start 134.632192 -11.722354)
		(mid 134.469942 -11.588575)
		(end 134.279894 -11.49858)
		(width 0.1397)
		(layer "In2.Cu")
		(net "PCIE_RX_N80")
	)
	(arc
		(start 132.513324 -14.959076)
		(mid 132.99161 -15.217335)
		(end 133.5278 -15.306548)
		(width 0.1397)
		(layer "In2.Cu")
		(net "PCIE_RX_N80")
	)
	(arc
		(start 138.970512 -15.76197)
		(mid 139.017685 -15.797084)
		(end 139.063984 -15.833344)
		(width 0.1397)
		(layer "In2.Cu")
		(net "PCIE_RX_N80")
	)
	(arc
		(start 226.498404 -40.398446)
		(mid 226.468646 -40.470288)
		(end 226.396804 -40.500046)
		(width 0.1016)
		(layer "In2.Cu")
		(net "PCIE_RX_N80")
	)
	(arc
		(start 132.067808 -12.97051)
		(mid 132.038833 -13.138954)
		(end 132.0292 -13.3096)
		(width 0.1397)
		(layer "In2.Cu")
		(net "PCIE_RX_N80")
	)
	(segment
		(start 255.599946 -33.999932)
		(end 256.099818 -33.50006)
		(width 0.136652)
		(layer "F.Cu")
		(net "PCIE_RX_N8")
	)
	(via
		(at 256.099818 -33.50006)
		(size 0.4572)
		(drill 0.2032)
		(layers "F.Cu" "B.Cu")
		(net "PCIE_RX_N8")
	)
	(segment
		(start 307.6448 -15.5448)
		(end 310.5658 -15.5448)
		(width 0.1397)
		(layer "In2.Cu")
		(net "PCIE_RX_N8")
	)
	(segment
		(start 275.164804 -30.426406)
		(end 277.253446 -30.095444)
		(width 0.1397)
		(layer "In2.Cu")
		(net "PCIE_RX_N8")
	)
	(segment
		(start 277.253446 -30.095444)
		(end 279.342342 -29.764736)
		(width 0.1397)
		(layer "In2.Cu")
		(net "PCIE_RX_N8")
	)
	(segment
		(start 259.570728 -32.1056)
		(end 259.648706 -32.027622)
		(width 0.1016)
		(layer "In2.Cu")
		(net "PCIE_RX_N8")
	)
	(segment
		(start 304.660808 -22.692614)
		(end 305.435 -21.586444)
		(width 0.1397)
		(layer "In2.Cu")
		(net "PCIE_RX_N8")
	)
	(segment
		(start 303.141126 -28.58897)
		(end 303.927002 -28.038806)
		(width 0.1397)
		(layer "In2.Cu")
		(net "PCIE_RX_N8")
	)
	(segment
		(start 300.750986 -29.010356)
		(end 303.141126 -28.58897)
		(width 0.1397)
		(layer "In2.Cu")
		(net "PCIE_RX_N8")
	)
	(segment
		(start 284.530546 -28.942284)
		(end 287.459166 -29.528008)
		(width 0.1397)
		(layer "In2.Cu")
		(net "PCIE_RX_N8")
	)
	(segment
		(start 305.435 -21.586444)
		(end 305.435 -17.7546)
		(width 0.1397)
		(layer "In2.Cu")
		(net "PCIE_RX_N8")
	)
	(segment
		(start 304.369724 -27.406346)
		(end 304.514504 -26.58491)
		(width 0.1397)
		(layer "In2.Cu")
		(net "PCIE_RX_N8")
	)
	(segment
		(start 259.691378 -32.027622)
		(end 262.906764 -32.027622)
		(width 0.1397)
		(layer "In2.Cu")
		(net "PCIE_RX_N8")
	)
	(segment
		(start 296.037 -29.1338)
		(end 296.83329 -28.57627)
		(width 0.1397)
		(layer "In2.Cu")
		(net "PCIE_RX_N8")
	)
	(segment
		(start 262.906764 -32.027622)
		(end 263.85901 -32.218122)
		(width 0.1397)
		(layer "In2.Cu")
		(net "PCIE_RX_N8")
	)
	(segment
		(start 296.83329 -28.57627)
		(end 297.561 -28.448)
		(width 0.1397)
		(layer "In2.Cu")
		(net "PCIE_RX_N8")
	)
	(segment
		(start 295.968674 -29.147516)
		(end 296.037 -29.1338)
		(width 0.1397)
		(layer "In2.Cu")
		(net "PCIE_RX_N8")
	)
	(segment
		(start 305.435 -17.7546)
		(end 307.6448 -15.5448)
		(width 0.1397)
		(layer "In2.Cu")
		(net "PCIE_RX_N8")
	)
	(segment
		(start 259.648706 -32.027622)
		(end 259.691378 -32.027622)
		(width 0.1016)
		(layer "In2.Cu")
		(net "PCIE_RX_N8")
	)
	(segment
		(start 311.134506 -13.083286)
		(end 311.134506 -12.530074)
		(width 0.1397)
		(layer "In2.Cu")
		(net "PCIE_RX_N8")
	)
	(segment
		(start 297.561 -28.448)
		(end 300.750986 -29.010356)
		(width 0.1397)
		(layer "In2.Cu")
		(net "PCIE_RX_N8")
	)
	(segment
		(start 287.459166 -29.528008)
		(end 289.91941 -29.134562)
		(width 0.1397)
		(layer "In2.Cu")
		(net "PCIE_RX_N8")
	)
	(segment
		(start 255.701292 -33.101534)
		(end 255.701292 -32.406082)
		(width 0.1016)
		(layer "In2.Cu")
		(net "PCIE_RX_N8")
	)
	(segment
		(start 289.91941 -29.134562)
		(end 292.9763 -29.74594)
		(width 0.1397)
		(layer "In2.Cu")
		(net "PCIE_RX_N8")
	)
	(segment
		(start 304.244502 -25.052528)
		(end 304.660808 -22.692614)
		(width 0.1397)
		(layer "In2.Cu")
		(net "PCIE_RX_N8")
	)
	(segment
		(start 256.001774 -32.1056)
		(end 259.570728 -32.1056)
		(width 0.1016)
		(layer "In2.Cu")
		(net "PCIE_RX_N8")
	)
	(segment
		(start 292.9763 -29.74594)
		(end 294.505634 -29.43987)
		(width 0.1397)
		(layer "In2.Cu")
		(net "PCIE_RX_N8")
	)
	(segment
		(start 311.38749 -14.72311)
		(end 311.38749 -13.816076)
		(width 0.1397)
		(layer "In2.Cu")
		(net "PCIE_RX_N8")
	)
	(segment
		(start 263.85901 -32.218122)
		(end 275.164804 -30.426406)
		(width 0.1397)
		(layer "In2.Cu")
		(net "PCIE_RX_N8")
	)
	(segment
		(start 294.505634 -29.43987)
		(end 295.968674 -29.147262)
		(width 0.1397)
		(layer "In2.Cu")
		(net "PCIE_RX_N8")
	)
	(segment
		(start 279.342342 -29.764736)
		(end 284.530546 -28.942284)
		(width 0.1397)
		(layer "In2.Cu")
		(net "PCIE_RX_N8")
	)
	(segment
		(start 304.514504 -26.58491)
		(end 304.244502 -25.052528)
		(width 0.1397)
		(layer "In2.Cu")
		(net "PCIE_RX_N8")
	)
	(segment
		(start 295.968674 -29.147262)
		(end 295.968674 -29.147516)
		(width 0.1397)
		(layer "In2.Cu")
		(net "PCIE_RX_N8")
	)
	(segment
		(start 310.5658 -15.5448)
		(end 311.38749 -14.72311)
		(width 0.1397)
		(layer "In2.Cu")
		(net "PCIE_RX_N8")
	)
	(segment
		(start 303.927002 -28.038806)
		(end 304.369724 -27.406346)
		(width 0.1397)
		(layer "In2.Cu")
		(net "PCIE_RX_N8")
	)
	(arc
		(start 311.290716 -13.438632)
		(mid 311.257592 -13.383601)
		(end 311.220104 -13.331444)
		(width 0.1397)
		(layer "In2.Cu")
		(net "PCIE_RX_N8")
	)
	(arc
		(start 311.14873 -13.189966)
		(mid 311.13805 -13.137103)
		(end 311.134506 -13.083286)
		(width 0.1397)
		(layer "In2.Cu")
		(net "PCIE_RX_N8")
	)
	(arc
		(start 255.701292 -32.406082)
		(mid 255.789301 -32.193609)
		(end 256.001774 -32.1056)
		(width 0.1016)
		(layer "In2.Cu")
		(net "PCIE_RX_N8")
	)
	(arc
		(start 311.152286 -13.201904)
		(mid 311.151126 -13.198353)
		(end 311.15 -13.194792)
		(width 0.1397)
		(layer "In2.Cu")
		(net "PCIE_RX_N8")
	)
	(arc
		(start 256.099818 -33.50006)
		(mid 255.818018 -33.383334)
		(end 255.701292 -33.101534)
		(width 0.1016)
		(layer "In2.Cu")
		(net "PCIE_RX_N8")
	)
	(arc
		(start 311.38749 -13.816076)
		(mid 311.362841 -13.62127)
		(end 311.290716 -13.438632)
		(width 0.1397)
		(layer "In2.Cu")
		(net "PCIE_RX_N8")
	)
	(arc
		(start 311.220104 -13.331444)
		(mid 311.18029 -13.269769)
		(end 311.152286 -13.201904)
		(width 0.1397)
		(layer "In2.Cu")
		(net "PCIE_RX_N8")
	)
	(arc
		(start 311.15 -13.194792)
		(mid 311.149357 -13.192381)
		(end 311.14873 -13.189966)
		(width 0.1397)
		(layer "In2.Cu")
		(net "PCIE_RX_N8")
	)
	(segment
		(start 226.600004 -45.999908)
		(end 226.100132 -45.500036)
		(width 0.136652)
		(layer "F.Cu")
		(net "PCIE_RX_N76")
	)
	(via
		(at 226.100132 -45.500036)
		(size 0.4572)
		(drill 0.2032)
		(layers "F.Cu" "B.Cu")
		(net "PCIE_RX_N76")
	)
	(segment
		(start 213.615778 -44.7802)
		(end 223.242378 -44.7802)
		(width 0.136652)
		(layer "B.Cu")
		(net "PCIE_RX_N76")
	)
	(segment
		(start 226.402646 -45.500036)
		(end 226.100132 -45.500036)
		(width 0.1016)
		(layer "B.Cu")
		(net "PCIE_RX_N76")
	)
	(segment
		(start 223.267778 -44.7802)
		(end 223.318578 -44.831)
		(width 0.1016)
		(layer "B.Cu")
		(net "PCIE_RX_N76")
	)
	(segment
		(start 226.47783 -45.499782)
		(end 226.403662 -45.500036)
		(width 0.1016)
		(layer "B.Cu")
		(net "PCIE_RX_N76")
	)
	(segment
		(start 224.72904 -45.903134)
		(end 226.3648 -45.903134)
		(width 0.1016)
		(layer "B.Cu")
		(net "PCIE_RX_N76")
	)
	(segment
		(start 212.457538 -45.0596)
		(end 212.941408 -45.0596)
		(width 0.136652)
		(layer "B.Cu")
		(net "PCIE_RX_N76")
	)
	(segment
		(start 226.441254 -45.871384)
		(end 226.567492 -45.745146)
		(width 0.1016)
		(layer "B.Cu")
		(net "PCIE_RX_N76")
	)
	(segment
		(start 223.318578 -44.831)
		(end 223.656906 -44.831)
		(width 0.1016)
		(layer "B.Cu")
		(net "PCIE_RX_N76")
	)
	(segment
		(start 223.242378 -44.7802)
		(end 223.267778 -44.7802)
		(width 0.1016)
		(layer "B.Cu")
		(net "PCIE_RX_N76")
	)
	(segment
		(start 223.656906 -44.831)
		(end 224.72904 -45.903134)
		(width 0.1016)
		(layer "B.Cu")
		(net "PCIE_RX_N76")
	)
	(arc
		(start 212.941408 -45.0596)
		(mid 213.026937 -45.045047)
		(end 213.102952 -45.003212)
		(width 0.136652)
		(layer "B.Cu")
		(net "PCIE_RX_N76")
	)
	(arc
		(start 213.125304 -44.9834)
		(mid 213.271669 -44.871613)
		(end 213.442296 -44.802298)
		(width 0.136652)
		(layer "B.Cu")
		(net "PCIE_RX_N76")
	)
	(arc
		(start 213.442296 -44.802298)
		(mid 213.528337 -44.785755)
		(end 213.615778 -44.7802)
		(width 0.136652)
		(layer "B.Cu")
		(net "PCIE_RX_N76")
	)
	(arc
		(start 211.7217 -44.7548)
		(mid 212.059305 -44.980381)
		(end 212.457538 -45.0596)
		(width 0.136652)
		(layer "B.Cu")
		(net "PCIE_RX_N76")
	)
	(arc
		(start 226.3648 -45.903134)
		(mid 226.406154 -45.894815)
		(end 226.441254 -45.871384)
		(width 0.1016)
		(layer "B.Cu")
		(net "PCIE_RX_N76")
	)
	(arc
		(start 226.567492 -45.745146)
		(mid 226.600932 -45.593856)
		(end 226.47783 -45.499782)
		(width 0.1016)
		(layer "B.Cu")
		(net "PCIE_RX_N76")
	)
	(arc
		(start 213.102952 -45.003212)
		(mid 213.114413 -44.993628)
		(end 213.125304 -44.9834)
		(width 0.136652)
		(layer "B.Cu")
		(net "PCIE_RX_N76")
	)
	(arc
		(start 226.403662 -45.500036)
		(mid 226.403154 -45.500037)
		(end 226.402646 -45.500036)
		(width 0.1016)
		(layer "B.Cu")
		(net "PCIE_RX_N76")
	)
	(segment
		(start 225.600006 -46.999906)
		(end 225.100134 -46.500034)
		(width 0.136652)
		(layer "F.Cu")
		(net "PCIE_RX_N75")
	)
	(via
		(at 225.100134 -46.500034)
		(size 0.4572)
		(drill 0.2032)
		(layers "F.Cu" "B.Cu")
		(net "PCIE_RX_N75")
	)
	(via
		(at 50.906172 -221.405704)
		(size 0.508)
		(drill 0.254)
		(layers "F.Cu" "B.Cu")
		(net "PCIE_RX_N75")
	)
	(segment
		(start 50.710846 -221.60103)
		(end 50.906172 -221.405704)
		(width 0.136652)
		(layer "B.Cu")
		(net "PCIE_RX_N75")
	)
	(segment
		(start 50.900076 -225.92538)
		(end 50.900076 -224.770442)
		(width 0.136652)
		(layer "B.Cu")
		(net "PCIE_RX_N75")
	)
	(segment
		(start 50.900076 -224.770442)
		(end 50.899822 -224.770188)
		(width 0.136652)
		(layer "B.Cu")
		(net "PCIE_RX_N75")
	)
	(segment
		(start 50.652426 -224.17278)
		(end 50.652426 -221.742)
		(width 0.136652)
		(layer "B.Cu")
		(net "PCIE_RX_N75")
	)
	(arc
		(start 50.652426 -221.742)
		(mid 50.667604 -221.665697)
		(end 50.710846 -221.60103)
		(width 0.136652)
		(layer "B.Cu")
		(net "PCIE_RX_N75")
	)
	(arc
		(start 50.899822 -224.770188)
		(mid 50.855584 -224.547791)
		(end 50.729642 -224.359216)
		(width 0.136652)
		(layer "B.Cu")
		(net "PCIE_RX_N75")
	)
	(arc
		(start 50.729642 -224.359216)
		(mid 50.672488 -224.273678)
		(end 50.652426 -224.17278)
		(width 0.136652)
		(layer "B.Cu")
		(net "PCIE_RX_N75")
	)
	(segment
		(start 75.744324 -192.747646)
		(end 68.397374 -194.043046)
		(width 0.1397)
		(layer "In2.Cu")
		(net "PCIE_RX_N75")
	)
	(segment
		(start 225.3996 -46.096936)
		(end 224.545652 -46.096936)
		(width 0.1016)
		(layer "In2.Cu")
		(net "PCIE_RX_N75")
	)
	(segment
		(start 221.5896 -46.228)
		(end 218.585034 -46.228)
		(width 0.1397)
		(layer "In2.Cu")
		(net "PCIE_RX_N75")
	)
	(segment
		(start 50.6476 -220.174566)
		(end 50.6476 -221.035626)
		(width 0.1397)
		(layer "In2.Cu")
		(net "PCIE_RX_N75")
	)
	(segment
		(start 68.397374 -194.043046)
		(end 59.328812 -200.3933)
		(width 0.1397)
		(layer "In2.Cu")
		(net "PCIE_RX_N75")
	)
	(segment
		(start 211.35467 -50.13071)
		(end 205.99146 -57.789826)
		(width 0.1397)
		(layer "In2.Cu")
		(net "PCIE_RX_N75")
	)
	(segment
		(start 221.730316 -46.087284)
		(end 221.5896 -46.228)
		(width 0.1397)
		(layer "In2.Cu")
		(net "PCIE_RX_N75")
	)
	(segment
		(start 50.72634 -221.226126)
		(end 50.906172 -221.405704)
		(width 0.1397)
		(layer "In2.Cu")
		(net "PCIE_RX_N75")
	)
	(segment
		(start 225.639122 -46.242224)
		(end 225.561144 -46.163992)
		(width 0.1016)
		(layer "In2.Cu")
		(net "PCIE_RX_N75")
	)
	(segment
		(start 53.848 -215.105488)
		(end 50.6476 -220.174566)
		(width 0.1397)
		(layer "In2.Cu")
		(net "PCIE_RX_N75")
	)
	(segment
		(start 224.536 -46.087284)
		(end 221.730316 -46.087284)
		(width 0.1397)
		(layer "In2.Cu")
		(net "PCIE_RX_N75")
	)
	(segment
		(start 53.848 -208.22031)
		(end 53.848 -215.105488)
		(width 0.1397)
		(layer "In2.Cu")
		(net "PCIE_RX_N75")
	)
	(segment
		(start 88.29548 -192.829688)
		(end 82.252566 -193.895218)
		(width 0.1397)
		(layer "In2.Cu")
		(net "PCIE_RX_N75")
	)
	(segment
		(start 225.100134 -46.512734)
		(end 225.305366 -46.717966)
		(width 0.1016)
		(layer "In2.Cu")
		(net "PCIE_RX_N75")
	)
	(segment
		(start 204.697838 -65.12687)
		(end 205.55585 -69.994526)
		(width 0.1397)
		(layer "In2.Cu")
		(net "PCIE_RX_N75")
	)
	(segment
		(start 216.370916 -46.618398)
		(end 211.35467 -50.13071)
		(width 0.1397)
		(layer "In2.Cu")
		(net "PCIE_RX_N75")
	)
	(segment
		(start 225.6028 -46.736)
		(end 225.6282 -46.7106)
		(width 0.1016)
		(layer "In2.Cu")
		(net "PCIE_RX_N75")
	)
	(segment
		(start 204.399134 -76.556616)
		(end 163.749482 -134.610602)
		(width 0.1397)
		(layer "In2.Cu")
		(net "PCIE_RX_N75")
	)
	(segment
		(start 205.55585 -69.994526)
		(end 204.399134 -76.556616)
		(width 0.1397)
		(layer "In2.Cu")
		(net "PCIE_RX_N75")
	)
	(segment
		(start 218.585034 -46.228)
		(end 216.370916 -46.618398)
		(width 0.1397)
		(layer "In2.Cu")
		(net "PCIE_RX_N75")
	)
	(segment
		(start 224.545652 -46.096936)
		(end 224.536 -46.087284)
		(width 0.1016)
		(layer "In2.Cu")
		(net "PCIE_RX_N75")
	)
	(segment
		(start 205.99146 -57.789826)
		(end 204.697838 -65.12687)
		(width 0.1397)
		(layer "In2.Cu")
		(net "PCIE_RX_N75")
	)
	(segment
		(start 102.648004 -177.394362)
		(end 95.25 -187.96)
		(width 0.1397)
		(layer "In2.Cu")
		(net "PCIE_RX_N75")
	)
	(segment
		(start 59.328812 -200.3933)
		(end 53.848 -208.22031)
		(width 0.1397)
		(layer "In2.Cu")
		(net "PCIE_RX_N75")
	)
	(segment
		(start 82.252566 -193.895218)
		(end 75.744324 -192.747646)
		(width 0.1397)
		(layer "In2.Cu")
		(net "PCIE_RX_N75")
	)
	(segment
		(start 163.749482 -134.610602)
		(end 102.648004 -177.394362)
		(width 0.1397)
		(layer "In2.Cu")
		(net "PCIE_RX_N75")
	)
	(segment
		(start 225.100134 -46.500034)
		(end 225.100134 -46.512734)
		(width 0.1016)
		(layer "In2.Cu")
		(net "PCIE_RX_N75")
	)
	(segment
		(start 95.25 -187.96)
		(end 88.29548 -192.829688)
		(width 0.1397)
		(layer "In2.Cu")
		(net "PCIE_RX_N75")
	)
	(segment
		(start 225.706432 -46.521624)
		(end 225.706432 -46.404784)
		(width 0.1016)
		(layer "In2.Cu")
		(net "PCIE_RX_N75")
	)
	(arc
		(start 225.706432 -46.404784)
		(mid 225.688934 -46.316817)
		(end 225.639122 -46.242224)
		(width 0.1016)
		(layer "In2.Cu")
		(net "PCIE_RX_N75")
	)
	(arc
		(start 225.523298 -46.133766)
		(mid 225.464106 -46.106438)
		(end 225.3996 -46.096936)
		(width 0.1016)
		(layer "In2.Cu")
		(net "PCIE_RX_N75")
	)
	(arc
		(start 225.4758 -46.788578)
		(mid 225.544522 -46.774908)
		(end 225.6028 -46.736)
		(width 0.1016)
		(layer "In2.Cu")
		(net "PCIE_RX_N75")
	)
	(arc
		(start 225.561144 -46.163992)
		(mid 225.54302 -46.147879)
		(end 225.523298 -46.133766)
		(width 0.1016)
		(layer "In2.Cu")
		(net "PCIE_RX_N75")
	)
	(arc
		(start 225.305366 -46.717966)
		(mid 225.383562 -46.770215)
		(end 225.4758 -46.788578)
		(width 0.1016)
		(layer "In2.Cu")
		(net "PCIE_RX_N75")
	)
	(arc
		(start 50.6476 -221.035626)
		(mid 50.668012 -221.138713)
		(end 50.72634 -221.226126)
		(width 0.1397)
		(layer "In2.Cu")
		(net "PCIE_RX_N75")
	)
	(arc
		(start 225.6282 -46.7106)
		(mid 225.686133 -46.623897)
		(end 225.706432 -46.521624)
		(width 0.1016)
		(layer "In2.Cu")
		(net "PCIE_RX_N75")
	)
	(segment
		(start 226.600004 -47.999904)
		(end 226.100132 -48.499776)
		(width 0.136652)
		(layer "F.Cu")
		(net "PCIE_RX_N74")
	)
	(via
		(at 226.100132 -48.499776)
		(size 0.4572)
		(drill 0.2032)
		(layers "F.Cu" "B.Cu")
		(net "PCIE_RX_N74")
	)
	(via
		(at 54.106318 -222.294704)
		(size 0.508)
		(drill 0.254)
		(layers "F.Cu" "B.Cu")
		(net "PCIE_RX_N74")
	)
	(segment
		(start 53.852572 -224.17278)
		(end 53.852572 -222.907352)
		(width 0.136652)
		(layer "B.Cu")
		(net "PCIE_RX_N74")
	)
	(segment
		(start 54.099968 -225.92538)
		(end 54.099968 -224.770188)
		(width 0.136652)
		(layer "B.Cu")
		(net "PCIE_RX_N74")
	)
	(arc
		(start 54.099968 -224.770188)
		(mid 54.05573 -224.547791)
		(end 53.929788 -224.359216)
		(width 0.136652)
		(layer "B.Cu")
		(net "PCIE_RX_N74")
	)
	(arc
		(start 53.929788 -224.359216)
		(mid 53.872634 -224.273678)
		(end 53.852572 -224.17278)
		(width 0.136652)
		(layer "B.Cu")
		(net "PCIE_RX_N74")
	)
	(arc
		(start 53.852572 -222.907352)
		(mid 53.918522 -222.575797)
		(end 54.106318 -222.294704)
		(width 0.136652)
		(layer "B.Cu")
		(net "PCIE_RX_N74")
	)
	(segment
		(start 219.127324 -47.752)
		(end 217.41511 -48.053752)
		(width 0.1397)
		(layer "In2.Cu")
		(net "PCIE_RX_N74")
	)
	(segment
		(start 60.729876 -202.332844)
		(end 57.048908 -207.589628)
		(width 0.1397)
		(layer "In2.Cu")
		(net "PCIE_RX_N74")
	)
	(segment
		(start 87.828628 -194.969638)
		(end 80.220058 -196.311266)
		(width 0.1397)
		(layer "In2.Cu")
		(net "PCIE_RX_N74")
	)
	(segment
		(start 71.247 -196.342)
		(end 68.067936 -198.568056)
		(width 0.1397)
		(layer "In2.Cu")
		(net "PCIE_RX_N74")
	)
	(segment
		(start 217.41511 -48.053752)
		(end 216.396062 -48.23333)
		(width 0.1397)
		(layer "In2.Cu")
		(net "PCIE_RX_N74")
	)
	(segment
		(start 226.6442 -48.622966)
		(end 226.6442 -48.176942)
		(width 0.1397)
		(layer "In2.Cu")
		(net "PCIE_RX_N74")
	)
	(segment
		(start 96.145858 -189.145926)
		(end 87.828628 -194.969638)
		(width 0.1397)
		(layer "In2.Cu")
		(net "PCIE_RX_N74")
	)
	(segment
		(start 65.446402 -199.030082)
		(end 60.729876 -202.332844)
		(width 0.1397)
		(layer "In2.Cu")
		(net "PCIE_RX_N74")
	)
	(segment
		(start 57.0484 -214.647272)
		(end 53.865018 -220.087698)
		(width 0.1397)
		(layer "In2.Cu")
		(net "PCIE_RX_N74")
	)
	(segment
		(start 68.067936 -198.568056)
		(end 65.446402 -199.030082)
		(width 0.1397)
		(layer "In2.Cu")
		(net "PCIE_RX_N74")
	)
	(segment
		(start 57.048654 -214.647272)
		(end 57.0484 -214.647272)
		(width 0.1397)
		(layer "In2.Cu")
		(net "PCIE_RX_N74")
	)
	(segment
		(start 207.638904 -57.974484)
		(end 206.128366 -66.537586)
		(width 0.1397)
		(layer "In2.Cu")
		(net "PCIE_RX_N74")
	)
	(segment
		(start 226.640898 -48.12284)
		(end 226.640644 -48.122586)
		(width 0.1397)
		(layer "In2.Cu")
		(net "PCIE_RX_N74")
	)
	(segment
		(start 53.865018 -220.087698)
		(end 53.865018 -221.7166)
		(width 0.1397)
		(layer "In2.Cu")
		(net "PCIE_RX_N74")
	)
	(segment
		(start 226.255326 -47.752)
		(end 219.127324 -47.752)
		(width 0.1397)
		(layer "In2.Cu")
		(net "PCIE_RX_N74")
	)
	(segment
		(start 206.78902 -70.285102)
		(end 205.399132 -78.165452)
		(width 0.1397)
		(layer "In2.Cu")
		(net "PCIE_RX_N74")
	)
	(segment
		(start 216.396062 -48.23333)
		(end 212.595968 -50.894234)
		(width 0.1397)
		(layer "In2.Cu")
		(net "PCIE_RX_N74")
	)
	(segment
		(start 57.048908 -207.589628)
		(end 57.048654 -214.647272)
		(width 0.1397)
		(layer "In2.Cu")
		(net "PCIE_RX_N74")
	)
	(segment
		(start 75.820524 -195.53555)
		(end 71.247 -196.342)
		(width 0.1397)
		(layer "In2.Cu")
		(net "PCIE_RX_N74")
	)
	(segment
		(start 80.220058 -196.311266)
		(end 75.820524 -195.53555)
		(width 0.1397)
		(layer "In2.Cu")
		(net "PCIE_RX_N74")
	)
	(segment
		(start 162.597846 -139.29233)
		(end 100.711 -182.626)
		(width 0.1397)
		(layer "In2.Cu")
		(net "PCIE_RX_N74")
	)
	(segment
		(start 100.711 -182.626)
		(end 96.145858 -189.145926)
		(width 0.1397)
		(layer "In2.Cu")
		(net "PCIE_RX_N74")
	)
	(segment
		(start 212.595968 -50.894234)
		(end 207.638904 -57.974484)
		(width 0.1397)
		(layer "In2.Cu")
		(net "PCIE_RX_N74")
	)
	(segment
		(start 206.128366 -66.537586)
		(end 206.78902 -70.285102)
		(width 0.1397)
		(layer "In2.Cu")
		(net "PCIE_RX_N74")
	)
	(segment
		(start 205.399132 -78.165452)
		(end 162.597846 -139.29233)
		(width 0.1397)
		(layer "In2.Cu")
		(net "PCIE_RX_N74")
	)
	(segment
		(start 226.100132 -48.499776)
		(end 226.100132 -48.622966)
		(width 0.1397)
		(layer "In2.Cu")
		(net "PCIE_RX_N74")
	)
	(segment
		(start 54.10327 -222.291402)
		(end 54.106318 -222.294704)
		(width 0.1397)
		(layer "In2.Cu")
		(net "PCIE_RX_N74")
	)
	(arc
		(start 226.59467 -47.97171)
		(mid 226.557932 -47.911985)
		(end 226.512374 -47.85868)
		(width 0.1397)
		(layer "In2.Cu")
		(net "PCIE_RX_N74")
	)
	(arc
		(start 226.100132 -48.622966)
		(mid 226.372166 -48.895)
		(end 226.6442 -48.622966)
		(width 0.1397)
		(layer "In2.Cu")
		(net "PCIE_RX_N74")
	)
	(arc
		(start 226.640644 -48.122586)
		(mid 226.624336 -48.045111)
		(end 226.59467 -47.97171)
		(width 0.1397)
		(layer "In2.Cu")
		(net "PCIE_RX_N74")
	)
	(arc
		(start 226.512374 -47.85868)
		(mid 226.39444 -47.779849)
		(end 226.255326 -47.752)
		(width 0.1397)
		(layer "In2.Cu")
		(net "PCIE_RX_N74")
	)
	(arc
		(start 53.865018 -221.7166)
		(mid 53.926991 -222.027689)
		(end 54.10327 -222.291402)
		(width 0.1397)
		(layer "In2.Cu")
		(net "PCIE_RX_N74")
	)
	(arc
		(start 226.6442 -48.176942)
		(mid 226.643368 -48.149841)
		(end 226.640898 -48.12284)
		(width 0.1397)
		(layer "In2.Cu")
		(net "PCIE_RX_N74")
	)
	(segment
		(start 225.438716 -49.389284)
		(end 225.3996 -49.4284)
		(width 0.136652)
		(layer "F.Cu")
		(net "PCIE_RX_N73")
	)
	(segment
		(start 225.227388 -49.499774)
		(end 225.100134 -49.499774)
		(width 0.136652)
		(layer "F.Cu")
		(net "PCIE_RX_N73")
	)
	(via
		(at 57.30621 -222.294704)
		(size 0.508)
		(drill 0.254)
		(layers "F.Cu" "B.Cu")
		(net "PCIE_RX_N73")
	)
	(via
		(at 225.100134 -49.499774)
		(size 0.4572)
		(drill 0.2032)
		(layers "F.Cu" "B.Cu")
		(net "PCIE_RX_N73")
	)
	(arc
		(start 225.600006 -48.999902)
		(mid 225.558089 -49.210635)
		(end 225.438716 -49.389284)
		(width 0.136652)
		(layer "F.Cu")
		(net "PCIE_RX_N73")
	)
	(arc
		(start 225.3996 -49.4284)
		(mid 225.320588 -49.481194)
		(end 225.227388 -49.499774)
		(width 0.136652)
		(layer "F.Cu")
		(net "PCIE_RX_N73")
	)
	(segment
		(start 57.300114 -224.770442)
		(end 57.29986 -224.770188)
		(width 0.136652)
		(layer "B.Cu")
		(net "PCIE_RX_N73")
	)
	(segment
		(start 57.052464 -224.17278)
		(end 57.052464 -222.907352)
		(width 0.136652)
		(layer "B.Cu")
		(net "PCIE_RX_N73")
	)
	(segment
		(start 57.300114 -225.92538)
		(end 57.300114 -224.770442)
		(width 0.136652)
		(layer "B.Cu")
		(net "PCIE_RX_N73")
	)
	(arc
		(start 57.052464 -222.907352)
		(mid 57.118414 -222.575797)
		(end 57.30621 -222.294704)
		(width 0.136652)
		(layer "B.Cu")
		(net "PCIE_RX_N73")
	)
	(arc
		(start 57.29986 -224.770188)
		(mid 57.255622 -224.547791)
		(end 57.12968 -224.359216)
		(width 0.136652)
		(layer "B.Cu")
		(net "PCIE_RX_N73")
	)
	(arc
		(start 57.12968 -224.359216)
		(mid 57.072526 -224.273678)
		(end 57.052464 -224.17278)
		(width 0.136652)
		(layer "B.Cu")
		(net "PCIE_RX_N73")
	)
	(segment
		(start 218.677744 -49.25949)
		(end 217.677492 -49.435766)
		(width 0.1397)
		(layer "In2.Cu")
		(net "PCIE_RX_N73")
	)
	(segment
		(start 60.488068 -209.838544)
		(end 60.706 -211.074)
		(width 0.1397)
		(layer "In2.Cu")
		(net "PCIE_RX_N73")
	)
	(segment
		(start 221.540324 -49.096676)
		(end 221.4372 -49.1998)
		(width 0.1016)
		(layer "In2.Cu")
		(net "PCIE_RX_N73")
	)
	(segment
		(start 209.784442 -76.247752)
		(end 166.348664 -138.279632)
		(width 0.1397)
		(layer "In2.Cu")
		(net "PCIE_RX_N73")
	)
	(segment
		(start 101.711252 -183.539384)
		(end 97.1042 -190.119)
		(width 0.1397)
		(layer "In2.Cu")
		(net "PCIE_RX_N73")
	)
	(segment
		(start 88.034368 -196.469762)
		(end 66.203322 -200.319132)
		(width 0.1397)
		(layer "In2.Cu")
		(net "PCIE_RX_N73")
	)
	(segment
		(start 212.848698 -52.817014)
		(end 210.801712 -55.7403)
		(width 0.1397)
		(layer "In2.Cu")
		(net "PCIE_RX_N73")
	)
	(segment
		(start 66.203322 -200.319132)
		(end 63.3222 -202.3364)
		(width 0.1397)
		(layer "In2.Cu")
		(net "PCIE_RX_N73")
	)
	(segment
		(start 219.017088 -49.1998)
		(end 218.677744 -49.25949)
		(width 0.1397)
		(layer "In2.Cu")
		(net "PCIE_RX_N73")
	)
	(segment
		(start 210.801712 -55.7403)
		(end 209.64906 -62.277498)
		(width 0.1397)
		(layer "In2.Cu")
		(net "PCIE_RX_N73")
	)
	(segment
		(start 57.06491 -219.309696)
		(end 57.06491 -221.712028)
		(width 0.1397)
		(layer "In2.Cu")
		(net "PCIE_RX_N73")
	)
	(segment
		(start 225.706432 -49.4538)
		(end 225.706432 -49.40554)
		(width 0.1016)
		(layer "In2.Cu")
		(net "PCIE_RX_N73")
	)
	(segment
		(start 166.348664 -138.279632)
		(end 101.711252 -183.539384)
		(width 0.1397)
		(layer "In2.Cu")
		(net "PCIE_RX_N73")
	)
	(segment
		(start 210.949286 -69.651626)
		(end 209.784442 -76.247752)
		(width 0.1397)
		(layer "In2.Cu")
		(net "PCIE_RX_N73")
	)
	(segment
		(start 217.677492 -49.435766)
		(end 212.848698 -52.817014)
		(width 0.1397)
		(layer "In2.Cu")
		(net "PCIE_RX_N73")
	)
	(segment
		(start 221.4372 -49.1998)
		(end 219.017088 -49.1998)
		(width 0.1397)
		(layer "In2.Cu")
		(net "PCIE_RX_N73")
	)
	(segment
		(start 225.631756 -49.62779)
		(end 225.636328 -49.623472)
		(width 0.1016)
		(layer "In2.Cu")
		(net "PCIE_RX_N73")
	)
	(segment
		(start 97.1042 -190.119)
		(end 88.034368 -196.469762)
		(width 0.1397)
		(layer "In2.Cu")
		(net "PCIE_RX_N73")
	)
	(segment
		(start 60.706 -211.074)
		(end 59.990736 -215.131142)
		(width 0.1397)
		(layer "In2.Cu")
		(net "PCIE_RX_N73")
	)
	(segment
		(start 225.290634 -49.690274)
		(end 225.48088 -49.690274)
		(width 0.1016)
		(layer "In2.Cu")
		(net "PCIE_RX_N73")
	)
	(segment
		(start 60.774072 -205.975458)
		(end 60.290456 -208.717134)
		(width 0.1397)
		(layer "In2.Cu")
		(net "PCIE_RX_N73")
	)
	(segment
		(start 225.380296 -49.096676)
		(end 221.540324 -49.096676)
		(width 0.1016)
		(layer "In2.Cu")
		(net "PCIE_RX_N73")
	)
	(segment
		(start 225.638106 -49.240694)
		(end 225.574606 -49.177194)
		(width 0.1016)
		(layer "In2.Cu")
		(net "PCIE_RX_N73")
	)
	(segment
		(start 59.990736 -215.131142)
		(end 57.06491 -219.309696)
		(width 0.1397)
		(layer "In2.Cu")
		(net "PCIE_RX_N73")
	)
	(segment
		(start 60.290456 -208.717134)
		(end 60.488068 -209.838544)
		(width 0.1397)
		(layer "In2.Cu")
		(net "PCIE_RX_N73")
	)
	(segment
		(start 209.64906 -62.277498)
		(end 210.949286 -69.651626)
		(width 0.1397)
		(layer "In2.Cu")
		(net "PCIE_RX_N73")
	)
	(segment
		(start 63.3222 -202.3364)
		(end 60.774072 -205.975458)
		(width 0.1397)
		(layer "In2.Cu")
		(net "PCIE_RX_N73")
	)
	(arc
		(start 57.06491 -221.712028)
		(mid 57.127631 -222.02735)
		(end 57.30621 -222.294704)
		(width 0.1397)
		(layer "In2.Cu")
		(net "PCIE_RX_N73")
	)
	(arc
		(start 225.574606 -49.177194)
		(mid 225.485456 -49.117626)
		(end 225.380296 -49.096676)
		(width 0.1016)
		(layer "In2.Cu")
		(net "PCIE_RX_N73")
	)
	(arc
		(start 225.48088 -49.690274)
		(mid 225.562529 -49.674033)
		(end 225.631756 -49.62779)
		(width 0.1016)
		(layer "In2.Cu")
		(net "PCIE_RX_N73")
	)
	(arc
		(start 225.100134 -49.499774)
		(mid 225.15593 -49.634478)
		(end 225.290634 -49.690274)
		(width 0.1016)
		(layer "In2.Cu")
		(net "PCIE_RX_N73")
	)
	(arc
		(start 225.706432 -49.40554)
		(mid 225.705014 -49.380115)
		(end 225.700844 -49.354994)
		(width 0.1016)
		(layer "In2.Cu")
		(net "PCIE_RX_N73")
	)
	(arc
		(start 225.636328 -49.623472)
		(mid 225.68826 -49.545611)
		(end 225.706432 -49.4538)
		(width 0.1016)
		(layer "In2.Cu")
		(net "PCIE_RX_N73")
	)
	(arc
		(start 225.700844 -49.354994)
		(mid 225.677629 -49.293368)
		(end 225.638106 -49.240694)
		(width 0.1016)
		(layer "In2.Cu")
		(net "PCIE_RX_N73")
	)
	(segment
		(start 226.600004 -49.9999)
		(end 226.600004 -50.193702)
		(width 0.136652)
		(layer "F.Cu")
		(net "PCIE_RX_N72")
	)
	(segment
		(start 226.260914 -50.499772)
		(end 226.100132 -50.499772)
		(width 0.136652)
		(layer "F.Cu")
		(net "PCIE_RX_N72")
	)
	(via
		(at 60.506102 -222.294704)
		(size 0.508)
		(drill 0.254)
		(layers "F.Cu" "B.Cu")
		(net "PCIE_RX_N72")
	)
	(via
		(at 226.100132 -50.499772)
		(size 0.4572)
		(drill 0.2032)
		(layers "F.Cu" "B.Cu")
		(net "PCIE_RX_N72")
	)
	(arc
		(start 226.5172 -50.3936)
		(mid 226.399615 -50.472168)
		(end 226.260914 -50.499772)
		(width 0.136652)
		(layer "F.Cu")
		(net "PCIE_RX_N72")
	)
	(arc
		(start 226.600004 -50.193702)
		(mid 226.578485 -50.301887)
		(end 226.5172 -50.3936)
		(width 0.136652)
		(layer "F.Cu")
		(net "PCIE_RX_N72")
	)
	(segment
		(start 60.500006 -225.92538)
		(end 60.500006 -224.770442)
		(width 0.136652)
		(layer "B.Cu")
		(net "PCIE_RX_N72")
	)
	(segment
		(start 60.500006 -224.770442)
		(end 60.499752 -224.770188)
		(width 0.136652)
		(layer "B.Cu")
		(net "PCIE_RX_N72")
	)
	(segment
		(start 60.252356 -224.17278)
		(end 60.252356 -222.907352)
		(width 0.136652)
		(layer "B.Cu")
		(net "PCIE_RX_N72")
	)
	(arc
		(start 60.329572 -224.359216)
		(mid 60.272418 -224.273678)
		(end 60.252356 -224.17278)
		(width 0.136652)
		(layer "B.Cu")
		(net "PCIE_RX_N72")
	)
	(arc
		(start 60.252356 -222.907352)
		(mid 60.318306 -222.575797)
		(end 60.506102 -222.294704)
		(width 0.136652)
		(layer "B.Cu")
		(net "PCIE_RX_N72")
	)
	(arc
		(start 60.499752 -224.770188)
		(mid 60.455514 -224.547791)
		(end 60.329572 -224.359216)
		(width 0.136652)
		(layer "B.Cu")
		(net "PCIE_RX_N72")
	)
	(segment
		(start 60.264802 -221.712028)
		(end 60.264802 -220.059504)
		(width 0.1397)
		(layer "In2.Cu")
		(net "PCIE_RX_N72")
	)
	(segment
		(start 63.8302 -204.8764)
		(end 69.505322 -200.90257)
		(width 0.1397)
		(layer "In2.Cu")
		(net "PCIE_RX_N72")
	)
	(segment
		(start 88.650064 -197.527164)
		(end 97.8154 -191.1096)
		(width 0.1397)
		(layer "In2.Cu")
		(net "PCIE_RX_N72")
	)
	(segment
		(start 210.873848 -62.000638)
		(end 211.898484 -56.190388)
		(width 0.1397)
		(layer "In2.Cu")
		(net "PCIE_RX_N72")
	)
	(segment
		(start 61.79439 -207.783684)
		(end 63.8302 -204.8764)
		(width 0.1397)
		(layer "In2.Cu")
		(net "PCIE_RX_N72")
	)
	(segment
		(start 97.8154 -191.1096)
		(end 99.972622 -188.02858)
		(width 0.1397)
		(layer "In2.Cu")
		(net "PCIE_RX_N72")
	)
	(segment
		(start 99.972622 -188.02858)
		(end 165.513258 -142.13713)
		(width 0.1397)
		(layer "In2.Cu")
		(net "PCIE_RX_N72")
	)
	(segment
		(start 212.015832 -74.52741)
		(end 211.44611 -71.29653)
		(width 0.1397)
		(layer "In2.Cu")
		(net "PCIE_RX_N72")
	)
	(segment
		(start 211.7344 -76.1238)
		(end 212.015832 -74.52741)
		(width 0.1397)
		(layer "In2.Cu")
		(net "PCIE_RX_N72")
	)
	(segment
		(start 61.849 -211.074)
		(end 61.531754 -209.274156)
		(width 0.1397)
		(layer "In2.Cu")
		(net "PCIE_RX_N72")
	)
	(segment
		(start 218.378786 -50.433478)
		(end 219.9005 -50.165)
		(width 0.1397)
		(layer "In2.Cu")
		(net "PCIE_RX_N72")
	)
	(segment
		(start 211.898484 -56.190388)
		(end 213.573868 -53.797708)
		(width 0.1397)
		(layer "In2.Cu")
		(net "PCIE_RX_N72")
	)
	(segment
		(start 226.574604 -50.177192)
		(end 226.638104 -50.240692)
		(width 0.1016)
		(layer "In2.Cu")
		(net "PCIE_RX_N72")
	)
	(segment
		(start 213.573868 -53.797708)
		(end 218.378786 -50.433478)
		(width 0.1397)
		(layer "In2.Cu")
		(net "PCIE_RX_N72")
	)
	(segment
		(start 211.44611 -71.29653)
		(end 211.979764 -68.271898)
		(width 0.1397)
		(layer "In2.Cu")
		(net "PCIE_RX_N72")
	)
	(segment
		(start 221.881446 -50.096674)
		(end 226.380294 -50.096674)
		(width 0.1016)
		(layer "In2.Cu")
		(net "PCIE_RX_N72")
	)
	(segment
		(start 226.70643 -50.405538)
		(end 226.70643 -50.453798)
		(width 0.1016)
		(layer "In2.Cu")
		(net "PCIE_RX_N72")
	)
	(segment
		(start 165.513258 -142.13713)
		(end 211.7344 -76.1238)
		(width 0.1397)
		(layer "In2.Cu")
		(net "PCIE_RX_N72")
	)
	(segment
		(start 211.979764 -68.271898)
		(end 210.873848 -62.000638)
		(width 0.1397)
		(layer "In2.Cu")
		(net "PCIE_RX_N72")
	)
	(segment
		(start 226.480878 -50.690272)
		(end 226.290632 -50.690272)
		(width 0.1016)
		(layer "In2.Cu")
		(net "PCIE_RX_N72")
	)
	(segment
		(start 60.264802 -220.059504)
		(end 61.849 -211.074)
		(width 0.1397)
		(layer "In2.Cu")
		(net "PCIE_RX_N72")
	)
	(segment
		(start 61.531754 -209.274156)
		(end 61.79439 -207.783684)
		(width 0.1397)
		(layer "In2.Cu")
		(net "PCIE_RX_N72")
	)
	(segment
		(start 69.505322 -200.90257)
		(end 88.650064 -197.527164)
		(width 0.1397)
		(layer "In2.Cu")
		(net "PCIE_RX_N72")
	)
	(segment
		(start 219.9005 -50.165)
		(end 221.7166 -50.165)
		(width 0.1397)
		(layer "In2.Cu")
		(net "PCIE_RX_N72")
	)
	(segment
		(start 226.636326 -50.62347)
		(end 226.631754 -50.627788)
		(width 0.1016)
		(layer "In2.Cu")
		(net "PCIE_RX_N72")
	)
	(arc
		(start 226.380294 -50.096674)
		(mid 226.485466 -50.117594)
		(end 226.574604 -50.177192)
		(width 0.1016)
		(layer "In2.Cu")
		(net "PCIE_RX_N72")
	)
	(arc
		(start 226.638104 -50.240692)
		(mid 226.68864 -50.316324)
		(end 226.70643 -50.405538)
		(width 0.1016)
		(layer "In2.Cu")
		(net "PCIE_RX_N72")
	)
	(arc
		(start 226.70643 -50.453798)
		(mid 226.688261 -50.54561)
		(end 226.636326 -50.62347)
		(width 0.1016)
		(layer "In2.Cu")
		(net "PCIE_RX_N72")
	)
	(arc
		(start 226.290632 -50.690272)
		(mid 226.155928 -50.634476)
		(end 226.100132 -50.499772)
		(width 0.1016)
		(layer "In2.Cu")
		(net "PCIE_RX_N72")
	)
	(arc
		(start 226.631754 -50.627788)
		(mid 226.562532 -50.674041)
		(end 226.480878 -50.690272)
		(width 0.1016)
		(layer "In2.Cu")
		(net "PCIE_RX_N72")
	)
	(arc
		(start 60.506102 -222.294704)
		(mid 60.327475 -222.02737)
		(end 60.264802 -221.712028)
		(width 0.1397)
		(layer "In2.Cu")
		(net "PCIE_RX_N72")
	)
	(arc
		(start 221.7166 -50.165)
		(mid 221.792232 -50.114464)
		(end 221.881446 -50.096674)
		(width 0.1016)
		(layer "In2.Cu")
		(net "PCIE_RX_N72")
	)
	(segment
		(start 225.487992 -52.388008)
		(end 225.473768 -52.402232)
		(width 0.136652)
		(layer "F.Cu")
		(net "PCIE_RX_N71")
	)
	(segment
		(start 225.600006 -51.999896)
		(end 225.600006 -52.117752)
		(width 0.136652)
		(layer "F.Cu")
		(net "PCIE_RX_N71")
	)
	(segment
		(start 225.238056 -52.499768)
		(end 225.100134 -52.499768)
		(width 0.136652)
		(layer "F.Cu")
		(net "PCIE_RX_N71")
	)
	(via
		(at 66.106294 -222.294704)
		(size 0.508)
		(drill 0.254)
		(layers "F.Cu" "B.Cu")
		(net "PCIE_RX_N71")
	)
	(via
		(at 225.100134 -52.499768)
		(size 0.4572)
		(drill 0.2032)
		(layers "F.Cu" "B.Cu")
		(net "PCIE_RX_N71")
	)
	(arc
		(start 225.473768 -52.402232)
		(mid 225.365608 -52.474439)
		(end 225.238056 -52.499768)
		(width 0.136652)
		(layer "F.Cu")
		(net "PCIE_RX_N71")
	)
	(arc
		(start 225.600006 -52.117752)
		(mid 225.570892 -52.264026)
		(end 225.487992 -52.388008)
		(width 0.136652)
		(layer "F.Cu")
		(net "PCIE_RX_N71")
	)
	(segment
		(start 65.852548 -224.17278)
		(end 65.852548 -222.907352)
		(width 0.136652)
		(layer "B.Cu")
		(net "PCIE_RX_N71")
	)
	(segment
		(start 66.100198 -224.770442)
		(end 66.099944 -224.770188)
		(width 0.136652)
		(layer "B.Cu")
		(net "PCIE_RX_N71")
	)
	(segment
		(start 66.100198 -225.92538)
		(end 66.100198 -224.770442)
		(width 0.136652)
		(layer "B.Cu")
		(net "PCIE_RX_N71")
	)
	(arc
		(start 65.929764 -224.359216)
		(mid 65.87261 -224.273678)
		(end 65.852548 -224.17278)
		(width 0.136652)
		(layer "B.Cu")
		(net "PCIE_RX_N71")
	)
	(arc
		(start 66.099944 -224.770188)
		(mid 66.055706 -224.547791)
		(end 65.929764 -224.359216)
		(width 0.136652)
		(layer "B.Cu")
		(net "PCIE_RX_N71")
	)
	(arc
		(start 65.852548 -222.907352)
		(mid 65.918498 -222.575797)
		(end 66.106294 -222.294704)
		(width 0.136652)
		(layer "B.Cu")
		(net "PCIE_RX_N71")
	)
	(segment
		(start 213.357206 -74.40549)
		(end 213.357206 -74.904346)
		(width 0.1397)
		(layer "In2.Cu")
		(net "PCIE_RX_N71")
	)
	(segment
		(start 168.341802 -141.861794)
		(end 99.972114 -189.734698)
		(width 0.1397)
		(layer "In2.Cu")
		(net "PCIE_RX_N71")
	)
	(segment
		(start 65.700402 -213.169246)
		(end 66.15811 -215.76665)
		(width 0.1397)
		(layer "In2.Cu")
		(net "PCIE_RX_N71")
	)
	(segment
		(start 212.728302 -78.471522)
		(end 168.341802 -141.861794)
		(width 0.1397)
		(layer "In2.Cu")
		(net "PCIE_RX_N71")
	)
	(segment
		(start 225.290634 -52.690268)
		(end 225.48088 -52.690268)
		(width 0.1016)
		(layer "In2.Cu")
		(net "PCIE_RX_N71")
	)
	(segment
		(start 225.638106 -52.240688)
		(end 225.574606 -52.177188)
		(width 0.1016)
		(layer "In2.Cu")
		(net "PCIE_RX_N71")
	)
	(segment
		(start 98.228912 -192.224406)
		(end 87.219028 -199.93356)
		(width 0.1397)
		(layer "In2.Cu")
		(net "PCIE_RX_N71")
	)
	(segment
		(start 212.806788 -71.277734)
		(end 212.806788 -71.284592)
		(width 0.1397)
		(layer "In2.Cu")
		(net "PCIE_RX_N71")
	)
	(segment
		(start 212.358478 -61.763656)
		(end 213.421468 -67.792092)
		(width 0.1397)
		(layer "In2.Cu")
		(net "PCIE_RX_N71")
	)
	(segment
		(start 66.675 -205.994)
		(end 65.913 -207.082136)
		(width 0.1397)
		(layer "In2.Cu")
		(net "PCIE_RX_N71")
	)
	(segment
		(start 65.913 -211.963)
		(end 65.700402 -213.169246)
		(width 0.1397)
		(layer "In2.Cu")
		(net "PCIE_RX_N71")
	)
	(segment
		(start 66.15811 -215.76665)
		(end 65.495932 -219.522294)
		(width 0.1397)
		(layer "In2.Cu")
		(net "PCIE_RX_N71")
	)
	(segment
		(start 219.3544 -52.1716)
		(end 217.738706 -52.456334)
		(width 0.1397)
		(layer "In2.Cu")
		(net "PCIE_RX_N71")
	)
	(segment
		(start 99.972114 -189.734698)
		(end 98.228912 -192.224406)
		(width 0.1397)
		(layer "In2.Cu")
		(net "PCIE_RX_N71")
	)
	(segment
		(start 225.380296 -52.09667)
		(end 221.694248 -52.09667)
		(width 0.1016)
		(layer "In2.Cu")
		(net "PCIE_RX_N71")
	)
	(segment
		(start 212.806788 -71.284592)
		(end 213.357206 -74.40549)
		(width 0.1397)
		(layer "In2.Cu")
		(net "PCIE_RX_N71")
	)
	(segment
		(start 221.5134 -52.1716)
		(end 219.3544 -52.1716)
		(width 0.1397)
		(layer "In2.Cu")
		(net "PCIE_RX_N71")
	)
	(segment
		(start 215.433402 -54.070504)
		(end 213.136988 -57.350152)
		(width 0.1397)
		(layer "In2.Cu")
		(net "PCIE_RX_N71")
	)
	(segment
		(start 71.327772 -202.736196)
		(end 66.675 -205.994)
		(width 0.1397)
		(layer "In2.Cu")
		(net "PCIE_RX_N71")
	)
	(segment
		(start 213.421468 -67.792092)
		(end 212.806788 -71.277734)
		(width 0.1397)
		(layer "In2.Cu")
		(net "PCIE_RX_N71")
	)
	(segment
		(start 65.495932 -219.522294)
		(end 65.864994 -221.615)
		(width 0.1397)
		(layer "In2.Cu")
		(net "PCIE_RX_N71")
	)
	(segment
		(start 225.631756 -52.627784)
		(end 225.636328 -52.623466)
		(width 0.1016)
		(layer "In2.Cu")
		(net "PCIE_RX_N71")
	)
	(segment
		(start 225.706432 -52.453794)
		(end 225.706432 -52.405534)
		(width 0.1016)
		(layer "In2.Cu")
		(net "PCIE_RX_N71")
	)
	(segment
		(start 217.738706 -52.456334)
		(end 215.433402 -54.070504)
		(width 0.1397)
		(layer "In2.Cu")
		(net "PCIE_RX_N71")
	)
	(segment
		(start 213.136988 -57.350152)
		(end 212.358478 -61.763656)
		(width 0.1397)
		(layer "In2.Cu")
		(net "PCIE_RX_N71")
	)
	(segment
		(start 87.219028 -199.93356)
		(end 71.327772 -202.736196)
		(width 0.1397)
		(layer "In2.Cu")
		(net "PCIE_RX_N71")
	)
	(segment
		(start 65.913 -207.082136)
		(end 65.913 -211.963)
		(width 0.1397)
		(layer "In2.Cu")
		(net "PCIE_RX_N71")
	)
	(segment
		(start 213.357206 -74.904346)
		(end 212.728302 -78.471522)
		(width 0.1397)
		(layer "In2.Cu")
		(net "PCIE_RX_N71")
	)
	(segment
		(start 65.864994 -221.615)
		(end 65.864994 -221.712028)
		(width 0.1397)
		(layer "In2.Cu")
		(net "PCIE_RX_N71")
	)
	(arc
		(start 225.48088 -52.690268)
		(mid 225.562529 -52.674027)
		(end 225.631756 -52.627784)
		(width 0.1016)
		(layer "In2.Cu")
		(net "PCIE_RX_N71")
	)
	(arc
		(start 225.700844 -52.354988)
		(mid 225.677629 -52.293362)
		(end 225.638106 -52.240688)
		(width 0.1016)
		(layer "In2.Cu")
		(net "PCIE_RX_N71")
	)
	(arc
		(start 225.574606 -52.177188)
		(mid 225.485456 -52.11762)
		(end 225.380296 -52.09667)
		(width 0.1016)
		(layer "In2.Cu")
		(net "PCIE_RX_N71")
	)
	(arc
		(start 225.706432 -52.405534)
		(mid 225.705014 -52.380109)
		(end 225.700844 -52.354988)
		(width 0.1016)
		(layer "In2.Cu")
		(net "PCIE_RX_N71")
	)
	(arc
		(start 221.694248 -52.09667)
		(mid 221.596366 -52.11614)
		(end 221.5134 -52.1716)
		(width 0.1016)
		(layer "In2.Cu")
		(net "PCIE_RX_N71")
	)
	(arc
		(start 225.100134 -52.499768)
		(mid 225.15593 -52.634472)
		(end 225.290634 -52.690268)
		(width 0.1016)
		(layer "In2.Cu")
		(net "PCIE_RX_N71")
	)
	(arc
		(start 65.864994 -221.712028)
		(mid 65.927715 -222.02735)
		(end 66.106294 -222.294704)
		(width 0.1397)
		(layer "In2.Cu")
		(net "PCIE_RX_N71")
	)
	(arc
		(start 225.636328 -52.623466)
		(mid 225.68826 -52.545605)
		(end 225.706432 -52.453794)
		(width 0.1016)
		(layer "In2.Cu")
		(net "PCIE_RX_N71")
	)
	(segment
		(start 226.574604 -53.269896)
		(end 226.551998 -53.317648)
		(width 0.136652)
		(layer "F.Cu")
		(net "PCIE_RX_N70")
	)
	(segment
		(start 226.600004 -52.999894)
		(end 226.600004 -53.157628)
		(width 0.136652)
		(layer "F.Cu")
		(net "PCIE_RX_N70")
	)
	(segment
		(start 226.394264 -53.440838)
		(end 226.100132 -53.499766)
		(width 0.136652)
		(layer "F.Cu")
		(net "PCIE_RX_N70")
	)
	(via
		(at 226.100132 -53.499766)
		(size 0.4572)
		(drill 0.2032)
		(layers "F.Cu" "B.Cu")
		(net "PCIE_RX_N70")
	)
	(via
		(at 69.306186 -222.294704)
		(size 0.508)
		(drill 0.254)
		(layers "F.Cu" "B.Cu")
		(net "PCIE_RX_N70")
	)
	(arc
		(start 226.600004 -53.157628)
		(mid 226.59354 -53.215171)
		(end 226.574604 -53.269896)
		(width 0.136652)
		(layer "F.Cu")
		(net "PCIE_RX_N70")
	)
	(arc
		(start 226.551998 -53.317648)
		(mid 226.487694 -53.397878)
		(end 226.394264 -53.440838)
		(width 0.136652)
		(layer "F.Cu")
		(net "PCIE_RX_N70")
	)
	(segment
		(start 69.30009 -225.92538)
		(end 69.30009 -224.770442)
		(width 0.136652)
		(layer "B.Cu")
		(net "PCIE_RX_N70")
	)
	(segment
		(start 69.05244 -224.17278)
		(end 69.05244 -222.907352)
		(width 0.136652)
		(layer "B.Cu")
		(net "PCIE_RX_N70")
	)
	(segment
		(start 69.30009 -224.770442)
		(end 69.299836 -224.770188)
		(width 0.136652)
		(layer "B.Cu")
		(net "PCIE_RX_N70")
	)
	(arc
		(start 69.05244 -222.907352)
		(mid 69.11839 -222.575797)
		(end 69.306186 -222.294704)
		(width 0.136652)
		(layer "B.Cu")
		(net "PCIE_RX_N70")
	)
	(arc
		(start 69.299836 -224.770188)
		(mid 69.255598 -224.547791)
		(end 69.129656 -224.359216)
		(width 0.136652)
		(layer "B.Cu")
		(net "PCIE_RX_N70")
	)
	(arc
		(start 69.129656 -224.359216)
		(mid 69.072502 -224.273678)
		(end 69.05244 -224.17278)
		(width 0.136652)
		(layer "B.Cu")
		(net "PCIE_RX_N70")
	)
	(segment
		(start 69.088 -214.67191)
		(end 69.088 -209.042)
		(width 0.1397)
		(layer "In2.Cu")
		(net "PCIE_RX_N70")
	)
	(segment
		(start 69.064886 -219.291408)
		(end 69.483732 -216.915746)
		(width 0.1397)
		(layer "In2.Cu")
		(net "PCIE_RX_N70")
	)
	(segment
		(start 169.175176 -142.496286)
		(end 213.635336 -79.00162)
		(width 0.1397)
		(layer "In2.Cu")
		(net "PCIE_RX_N70")
	)
	(segment
		(start 72.449944 -204.884782)
		(end 87.70747 -202.195176)
		(width 0.1397)
		(layer "In2.Cu")
		(net "PCIE_RX_N70")
	)
	(segment
		(start 69.32295 -207.709008)
		(end 70.194932 -206.4639)
		(width 0.1397)
		(layer "In2.Cu")
		(net "PCIE_RX_N70")
	)
	(segment
		(start 221.900242 -53.096668)
		(end 226.380294 -53.096668)
		(width 0.1016)
		(layer "In2.Cu")
		(net "PCIE_RX_N70")
	)
	(segment
		(start 70.194932 -206.4639)
		(end 72.449944 -204.884782)
		(width 0.1397)
		(layer "In2.Cu")
		(net "PCIE_RX_N70")
	)
	(segment
		(start 69.483732 -216.915746)
		(end 69.088 -214.67191)
		(width 0.1397)
		(layer "In2.Cu")
		(net "PCIE_RX_N70")
	)
	(segment
		(start 213.86038 -63.73241)
		(end 215.144604 -56.448706)
		(width 0.1397)
		(layer "In2.Cu")
		(net "PCIE_RX_N70")
	)
	(segment
		(start 100.801424 -190.372238)
		(end 169.175176 -142.496286)
		(width 0.1397)
		(layer "In2.Cu")
		(net "PCIE_RX_N70")
	)
	(segment
		(start 87.70747 -202.195176)
		(end 97.155 -195.58)
		(width 0.1397)
		(layer "In2.Cu")
		(net "PCIE_RX_N70")
	)
	(segment
		(start 213.635336 -79.00162)
		(end 214.54364 -73.850754)
		(width 0.1397)
		(layer "In2.Cu")
		(net "PCIE_RX_N70")
	)
	(segment
		(start 226.574604 -53.177186)
		(end 226.638104 -53.240686)
		(width 0.1016)
		(layer "In2.Cu")
		(net "PCIE_RX_N70")
	)
	(segment
		(start 69.088 -209.042)
		(end 69.32295 -207.709008)
		(width 0.1397)
		(layer "In2.Cu")
		(net "PCIE_RX_N70")
	)
	(segment
		(start 226.480878 -53.690266)
		(end 226.290632 -53.690266)
		(width 0.1016)
		(layer "In2.Cu")
		(net "PCIE_RX_N70")
	)
	(segment
		(start 214.54364 -73.850754)
		(end 213.995 -70.739)
		(width 0.1397)
		(layer "In2.Cu")
		(net "PCIE_RX_N70")
	)
	(segment
		(start 69.064886 -221.712028)
		(end 69.064886 -219.291408)
		(width 0.1397)
		(layer "In2.Cu")
		(net "PCIE_RX_N70")
	)
	(segment
		(start 214.545418 -67.617594)
		(end 213.86038 -63.73241)
		(width 0.1397)
		(layer "In2.Cu")
		(net "PCIE_RX_N70")
	)
	(segment
		(start 218.323668 -53.442362)
		(end 219.9132 -53.1622)
		(width 0.1397)
		(layer "In2.Cu")
		(net "PCIE_RX_N70")
	)
	(segment
		(start 226.636326 -53.623464)
		(end 226.631754 -53.627782)
		(width 0.1016)
		(layer "In2.Cu")
		(net "PCIE_RX_N70")
	)
	(segment
		(start 216.216738 -54.917594)
		(end 218.323668 -53.442362)
		(width 0.1397)
		(layer "In2.Cu")
		(net "PCIE_RX_N70")
	)
	(segment
		(start 215.144604 -56.448706)
		(end 216.216738 -54.917594)
		(width 0.1397)
		(layer "In2.Cu")
		(net "PCIE_RX_N70")
	)
	(segment
		(start 219.9132 -53.1622)
		(end 221.742 -53.1622)
		(width 0.1397)
		(layer "In2.Cu")
		(net "PCIE_RX_N70")
	)
	(segment
		(start 213.995 -70.739)
		(end 214.545418 -67.617594)
		(width 0.1397)
		(layer "In2.Cu")
		(net "PCIE_RX_N70")
	)
	(segment
		(start 97.155 -195.58)
		(end 100.801424 -190.372238)
		(width 0.1397)
		(layer "In2.Cu")
		(net "PCIE_RX_N70")
	)
	(segment
		(start 226.70643 -53.405532)
		(end 226.70643 -53.453792)
		(width 0.1016)
		(layer "In2.Cu")
		(net "PCIE_RX_N70")
	)
	(arc
		(start 69.306186 -222.294704)
		(mid 69.127559 -222.02737)
		(end 69.064886 -221.712028)
		(width 0.1397)
		(layer "In2.Cu")
		(net "PCIE_RX_N70")
	)
	(arc
		(start 226.70643 -53.453792)
		(mid 226.688261 -53.545604)
		(end 226.636326 -53.623464)
		(width 0.1016)
		(layer "In2.Cu")
		(net "PCIE_RX_N70")
	)
	(arc
		(start 226.700842 -53.354986)
		(mid 226.705024 -53.380106)
		(end 226.70643 -53.405532)
		(width 0.1016)
		(layer "In2.Cu")
		(net "PCIE_RX_N70")
	)
	(arc
		(start 226.631754 -53.627782)
		(mid 226.562532 -53.674035)
		(end 226.480878 -53.690266)
		(width 0.1016)
		(layer "In2.Cu")
		(net "PCIE_RX_N70")
	)
	(arc
		(start 226.380294 -53.096668)
		(mid 226.485466 -53.117588)
		(end 226.574604 -53.177186)
		(width 0.1016)
		(layer "In2.Cu")
		(net "PCIE_RX_N70")
	)
	(arc
		(start 226.638104 -53.240686)
		(mid 226.677626 -53.293361)
		(end 226.700842 -53.354986)
		(width 0.1016)
		(layer "In2.Cu")
		(net "PCIE_RX_N70")
	)
	(arc
		(start 221.742 -53.1622)
		(mid 221.814602 -53.113689)
		(end 221.900242 -53.096668)
		(width 0.1016)
		(layer "In2.Cu")
		(net "PCIE_RX_N70")
	)
	(arc
		(start 226.290632 -53.690266)
		(mid 226.155928 -53.63447)
		(end 226.100132 -53.499766)
		(width 0.1016)
		(layer "In2.Cu")
		(net "PCIE_RX_N70")
	)
	(segment
		(start 249.599958 -30.999938)
		(end 250.09983 -30.500066)
		(width 0.136652)
		(layer "F.Cu")
		(net "PCIE_RX_N7")
	)
	(via
		(at 250.09983 -30.500066)
		(size 0.4572)
		(drill 0.2032)
		(layers "F.Cu" "B.Cu")
		(net "PCIE_RX_N7")
	)
	(segment
		(start 265.10615 -24.491442)
		(end 261.430008 -25.139904)
		(width 0.1397)
		(layer "In2.Cu")
		(net "PCIE_RX_N7")
	)
	(segment
		(start 289.87242 -28.0924)
		(end 287.698688 -28.475686)
		(width 0.1397)
		(layer "In2.Cu")
		(net "PCIE_RX_N7")
	)
	(segment
		(start 303.55032 -22.050756)
		(end 302.67656 -22.662642)
		(width 0.1397)
		(layer "In2.Cu")
		(net "PCIE_RX_N7")
	)
	(segment
		(start 295.381934 -27.635454)
		(end 294.478202 -28.268422)
		(width 0.1397)
		(layer "In2.Cu")
		(net "PCIE_RX_N7")
	)
	(segment
		(start 300.656244 -23.01875)
		(end 298.793662 -22.690328)
		(width 0.1397)
		(layer "In2.Cu")
		(net "PCIE_RX_N7")
	)
	(segment
		(start 297.165014 -23.37689)
		(end 296.317416 -24.587454)
		(width 0.1397)
		(layer "In2.Cu")
		(net "PCIE_RX_N7")
	)
	(segment
		(start 297.927522 -22.842982)
		(end 297.165014 -23.37689)
		(width 0.1397)
		(layer "In2.Cu")
		(net "PCIE_RX_N7")
	)
	(segment
		(start 303.982374 -15.17396)
		(end 304.3174 -17.088104)
		(width 0.1397)
		(layer "In2.Cu")
		(net "PCIE_RX_N7")
	)
	(segment
		(start 250.571 -29.829506)
		(end 250.2408 -30.159706)
		(width 0.1397)
		(layer "In2.Cu")
		(net "PCIE_RX_N7")
	)
	(segment
		(start 302.644048 -13.835126)
		(end 303.98212 -15.173452)
		(width 0.1397)
		(layer "In2.Cu")
		(net "PCIE_RX_N7")
	)
	(segment
		(start 302.062388 -13.253212)
		(end 302.644048 -13.835126)
		(width 0.1397)
		(layer "In2.Cu")
		(net "PCIE_RX_N7")
	)
	(segment
		(start 294.478202 -28.268422)
		(end 292.674802 -28.58643)
		(width 0.1397)
		(layer "In2.Cu")
		(net "PCIE_RX_N7")
	)
	(segment
		(start 250.571 -29.229558)
		(end 250.571 -29.829506)
		(width 0.1397)
		(layer "In2.Cu")
		(net "PCIE_RX_N7")
	)
	(segment
		(start 303.98212 -15.173452)
		(end 303.982374 -15.17396)
		(width 0.1397)
		(layer "In2.Cu")
		(net "PCIE_RX_N7")
	)
	(segment
		(start 296.317416 -24.587454)
		(end 295.91381 -26.875994)
		(width 0.1397)
		(layer "In2.Cu")
		(net "PCIE_RX_N7")
	)
	(segment
		(start 302.67656 -22.662642)
		(end 300.656244 -23.01875)
		(width 0.1397)
		(layer "In2.Cu")
		(net "PCIE_RX_N7")
	)
	(segment
		(start 292.674802 -28.58643)
		(end 289.87242 -28.0924)
		(width 0.1397)
		(layer "In2.Cu")
		(net "PCIE_RX_N7")
	)
	(segment
		(start 298.793662 -22.690328)
		(end 297.927522 -22.842982)
		(width 0.1397)
		(layer "In2.Cu")
		(net "PCIE_RX_N7")
	)
	(segment
		(start 304.3174 -17.088104)
		(end 304.3174 -20.754848)
		(width 0.1397)
		(layer "In2.Cu")
		(net "PCIE_RX_N7")
	)
	(segment
		(start 254.70104 -25.099518)
		(end 250.571 -29.229558)
		(width 0.1397)
		(layer "In2.Cu")
		(net "PCIE_RX_N7")
	)
	(segment
		(start 287.698688 -28.475686)
		(end 265.10615 -24.491442)
		(width 0.1397)
		(layer "In2.Cu")
		(net "PCIE_RX_N7")
	)
	(segment
		(start 261.430008 -25.139904)
		(end 258.316984 -24.51735)
		(width 0.1397)
		(layer "In2.Cu")
		(net "PCIE_RX_N7")
	)
	(segment
		(start 295.91381 -26.875994)
		(end 295.381934 -27.635454)
		(width 0.1397)
		(layer "In2.Cu")
		(net "PCIE_RX_N7")
	)
	(segment
		(start 304.202592 -21.119084)
		(end 303.55032 -22.050756)
		(width 0.1397)
		(layer "In2.Cu")
		(net "PCIE_RX_N7")
	)
	(segment
		(start 258.316984 -24.51735)
		(end 254.70104 -25.099518)
		(width 0.1397)
		(layer "In2.Cu")
		(net "PCIE_RX_N7")
	)
	(arc
		(start 304.3174 -20.754848)
		(mid 304.288021 -20.945801)
		(end 304.202592 -21.119084)
		(width 0.1397)
		(layer "In2.Cu")
		(net "PCIE_RX_N7")
	)
	(arc
		(start 250.2408 -30.159706)
		(mid 250.136458 -30.315864)
		(end 250.09983 -30.500066)
		(width 0.1397)
		(layer "In2.Cu")
		(net "PCIE_RX_N7")
	)
	(arc
		(start 302.38446 -12.530074)
		(mid 301.974791 -12.780959)
		(end 302.062388 -13.253212)
		(width 0.1397)
		(layer "In2.Cu")
		(net "PCIE_RX_N7")
	)
	(segment
		(start 225.25355 -54.499764)
		(end 225.100134 -54.499764)
		(width 0.136652)
		(layer "F.Cu")
		(net "PCIE_RX_N69")
	)
	(segment
		(start 225.600006 -53.999892)
		(end 225.600006 -54.10835)
		(width 0.136652)
		(layer "F.Cu")
		(net "PCIE_RX_N69")
	)
	(segment
		(start 225.400108 -54.459124)
		(end 225.346768 -54.481222)
		(width 0.136652)
		(layer "F.Cu")
		(net "PCIE_RX_N69")
	)
	(segment
		(start 225.575622 -54.231286)
		(end 225.538792 -54.32044)
		(width 0.136652)
		(layer "F.Cu")
		(net "PCIE_RX_N69")
	)
	(via
		(at 72.517 -220.0148)
		(size 0.508)
		(drill 0.254)
		(layers "F.Cu" "B.Cu")
		(net "PCIE_RX_N69")
	)
	(via
		(at 225.100134 -54.499764)
		(size 0.4572)
		(drill 0.2032)
		(layers "F.Cu" "B.Cu")
		(net "PCIE_RX_N69")
	)
	(arc
		(start 225.346768 -54.481222)
		(mid 225.301072 -54.495084)
		(end 225.25355 -54.499764)
		(width 0.136652)
		(layer "F.Cu")
		(net "PCIE_RX_N69")
	)
	(arc
		(start 225.538792 -54.32044)
		(mid 225.483245 -54.403577)
		(end 225.400108 -54.459124)
		(width 0.136652)
		(layer "F.Cu")
		(net "PCIE_RX_N69")
	)
	(arc
		(start 225.600006 -54.10835)
		(mid 225.593842 -54.171012)
		(end 225.575622 -54.231286)
		(width 0.136652)
		(layer "F.Cu")
		(net "PCIE_RX_N69")
	)
	(segment
		(start 72.499982 -225.92538)
		(end 72.499982 -224.770188)
		(width 0.136652)
		(layer "B.Cu")
		(net "PCIE_RX_N69")
	)
	(segment
		(start 72.252586 -224.17278)
		(end 72.252586 -220.653102)
		(width 0.136652)
		(layer "B.Cu")
		(net "PCIE_RX_N69")
	)
	(arc
		(start 72.252586 -220.653102)
		(mid 72.321301 -220.307648)
		(end 72.517 -220.0148)
		(width 0.136652)
		(layer "B.Cu")
		(net "PCIE_RX_N69")
	)
	(arc
		(start 72.329802 -224.359216)
		(mid 72.272648 -224.273678)
		(end 72.252586 -224.17278)
		(width 0.136652)
		(layer "B.Cu")
		(net "PCIE_RX_N69")
	)
	(arc
		(start 72.499982 -224.770188)
		(mid 72.455744 -224.547791)
		(end 72.329802 -224.359216)
		(width 0.136652)
		(layer "B.Cu")
		(net "PCIE_RX_N69")
	)
	(segment
		(start 217.373708 -55.51805)
		(end 218.930982 -54.427628)
		(width 0.1397)
		(layer "In2.Cu")
		(net "PCIE_RX_N69")
	)
	(segment
		(start 218.930982 -54.427628)
		(end 220.345 -54.1782)
		(width 0.1397)
		(layer "In2.Cu")
		(net "PCIE_RX_N69")
	)
	(segment
		(start 98.164142 -196.587618)
		(end 100.328984 -193.495676)
		(width 0.1397)
		(layer "In2.Cu")
		(net "PCIE_RX_N69")
	)
	(segment
		(start 73.302114 -210.061302)
		(end 73.66 -209.55)
		(width 0.1397)
		(layer "In2.Cu")
		(net "PCIE_RX_N69")
	)
	(segment
		(start 225.636328 -54.623462)
		(end 225.631756 -54.62778)
		(width 0.1016)
		(layer "In2.Cu")
		(net "PCIE_RX_N69")
	)
	(segment
		(start 170.376596 -144.448022)
		(end 214.118444 -81.9785)
		(width 0.1397)
		(layer "In2.Cu")
		(net "PCIE_RX_N69")
	)
	(segment
		(start 220.345 -54.1782)
		(end 221.5642 -54.1782)
		(width 0.1397)
		(layer "In2.Cu")
		(net "PCIE_RX_N69")
	)
	(segment
		(start 72.2757 -219.432124)
		(end 72.2757 -217.861642)
		(width 0.1397)
		(layer "In2.Cu")
		(net "PCIE_RX_N69")
	)
	(segment
		(start 221.76105 -54.096666)
		(end 225.386392 -54.096666)
		(width 0.1016)
		(layer "In2.Cu")
		(net "PCIE_RX_N69")
	)
	(segment
		(start 225.706432 -54.40553)
		(end 225.706432 -54.45379)
		(width 0.1016)
		(layer "In2.Cu")
		(net "PCIE_RX_N69")
	)
	(segment
		(start 225.48088 -54.690264)
		(end 225.290634 -54.690264)
		(width 0.1016)
		(layer "In2.Cu")
		(net "PCIE_RX_N69")
	)
	(segment
		(start 84.263992 -206.320136)
		(end 98.164142 -196.587618)
		(width 0.1397)
		(layer "In2.Cu")
		(net "PCIE_RX_N69")
	)
	(segment
		(start 214.118444 -81.9785)
		(end 215.661494 -73.230994)
		(width 0.1397)
		(layer "In2.Cu")
		(net "PCIE_RX_N69")
	)
	(segment
		(start 72.211692 -216.244678)
		(end 73.302114 -210.061302)
		(width 0.1397)
		(layer "In2.Cu")
		(net "PCIE_RX_N69")
	)
	(segment
		(start 215.873584 -67.553586)
		(end 215.143334 -63.412624)
		(width 0.1397)
		(layer "In2.Cu")
		(net "PCIE_RX_N69")
	)
	(segment
		(start 72.2757 -217.861642)
		(end 72.386444 -217.233754)
		(width 0.1397)
		(layer "In2.Cu")
		(net "PCIE_RX_N69")
	)
	(segment
		(start 215.143334 -63.412624)
		(end 216.253314 -57.11825)
		(width 0.1397)
		(layer "In2.Cu")
		(net "PCIE_RX_N69")
	)
	(segment
		(start 100.328984 -193.495676)
		(end 170.376596 -144.448022)
		(width 0.1397)
		(layer "In2.Cu")
		(net "PCIE_RX_N69")
	)
	(segment
		(start 73.66 -209.55)
		(end 76.256896 -207.731614)
		(width 0.1397)
		(layer "In2.Cu")
		(net "PCIE_RX_N69")
	)
	(segment
		(start 225.570288 -54.172866)
		(end 225.638106 -54.240684)
		(width 0.1016)
		(layer "In2.Cu")
		(net "PCIE_RX_N69")
	)
	(segment
		(start 216.253314 -57.11825)
		(end 217.373708 -55.51805)
		(width 0.1397)
		(layer "In2.Cu")
		(net "PCIE_RX_N69")
	)
	(segment
		(start 215.267032 -70.993254)
		(end 215.873584 -67.553586)
		(width 0.1397)
		(layer "In2.Cu")
		(net "PCIE_RX_N69")
	)
	(segment
		(start 215.661494 -73.230994)
		(end 215.267032 -70.993254)
		(width 0.1397)
		(layer "In2.Cu")
		(net "PCIE_RX_N69")
	)
	(segment
		(start 76.256896 -207.731614)
		(end 84.263992 -206.320136)
		(width 0.1397)
		(layer "In2.Cu")
		(net "PCIE_RX_N69")
	)
	(segment
		(start 72.386444 -217.233754)
		(end 72.211692 -216.244678)
		(width 0.1397)
		(layer "In2.Cu")
		(net "PCIE_RX_N69")
	)
	(arc
		(start 225.386392 -54.096666)
		(mid 225.485926 -54.116465)
		(end 225.570288 -54.172866)
		(width 0.1016)
		(layer "In2.Cu")
		(net "PCIE_RX_N69")
	)
	(arc
		(start 225.638106 -54.240684)
		(mid 225.688642 -54.316316)
		(end 225.706432 -54.40553)
		(width 0.1016)
		(layer "In2.Cu")
		(net "PCIE_RX_N69")
	)
	(arc
		(start 225.290634 -54.690264)
		(mid 225.15593 -54.634468)
		(end 225.100134 -54.499764)
		(width 0.1016)
		(layer "In2.Cu")
		(net "PCIE_RX_N69")
	)
	(arc
		(start 221.5642 -54.1782)
		(mid 221.654516 -54.117853)
		(end 221.76105 -54.096666)
		(width 0.1016)
		(layer "In2.Cu")
		(net "PCIE_RX_N69")
	)
	(arc
		(start 225.631756 -54.62778)
		(mid 225.562534 -54.674033)
		(end 225.48088 -54.690264)
		(width 0.1016)
		(layer "In2.Cu")
		(net "PCIE_RX_N69")
	)
	(arc
		(start 72.517 -220.0148)
		(mid 72.338373 -219.747466)
		(end 72.2757 -219.432124)
		(width 0.1397)
		(layer "In2.Cu")
		(net "PCIE_RX_N69")
	)
	(arc
		(start 225.706432 -54.45379)
		(mid 225.688263 -54.545602)
		(end 225.636328 -54.623462)
		(width 0.1016)
		(layer "In2.Cu")
		(net "PCIE_RX_N69")
	)
	(segment
		(start 226.206812 -55.499762)
		(end 226.100132 -55.499762)
		(width 0.136652)
		(layer "F.Cu")
		(net "PCIE_RX_N68")
	)
	(segment
		(start 226.600004 -54.99989)
		(end 226.481894 -55.284878)
		(width 0.136652)
		(layer "F.Cu")
		(net "PCIE_RX_N68")
	)
	(via
		(at 78.98257 -219.881704)
		(size 0.508)
		(drill 0.254)
		(layers "F.Cu" "B.Cu")
		(net "PCIE_RX_N68")
	)
	(via
		(at 226.100132 -55.499762)
		(size 0.4572)
		(drill 0.2032)
		(layers "F.Cu" "B.Cu")
		(net "PCIE_RX_N68")
	)
	(arc
		(start 226.481894 -55.284878)
		(mid 226.442162 -55.3592)
		(end 226.388676 -55.424324)
		(width 0.136652)
		(layer "F.Cu")
		(net "PCIE_RX_N68")
	)
	(arc
		(start 226.388676 -55.424324)
		(mid 226.305251 -55.48016)
		(end 226.206812 -55.499762)
		(width 0.136652)
		(layer "F.Cu")
		(net "PCIE_RX_N68")
	)
	(segment
		(start 78.900274 -224.770442)
		(end 78.90002 -224.770188)
		(width 0.136652)
		(layer "B.Cu")
		(net "PCIE_RX_N68")
	)
	(segment
		(start 78.652624 -224.17278)
		(end 78.652624 -220.4212)
		(width 0.136652)
		(layer "B.Cu")
		(net "PCIE_RX_N68")
	)
	(segment
		(start 78.800706 -220.063314)
		(end 78.98257 -219.881704)
		(width 0.136652)
		(layer "B.Cu")
		(net "PCIE_RX_N68")
	)
	(segment
		(start 78.90002 -225.92538)
		(end 78.90002 -224.770696)
		(width 0.136652)
		(layer "B.Cu")
		(net "PCIE_RX_N68")
	)
	(segment
		(start 78.90002 -224.770696)
		(end 78.900274 -224.770442)
		(width 0.136652)
		(layer "B.Cu")
		(net "PCIE_RX_N68")
	)
	(arc
		(start 78.90002 -224.770188)
		(mid 78.855782 -224.547791)
		(end 78.72984 -224.359216)
		(width 0.136652)
		(layer "B.Cu")
		(net "PCIE_RX_N68")
	)
	(arc
		(start 78.652624 -220.4212)
		(mid 78.691056 -220.227521)
		(end 78.800706 -220.063314)
		(width 0.136652)
		(layer "B.Cu")
		(net "PCIE_RX_N68")
	)
	(arc
		(start 78.72984 -224.359216)
		(mid 78.672686 -224.273678)
		(end 78.652624 -224.17278)
		(width 0.136652)
		(layer "B.Cu")
		(net "PCIE_RX_N68")
	)
	(segment
		(start 226.70643 -55.405528)
		(end 226.70643 -55.453788)
		(width 0.1016)
		(layer "In2.Cu")
		(net "PCIE_RX_N68")
	)
	(segment
		(start 100.788216 -194.762882)
		(end 171.125134 -145.514314)
		(width 0.1397)
		(layer "In2.Cu")
		(net "PCIE_RX_N68")
	)
	(segment
		(start 78.74127 -216.841578)
		(end 77.836268 -211.709)
		(width 0.1397)
		(layer "In2.Cu")
		(net "PCIE_RX_N68")
	)
	(segment
		(start 216.23274 -62.249304)
		(end 216.91346 -58.390536)
		(width 0.1397)
		(layer "In2.Cu")
		(net "PCIE_RX_N68")
	)
	(segment
		(start 77.836268 -211.709)
		(end 78.094078 -210.247738)
		(width 0.1397)
		(layer "In2.Cu")
		(net "PCIE_RX_N68")
	)
	(segment
		(start 99.06 -197.231)
		(end 100.788216 -194.762882)
		(width 0.1397)
		(layer "In2.Cu")
		(net "PCIE_RX_N68")
	)
	(segment
		(start 219.573602 -55.360062)
		(end 220.8022 -55.1434)
		(width 0.1397)
		(layer "In2.Cu")
		(net "PCIE_RX_N68")
	)
	(segment
		(start 215.3412 -82.36966)
		(end 216.77757 -74.227436)
		(width 0.1397)
		(layer "In2.Cu")
		(net "PCIE_RX_N68")
	)
	(segment
		(start 82.607658 -208.75244)
		(end 82.666586 -208.711292)
		(width 0.1397)
		(layer "In2.Cu")
		(net "PCIE_RX_N68")
	)
	(segment
		(start 79.379572 -209.347308)
		(end 79.380842 -209.346292)
		(width 0.1397)
		(layer "In2.Cu")
		(net "PCIE_RX_N68")
	)
	(segment
		(start 226.480878 -55.690262)
		(end 226.290632 -55.690262)
		(width 0.1016)
		(layer "In2.Cu")
		(net "PCIE_RX_N68")
	)
	(segment
		(start 220.8022 -55.1434)
		(end 221.8182 -55.1434)
		(width 0.1397)
		(layer "In2.Cu")
		(net "PCIE_RX_N68")
	)
	(segment
		(start 216.91346 -58.390536)
		(end 218.51747 -56.09971)
		(width 0.1397)
		(layer "In2.Cu")
		(net "PCIE_RX_N68")
	)
	(segment
		(start 221.930976 -55.096664)
		(end 226.380294 -55.096664)
		(width 0.1016)
		(layer "In2.Cu")
		(net "PCIE_RX_N68")
	)
	(segment
		(start 216.38641 -72.009254)
		(end 217.17 -67.564)
		(width 0.1397)
		(layer "In2.Cu")
		(net "PCIE_RX_N68")
	)
	(segment
		(start 171.125134 -145.514314)
		(end 215.3412 -82.36966)
		(width 0.1397)
		(layer "In2.Cu")
		(net "PCIE_RX_N68")
	)
	(segment
		(start 79.380842 -209.346292)
		(end 82.607658 -208.75244)
		(width 0.1397)
		(layer "In2.Cu")
		(net "PCIE_RX_N68")
	)
	(segment
		(start 216.77757 -74.227436)
		(end 216.38641 -72.009254)
		(width 0.1397)
		(layer "In2.Cu")
		(net "PCIE_RX_N68")
	)
	(segment
		(start 78.094078 -210.247738)
		(end 79.379572 -209.347308)
		(width 0.1397)
		(layer "In2.Cu")
		(net "PCIE_RX_N68")
	)
	(segment
		(start 217.17 -67.564)
		(end 216.23274 -62.249304)
		(width 0.1397)
		(layer "In2.Cu")
		(net "PCIE_RX_N68")
	)
	(segment
		(start 218.51747 -56.09971)
		(end 219.573602 -55.360062)
		(width 0.1397)
		(layer "In2.Cu")
		(net "PCIE_RX_N68")
	)
	(segment
		(start 226.574604 -55.177182)
		(end 226.638104 -55.240682)
		(width 0.1016)
		(layer "In2.Cu")
		(net "PCIE_RX_N68")
	)
	(segment
		(start 82.666586 -208.711292)
		(end 82.66684 -208.711292)
		(width 0.1397)
		(layer "In2.Cu")
		(net "PCIE_RX_N68")
	)
	(segment
		(start 78.74127 -219.299028)
		(end 78.74127 -216.841578)
		(width 0.1397)
		(layer "In2.Cu")
		(net "PCIE_RX_N68")
	)
	(segment
		(start 226.636326 -55.62346)
		(end 226.631754 -55.627778)
		(width 0.1016)
		(layer "In2.Cu")
		(net "PCIE_RX_N68")
	)
	(segment
		(start 82.66684 -208.711292)
		(end 99.06 -197.231)
		(width 0.1397)
		(layer "In2.Cu")
		(net "PCIE_RX_N68")
	)
	(arc
		(start 78.98257 -219.881704)
		(mid 78.803943 -219.61437)
		(end 78.74127 -219.299028)
		(width 0.1397)
		(layer "In2.Cu")
		(net "PCIE_RX_N68")
	)
	(arc
		(start 226.631754 -55.627778)
		(mid 226.562532 -55.674031)
		(end 226.480878 -55.690262)
		(width 0.1016)
		(layer "In2.Cu")
		(net "PCIE_RX_N68")
	)
	(arc
		(start 221.8182 -55.1434)
		(mid 221.869942 -55.108827)
		(end 221.930976 -55.096664)
		(width 0.1016)
		(layer "In2.Cu")
		(net "PCIE_RX_N68")
	)
	(arc
		(start 226.638104 -55.240682)
		(mid 226.68864 -55.316314)
		(end 226.70643 -55.405528)
		(width 0.1016)
		(layer "In2.Cu")
		(net "PCIE_RX_N68")
	)
	(arc
		(start 226.290632 -55.690262)
		(mid 226.155928 -55.634466)
		(end 226.100132 -55.499762)
		(width 0.1016)
		(layer "In2.Cu")
		(net "PCIE_RX_N68")
	)
	(arc
		(start 226.70643 -55.453788)
		(mid 226.688261 -55.5456)
		(end 226.636326 -55.62346)
		(width 0.1016)
		(layer "In2.Cu")
		(net "PCIE_RX_N68")
	)
	(arc
		(start 226.380294 -55.096664)
		(mid 226.485466 -55.117584)
		(end 226.574604 -55.177182)
		(width 0.1016)
		(layer "In2.Cu")
		(net "PCIE_RX_N68")
	)
	(segment
		(start 225.600006 -55.999888)
		(end 225.600006 -56.15178)
		(width 0.136652)
		(layer "F.Cu")
		(net "PCIE_RX_N67")
	)
	(segment
		(start 225.347022 -56.446166)
		(end 225.100134 -56.49976)
		(width 0.136652)
		(layer "F.Cu")
		(net "PCIE_RX_N67")
	)
	(via
		(at 225.100134 -56.49976)
		(size 0.4572)
		(drill 0.2032)
		(layers "F.Cu" "B.Cu")
		(net "PCIE_RX_N67")
	)
	(via
		(at 82.106262 -222.294704)
		(size 0.508)
		(drill 0.254)
		(layers "F.Cu" "B.Cu")
		(net "PCIE_RX_N67")
	)
	(arc
		(start 225.600006 -56.15178)
		(mid 225.593152 -56.212138)
		(end 225.572828 -56.269382)
		(width 0.136652)
		(layer "F.Cu")
		(net "PCIE_RX_N67")
	)
	(arc
		(start 225.572828 -56.269382)
		(mid 225.480222 -56.383725)
		(end 225.347022 -56.446166)
		(width 0.136652)
		(layer "F.Cu")
		(net "PCIE_RX_N67")
	)
	(segment
		(start 82.100166 -224.770442)
		(end 82.099912 -224.770188)
		(width 0.136652)
		(layer "B.Cu")
		(net "PCIE_RX_N67")
	)
	(segment
		(start 82.100166 -225.92538)
		(end 82.100166 -224.770442)
		(width 0.136652)
		(layer "B.Cu")
		(net "PCIE_RX_N67")
	)
	(segment
		(start 81.852516 -224.17278)
		(end 81.852516 -222.907352)
		(width 0.136652)
		(layer "B.Cu")
		(net "PCIE_RX_N67")
	)
	(arc
		(start 81.929732 -224.359216)
		(mid 81.872578 -224.273678)
		(end 81.852516 -224.17278)
		(width 0.136652)
		(layer "B.Cu")
		(net "PCIE_RX_N67")
	)
	(arc
		(start 81.852516 -222.907352)
		(mid 81.918466 -222.575797)
		(end 82.106262 -222.294704)
		(width 0.136652)
		(layer "B.Cu")
		(net "PCIE_RX_N67")
	)
	(arc
		(start 82.099912 -224.770188)
		(mid 82.055674 -224.547791)
		(end 81.929732 -224.359216)
		(width 0.136652)
		(layer "B.Cu")
		(net "PCIE_RX_N67")
	)
	(segment
		(start 218.290648 -67.575176)
		(end 217.319606 -62.067948)
		(width 0.1397)
		(layer "In2.Cu")
		(net "PCIE_RX_N67")
	)
	(segment
		(start 84.709508 -214.756746)
		(end 84.813648 -214.166196)
		(width 0.1397)
		(layer "In2.Cu")
		(net "PCIE_RX_N67")
	)
	(segment
		(start 172.736764 -145.688304)
		(end 216.544398 -83.129628)
		(width 0.1397)
		(layer "In2.Cu")
		(net "PCIE_RX_N67")
	)
	(segment
		(start 85.09 -209.042)
		(end 85.772244 -208.067402)
		(width 0.1397)
		(layer "In2.Cu")
		(net "PCIE_RX_N67")
	)
	(segment
		(start 225.706432 -56.405526)
		(end 225.706432 -56.453786)
		(width 0.1016)
		(layer "In2.Cu")
		(net "PCIE_RX_N67")
	)
	(segment
		(start 84.813648 -214.166196)
		(end 85.09 -212.598)
		(width 0.1397)
		(layer "In2.Cu")
		(net "PCIE_RX_N67")
	)
	(segment
		(start 218.270582 -73.346564)
		(end 217.778076 -70.482968)
		(width 0.1397)
		(layer "In2.Cu")
		(net "PCIE_RX_N67")
	)
	(segment
		(start 225.48088 -56.69026)
		(end 225.290634 -56.69026)
		(width 0.1016)
		(layer "In2.Cu")
		(net "PCIE_RX_N67")
	)
	(segment
		(start 85.772244 -208.067402)
		(end 99.594162 -198.391272)
		(width 0.1397)
		(layer "In2.Cu")
		(net "PCIE_RX_N67")
	)
	(segment
		(start 225.636328 -56.623458)
		(end 225.631756 -56.627776)
		(width 0.1016)
		(layer "In2.Cu")
		(net "PCIE_RX_N67")
	)
	(segment
		(start 217.778076 -70.482968)
		(end 218.290648 -67.575176)
		(width 0.1397)
		(layer "In2.Cu")
		(net "PCIE_RX_N67")
	)
	(segment
		(start 219.018612 -57.178702)
		(end 220.223588 -56.334914)
		(width 0.1397)
		(layer "In2.Cu")
		(net "PCIE_RX_N67")
	)
	(segment
		(start 217.90025 -58.775854)
		(end 219.018612 -57.178702)
		(width 0.1397)
		(layer "In2.Cu")
		(net "PCIE_RX_N67")
	)
	(segment
		(start 99.594162 -198.391272)
		(end 101.595682 -195.532248)
		(width 0.1397)
		(layer "In2.Cu")
		(net "PCIE_RX_N67")
	)
	(segment
		(start 225.574606 -56.17718)
		(end 225.638106 -56.24068)
		(width 0.1016)
		(layer "In2.Cu")
		(net "PCIE_RX_N67")
	)
	(segment
		(start 217.319606 -62.067948)
		(end 217.90025 -58.775854)
		(width 0.1397)
		(layer "In2.Cu")
		(net "PCIE_RX_N67")
	)
	(segment
		(start 81.864962 -219.583)
		(end 84.529168 -215.778334)
		(width 0.1397)
		(layer "In2.Cu")
		(net "PCIE_RX_N67")
	)
	(segment
		(start 84.529168 -215.778334)
		(end 84.709508 -214.756746)
		(width 0.1397)
		(layer "In2.Cu")
		(net "PCIE_RX_N67")
	)
	(segment
		(start 101.595682 -195.532248)
		(end 172.736764 -145.688304)
		(width 0.1397)
		(layer "In2.Cu")
		(net "PCIE_RX_N67")
	)
	(segment
		(start 221.740984 -56.096662)
		(end 225.380296 -56.096662)
		(width 0.1016)
		(layer "In2.Cu")
		(net "PCIE_RX_N67")
	)
	(segment
		(start 216.544398 -83.129628)
		(end 218.270582 -73.346564)
		(width 0.1397)
		(layer "In2.Cu")
		(net "PCIE_RX_N67")
	)
	(segment
		(start 85.09 -212.598)
		(end 85.09 -209.042)
		(width 0.1397)
		(layer "In2.Cu")
		(net "PCIE_RX_N67")
	)
	(segment
		(start 220.223588 -56.334914)
		(end 221.219014 -56.1594)
		(width 0.1397)
		(layer "In2.Cu")
		(net "PCIE_RX_N67")
	)
	(segment
		(start 81.864962 -221.712028)
		(end 81.864962 -219.583)
		(width 0.1397)
		(layer "In2.Cu")
		(net "PCIE_RX_N67")
	)
	(segment
		(start 221.219014 -56.1594)
		(end 221.5896 -56.1594)
		(width 0.1397)
		(layer "In2.Cu")
		(net "PCIE_RX_N67")
	)
	(arc
		(start 225.638106 -56.24068)
		(mid 225.688642 -56.316312)
		(end 225.706432 -56.405526)
		(width 0.1016)
		(layer "In2.Cu")
		(net "PCIE_RX_N67")
	)
	(arc
		(start 225.631756 -56.627776)
		(mid 225.562534 -56.674029)
		(end 225.48088 -56.69026)
		(width 0.1016)
		(layer "In2.Cu")
		(net "PCIE_RX_N67")
	)
	(arc
		(start 221.5896 -56.1594)
		(mid 221.659056 -56.112991)
		(end 221.740984 -56.096662)
		(width 0.1016)
		(layer "In2.Cu")
		(net "PCIE_RX_N67")
	)
	(arc
		(start 225.706432 -56.453786)
		(mid 225.688263 -56.545598)
		(end 225.636328 -56.623458)
		(width 0.1016)
		(layer "In2.Cu")
		(net "PCIE_RX_N67")
	)
	(arc
		(start 82.106262 -222.294704)
		(mid 81.927635 -222.02737)
		(end 81.864962 -221.712028)
		(width 0.1397)
		(layer "In2.Cu")
		(net "PCIE_RX_N67")
	)
	(arc
		(start 225.290634 -56.69026)
		(mid 225.15593 -56.634464)
		(end 225.100134 -56.49976)
		(width 0.1016)
		(layer "In2.Cu")
		(net "PCIE_RX_N67")
	)
	(arc
		(start 225.380296 -56.096662)
		(mid 225.485468 -56.117582)
		(end 225.574606 -56.17718)
		(width 0.1016)
		(layer "In2.Cu")
		(net "PCIE_RX_N67")
	)
	(segment
		(start 226.600004 -56.999886)
		(end 226.600004 -57.141364)
		(width 0.136652)
		(layer "F.Cu")
		(net "PCIE_RX_N66")
	)
	(segment
		(start 226.57943 -57.244488)
		(end 226.56419 -57.281318)
		(width 0.136652)
		(layer "F.Cu")
		(net "PCIE_RX_N66")
	)
	(segment
		(start 226.233482 -57.499758)
		(end 226.100132 -57.499758)
		(width 0.136652)
		(layer "F.Cu")
		(net "PCIE_RX_N66")
	)
	(segment
		(start 226.395026 -57.450228)
		(end 226.314508 -57.483502)
		(width 0.136652)
		(layer "F.Cu")
		(net "PCIE_RX_N66")
	)
	(via
		(at 85.306154 -222.294704)
		(size 0.508)
		(drill 0.254)
		(layers "F.Cu" "B.Cu")
		(net "PCIE_RX_N66")
	)
	(via
		(at 226.100132 -57.499758)
		(size 0.4572)
		(drill 0.2032)
		(layers "F.Cu" "B.Cu")
		(net "PCIE_RX_N66")
	)
	(arc
		(start 226.600004 -57.141364)
		(mid 226.59481 -57.193942)
		(end 226.57943 -57.244488)
		(width 0.136652)
		(layer "F.Cu")
		(net "PCIE_RX_N66")
	)
	(arc
		(start 226.314508 -57.483502)
		(mid 226.274794 -57.4956)
		(end 226.233482 -57.499758)
		(width 0.136652)
		(layer "F.Cu")
		(net "PCIE_RX_N66")
	)
	(arc
		(start 226.56419 -57.281318)
		(mid 226.496388 -57.382572)
		(end 226.395026 -57.450228)
		(width 0.136652)
		(layer "F.Cu")
		(net "PCIE_RX_N66")
	)
	(segment
		(start 85.300058 -224.770442)
		(end 85.299804 -224.770188)
		(width 0.136652)
		(layer "B.Cu")
		(net "PCIE_RX_N66")
	)
	(segment
		(start 85.052408 -224.17278)
		(end 85.052408 -222.907352)
		(width 0.136652)
		(layer "B.Cu")
		(net "PCIE_RX_N66")
	)
	(segment
		(start 85.300058 -225.92538)
		(end 85.300058 -224.770442)
		(width 0.136652)
		(layer "B.Cu")
		(net "PCIE_RX_N66")
	)
	(arc
		(start 85.299804 -224.770188)
		(mid 85.255566 -224.547791)
		(end 85.129624 -224.359216)
		(width 0.136652)
		(layer "B.Cu")
		(net "PCIE_RX_N66")
	)
	(arc
		(start 85.129624 -224.359216)
		(mid 85.07247 -224.273678)
		(end 85.052408 -224.17278)
		(width 0.136652)
		(layer "B.Cu")
		(net "PCIE_RX_N66")
	)
	(arc
		(start 85.052408 -222.907352)
		(mid 85.118358 -222.575797)
		(end 85.306154 -222.294704)
		(width 0.136652)
		(layer "B.Cu")
		(net "PCIE_RX_N66")
	)
	(segment
		(start 219.921582 -67.20459)
		(end 219.246704 -71.032116)
		(width 0.1397)
		(layer "In2.Cu")
		(net "PCIE_RX_N66")
	)
	(segment
		(start 226.638104 -57.240678)
		(end 226.574604 -57.177178)
		(width 0.1016)
		(layer "In2.Cu")
		(net "PCIE_RX_N66")
	)
	(segment
		(start 100.33 -199.136)
		(end 89.199466 -206.929736)
		(width 0.1397)
		(layer "In2.Cu")
		(net "PCIE_RX_N66")
	)
	(segment
		(start 218.951302 -61.700156)
		(end 219.921582 -67.20459)
		(width 0.1397)
		(layer "In2.Cu")
		(net "PCIE_RX_N66")
	)
	(segment
		(start 101.967538 -196.797422)
		(end 100.33 -199.136)
		(width 0.1397)
		(layer "In2.Cu")
		(net "PCIE_RX_N66")
	)
	(segment
		(start 226.380294 -57.09666)
		(end 222.068136 -57.09666)
		(width 0.1016)
		(layer "In2.Cu")
		(net "PCIE_RX_N66")
	)
	(segment
		(start 88.257634 -208.27492)
		(end 88.257634 -213.487)
		(width 0.1397)
		(layer "In2.Cu")
		(net "PCIE_RX_N66")
	)
	(segment
		(start 218.092528 -82.359246)
		(end 172.58792 -147.347432)
		(width 0.1397)
		(layer "In2.Cu")
		(net "PCIE_RX_N66")
	)
	(segment
		(start 89.199466 -206.929736)
		(end 88.257634 -208.27492)
		(width 0.1397)
		(layer "In2.Cu")
		(net "PCIE_RX_N66")
	)
	(segment
		(start 219.35821 -59.39155)
		(end 218.951302 -61.700156)
		(width 0.1397)
		(layer "In2.Cu")
		(net "PCIE_RX_N66")
	)
	(segment
		(start 87.93988 -215.289638)
		(end 85.322156 -219.028264)
		(width 0.1397)
		(layer "In2.Cu")
		(net "PCIE_RX_N66")
	)
	(segment
		(start 85.322156 -219.028264)
		(end 85.064854 -220.487748)
		(width 0.1397)
		(layer "In2.Cu")
		(net "PCIE_RX_N66")
	)
	(segment
		(start 226.70643 -57.453784)
		(end 226.70643 -57.405524)
		(width 0.1016)
		(layer "In2.Cu")
		(net "PCIE_RX_N66")
	)
	(segment
		(start 85.064854 -220.487748)
		(end 85.064854 -221.712028)
		(width 0.1397)
		(layer "In2.Cu")
		(net "PCIE_RX_N66")
	)
	(segment
		(start 221.54896 -57.2008)
		(end 219.35821 -59.39155)
		(width 0.1397)
		(layer "In2.Cu")
		(net "PCIE_RX_N66")
	)
	(segment
		(start 219.246704 -71.032116)
		(end 219.66809 -73.423272)
		(width 0.1397)
		(layer "In2.Cu")
		(net "PCIE_RX_N66")
	)
	(segment
		(start 221.8182 -57.2008)
		(end 221.54896 -57.2008)
		(width 0.1397)
		(layer "In2.Cu")
		(net "PCIE_RX_N66")
	)
	(segment
		(start 88.257634 -213.487)
		(end 87.93988 -215.289638)
		(width 0.1397)
		(layer "In2.Cu")
		(net "PCIE_RX_N66")
	)
	(segment
		(start 226.290632 -57.690258)
		(end 226.480878 -57.690258)
		(width 0.1016)
		(layer "In2.Cu")
		(net "PCIE_RX_N66")
	)
	(segment
		(start 226.631754 -57.627774)
		(end 226.636326 -57.623456)
		(width 0.1016)
		(layer "In2.Cu")
		(net "PCIE_RX_N66")
	)
	(segment
		(start 172.58792 -147.347432)
		(end 101.967538 -196.797422)
		(width 0.1397)
		(layer "In2.Cu")
		(net "PCIE_RX_N66")
	)
	(segment
		(start 219.66809 -73.423272)
		(end 218.092528 -82.359246)
		(width 0.1397)
		(layer "In2.Cu")
		(net "PCIE_RX_N66")
	)
	(segment
		(start 221.819216 -57.199784)
		(end 221.8182 -57.2008)
		(width 0.1016)
		(layer "In2.Cu")
		(net "PCIE_RX_N66")
	)
	(arc
		(start 85.064854 -221.712028)
		(mid 85.127575 -222.02735)
		(end 85.306154 -222.294704)
		(width 0.1397)
		(layer "In2.Cu")
		(net "PCIE_RX_N66")
	)
	(arc
		(start 222.068136 -57.09666)
		(mid 221.933415 -57.123458)
		(end 221.819216 -57.199784)
		(width 0.1016)
		(layer "In2.Cu")
		(net "PCIE_RX_N66")
	)
	(arc
		(start 226.480878 -57.690258)
		(mid 226.562527 -57.674017)
		(end 226.631754 -57.627774)
		(width 0.1016)
		(layer "In2.Cu")
		(net "PCIE_RX_N66")
	)
	(arc
		(start 226.574604 -57.177178)
		(mid 226.485454 -57.11761)
		(end 226.380294 -57.09666)
		(width 0.1016)
		(layer "In2.Cu")
		(net "PCIE_RX_N66")
	)
	(arc
		(start 226.100132 -57.499758)
		(mid 226.155928 -57.634462)
		(end 226.290632 -57.690258)
		(width 0.1016)
		(layer "In2.Cu")
		(net "PCIE_RX_N66")
	)
	(arc
		(start 226.70643 -57.405524)
		(mid 226.688681 -57.316293)
		(end 226.638104 -57.240678)
		(width 0.1016)
		(layer "In2.Cu")
		(net "PCIE_RX_N66")
	)
	(arc
		(start 226.636326 -57.623456)
		(mid 226.688258 -57.545595)
		(end 226.70643 -57.453784)
		(width 0.1016)
		(layer "In2.Cu")
		(net "PCIE_RX_N66")
	)
	(segment
		(start 225.210116 -58.499756)
		(end 225.100134 -58.499756)
		(width 0.136652)
		(layer "F.Cu")
		(net "PCIE_RX_N65")
	)
	(segment
		(start 225.600006 -57.999884)
		(end 225.600006 -58.021474)
		(width 0.136652)
		(layer "F.Cu")
		(net "PCIE_RX_N65")
	)
	(segment
		(start 225.460052 -58.359802)
		(end 225.397568 -58.422286)
		(width 0.136652)
		(layer "F.Cu")
		(net "PCIE_RX_N65")
	)
	(via
		(at 88.5063 -222.294704)
		(size 0.508)
		(drill 0.254)
		(layers "F.Cu" "B.Cu")
		(net "PCIE_RX_N65")
	)
	(via
		(at 225.100134 -58.499756)
		(size 0.4572)
		(drill 0.2032)
		(layers "F.Cu" "B.Cu")
		(net "PCIE_RX_N65")
	)
	(arc
		(start 225.397568 -58.422286)
		(mid 225.311536 -58.479645)
		(end 225.210116 -58.499756)
		(width 0.136652)
		(layer "F.Cu")
		(net "PCIE_RX_N65")
	)
	(arc
		(start 225.600006 -58.021474)
		(mid 225.563682 -58.204558)
		(end 225.460052 -58.359802)
		(width 0.136652)
		(layer "F.Cu")
		(net "PCIE_RX_N65")
	)
	(segment
		(start 88.500204 -225.92538)
		(end 88.500204 -224.770442)
		(width 0.136652)
		(layer "B.Cu")
		(net "PCIE_RX_N65")
	)
	(segment
		(start 88.252554 -224.17278)
		(end 88.252554 -222.907352)
		(width 0.136652)
		(layer "B.Cu")
		(net "PCIE_RX_N65")
	)
	(segment
		(start 88.500204 -224.770442)
		(end 88.49995 -224.770188)
		(width 0.136652)
		(layer "B.Cu")
		(net "PCIE_RX_N65")
	)
	(arc
		(start 88.49995 -224.770188)
		(mid 88.455712 -224.547791)
		(end 88.32977 -224.359216)
		(width 0.136652)
		(layer "B.Cu")
		(net "PCIE_RX_N65")
	)
	(arc
		(start 88.32977 -224.359216)
		(mid 88.272616 -224.273678)
		(end 88.252554 -224.17278)
		(width 0.136652)
		(layer "B.Cu")
		(net "PCIE_RX_N65")
	)
	(arc
		(start 88.252554 -222.907352)
		(mid 88.318504 -222.575797)
		(end 88.5063 -222.294704)
		(width 0.136652)
		(layer "B.Cu")
		(net "PCIE_RX_N65")
	)
	(segment
		(start 102.802944 -197.925944)
		(end 172.668946 -149.004528)
		(width 0.1397)
		(layer "In2.Cu")
		(net "PCIE_RX_N65")
	)
	(segment
		(start 92.922598 -205.90891)
		(end 101.340666 -200.014332)
		(width 0.1397)
		(layer "In2.Cu")
		(net "PCIE_RX_N65")
	)
	(segment
		(start 219.987622 -62.540388)
		(end 220.530166 -59.46394)
		(width 0.1397)
		(layer "In2.Cu")
		(net "PCIE_RX_N65")
	)
	(segment
		(start 220.827092 -73.58634)
		(end 220.23451 -70.04939)
		(width 0.1397)
		(layer "In2.Cu")
		(net "PCIE_RX_N65")
	)
	(segment
		(start 101.340666 -200.014332)
		(end 102.802944 -197.925944)
		(width 0.1397)
		(layer "In2.Cu")
		(net "PCIE_RX_N65")
	)
	(segment
		(start 220.530166 -59.46394)
		(end 221.81439 -58.179716)
		(width 0.1397)
		(layer "In2.Cu")
		(net "PCIE_RX_N65")
	)
	(segment
		(start 88.265 -221.712028)
		(end 88.265 -221.289372)
		(width 0.1397)
		(layer "In2.Cu")
		(net "PCIE_RX_N65")
	)
	(segment
		(start 225.48088 -58.690256)
		(end 225.290634 -58.690256)
		(width 0.1016)
		(layer "In2.Cu")
		(net "PCIE_RX_N65")
	)
	(segment
		(start 88.626442 -219.239084)
		(end 91.091258 -215.718898)
		(width 0.1397)
		(layer "In2.Cu")
		(net "PCIE_RX_N65")
	)
	(segment
		(start 91.44 -213.741)
		(end 91.44 -208.026)
		(width 0.1397)
		(layer "In2.Cu")
		(net "PCIE_RX_N65")
	)
	(segment
		(start 172.668946 -149.004528)
		(end 219.262198 -82.463386)
		(width 0.1397)
		(layer "In2.Cu")
		(net "PCIE_RX_N65")
	)
	(segment
		(start 88.265 -221.289372)
		(end 88.626442 -219.239084)
		(width 0.1397)
		(layer "In2.Cu")
		(net "PCIE_RX_N65")
	)
	(segment
		(start 225.706432 -58.405522)
		(end 225.706432 -58.453782)
		(width 0.1016)
		(layer "In2.Cu")
		(net "PCIE_RX_N65")
	)
	(segment
		(start 225.570288 -58.172858)
		(end 225.638106 -58.240676)
		(width 0.1016)
		(layer "In2.Cu")
		(net "PCIE_RX_N65")
	)
	(segment
		(start 219.262198 -82.463386)
		(end 220.827092 -73.58634)
		(width 0.1397)
		(layer "In2.Cu")
		(net "PCIE_RX_N65")
	)
	(segment
		(start 220.81998 -67.121786)
		(end 219.987622 -62.956186)
		(width 0.1397)
		(layer "In2.Cu")
		(net "PCIE_RX_N65")
	)
	(segment
		(start 219.987622 -62.956186)
		(end 219.987622 -62.540388)
		(width 0.1397)
		(layer "In2.Cu")
		(net "PCIE_RX_N65")
	)
	(segment
		(start 91.091258 -215.718898)
		(end 91.44 -213.741)
		(width 0.1397)
		(layer "In2.Cu")
		(net "PCIE_RX_N65")
	)
	(segment
		(start 220.23451 -70.04939)
		(end 220.81998 -67.121786)
		(width 0.1397)
		(layer "In2.Cu")
		(net "PCIE_RX_N65")
	)
	(segment
		(start 222.014796 -58.096658)
		(end 225.386392 -58.096658)
		(width 0.1016)
		(layer "In2.Cu")
		(net "PCIE_RX_N65")
	)
	(segment
		(start 225.636328 -58.623454)
		(end 225.631756 -58.627772)
		(width 0.1016)
		(layer "In2.Cu")
		(net "PCIE_RX_N65")
	)
	(segment
		(start 91.44 -208.026)
		(end 92.922598 -205.90891)
		(width 0.1397)
		(layer "In2.Cu")
		(net "PCIE_RX_N65")
	)
	(arc
		(start 225.631756 -58.627772)
		(mid 225.562534 -58.674025)
		(end 225.48088 -58.690256)
		(width 0.1016)
		(layer "In2.Cu")
		(net "PCIE_RX_N65")
	)
	(arc
		(start 225.706432 -58.453782)
		(mid 225.688263 -58.545594)
		(end 225.636328 -58.623454)
		(width 0.1016)
		(layer "In2.Cu")
		(net "PCIE_RX_N65")
	)
	(arc
		(start 221.81439 -58.179716)
		(mid 221.906337 -58.118279)
		(end 222.014796 -58.096658)
		(width 0.1016)
		(layer "In2.Cu")
		(net "PCIE_RX_N65")
	)
	(arc
		(start 225.290634 -58.690256)
		(mid 225.15593 -58.63446)
		(end 225.100134 -58.499756)
		(width 0.1016)
		(layer "In2.Cu")
		(net "PCIE_RX_N65")
	)
	(arc
		(start 225.638106 -58.240676)
		(mid 225.688642 -58.316308)
		(end 225.706432 -58.405522)
		(width 0.1016)
		(layer "In2.Cu")
		(net "PCIE_RX_N65")
	)
	(arc
		(start 88.5063 -222.294704)
		(mid 88.327673 -222.02737)
		(end 88.265 -221.712028)
		(width 0.1397)
		(layer "In2.Cu")
		(net "PCIE_RX_N65")
	)
	(arc
		(start 225.386392 -58.096658)
		(mid 225.485926 -58.116457)
		(end 225.570288 -58.172858)
		(width 0.1016)
		(layer "In2.Cu")
		(net "PCIE_RX_N65")
	)
	(via
		(at 226.100132 -59.499754)
		(size 0.4572)
		(drill 0.2032)
		(layers "F.Cu" "B.Cu")
		(net "PCIE_RX_N64")
	)
	(via
		(at 91.706192 -222.294704)
		(size 0.508)
		(drill 0.254)
		(layers "F.Cu" "B.Cu")
		(net "PCIE_RX_N64")
	)
	(arc
		(start 226.600004 -58.999882)
		(mid 226.565661 -59.203798)
		(end 226.4664 -59.3852)
		(width 0.136652)
		(layer "F.Cu")
		(net "PCIE_RX_N64")
	)
	(arc
		(start 226.4664 -59.3852)
		(mid 226.300991 -59.49908)
		(end 226.100132 -59.499754)
		(width 0.136652)
		(layer "F.Cu")
		(net "PCIE_RX_N64")
	)
	(segment
		(start 91.452446 -224.17278)
		(end 91.452446 -222.907352)
		(width 0.136652)
		(layer "B.Cu")
		(net "PCIE_RX_N64")
	)
	(segment
		(start 91.700096 -224.770442)
		(end 91.699842 -224.770188)
		(width 0.136652)
		(layer "B.Cu")
		(net "PCIE_RX_N64")
	)
	(segment
		(start 91.700096 -225.92538)
		(end 91.700096 -224.770442)
		(width 0.136652)
		(layer "B.Cu")
		(net "PCIE_RX_N64")
	)
	(arc
		(start 91.452446 -222.907352)
		(mid 91.518396 -222.575797)
		(end 91.706192 -222.294704)
		(width 0.136652)
		(layer "B.Cu")
		(net "PCIE_RX_N64")
	)
	(arc
		(start 91.529662 -224.359216)
		(mid 91.472508 -224.273678)
		(end 91.452446 -224.17278)
		(width 0.136652)
		(layer "B.Cu")
		(net "PCIE_RX_N64")
	)
	(arc
		(start 91.699842 -224.770188)
		(mid 91.655604 -224.547791)
		(end 91.529662 -224.359216)
		(width 0.136652)
		(layer "B.Cu")
		(net "PCIE_RX_N64")
	)
	(segment
		(start 226.70643 -59.40552)
		(end 226.70643 -59.45378)
		(width 0.1016)
		(layer "In2.Cu")
		(net "PCIE_RX_N64")
	)
	(segment
		(start 101.89718 -200.570846)
		(end 103.177848 -198.741792)
		(width 0.1397)
		(layer "In2.Cu")
		(net "PCIE_RX_N64")
	)
	(segment
		(start 91.694 -218.694)
		(end 94.491048 -214.699342)
		(width 0.1397)
		(layer "In2.Cu")
		(net "PCIE_RX_N64")
	)
	(segment
		(start 226.480878 -59.690254)
		(end 226.290632 -59.690254)
		(width 0.1016)
		(layer "In2.Cu")
		(net "PCIE_RX_N64")
	)
	(segment
		(start 220.259148 -83.672426)
		(end 222.115634 -73.140824)
		(width 0.1397)
		(layer "In2.Cu")
		(net "PCIE_RX_N64")
	)
	(segment
		(start 91.464892 -219.992956)
		(end 91.694 -218.694)
		(width 0.1397)
		(layer "In2.Cu")
		(net "PCIE_RX_N64")
	)
	(segment
		(start 91.464892 -221.712028)
		(end 91.464892 -219.992956)
		(width 0.1397)
		(layer "In2.Cu")
		(net "PCIE_RX_N64")
	)
	(segment
		(start 226.574604 -59.177174)
		(end 226.638104 -59.240674)
		(width 0.1016)
		(layer "In2.Cu")
		(net "PCIE_RX_N64")
	)
	(segment
		(start 220.926914 -63.380874)
		(end 220.926914 -62.96787)
		(width 0.1397)
		(layer "In2.Cu")
		(net "PCIE_RX_N64")
	)
	(segment
		(start 221.345506 -68.770754)
		(end 221.674944 -67.121786)
		(width 0.1397)
		(layer "In2.Cu")
		(net "PCIE_RX_N64")
	)
	(segment
		(start 94.491048 -214.699342)
		(end 95.774256 -207.42275)
		(width 0.1397)
		(layer "In2.Cu")
		(net "PCIE_RX_N64")
	)
	(segment
		(start 103.177848 -198.741792)
		(end 174.805086 -148.587714)
		(width 0.1397)
		(layer "In2.Cu")
		(net "PCIE_RX_N64")
	)
	(segment
		(start 222.631 -59.096656)
		(end 226.380294 -59.096656)
		(width 0.1016)
		(layer "In2.Cu")
		(net "PCIE_RX_N64")
	)
	(segment
		(start 95.774256 -207.42275)
		(end 99.296728 -202.391772)
		(width 0.1397)
		(layer "In2.Cu")
		(net "PCIE_RX_N64")
	)
	(segment
		(start 220.926914 -62.96787)
		(end 221.416372 -60.193428)
		(width 0.1397)
		(layer "In2.Cu")
		(net "PCIE_RX_N64")
	)
	(segment
		(start 221.674944 -67.121786)
		(end 220.926914 -63.380874)
		(width 0.1397)
		(layer "In2.Cu")
		(net "PCIE_RX_N64")
	)
	(segment
		(start 226.636326 -59.623452)
		(end 226.631754 -59.62777)
		(width 0.1016)
		(layer "In2.Cu")
		(net "PCIE_RX_N64")
	)
	(segment
		(start 221.416372 -60.193428)
		(end 222.4278 -59.182)
		(width 0.1397)
		(layer "In2.Cu")
		(net "PCIE_RX_N64")
	)
	(segment
		(start 222.115634 -73.140824)
		(end 221.345506 -68.770754)
		(width 0.1397)
		(layer "In2.Cu")
		(net "PCIE_RX_N64")
	)
	(segment
		(start 222.4278 -59.182)
		(end 222.429832 -59.179968)
		(width 0.1016)
		(layer "In2.Cu")
		(net "PCIE_RX_N64")
	)
	(segment
		(start 174.805086 -148.587714)
		(end 220.259148 -83.672426)
		(width 0.1397)
		(layer "In2.Cu")
		(net "PCIE_RX_N64")
	)
	(segment
		(start 99.296728 -202.391772)
		(end 101.89718 -200.570846)
		(width 0.1397)
		(layer "In2.Cu")
		(net "PCIE_RX_N64")
	)
	(arc
		(start 226.70643 -59.45378)
		(mid 226.688261 -59.545592)
		(end 226.636326 -59.623452)
		(width 0.1016)
		(layer "In2.Cu")
		(net "PCIE_RX_N64")
	)
	(arc
		(start 226.380294 -59.096656)
		(mid 226.485466 -59.117576)
		(end 226.574604 -59.177174)
		(width 0.1016)
		(layer "In2.Cu")
		(net "PCIE_RX_N64")
	)
	(arc
		(start 226.638104 -59.240674)
		(mid 226.68864 -59.316306)
		(end 226.70643 -59.40552)
		(width 0.1016)
		(layer "In2.Cu")
		(net "PCIE_RX_N64")
	)
	(arc
		(start 222.429832 -59.179968)
		(mid 222.522129 -59.118297)
		(end 222.631 -59.096656)
		(width 0.1016)
		(layer "In2.Cu")
		(net "PCIE_RX_N64")
	)
	(arc
		(start 226.290632 -59.690254)
		(mid 226.155928 -59.634458)
		(end 226.100132 -59.499754)
		(width 0.1016)
		(layer "In2.Cu")
		(net "PCIE_RX_N64")
	)
	(arc
		(start 91.706192 -222.294704)
		(mid 91.527565 -222.02737)
		(end 91.464892 -221.712028)
		(width 0.1397)
		(layer "In2.Cu")
		(net "PCIE_RX_N64")
	)
	(arc
		(start 226.631754 -59.62777)
		(mid 226.562532 -59.674023)
		(end 226.480878 -59.690254)
		(width 0.1016)
		(layer "In2.Cu")
		(net "PCIE_RX_N64")
	)
	(segment
		(start 223.60001 -62.999874)
		(end 223.100138 -63.499746)
		(width 0.136652)
		(layer "F.Cu")
		(net "PCIE_RX_N63")
	)
	(via
		(at 223.100138 -63.499746)
		(size 0.4572)
		(drill 0.2032)
		(layers "F.Cu" "B.Cu")
		(net "PCIE_RX_N63")
	)
	(via
		(at 97.306384 -222.294704)
		(size 0.508)
		(drill 0.254)
		(layers "F.Cu" "B.Cu")
		(net "PCIE_RX_N63")
	)
	(segment
		(start 97.300034 -225.92538)
		(end 97.300034 -224.770188)
		(width 0.136652)
		(layer "B.Cu")
		(net "PCIE_RX_N63")
	)
	(segment
		(start 97.052638 -224.17278)
		(end 97.052638 -222.907352)
		(width 0.136652)
		(layer "B.Cu")
		(net "PCIE_RX_N63")
	)
	(arc
		(start 97.300034 -224.770188)
		(mid 97.255796 -224.547791)
		(end 97.129854 -224.359216)
		(width 0.136652)
		(layer "B.Cu")
		(net "PCIE_RX_N63")
	)
	(arc
		(start 97.129854 -224.359216)
		(mid 97.0727 -224.273678)
		(end 97.052638 -224.17278)
		(width 0.136652)
		(layer "B.Cu")
		(net "PCIE_RX_N63")
	)
	(arc
		(start 97.052638 -222.907352)
		(mid 97.118588 -222.575797)
		(end 97.306384 -222.294704)
		(width 0.136652)
		(layer "B.Cu")
		(net "PCIE_RX_N63")
	)
	(segment
		(start 222.69704 -63.30188)
		(end 222.69704 -66.78803)
		(width 0.1016)
		(layer "In2.Cu")
		(net "PCIE_RX_N63")
	)
	(segment
		(start 99.06 -205.232)
		(end 96.64319 -208.683606)
		(width 0.1397)
		(layer "In2.Cu")
		(net "PCIE_RX_N63")
	)
	(segment
		(start 222.777304 -63.110364)
		(end 222.776034 -63.11138)
		(width 0.1016)
		(layer "In2.Cu")
		(net "PCIE_RX_N63")
	)
	(segment
		(start 104.27208 -199.437244)
		(end 101.326442 -203.645008)
		(width 0.1397)
		(layer "In2.Cu")
		(net "PCIE_RX_N63")
	)
	(segment
		(start 223.109028 -73.140824)
		(end 221.116398 -85.168486)
		(width 0.1397)
		(layer "In2.Cu")
		(net "PCIE_RX_N63")
	)
	(segment
		(start 222.70339 -66.815462)
		(end 222.7199 -66.849752)
		(width 0.1016)
		(layer "In2.Cu")
		(net "PCIE_RX_N63")
	)
	(segment
		(start 101.326442 -203.645008)
		(end 99.06 -205.232)
		(width 0.1397)
		(layer "In2.Cu")
		(net "PCIE_RX_N63")
	)
	(segment
		(start 96.64319 -208.683606)
		(end 95.875602 -213.037166)
		(width 0.1397)
		(layer "In2.Cu")
		(net "PCIE_RX_N63")
	)
	(segment
		(start 222.7199 -70.933564)
		(end 223.109028 -73.140824)
		(width 0.1397)
		(layer "In2.Cu")
		(net "PCIE_RX_N63")
	)
	(segment
		(start 95.875602 -213.037166)
		(end 97.151952 -220.276928)
		(width 0.1397)
		(layer "In2.Cu")
		(net "PCIE_RX_N63")
	)
	(segment
		(start 223.204532 -63.162434)
		(end 223.13138 -63.091314)
		(width 0.1016)
		(layer "In2.Cu")
		(net "PCIE_RX_N63")
	)
	(segment
		(start 222.7199 -66.849752)
		(end 222.7199 -70.933564)
		(width 0.1397)
		(layer "In2.Cu")
		(net "PCIE_RX_N63")
	)
	(segment
		(start 176.535334 -148.838158)
		(end 104.27208 -199.437244)
		(width 0.1397)
		(layer "In2.Cu")
		(net "PCIE_RX_N63")
	)
	(segment
		(start 223.100138 -63.499746)
		(end 223.204532 -63.395352)
		(width 0.1016)
		(layer "In2.Cu")
		(net "PCIE_RX_N63")
	)
	(segment
		(start 97.151952 -220.276928)
		(end 97.065084 -220.769688)
		(width 0.1397)
		(layer "In2.Cu")
		(net "PCIE_RX_N63")
	)
	(segment
		(start 97.065084 -220.769688)
		(end 97.065084 -221.712028)
		(width 0.1397)
		(layer "In2.Cu")
		(net "PCIE_RX_N63")
	)
	(segment
		(start 222.996252 -63.03518)
		(end 222.958406 -63.03518)
		(width 0.1016)
		(layer "In2.Cu")
		(net "PCIE_RX_N63")
	)
	(segment
		(start 221.116398 -85.168486)
		(end 176.535334 -148.838158)
		(width 0.1397)
		(layer "In2.Cu")
		(net "PCIE_RX_N63")
	)
	(arc
		(start 222.725488 -63.181484)
		(mid 222.704253 -63.240027)
		(end 222.69704 -63.30188)
		(width 0.1016)
		(layer "In2.Cu")
		(net "PCIE_RX_N63")
	)
	(arc
		(start 222.776034 -63.11138)
		(mid 222.747942 -63.144399)
		(end 222.725488 -63.181484)
		(width 0.1016)
		(layer "In2.Cu")
		(net "PCIE_RX_N63")
	)
	(arc
		(start 223.204532 -63.395352)
		(mid 223.252718 -63.27893)
		(end 223.204532 -63.162434)
		(width 0.1016)
		(layer "In2.Cu")
		(net "PCIE_RX_N63")
	)
	(arc
		(start 223.13138 -63.091314)
		(mid 223.069398 -63.049806)
		(end 222.996252 -63.03518)
		(width 0.1016)
		(layer "In2.Cu")
		(net "PCIE_RX_N63")
	)
	(arc
		(start 222.69704 -66.78803)
		(mid 222.698683 -66.802099)
		(end 222.70339 -66.815462)
		(width 0.1016)
		(layer "In2.Cu")
		(net "PCIE_RX_N63")
	)
	(arc
		(start 222.958406 -63.03518)
		(mid 222.860383 -63.054772)
		(end 222.777304 -63.110364)
		(width 0.1016)
		(layer "In2.Cu")
		(net "PCIE_RX_N63")
	)
	(arc
		(start 97.065084 -221.712028)
		(mid 97.127805 -222.02735)
		(end 97.306384 -222.294704)
		(width 0.1397)
		(layer "In2.Cu")
		(net "PCIE_RX_N63")
	)
	(segment
		(start 224.600008 -61.999876)
		(end 224.100136 -62.499748)
		(width 0.136652)
		(layer "F.Cu")
		(net "PCIE_RX_N62")
	)
	(via
		(at 100.506276 -222.294704)
		(size 0.508)
		(drill 0.254)
		(layers "F.Cu" "B.Cu")
		(net "PCIE_RX_N62")
	)
	(via
		(at 224.100136 -62.499748)
		(size 0.4572)
		(drill 0.2032)
		(layers "F.Cu" "B.Cu")
		(net "PCIE_RX_N62")
	)
	(segment
		(start 100.50018 -225.92538)
		(end 100.50018 -224.770442)
		(width 0.136652)
		(layer "B.Cu")
		(net "PCIE_RX_N62")
	)
	(segment
		(start 100.25253 -224.17278)
		(end 100.25253 -222.907352)
		(width 0.136652)
		(layer "B.Cu")
		(net "PCIE_RX_N62")
	)
	(segment
		(start 100.50018 -224.770442)
		(end 100.499926 -224.770188)
		(width 0.136652)
		(layer "B.Cu")
		(net "PCIE_RX_N62")
	)
	(arc
		(start 100.25253 -222.907352)
		(mid 100.31848 -222.575797)
		(end 100.506276 -222.294704)
		(width 0.136652)
		(layer "B.Cu")
		(net "PCIE_RX_N62")
	)
	(arc
		(start 100.329746 -224.359216)
		(mid 100.272592 -224.273678)
		(end 100.25253 -224.17278)
		(width 0.136652)
		(layer "B.Cu")
		(net "PCIE_RX_N62")
	)
	(arc
		(start 100.499926 -224.770188)
		(mid 100.455688 -224.547791)
		(end 100.329746 -224.359216)
		(width 0.136652)
		(layer "B.Cu")
		(net "PCIE_RX_N62")
	)
	(segment
		(start 100.22586 -213.614)
		(end 100.22586 -208.771998)
		(width 0.1397)
		(layer "In2.Cu")
		(net "PCIE_RX_N62")
	)
	(segment
		(start 99.868736 -215.639142)
		(end 100.22586 -213.614)
		(width 0.1397)
		(layer "In2.Cu")
		(net "PCIE_RX_N62")
	)
	(segment
		(start 100.264976 -221.348554)
		(end 100.570284 -219.617798)
		(width 0.1397)
		(layer "In2.Cu")
		(net "PCIE_RX_N62")
	)
	(segment
		(start 223.776032 -62.111382)
		(end 223.777302 -62.110366)
		(width 0.1016)
		(layer "In2.Cu")
		(net "PCIE_RX_N62")
	)
	(segment
		(start 224.153222 -62.1792)
		(end 224.153222 -62.371478)
		(width 0.1016)
		(layer "In2.Cu")
		(net "PCIE_RX_N62")
	)
	(segment
		(start 106.052366 -200.451466)
		(end 176.041812 -151.444452)
		(width 0.1397)
		(layer "In2.Cu")
		(net "PCIE_RX_N62")
	)
	(segment
		(start 100.264976 -221.712028)
		(end 100.264976 -221.348554)
		(width 0.1397)
		(layer "In2.Cu")
		(net "PCIE_RX_N62")
	)
	(segment
		(start 223.773746 -66.826638)
		(end 223.697038 -66.81089)
		(width 0.1016)
		(layer "In2.Cu")
		(net "PCIE_RX_N62")
	)
	(segment
		(start 100.570284 -219.617798)
		(end 99.868736 -215.639142)
		(width 0.1397)
		(layer "In2.Cu")
		(net "PCIE_RX_N62")
	)
	(segment
		(start 223.958404 -62.035182)
		(end 224.009204 -62.035182)
		(width 0.1016)
		(layer "In2.Cu")
		(net "PCIE_RX_N62")
	)
	(segment
		(start 223.755712 -69.137022)
		(end 223.773492 -66.852038)
		(width 0.1397)
		(layer "In2.Cu")
		(net "PCIE_RX_N62")
	)
	(segment
		(start 222.505778 -85.08873)
		(end 224.40265 -74.323956)
		(width 0.1397)
		(layer "In2.Cu")
		(net "PCIE_RX_N62")
	)
	(segment
		(start 100.22586 -208.771998)
		(end 106.052366 -200.451466)
		(width 0.1397)
		(layer "In2.Cu")
		(net "PCIE_RX_N62")
	)
	(segment
		(start 176.041812 -151.444452)
		(end 222.505778 -85.08873)
		(width 0.1397)
		(layer "In2.Cu")
		(net "PCIE_RX_N62")
	)
	(segment
		(start 223.697038 -66.81089)
		(end 223.697038 -62.302136)
		(width 0.1016)
		(layer "In2.Cu")
		(net "PCIE_RX_N62")
	)
	(segment
		(start 224.40265 -74.323956)
		(end 223.755712 -69.137022)
		(width 0.1397)
		(layer "In2.Cu")
		(net "PCIE_RX_N62")
	)
	(segment
		(start 223.773492 -66.852038)
		(end 223.773746 -66.826638)
		(width 0.1016)
		(layer "In2.Cu")
		(net "PCIE_RX_N62")
	)
	(arc
		(start 100.506276 -222.294704)
		(mid 100.327649 -222.02737)
		(end 100.264976 -221.712028)
		(width 0.1397)
		(layer "In2.Cu")
		(net "PCIE_RX_N62")
	)
	(arc
		(start 223.697038 -62.302136)
		(mid 223.717571 -62.198908)
		(end 223.776032 -62.111382)
		(width 0.1016)
		(layer "In2.Cu")
		(net "PCIE_RX_N62")
	)
	(arc
		(start 224.009204 -62.035182)
		(mid 224.11104 -62.077364)
		(end 224.153222 -62.1792)
		(width 0.1016)
		(layer "In2.Cu")
		(net "PCIE_RX_N62")
	)
	(arc
		(start 223.777302 -62.110366)
		(mid 223.860377 -62.054764)
		(end 223.958404 -62.035182)
		(width 0.1016)
		(layer "In2.Cu")
		(net "PCIE_RX_N62")
	)
	(arc
		(start 224.153222 -62.371478)
		(mid 224.139417 -62.44088)
		(end 224.100136 -62.499748)
		(width 0.1016)
		(layer "In2.Cu")
		(net "PCIE_RX_N62")
	)
	(segment
		(start 225.600006 -62.999874)
		(end 225.100134 -63.499746)
		(width 0.136652)
		(layer "F.Cu")
		(net "PCIE_RX_N61")
	)
	(via
		(at 103.706168 -222.294704)
		(size 0.508)
		(drill 0.254)
		(layers "F.Cu" "B.Cu")
		(net "PCIE_RX_N61")
	)
	(via
		(at 225.100134 -63.499746)
		(size 0.4572)
		(drill 0.2032)
		(layers "F.Cu" "B.Cu")
		(net "PCIE_RX_N61")
	)
	(segment
		(start 103.452422 -224.17278)
		(end 103.452422 -222.907352)
		(width 0.136652)
		(layer "B.Cu")
		(net "PCIE_RX_N61")
	)
	(segment
		(start 103.700072 -224.770442)
		(end 103.699818 -224.770188)
		(width 0.136652)
		(layer "B.Cu")
		(net "PCIE_RX_N61")
	)
	(segment
		(start 103.700072 -225.92538)
		(end 103.700072 -224.770442)
		(width 0.136652)
		(layer "B.Cu")
		(net "PCIE_RX_N61")
	)
	(arc
		(start 103.452422 -222.907352)
		(mid 103.518372 -222.575797)
		(end 103.706168 -222.294704)
		(width 0.136652)
		(layer "B.Cu")
		(net "PCIE_RX_N61")
	)
	(arc
		(start 103.699818 -224.770188)
		(mid 103.65558 -224.547791)
		(end 103.529638 -224.359216)
		(width 0.136652)
		(layer "B.Cu")
		(net "PCIE_RX_N61")
	)
	(arc
		(start 103.529638 -224.359216)
		(mid 103.472484 -224.273678)
		(end 103.452422 -224.17278)
		(width 0.136652)
		(layer "B.Cu")
		(net "PCIE_RX_N61")
	)
	(segment
		(start 224.7519 -69.236082)
		(end 224.7519 -67.206876)
		(width 0.1397)
		(layer "In2.Cu")
		(net "PCIE_RX_N61")
	)
	(segment
		(start 103.759 -207.899)
		(end 109.045502 -200.34885)
		(width 0.1397)
		(layer "In2.Cu")
		(net "PCIE_RX_N61")
	)
	(segment
		(start 103.464868 -221.080584)
		(end 103.749348 -219.46743)
		(width 0.1397)
		(layer "In2.Cu")
		(net "PCIE_RX_N61")
	)
	(segment
		(start 103.506016 -213.741)
		(end 103.506016 -209.333592)
		(width 0.1397)
		(layer "In2.Cu")
		(net "PCIE_RX_N61")
	)
	(segment
		(start 225.099118 -63.072264)
		(end 225.171 -63.144654)
		(width 0.1016)
		(layer "In2.Cu")
		(net "PCIE_RX_N61")
	)
	(segment
		(start 176.87163 -152.857708)
		(end 223.409256 -86.394036)
		(width 0.1397)
		(layer "In2.Cu")
		(net "PCIE_RX_N61")
	)
	(segment
		(start 109.045502 -200.34885)
		(end 176.87163 -152.857708)
		(width 0.1397)
		(layer "In2.Cu")
		(net "PCIE_RX_N61")
	)
	(segment
		(start 224.7392 -67.181476)
		(end 224.73412 -67.181476)
		(width 0.1016)
		(layer "In2.Cu")
		(net "PCIE_RX_N61")
	)
	(segment
		(start 224.73412 -67.181476)
		(end 224.697036 -67.144392)
		(width 0.1016)
		(layer "In2.Cu")
		(net "PCIE_RX_N61")
	)
	(segment
		(start 223.409256 -86.394036)
		(end 225.58375 -74.067416)
		(width 0.1397)
		(layer "In2.Cu")
		(net "PCIE_RX_N61")
	)
	(segment
		(start 103.749348 -219.46743)
		(end 103.12273 -215.914478)
		(width 0.1397)
		(layer "In2.Cu")
		(net "PCIE_RX_N61")
	)
	(segment
		(start 224.7519 -67.206876)
		(end 224.7519 -67.194176)
		(width 0.1016)
		(layer "In2.Cu")
		(net "PCIE_RX_N61")
	)
	(segment
		(start 103.464868 -221.712028)
		(end 103.464868 -221.080584)
		(width 0.1397)
		(layer "In2.Cu")
		(net "PCIE_RX_N61")
	)
	(segment
		(start 225.171 -63.42888)
		(end 225.100134 -63.499746)
		(width 0.1016)
		(layer "In2.Cu")
		(net "PCIE_RX_N61")
	)
	(segment
		(start 224.958402 -63.03518)
		(end 225.009202 -63.03518)
		(width 0.1016)
		(layer "In2.Cu")
		(net "PCIE_RX_N61")
	)
	(segment
		(start 224.752154 -69.236082)
		(end 224.7519 -69.236082)
		(width 0.1397)
		(layer "In2.Cu")
		(net "PCIE_RX_N61")
	)
	(segment
		(start 103.12273 -215.914478)
		(end 103.506016 -213.741)
		(width 0.1397)
		(layer "In2.Cu")
		(net "PCIE_RX_N61")
	)
	(segment
		(start 224.697036 -67.144392)
		(end 224.697036 -63.302134)
		(width 0.1016)
		(layer "In2.Cu")
		(net "PCIE_RX_N61")
	)
	(segment
		(start 225.58375 -74.067416)
		(end 224.752154 -69.236082)
		(width 0.1397)
		(layer "In2.Cu")
		(net "PCIE_RX_N61")
	)
	(segment
		(start 103.506016 -209.333592)
		(end 103.759 -207.899)
		(width 0.1397)
		(layer "In2.Cu")
		(net "PCIE_RX_N61")
	)
	(segment
		(start 224.7519 -67.194176)
		(end 224.7392 -67.181476)
		(width 0.1016)
		(layer "In2.Cu")
		(net "PCIE_RX_N61")
	)
	(segment
		(start 224.77603 -63.11138)
		(end 224.7773 -63.110364)
		(width 0.1016)
		(layer "In2.Cu")
		(net "PCIE_RX_N61")
	)
	(arc
		(start 225.171 -63.144654)
		(mid 225.229992 -63.286804)
		(end 225.171 -63.42888)
		(width 0.1016)
		(layer "In2.Cu")
		(net "PCIE_RX_N61")
	)
	(arc
		(start 224.7773 -63.110364)
		(mid 224.860375 -63.054762)
		(end 224.958402 -63.03518)
		(width 0.1016)
		(layer "In2.Cu")
		(net "PCIE_RX_N61")
	)
	(arc
		(start 224.697036 -63.302134)
		(mid 224.717569 -63.198906)
		(end 224.77603 -63.11138)
		(width 0.1016)
		(layer "In2.Cu")
		(net "PCIE_RX_N61")
	)
	(arc
		(start 103.706168 -222.294704)
		(mid 103.527541 -222.02737)
		(end 103.464868 -221.712028)
		(width 0.1397)
		(layer "In2.Cu")
		(net "PCIE_RX_N61")
	)
	(arc
		(start 225.009202 -63.03518)
		(mid 225.057857 -63.044764)
		(end 225.099118 -63.072264)
		(width 0.1016)
		(layer "In2.Cu")
		(net "PCIE_RX_N61")
	)
	(segment
		(start 226.600004 -61.999876)
		(end 226.100132 -62.499748)
		(width 0.136652)
		(layer "F.Cu")
		(net "PCIE_RX_N60")
	)
	(via
		(at 226.100132 -62.499748)
		(size 0.4572)
		(drill 0.2032)
		(layers "F.Cu" "B.Cu")
		(net "PCIE_RX_N60")
	)
	(via
		(at 106.906314 -222.294704)
		(size 0.508)
		(drill 0.254)
		(layers "F.Cu" "B.Cu")
		(net "PCIE_RX_N60")
	)
	(segment
		(start 106.652568 -224.17278)
		(end 106.652568 -222.907352)
		(width 0.136652)
		(layer "B.Cu")
		(net "PCIE_RX_N60")
	)
	(segment
		(start 106.899964 -225.92538)
		(end 106.899964 -224.770188)
		(width 0.136652)
		(layer "B.Cu")
		(net "PCIE_RX_N60")
	)
	(arc
		(start 106.652568 -222.907352)
		(mid 106.718518 -222.575797)
		(end 106.906314 -222.294704)
		(width 0.136652)
		(layer "B.Cu")
		(net "PCIE_RX_N60")
	)
	(arc
		(start 106.729784 -224.359216)
		(mid 106.67263 -224.273678)
		(end 106.652568 -224.17278)
		(width 0.136652)
		(layer "B.Cu")
		(net "PCIE_RX_N60")
	)
	(arc
		(start 106.899964 -224.770188)
		(mid 106.855726 -224.547791)
		(end 106.729784 -224.359216)
		(width 0.136652)
		(layer "B.Cu")
		(net "PCIE_RX_N60")
	)
	(segment
		(start 106.665014 -221.712028)
		(end 106.665014 -221.064836)
		(width 0.1397)
		(layer "In2.Cu")
		(net "PCIE_RX_N60")
	)
	(segment
		(start 111.348012 -200.41489)
		(end 178.605942 -153.319988)
		(width 0.1397)
		(layer "In2.Cu")
		(net "PCIE_RX_N60")
	)
	(segment
		(start 225.7679 -69.463666)
		(end 225.7679 -67.276472)
		(width 0.1397)
		(layer "In2.Cu")
		(net "PCIE_RX_N60")
	)
	(segment
		(start 106.68 -213.614)
		(end 106.68 -209.88909)
		(width 0.1397)
		(layer "In2.Cu")
		(net "PCIE_RX_N60")
	)
	(segment
		(start 226.110292 -62.077092)
		(end 226.182428 -62.149228)
		(width 0.1016)
		(layer "In2.Cu")
		(net "PCIE_RX_N60")
	)
	(segment
		(start 225.776028 -62.111382)
		(end 225.777298 -62.110366)
		(width 0.1016)
		(layer "In2.Cu")
		(net "PCIE_RX_N60")
	)
	(segment
		(start 226.709986 -74.806048)
		(end 225.7679 -69.463666)
		(width 0.1397)
		(layer "In2.Cu")
		(net "PCIE_RX_N60")
	)
	(segment
		(start 106.906568 -219.695522)
		(end 106.25709 -216.012014)
		(width 0.1397)
		(layer "In2.Cu")
		(net "PCIE_RX_N60")
	)
	(segment
		(start 225.9584 -62.035182)
		(end 226.0092 -62.035182)
		(width 0.1016)
		(layer "In2.Cu")
		(net "PCIE_RX_N60")
	)
	(segment
		(start 225.697034 -67.205606)
		(end 225.697034 -62.30239)
		(width 0.1016)
		(layer "In2.Cu")
		(net "PCIE_RX_N60")
	)
	(segment
		(start 106.25709 -216.012014)
		(end 106.68 -213.614)
		(width 0.1397)
		(layer "In2.Cu")
		(net "PCIE_RX_N60")
	)
	(segment
		(start 106.665014 -221.064836)
		(end 106.906568 -219.695522)
		(width 0.1397)
		(layer "In2.Cu")
		(net "PCIE_RX_N60")
	)
	(segment
		(start 226.182428 -62.417452)
		(end 226.100132 -62.499748)
		(width 0.1016)
		(layer "In2.Cu")
		(net "PCIE_RX_N60")
	)
	(segment
		(start 106.68 -209.88909)
		(end 107.34167 -206.137256)
		(width 0.1397)
		(layer "In2.Cu")
		(net "PCIE_RX_N60")
	)
	(segment
		(start 178.605942 -153.319988)
		(end 224.398078 -87.919052)
		(width 0.1397)
		(layer "In2.Cu")
		(net "PCIE_RX_N60")
	)
	(segment
		(start 224.398078 -87.919052)
		(end 226.709986 -74.806048)
		(width 0.1397)
		(layer "In2.Cu")
		(net "PCIE_RX_N60")
	)
	(segment
		(start 225.7679 -67.276472)
		(end 225.697034 -67.205606)
		(width 0.1016)
		(layer "In2.Cu")
		(net "PCIE_RX_N60")
	)
	(segment
		(start 107.34167 -206.137256)
		(end 111.348012 -200.41489)
		(width 0.1397)
		(layer "In2.Cu")
		(net "PCIE_RX_N60")
	)
	(arc
		(start 226.182428 -62.149228)
		(mid 226.237979 -62.28334)
		(end 226.182428 -62.417452)
		(width 0.1016)
		(layer "In2.Cu")
		(net "PCIE_RX_N60")
	)
	(arc
		(start 225.777298 -62.110366)
		(mid 225.860373 -62.054764)
		(end 225.9584 -62.035182)
		(width 0.1016)
		(layer "In2.Cu")
		(net "PCIE_RX_N60")
	)
	(arc
		(start 225.697034 -62.30239)
		(mid 225.717519 -62.199025)
		(end 225.776028 -62.111382)
		(width 0.1016)
		(layer "In2.Cu")
		(net "PCIE_RX_N60")
	)
	(arc
		(start 226.0092 -62.035182)
		(mid 226.063924 -62.046067)
		(end 226.110292 -62.077092)
		(width 0.1016)
		(layer "In2.Cu")
		(net "PCIE_RX_N60")
	)
	(arc
		(start 106.906314 -222.294704)
		(mid 106.727687 -222.02737)
		(end 106.665014 -221.712028)
		(width 0.1397)
		(layer "In2.Cu")
		(net "PCIE_RX_N60")
	)
	(segment
		(start 248.59996 -29.99994)
		(end 249.099832 -29.500068)
		(width 0.136652)
		(layer "F.Cu")
		(net "PCIE_RX_N6")
	)
	(via
		(at 249.099832 -29.500068)
		(size 0.4572)
		(drill 0.2032)
		(layers "F.Cu" "B.Cu")
		(net "PCIE_RX_N6")
	)
	(segment
		(start 295.534842 -22.537166)
		(end 293.610284 -25.285954)
		(width 0.1397)
		(layer "In2.Cu")
		(net "PCIE_RX_N6")
	)
	(segment
		(start 295.90492 -20.43938)
		(end 295.534842 -22.537166)
		(width 0.1397)
		(layer "In2.Cu")
		(net "PCIE_RX_N6")
	)
	(segment
		(start 292.46195 -26.090118)
		(end 290.900866 -26.3652)
		(width 0.1397)
		(layer "In2.Cu")
		(net "PCIE_RX_N6")
	)
	(segment
		(start 261.049262 -23.938992)
		(end 257.873246 -23.3045)
		(width 0.1397)
		(layer "In2.Cu")
		(net "PCIE_RX_N6")
	)
	(segment
		(start 285.546038 -26.3652)
		(end 284.070552 -25.814274)
		(width 0.1397)
		(layer "In2.Cu")
		(net "PCIE_RX_N6")
	)
	(segment
		(start 302.416464 -17.28343)
		(end 302.41621 -17.28343)
		(width 0.1397)
		(layer "In2.Cu")
		(net "PCIE_RX_N6")
	)
	(segment
		(start 302.167544 -18.915888)
		(end 301.53483 -19.233134)
		(width 0.1397)
		(layer "In2.Cu")
		(net "PCIE_RX_N6")
	)
	(segment
		(start 284.070552 -25.814274)
		(end 277.654766 -24.682958)
		(width 0.1397)
		(layer "In2.Cu")
		(net "PCIE_RX_N6")
	)
	(segment
		(start 297.069256 -19.591782)
		(end 295.90492 -20.43938)
		(width 0.1397)
		(layer "In2.Cu")
		(net "PCIE_RX_N6")
	)
	(segment
		(start 301.049944 -19.298158)
		(end 300.552358 -19.36496)
		(width 0.1397)
		(layer "In2.Cu")
		(net "PCIE_RX_N6")
	)
	(segment
		(start 290.900866 -26.3652)
		(end 285.546038 -26.3652)
		(width 0.1397)
		(layer "In2.Cu")
		(net "PCIE_RX_N6")
	)
	(segment
		(start 300.552358 -19.36496)
		(end 299.307504 -19.012408)
		(width 0.1397)
		(layer "In2.Cu")
		(net "PCIE_RX_N6")
	)
	(segment
		(start 253.650496 -24.032464)
		(end 249.736864 -27.946096)
		(width 0.1397)
		(layer "In2.Cu")
		(net "PCIE_RX_N6")
	)
	(segment
		(start 302.337216 -18.704306)
		(end 302.167544 -18.915888)
		(width 0.1397)
		(layer "In2.Cu")
		(net "PCIE_RX_N6")
	)
	(segment
		(start 302.38446 -16.330168)
		(end 302.264318 -16.303244)
		(width 0.1397)
		(layer "In2.Cu")
		(net "PCIE_RX_N6")
	)
	(segment
		(start 249.736864 -27.946096)
		(end 249.317764 -28.364942)
		(width 0.1397)
		(layer "In2.Cu")
		(net "PCIE_RX_N6")
	)
	(segment
		(start 301.53483 -19.233134)
		(end 301.049944 -19.298158)
		(width 0.1397)
		(layer "In2.Cu")
		(net "PCIE_RX_N6")
	)
	(segment
		(start 302.462184 -18.548858)
		(end 302.337216 -18.704306)
		(width 0.1397)
		(layer "In2.Cu")
		(net "PCIE_RX_N6")
	)
	(segment
		(start 293.610284 -25.285954)
		(end 292.46195 -26.090118)
		(width 0.1397)
		(layer "In2.Cu")
		(net "PCIE_RX_N6")
	)
	(segment
		(start 257.873246 -23.3045)
		(end 253.650496 -24.032464)
		(width 0.1397)
		(layer "In2.Cu")
		(net "PCIE_RX_N6")
	)
	(segment
		(start 274.231862 -25.286716)
		(end 264.223754 -23.3045)
		(width 0.1397)
		(layer "In2.Cu")
		(net "PCIE_RX_N6")
	)
	(segment
		(start 264.223754 -23.3045)
		(end 261.049262 -23.938992)
		(width 0.1397)
		(layer "In2.Cu")
		(net "PCIE_RX_N6")
	)
	(segment
		(start 277.654766 -24.682958)
		(end 274.231862 -25.286716)
		(width 0.1397)
		(layer "In2.Cu")
		(net "PCIE_RX_N6")
	)
	(segment
		(start 299.307504 -19.012408)
		(end 297.069256 -19.591782)
		(width 0.1397)
		(layer "In2.Cu")
		(net "PCIE_RX_N6")
	)
	(arc
		(start 302.264318 -16.303244)
		(mid 302.030263 -16.379063)
		(end 301.889922 -16.58112)
		(width 0.1397)
		(layer "In2.Cu")
		(net "PCIE_RX_N6")
	)
	(arc
		(start 302.087026 -17.0942)
		(mid 302.153904 -17.113119)
		(end 302.218344 -17.139158)
		(width 0.1397)
		(layer "In2.Cu")
		(net "PCIE_RX_N6")
	)
	(arc
		(start 249.002804 -29.062172)
		(mid 249.015307 -29.289103)
		(end 249.099832 -29.500068)
		(width 0.1397)
		(layer "In2.Cu")
		(net "PCIE_RX_N6")
	)
	(arc
		(start 302.218344 -17.139158)
		(mid 302.324334 -17.201774)
		(end 302.416464 -17.28343)
		(width 0.1397)
		(layer "In2.Cu")
		(net "PCIE_RX_N6")
	)
	(arc
		(start 302.41621 -17.28343)
		(mid 302.675064 -17.907546)
		(end 302.462184 -18.548858)
		(width 0.1397)
		(layer "In2.Cu")
		(net "PCIE_RX_N6")
	)
	(arc
		(start 301.889922 -16.58112)
		(mid 301.90225 -16.870768)
		(end 302.087026 -17.0942)
		(width 0.1397)
		(layer "In2.Cu")
		(net "PCIE_RX_N6")
	)
	(arc
		(start 249.317764 -28.364942)
		(mid 249.104719 -28.688449)
		(end 249.002804 -29.062172)
		(width 0.1397)
		(layer "In2.Cu")
		(net "PCIE_RX_N6")
	)
	(segment
		(start 227.600002 -62.999874)
		(end 227.10013 -63.499746)
		(width 0.136652)
		(layer "F.Cu")
		(net "PCIE_RX_N59")
	)
	(via
		(at 137.706354 -222.294704)
		(size 0.508)
		(drill 0.254)
		(layers "F.Cu" "B.Cu")
		(net "PCIE_RX_N59")
	)
	(via
		(at 227.10013 -63.499746)
		(size 0.4572)
		(drill 0.2032)
		(layers "F.Cu" "B.Cu")
		(net "PCIE_RX_N59")
	)
	(segment
		(start 137.452608 -224.17278)
		(end 137.452608 -222.907352)
		(width 0.136652)
		(layer "B.Cu")
		(net "PCIE_RX_N59")
	)
	(segment
		(start 137.700004 -225.92538)
		(end 137.700004 -224.770188)
		(width 0.136652)
		(layer "B.Cu")
		(net "PCIE_RX_N59")
	)
	(arc
		(start 137.700004 -224.770188)
		(mid 137.655766 -224.547791)
		(end 137.529824 -224.359216)
		(width 0.136652)
		(layer "B.Cu")
		(net "PCIE_RX_N59")
	)
	(arc
		(start 137.529824 -224.359216)
		(mid 137.47267 -224.273678)
		(end 137.452608 -224.17278)
		(width 0.136652)
		(layer "B.Cu")
		(net "PCIE_RX_N59")
	)
	(arc
		(start 137.452608 -222.907352)
		(mid 137.518558 -222.575797)
		(end 137.706354 -222.294704)
		(width 0.136652)
		(layer "B.Cu")
		(net "PCIE_RX_N59")
	)
	(segment
		(start 227.203 -63.251334)
		(end 227.203 -63.1952)
		(width 0.1016)
		(layer "In2.Cu")
		(net "PCIE_RX_N59")
	)
	(segment
		(start 140.6398 -213.868)
		(end 140.320268 -215.67902)
		(width 0.1397)
		(layer "In2.Cu")
		(net "PCIE_RX_N59")
	)
	(segment
		(start 227.831142 -75.319636)
		(end 227.074984 -79.60614)
		(width 0.1397)
		(layer "In2.Cu")
		(net "PCIE_RX_N59")
	)
	(segment
		(start 226.697032 -63.302134)
		(end 226.697032 -67.058032)
		(width 0.1016)
		(layer "In2.Cu")
		(net "PCIE_RX_N59")
	)
	(segment
		(start 140.320268 -215.67902)
		(end 137.465054 -219.756736)
		(width 0.1397)
		(layer "In2.Cu")
		(net "PCIE_RX_N59")
	)
	(segment
		(start 226.697032 -67.058032)
		(end 226.7585 -67.1195)
		(width 0.1016)
		(layer "In2.Cu")
		(net "PCIE_RX_N59")
	)
	(segment
		(start 227.074984 -79.60614)
		(end 226.5172 -87.285068)
		(width 0.1397)
		(layer "In2.Cu")
		(net "PCIE_RX_N59")
	)
	(segment
		(start 144.243552 -204.779372)
		(end 143.161766 -205.861158)
		(width 0.1397)
		(layer "In2.Cu")
		(net "PCIE_RX_N59")
	)
	(segment
		(start 226.5172 -87.285068)
		(end 144.247108 -204.778864)
		(width 0.1397)
		(layer "In2.Cu")
		(net "PCIE_RX_N59")
	)
	(segment
		(start 143.161766 -205.861158)
		(end 140.6398 -209.463132)
		(width 0.1397)
		(layer "In2.Cu")
		(net "PCIE_RX_N59")
	)
	(segment
		(start 140.6398 -209.463132)
		(end 140.6398 -213.868)
		(width 0.1397)
		(layer "In2.Cu")
		(net "PCIE_RX_N59")
	)
	(segment
		(start 137.465054 -219.756736)
		(end 137.465054 -221.712028)
		(width 0.1397)
		(layer "In2.Cu")
		(net "PCIE_RX_N59")
	)
	(segment
		(start 226.7585 -69.235574)
		(end 227.831142 -75.319636)
		(width 0.1397)
		(layer "In2.Cu")
		(net "PCIE_RX_N59")
	)
	(segment
		(start 144.2466 -204.779372)
		(end 144.243552 -204.779372)
		(width 0.1397)
		(layer "In2.Cu")
		(net "PCIE_RX_N59")
	)
	(segment
		(start 226.7585 -67.1195)
		(end 226.7585 -69.235574)
		(width 0.1397)
		(layer "In2.Cu")
		(net "PCIE_RX_N59")
	)
	(segment
		(start 144.247108 -204.778864)
		(end 144.2466 -204.779372)
		(width 0.1397)
		(layer "In2.Cu")
		(net "PCIE_RX_N59")
	)
	(segment
		(start 226.777296 -63.110364)
		(end 226.776026 -63.11138)
		(width 0.1016)
		(layer "In2.Cu")
		(net "PCIE_RX_N59")
	)
	(segment
		(start 227.04298 -63.03518)
		(end 226.958398 -63.03518)
		(width 0.1016)
		(layer "In2.Cu")
		(net "PCIE_RX_N59")
	)
	(arc
		(start 137.465054 -221.712028)
		(mid 137.527775 -222.02735)
		(end 137.706354 -222.294704)
		(width 0.1397)
		(layer "In2.Cu")
		(net "PCIE_RX_N59")
	)
	(arc
		(start 227.203 -63.1952)
		(mid 227.156131 -63.082049)
		(end 227.04298 -63.03518)
		(width 0.1016)
		(layer "In2.Cu")
		(net "PCIE_RX_N59")
	)
	(arc
		(start 226.776026 -63.11138)
		(mid 226.717548 -63.198899)
		(end 226.697032 -63.302134)
		(width 0.1016)
		(layer "In2.Cu")
		(net "PCIE_RX_N59")
	)
	(arc
		(start 226.958398 -63.03518)
		(mid 226.860375 -63.054772)
		(end 226.777296 -63.110364)
		(width 0.1016)
		(layer "In2.Cu")
		(net "PCIE_RX_N59")
	)
	(arc
		(start 227.10013 -63.499746)
		(mid 227.176284 -63.385774)
		(end 227.203 -63.251334)
		(width 0.1016)
		(layer "In2.Cu")
		(net "PCIE_RX_N59")
	)
	(segment
		(start 228.6 -61.999876)
		(end 228.100128 -62.499748)
		(width 0.136652)
		(layer "F.Cu")
		(net "PCIE_RX_N58")
	)
	(via
		(at 140.9065 -222.294704)
		(size 0.508)
		(drill 0.254)
		(layers "F.Cu" "B.Cu")
		(net "PCIE_RX_N58")
	)
	(via
		(at 228.100128 -62.499748)
		(size 0.4572)
		(drill 0.2032)
		(layers "F.Cu" "B.Cu")
		(net "PCIE_RX_N58")
	)
	(segment
		(start 140.652754 -224.17278)
		(end 140.652754 -222.907352)
		(width 0.136652)
		(layer "B.Cu")
		(net "PCIE_RX_N58")
	)
	(segment
		(start 140.90015 -225.92538)
		(end 140.90015 -224.770188)
		(width 0.136652)
		(layer "B.Cu")
		(net "PCIE_RX_N58")
	)
	(arc
		(start 140.652754 -222.907352)
		(mid 140.718704 -222.575797)
		(end 140.9065 -222.294704)
		(width 0.136652)
		(layer "B.Cu")
		(net "PCIE_RX_N58")
	)
	(arc
		(start 140.72997 -224.359216)
		(mid 140.672816 -224.273678)
		(end 140.652754 -224.17278)
		(width 0.136652)
		(layer "B.Cu")
		(net "PCIE_RX_N58")
	)
	(arc
		(start 140.90015 -224.770188)
		(mid 140.855912 -224.547791)
		(end 140.72997 -224.359216)
		(width 0.136652)
		(layer "B.Cu")
		(net "PCIE_RX_N58")
	)
	(segment
		(start 140.6652 -220.198442)
		(end 143.35887 -216.351358)
		(width 0.1397)
		(layer "In2.Cu")
		(net "PCIE_RX_N58")
	)
	(segment
		(start 143.8148 -209.423)
		(end 144.13611 -207.60055)
		(width 0.1397)
		(layer "In2.Cu")
		(net "PCIE_RX_N58")
	)
	(segment
		(start 143.8148 -213.7664)
		(end 143.8148 -209.423)
		(width 0.1397)
		(layer "In2.Cu")
		(net "PCIE_RX_N58")
	)
	(segment
		(start 227.78085 -67.1322)
		(end 227.69703 -67.04838)
		(width 0.1016)
		(layer "In2.Cu")
		(net "PCIE_RX_N58")
	)
	(segment
		(start 228.153214 -62.1792)
		(end 228.153214 -62.371478)
		(width 0.1016)
		(layer "In2.Cu")
		(net "PCIE_RX_N58")
	)
	(segment
		(start 227.69703 -67.04838)
		(end 227.69703 -62.302136)
		(width 0.1016)
		(layer "In2.Cu")
		(net "PCIE_RX_N58")
	)
	(segment
		(start 227.958396 -62.035182)
		(end 228.009196 -62.035182)
		(width 0.1016)
		(layer "In2.Cu")
		(net "PCIE_RX_N58")
	)
	(segment
		(start 227.776024 -62.111382)
		(end 227.777294 -62.110366)
		(width 0.1016)
		(layer "In2.Cu")
		(net "PCIE_RX_N58")
	)
	(segment
		(start 228.194108 -79.172054)
		(end 228.863652 -75.376532)
		(width 0.1397)
		(layer "In2.Cu")
		(net "PCIE_RX_N58")
	)
	(segment
		(start 228.597714 -81.46034)
		(end 228.194108 -79.172054)
		(width 0.1397)
		(layer "In2.Cu")
		(net "PCIE_RX_N58")
	)
	(segment
		(start 143.35887 -216.351358)
		(end 143.8148 -213.7664)
		(width 0.1397)
		(layer "In2.Cu")
		(net "PCIE_RX_N58")
	)
	(segment
		(start 227.297234 -88.83523)
		(end 228.597714 -81.46034)
		(width 0.1397)
		(layer "In2.Cu")
		(net "PCIE_RX_N58")
	)
	(segment
		(start 144.13611 -207.60055)
		(end 227.297234 -88.83523)
		(width 0.1397)
		(layer "In2.Cu")
		(net "PCIE_RX_N58")
	)
	(segment
		(start 140.6652 -221.712028)
		(end 140.6652 -220.198442)
		(width 0.1397)
		(layer "In2.Cu")
		(net "PCIE_RX_N58")
	)
	(segment
		(start 227.78085 -69.235574)
		(end 227.78085 -67.1322)
		(width 0.1397)
		(layer "In2.Cu")
		(net "PCIE_RX_N58")
	)
	(segment
		(start 228.863652 -75.376532)
		(end 227.78085 -69.235574)
		(width 0.1397)
		(layer "In2.Cu")
		(net "PCIE_RX_N58")
	)
	(arc
		(start 140.9065 -222.294704)
		(mid 140.727873 -222.02737)
		(end 140.6652 -221.712028)
		(width 0.1397)
		(layer "In2.Cu")
		(net "PCIE_RX_N58")
	)
	(arc
		(start 228.009196 -62.035182)
		(mid 228.111032 -62.077364)
		(end 228.153214 -62.1792)
		(width 0.1016)
		(layer "In2.Cu")
		(net "PCIE_RX_N58")
	)
	(arc
		(start 227.69703 -62.302136)
		(mid 227.717563 -62.198908)
		(end 227.776024 -62.111382)
		(width 0.1016)
		(layer "In2.Cu")
		(net "PCIE_RX_N58")
	)
	(arc
		(start 227.777294 -62.110366)
		(mid 227.860369 -62.054764)
		(end 227.958396 -62.035182)
		(width 0.1016)
		(layer "In2.Cu")
		(net "PCIE_RX_N58")
	)
	(arc
		(start 228.153214 -62.371478)
		(mid 228.139409 -62.44088)
		(end 228.100128 -62.499748)
		(width 0.1016)
		(layer "In2.Cu")
		(net "PCIE_RX_N58")
	)
	(segment
		(start 229.599998 -62.999874)
		(end 229.100126 -63.499746)
		(width 0.136652)
		(layer "F.Cu")
		(net "PCIE_RX_N57")
	)
	(via
		(at 144.106392 -222.294704)
		(size 0.508)
		(drill 0.254)
		(layers "F.Cu" "B.Cu")
		(net "PCIE_RX_N57")
	)
	(via
		(at 229.100126 -63.499746)
		(size 0.4572)
		(drill 0.2032)
		(layers "F.Cu" "B.Cu")
		(net "PCIE_RX_N57")
	)
	(segment
		(start 144.100042 -225.92538)
		(end 144.100042 -224.770188)
		(width 0.136652)
		(layer "B.Cu")
		(net "PCIE_RX_N57")
	)
	(segment
		(start 143.852646 -224.17278)
		(end 143.852646 -222.907352)
		(width 0.136652)
		(layer "B.Cu")
		(net "PCIE_RX_N57")
	)
	(arc
		(start 143.852646 -222.907352)
		(mid 143.918596 -222.575797)
		(end 144.106392 -222.294704)
		(width 0.136652)
		(layer "B.Cu")
		(net "PCIE_RX_N57")
	)
	(arc
		(start 143.929862 -224.359216)
		(mid 143.872708 -224.273678)
		(end 143.852646 -224.17278)
		(width 0.136652)
		(layer "B.Cu")
		(net "PCIE_RX_N57")
	)
	(arc
		(start 144.100042 -224.770188)
		(mid 144.055804 -224.547791)
		(end 143.929862 -224.359216)
		(width 0.136652)
		(layer "B.Cu")
		(net "PCIE_RX_N57")
	)
	(segment
		(start 229.735126 -81.99755)
		(end 229.244144 -79.21244)
		(width 0.1397)
		(layer "In2.Cu")
		(net "PCIE_RX_N57")
	)
	(segment
		(start 229.244144 -79.21244)
		(end 229.890574 -75.546458)
		(width 0.1397)
		(layer "In2.Cu")
		(net "PCIE_RX_N57")
	)
	(segment
		(start 228.697028 -67.076828)
		(end 228.697028 -63.302134)
		(width 0.1016)
		(layer "In2.Cu")
		(net "PCIE_RX_N57")
	)
	(segment
		(start 143.865092 -221.712028)
		(end 143.865092 -219.433902)
		(width 0.1397)
		(layer "In2.Cu")
		(net "PCIE_RX_N57")
	)
	(segment
		(start 147.788884 -204.756512)
		(end 228.384862 -89.65565)
		(width 0.1397)
		(layer "In2.Cu")
		(net "PCIE_RX_N57")
	)
	(segment
		(start 228.7778 -67.1576)
		(end 228.697028 -67.076828)
		(width 0.1016)
		(layer "In2.Cu")
		(net "PCIE_RX_N57")
	)
	(segment
		(start 229.890574 -75.546458)
		(end 228.7778 -69.235574)
		(width 0.1397)
		(layer "In2.Cu")
		(net "PCIE_RX_N57")
	)
	(segment
		(start 229.153212 -63.179198)
		(end 229.153212 -63.371476)
		(width 0.1016)
		(layer "In2.Cu")
		(net "PCIE_RX_N57")
	)
	(segment
		(start 228.7778 -69.235574)
		(end 228.7778 -67.1576)
		(width 0.1397)
		(layer "In2.Cu")
		(net "PCIE_RX_N57")
	)
	(segment
		(start 147.0406 -213.4362)
		(end 147.0406 -208.999836)
		(width 0.1397)
		(layer "In2.Cu")
		(net "PCIE_RX_N57")
	)
	(segment
		(start 228.958394 -63.03518)
		(end 229.009194 -63.03518)
		(width 0.1016)
		(layer "In2.Cu")
		(net "PCIE_RX_N57")
	)
	(segment
		(start 229.735126 -81.997804)
		(end 229.735126 -81.99755)
		(width 0.1397)
		(layer "In2.Cu")
		(net "PCIE_RX_N57")
	)
	(segment
		(start 147.0406 -208.999836)
		(end 147.788884 -204.756512)
		(width 0.1397)
		(layer "In2.Cu")
		(net "PCIE_RX_N57")
	)
	(segment
		(start 228.384862 -89.65565)
		(end 229.735126 -81.997804)
		(width 0.1397)
		(layer "In2.Cu")
		(net "PCIE_RX_N57")
	)
	(segment
		(start 146.695922 -215.390984)
		(end 147.0406 -213.4362)
		(width 0.1397)
		(layer "In2.Cu")
		(net "PCIE_RX_N57")
	)
	(segment
		(start 228.776022 -63.11138)
		(end 228.777292 -63.110364)
		(width 0.1016)
		(layer "In2.Cu")
		(net "PCIE_RX_N57")
	)
	(segment
		(start 143.865092 -219.433902)
		(end 146.695922 -215.390984)
		(width 0.1397)
		(layer "In2.Cu")
		(net "PCIE_RX_N57")
	)
	(arc
		(start 228.697028 -63.302134)
		(mid 228.717561 -63.198906)
		(end 228.776022 -63.11138)
		(width 0.1016)
		(layer "In2.Cu")
		(net "PCIE_RX_N57")
	)
	(arc
		(start 229.009194 -63.03518)
		(mid 229.11103 -63.077362)
		(end 229.153212 -63.179198)
		(width 0.1016)
		(layer "In2.Cu")
		(net "PCIE_RX_N57")
	)
	(arc
		(start 229.153212 -63.371476)
		(mid 229.139407 -63.440878)
		(end 229.100126 -63.499746)
		(width 0.1016)
		(layer "In2.Cu")
		(net "PCIE_RX_N57")
	)
	(arc
		(start 144.106392 -222.294704)
		(mid 143.927765 -222.02737)
		(end 143.865092 -221.712028)
		(width 0.1397)
		(layer "In2.Cu")
		(net "PCIE_RX_N57")
	)
	(arc
		(start 228.777292 -63.110364)
		(mid 228.860367 -63.054762)
		(end 228.958394 -63.03518)
		(width 0.1016)
		(layer "In2.Cu")
		(net "PCIE_RX_N57")
	)
	(segment
		(start 230.599996 -61.999876)
		(end 230.100124 -62.499748)
		(width 0.136652)
		(layer "F.Cu")
		(net "PCIE_RX_N56")
	)
	(via
		(at 230.100124 -62.499748)
		(size 0.4572)
		(drill 0.2032)
		(layers "F.Cu" "B.Cu")
		(net "PCIE_RX_N56")
	)
	(via
		(at 147.306538 -222.294704)
		(size 0.508)
		(drill 0.254)
		(layers "F.Cu" "B.Cu")
		(net "PCIE_RX_N56")
	)
	(segment
		(start 147.300188 -225.92538)
		(end 147.300188 -224.770188)
		(width 0.136652)
		(layer "B.Cu")
		(net "PCIE_RX_N56")
	)
	(segment
		(start 147.052792 -224.17278)
		(end 147.052792 -222.907352)
		(width 0.136652)
		(layer "B.Cu")
		(net "PCIE_RX_N56")
	)
	(arc
		(start 147.130008 -224.359216)
		(mid 147.072854 -224.273678)
		(end 147.052792 -224.17278)
		(width 0.136652)
		(layer "B.Cu")
		(net "PCIE_RX_N56")
	)
	(arc
		(start 147.052792 -222.907352)
		(mid 147.118742 -222.575797)
		(end 147.306538 -222.294704)
		(width 0.136652)
		(layer "B.Cu")
		(net "PCIE_RX_N56")
	)
	(arc
		(start 147.300188 -224.770188)
		(mid 147.25595 -224.547791)
		(end 147.130008 -224.359216)
		(width 0.136652)
		(layer "B.Cu")
		(net "PCIE_RX_N56")
	)
	(segment
		(start 230.873808 -75.505056)
		(end 229.7684 -69.235574)
		(width 0.1397)
		(layer "In2.Cu")
		(net "PCIE_RX_N56")
	)
	(segment
		(start 229.7684 -69.235574)
		(end 229.7684 -67.1576)
		(width 0.1397)
		(layer "In2.Cu")
		(net "PCIE_RX_N56")
	)
	(segment
		(start 229.77602 -62.111382)
		(end 229.77729 -62.110366)
		(width 0.1016)
		(layer "In2.Cu")
		(net "PCIE_RX_N56")
	)
	(segment
		(start 230.83647 -96.634808)
		(end 232.349548 -88.054942)
		(width 0.1397)
		(layer "In2.Cu")
		(net "PCIE_RX_N56")
	)
	(segment
		(start 229.958392 -62.035182)
		(end 230.030782 -62.035182)
		(width 0.1016)
		(layer "In2.Cu")
		(net "PCIE_RX_N56")
	)
	(segment
		(start 229.697026 -67.086226)
		(end 229.697026 -62.302136)
		(width 0.1016)
		(layer "In2.Cu")
		(net "PCIE_RX_N56")
	)
	(segment
		(start 230.202994 -62.195202)
		(end 230.202994 -62.251336)
		(width 0.1016)
		(layer "In2.Cu")
		(net "PCIE_RX_N56")
	)
	(segment
		(start 147.065238 -221.712028)
		(end 147.065238 -219.438728)
		(width 0.1397)
		(layer "In2.Cu")
		(net "PCIE_RX_N56")
	)
	(segment
		(start 147.065238 -219.438728)
		(end 149.998938 -215.248998)
		(width 0.1397)
		(layer "In2.Cu")
		(net "PCIE_RX_N56")
	)
	(segment
		(start 149.998938 -215.248998)
		(end 150.2918 -213.5886)
		(width 0.1397)
		(layer "In2.Cu")
		(net "PCIE_RX_N56")
	)
	(segment
		(start 150.2918 -213.5886)
		(end 150.2918 -206.45247)
		(width 0.1397)
		(layer "In2.Cu")
		(net "PCIE_RX_N56")
	)
	(segment
		(start 158.451042 -192.860676)
		(end 168.275 -185.982102)
		(width 0.1397)
		(layer "In2.Cu")
		(net "PCIE_RX_N56")
	)
	(segment
		(start 150.749 -203.8604)
		(end 158.451042 -192.860676)
		(width 0.1397)
		(layer "In2.Cu")
		(net "PCIE_RX_N56")
	)
	(segment
		(start 147.064984 -221.712028)
		(end 147.065238 -221.712028)
		(width 0.1397)
		(layer "In2.Cu")
		(net "PCIE_RX_N56")
	)
	(segment
		(start 229.7684 -67.1576)
		(end 229.697026 -67.086226)
		(width 0.1016)
		(layer "In2.Cu")
		(net "PCIE_RX_N56")
	)
	(segment
		(start 232.349548 -88.054942)
		(end 230.505 -77.597)
		(width 0.1397)
		(layer "In2.Cu")
		(net "PCIE_RX_N56")
	)
	(segment
		(start 230.505 -77.597)
		(end 230.873808 -75.505056)
		(width 0.1397)
		(layer "In2.Cu")
		(net "PCIE_RX_N56")
	)
	(segment
		(start 150.2918 -206.45247)
		(end 150.749 -203.8604)
		(width 0.1397)
		(layer "In2.Cu")
		(net "PCIE_RX_N56")
	)
	(segment
		(start 168.275 -185.982102)
		(end 230.83647 -96.634808)
		(width 0.1397)
		(layer "In2.Cu")
		(net "PCIE_RX_N56")
	)
	(arc
		(start 229.77729 -62.110366)
		(mid 229.860365 -62.054764)
		(end 229.958392 -62.035182)
		(width 0.1016)
		(layer "In2.Cu")
		(net "PCIE_RX_N56")
	)
	(arc
		(start 230.030782 -62.035182)
		(mid 230.102808 -62.049509)
		(end 230.163878 -62.0903)
		(width 0.1016)
		(layer "In2.Cu")
		(net "PCIE_RX_N56")
	)
	(arc
		(start 229.697026 -62.302136)
		(mid 229.717559 -62.198908)
		(end 229.77602 -62.111382)
		(width 0.1016)
		(layer "In2.Cu")
		(net "PCIE_RX_N56")
	)
	(arc
		(start 230.163878 -62.0903)
		(mid 230.192888 -62.139225)
		(end 230.202994 -62.195202)
		(width 0.1016)
		(layer "In2.Cu")
		(net "PCIE_RX_N56")
	)
	(arc
		(start 230.202994 -62.251336)
		(mid 230.176254 -62.385766)
		(end 230.100124 -62.499748)
		(width 0.1016)
		(layer "In2.Cu")
		(net "PCIE_RX_N56")
	)
	(arc
		(start 147.306538 -222.294704)
		(mid 147.127774 -222.027399)
		(end 147.064984 -221.712028)
		(width 0.1397)
		(layer "In2.Cu")
		(net "PCIE_RX_N56")
	)
	(segment
		(start 232.599992 -62.999874)
		(end 232.10012 -63.499746)
		(width 0.136652)
		(layer "F.Cu")
		(net "PCIE_RX_N55")
	)
	(via
		(at 150.50643 -222.294704)
		(size 0.508)
		(drill 0.254)
		(layers "F.Cu" "B.Cu")
		(net "PCIE_RX_N55")
	)
	(via
		(at 232.10012 -63.499746)
		(size 0.4572)
		(drill 0.2032)
		(layers "F.Cu" "B.Cu")
		(net "PCIE_RX_N55")
	)
	(segment
		(start 150.252684 -224.17278)
		(end 150.252684 -222.907352)
		(width 0.136652)
		(layer "B.Cu")
		(net "PCIE_RX_N55")
	)
	(segment
		(start 150.50008 -225.92538)
		(end 150.50008 -224.770188)
		(width 0.136652)
		(layer "B.Cu")
		(net "PCIE_RX_N55")
	)
	(arc
		(start 150.50008 -224.770188)
		(mid 150.455842 -224.547791)
		(end 150.3299 -224.359216)
		(width 0.136652)
		(layer "B.Cu")
		(net "PCIE_RX_N55")
	)
	(arc
		(start 150.3299 -224.359216)
		(mid 150.272746 -224.273678)
		(end 150.252684 -224.17278)
		(width 0.136652)
		(layer "B.Cu")
		(net "PCIE_RX_N55")
	)
	(arc
		(start 150.252684 -222.907352)
		(mid 150.318634 -222.575797)
		(end 150.50643 -222.294704)
		(width 0.136652)
		(layer "B.Cu")
		(net "PCIE_RX_N55")
	)
	(segment
		(start 231.7496 -67.2846)
		(end 231.697022 -67.232022)
		(width 0.1016)
		(layer "In2.Cu")
		(net "PCIE_RX_N55")
	)
	(segment
		(start 231.697022 -67.232022)
		(end 231.697022 -63.30188)
		(width 0.1016)
		(layer "In2.Cu")
		(net "PCIE_RX_N55")
	)
	(segment
		(start 231.7496 -69.235574)
		(end 231.7496 -67.2846)
		(width 0.1397)
		(layer "In2.Cu")
		(net "PCIE_RX_N55")
	)
	(segment
		(start 232.413556 -74.40168)
		(end 231.626156 -69.935852)
		(width 0.1397)
		(layer "In2.Cu")
		(net "PCIE_RX_N55")
	)
	(segment
		(start 153.492454 -209.636614)
		(end 231.57561 -98.122232)
		(width 0.1397)
		(layer "In2.Cu")
		(net "PCIE_RX_N55")
	)
	(segment
		(start 233.488738 -87.272114)
		(end 231.816656 -77.7875)
		(width 0.1397)
		(layer "In2.Cu")
		(net "PCIE_RX_N55")
	)
	(segment
		(start 153.042874 -216.18956)
		(end 153.492454 -213.6394)
		(width 0.1397)
		(layer "In2.Cu")
		(net "PCIE_RX_N55")
	)
	(segment
		(start 231.776016 -63.11138)
		(end 231.777286 -63.110364)
		(width 0.1016)
		(layer "In2.Cu")
		(net "PCIE_RX_N55")
	)
	(segment
		(start 231.816656 -77.7875)
		(end 232.413556 -74.40168)
		(width 0.1397)
		(layer "In2.Cu")
		(net "PCIE_RX_N55")
	)
	(segment
		(start 232.131362 -63.091314)
		(end 232.140252 -63.09995)
		(width 0.1016)
		(layer "In2.Cu")
		(net "PCIE_RX_N55")
	)
	(segment
		(start 153.492454 -213.6394)
		(end 153.492454 -209.636614)
		(width 0.1397)
		(layer "In2.Cu")
		(net "PCIE_RX_N55")
	)
	(segment
		(start 231.958388 -63.03518)
		(end 231.996234 -63.03518)
		(width 0.1016)
		(layer "In2.Cu")
		(net "PCIE_RX_N55")
	)
	(segment
		(start 231.57561 -98.122232)
		(end 233.488738 -87.272114)
		(width 0.1397)
		(layer "In2.Cu")
		(net "PCIE_RX_N55")
	)
	(segment
		(start 150.26513 -220.156786)
		(end 153.042874 -216.18956)
		(width 0.1397)
		(layer "In2.Cu")
		(net "PCIE_RX_N55")
	)
	(segment
		(start 150.26513 -221.712028)
		(end 150.26513 -220.156786)
		(width 0.1397)
		(layer "In2.Cu")
		(net "PCIE_RX_N55")
	)
	(segment
		(start 231.626156 -69.935852)
		(end 231.7496 -69.235574)
		(width 0.1397)
		(layer "In2.Cu")
		(net "PCIE_RX_N55")
	)
	(arc
		(start 231.697022 -63.30188)
		(mid 231.704267 -63.240035)
		(end 231.72547 -63.181484)
		(width 0.1016)
		(layer "In2.Cu")
		(net "PCIE_RX_N55")
	)
	(arc
		(start 231.777286 -63.110364)
		(mid 231.860361 -63.054762)
		(end 231.958388 -63.03518)
		(width 0.1016)
		(layer "In2.Cu")
		(net "PCIE_RX_N55")
	)
	(arc
		(start 150.50643 -222.294704)
		(mid 150.327803 -222.02737)
		(end 150.26513 -221.712028)
		(width 0.1397)
		(layer "In2.Cu")
		(net "PCIE_RX_N55")
	)
	(arc
		(start 231.72547 -63.181484)
		(mid 231.747912 -63.14439)
		(end 231.776016 -63.11138)
		(width 0.1016)
		(layer "In2.Cu")
		(net "PCIE_RX_N55")
	)
	(arc
		(start 232.20299 -63.251334)
		(mid 232.17625 -63.385764)
		(end 232.10012 -63.499746)
		(width 0.1016)
		(layer "In2.Cu")
		(net "PCIE_RX_N55")
	)
	(arc
		(start 231.996234 -63.03518)
		(mid 232.069373 -63.049822)
		(end 232.131362 -63.091314)
		(width 0.1016)
		(layer "In2.Cu")
		(net "PCIE_RX_N55")
	)
	(arc
		(start 232.140252 -63.09995)
		(mid 232.186661 -63.169406)
		(end 232.20299 -63.251334)
		(width 0.1016)
		(layer "In2.Cu")
		(net "PCIE_RX_N55")
	)
	(segment
		(start 233.59999 -61.999876)
		(end 233.100118 -62.499748)
		(width 0.136652)
		(layer "F.Cu")
		(net "PCIE_RX_N54")
	)
	(via
		(at 233.100118 -62.499748)
		(size 0.4572)
		(drill 0.2032)
		(layers "F.Cu" "B.Cu")
		(net "PCIE_RX_N54")
	)
	(via
		(at 153.706576 -222.294704)
		(size 0.508)
		(drill 0.254)
		(layers "F.Cu" "B.Cu")
		(net "PCIE_RX_N54")
	)
	(segment
		(start 153.45283 -224.17278)
		(end 153.45283 -222.907352)
		(width 0.136652)
		(layer "B.Cu")
		(net "PCIE_RX_N54")
	)
	(segment
		(start 153.700226 -225.92538)
		(end 153.700226 -224.770188)
		(width 0.136652)
		(layer "B.Cu")
		(net "PCIE_RX_N54")
	)
	(arc
		(start 153.45283 -222.907352)
		(mid 153.51878 -222.575797)
		(end 153.706576 -222.294704)
		(width 0.136652)
		(layer "B.Cu")
		(net "PCIE_RX_N54")
	)
	(arc
		(start 153.700226 -224.770188)
		(mid 153.655988 -224.547791)
		(end 153.530046 -224.359216)
		(width 0.136652)
		(layer "B.Cu")
		(net "PCIE_RX_N54")
	)
	(arc
		(start 153.530046 -224.359216)
		(mid 153.472892 -224.273678)
		(end 153.45283 -224.17278)
		(width 0.136652)
		(layer "B.Cu")
		(net "PCIE_RX_N54")
	)
	(segment
		(start 159.8422 -209.031078)
		(end 165.331394 -201.191622)
		(width 0.1397)
		(layer "In2.Cu")
		(net "PCIE_RX_N54")
	)
	(segment
		(start 154.04338 -219.48902)
		(end 158.903162 -216.086182)
		(width 0.1397)
		(layer "In2.Cu")
		(net "PCIE_RX_N54")
	)
	(segment
		(start 153.465276 -220.31452)
		(end 154.04338 -219.48902)
		(width 0.1397)
		(layer "In2.Cu")
		(net "PCIE_RX_N54")
	)
	(segment
		(start 232.958386 -62.035182)
		(end 232.996232 -62.035182)
		(width 0.1016)
		(layer "In2.Cu")
		(net "PCIE_RX_N54")
	)
	(segment
		(start 232.7656 -69.235574)
		(end 232.7656 -67.2338)
		(width 0.1397)
		(layer "In2.Cu")
		(net "PCIE_RX_N54")
	)
	(segment
		(start 233.37266 -74.730102)
		(end 232.584752 -70.261734)
		(width 0.1397)
		(layer "In2.Cu")
		(net "PCIE_RX_N54")
	)
	(segment
		(start 232.69702 -67.16522)
		(end 232.69702 -62.301882)
		(width 0.1016)
		(layer "In2.Cu")
		(net "PCIE_RX_N54")
	)
	(segment
		(start 159.515556 -215.21166)
		(end 159.8422 -213.36)
		(width 0.1397)
		(layer "In2.Cu")
		(net "PCIE_RX_N54")
	)
	(segment
		(start 165.331394 -201.191622)
		(end 166.810944 -192.800986)
		(width 0.1397)
		(layer "In2.Cu")
		(net "PCIE_RX_N54")
	)
	(segment
		(start 232.776014 -62.111382)
		(end 232.777284 -62.110366)
		(width 0.1016)
		(layer "In2.Cu")
		(net "PCIE_RX_N54")
	)
	(segment
		(start 232.584752 -70.261734)
		(end 232.7656 -69.235574)
		(width 0.1397)
		(layer "In2.Cu")
		(net "PCIE_RX_N54")
	)
	(segment
		(start 153.465276 -221.712028)
		(end 153.465276 -220.31452)
		(width 0.1397)
		(layer "In2.Cu")
		(net "PCIE_RX_N54")
	)
	(segment
		(start 166.810944 -192.800986)
		(end 232.458768 -99.04603)
		(width 0.1397)
		(layer "In2.Cu")
		(net "PCIE_RX_N54")
	)
	(segment
		(start 232.853484 -77.675232)
		(end 233.37266 -74.730102)
		(width 0.1397)
		(layer "In2.Cu")
		(net "PCIE_RX_N54")
	)
	(segment
		(start 232.7656 -67.2338)
		(end 232.69702 -67.16522)
		(width 0.1016)
		(layer "In2.Cu")
		(net "PCIE_RX_N54")
	)
	(segment
		(start 232.458768 -99.04603)
		(end 234.540298 -87.241634)
		(width 0.1397)
		(layer "In2.Cu")
		(net "PCIE_RX_N54")
	)
	(segment
		(start 233.13136 -62.091316)
		(end 233.14025 -62.099952)
		(width 0.1016)
		(layer "In2.Cu")
		(net "PCIE_RX_N54")
	)
	(segment
		(start 234.540298 -87.241634)
		(end 232.853484 -77.675232)
		(width 0.1397)
		(layer "In2.Cu")
		(net "PCIE_RX_N54")
	)
	(segment
		(start 159.8422 -213.36)
		(end 159.8422 -209.031078)
		(width 0.1397)
		(layer "In2.Cu")
		(net "PCIE_RX_N54")
	)
	(segment
		(start 158.903162 -216.086182)
		(end 159.515556 -215.21166)
		(width 0.1397)
		(layer "In2.Cu")
		(net "PCIE_RX_N54")
	)
	(arc
		(start 232.725468 -62.181486)
		(mid 232.74791 -62.144392)
		(end 232.776014 -62.111382)
		(width 0.1016)
		(layer "In2.Cu")
		(net "PCIE_RX_N54")
	)
	(arc
		(start 232.69702 -62.301882)
		(mid 232.704265 -62.240037)
		(end 232.725468 -62.181486)
		(width 0.1016)
		(layer "In2.Cu")
		(net "PCIE_RX_N54")
	)
	(arc
		(start 232.996232 -62.035182)
		(mid 233.069371 -62.049824)
		(end 233.13136 -62.091316)
		(width 0.1016)
		(layer "In2.Cu")
		(net "PCIE_RX_N54")
	)
	(arc
		(start 233.14025 -62.099952)
		(mid 233.186659 -62.169408)
		(end 233.202988 -62.251336)
		(width 0.1016)
		(layer "In2.Cu")
		(net "PCIE_RX_N54")
	)
	(arc
		(start 153.706576 -222.294704)
		(mid 153.527949 -222.02737)
		(end 153.465276 -221.712028)
		(width 0.1397)
		(layer "In2.Cu")
		(net "PCIE_RX_N54")
	)
	(arc
		(start 233.202988 -62.251336)
		(mid 233.176248 -62.385766)
		(end 233.100118 -62.499748)
		(width 0.1016)
		(layer "In2.Cu")
		(net "PCIE_RX_N54")
	)
	(arc
		(start 232.777284 -62.110366)
		(mid 232.860359 -62.054764)
		(end 232.958386 -62.035182)
		(width 0.1016)
		(layer "In2.Cu")
		(net "PCIE_RX_N54")
	)
	(segment
		(start 234.599988 -62.999874)
		(end 234.100116 -63.499746)
		(width 0.136652)
		(layer "F.Cu")
		(net "PCIE_RX_N53")
	)
	(via
		(at 234.100116 -63.499746)
		(size 0.4572)
		(drill 0.2032)
		(layers "F.Cu" "B.Cu")
		(net "PCIE_RX_N53")
	)
	(via
		(at 156.906468 -222.294704)
		(size 0.508)
		(drill 0.254)
		(layers "F.Cu" "B.Cu")
		(net "PCIE_RX_N53")
	)
	(segment
		(start 156.693108 -222.508064)
		(end 156.906468 -222.294704)
		(width 0.136652)
		(layer "B.Cu")
		(net "PCIE_RX_N53")
	)
	(segment
		(start 156.900118 -225.92538)
		(end 156.900118 -224.770188)
		(width 0.136652)
		(layer "B.Cu")
		(net "PCIE_RX_N53")
	)
	(segment
		(start 156.652722 -224.17278)
		(end 156.652722 -222.6056)
		(width 0.136652)
		(layer "B.Cu")
		(net "PCIE_RX_N53")
	)
	(arc
		(start 156.900118 -224.770188)
		(mid 156.85588 -224.547791)
		(end 156.729938 -224.359216)
		(width 0.136652)
		(layer "B.Cu")
		(net "PCIE_RX_N53")
	)
	(arc
		(start 156.729938 -224.359216)
		(mid 156.672784 -224.273678)
		(end 156.652722 -224.17278)
		(width 0.136652)
		(layer "B.Cu")
		(net "PCIE_RX_N53")
	)
	(arc
		(start 156.652722 -222.6056)
		(mid 156.663221 -222.55282)
		(end 156.693108 -222.508064)
		(width 0.136652)
		(layer "B.Cu")
		(net "PCIE_RX_N53")
	)
	(segment
		(start 233.7308 -69.235574)
		(end 233.7308 -67.2338)
		(width 0.1397)
		(layer "In2.Cu")
		(net "PCIE_RX_N53")
	)
	(segment
		(start 156.665168 -220.627194)
		(end 157.433264 -219.530422)
		(width 0.1397)
		(layer "In2.Cu")
		(net "PCIE_RX_N53")
	)
	(segment
		(start 233.776012 -63.11138)
		(end 233.777282 -63.110364)
		(width 0.1016)
		(layer "In2.Cu")
		(net "PCIE_RX_N53")
	)
	(segment
		(start 157.433264 -219.530422)
		(end 161.7472 -216.5096)
		(width 0.1397)
		(layer "In2.Cu")
		(net "PCIE_RX_N53")
	)
	(segment
		(start 156.665168 -221.712028)
		(end 156.665168 -220.627194)
		(width 0.1397)
		(layer "In2.Cu")
		(net "PCIE_RX_N53")
	)
	(segment
		(start 233.839766 -77.625194)
		(end 234.315 -74.93)
		(width 0.1397)
		(layer "In2.Cu")
		(net "PCIE_RX_N53")
	)
	(segment
		(start 235.557314 -87.36584)
		(end 233.839766 -77.625194)
		(width 0.1397)
		(layer "In2.Cu")
		(net "PCIE_RX_N53")
	)
	(segment
		(start 164.397944 -212.723984)
		(end 166.020496 -203.522834)
		(width 0.1397)
		(layer "In2.Cu")
		(net "PCIE_RX_N53")
	)
	(segment
		(start 233.520996 -70.427088)
		(end 233.7308 -69.235574)
		(width 0.1397)
		(layer "In2.Cu")
		(net "PCIE_RX_N53")
	)
	(segment
		(start 166.020496 -203.522834)
		(end 231.586532 -109.884464)
		(width 0.1397)
		(layer "In2.Cu")
		(net "PCIE_RX_N53")
	)
	(segment
		(start 161.7472 -216.5096)
		(end 164.397944 -212.723984)
		(width 0.1397)
		(layer "In2.Cu")
		(net "PCIE_RX_N53")
	)
	(segment
		(start 231.586532 -109.884464)
		(end 235.557314 -87.36584)
		(width 0.1397)
		(layer "In2.Cu")
		(net "PCIE_RX_N53")
	)
	(segment
		(start 233.697018 -67.200018)
		(end 233.697018 -63.30188)
		(width 0.1016)
		(layer "In2.Cu")
		(net "PCIE_RX_N53")
	)
	(segment
		(start 234.315 -74.93)
		(end 233.520996 -70.427088)
		(width 0.1397)
		(layer "In2.Cu")
		(net "PCIE_RX_N53")
	)
	(segment
		(start 233.7308 -67.2338)
		(end 233.697018 -67.200018)
		(width 0.1016)
		(layer "In2.Cu")
		(net "PCIE_RX_N53")
	)
	(segment
		(start 234.131358 -63.091314)
		(end 234.140248 -63.09995)
		(width 0.1016)
		(layer "In2.Cu")
		(net "PCIE_RX_N53")
	)
	(segment
		(start 233.958384 -63.03518)
		(end 233.99623 -63.03518)
		(width 0.1016)
		(layer "In2.Cu")
		(net "PCIE_RX_N53")
	)
	(arc
		(start 234.202986 -63.251334)
		(mid 234.176246 -63.385764)
		(end 234.100116 -63.499746)
		(width 0.1016)
		(layer "In2.Cu")
		(net "PCIE_RX_N53")
	)
	(arc
		(start 156.906468 -222.294704)
		(mid 156.727841 -222.02737)
		(end 156.665168 -221.712028)
		(width 0.1397)
		(layer "In2.Cu")
		(net "PCIE_RX_N53")
	)
	(arc
		(start 233.99623 -63.03518)
		(mid 234.069369 -63.049822)
		(end 234.131358 -63.091314)
		(width 0.1016)
		(layer "In2.Cu")
		(net "PCIE_RX_N53")
	)
	(arc
		(start 234.140248 -63.09995)
		(mid 234.186657 -63.169406)
		(end 234.202986 -63.251334)
		(width 0.1016)
		(layer "In2.Cu")
		(net "PCIE_RX_N53")
	)
	(arc
		(start 233.697018 -63.30188)
		(mid 233.704263 -63.240035)
		(end 233.725466 -63.181484)
		(width 0.1016)
		(layer "In2.Cu")
		(net "PCIE_RX_N53")
	)
	(arc
		(start 233.725466 -63.181484)
		(mid 233.747908 -63.14439)
		(end 233.776012 -63.11138)
		(width 0.1016)
		(layer "In2.Cu")
		(net "PCIE_RX_N53")
	)
	(arc
		(start 233.777282 -63.110364)
		(mid 233.860357 -63.054762)
		(end 233.958384 -63.03518)
		(width 0.1016)
		(layer "In2.Cu")
		(net "PCIE_RX_N53")
	)
	(segment
		(start 235.599986 -61.999876)
		(end 235.100114 -62.499748)
		(width 0.136652)
		(layer "F.Cu")
		(net "PCIE_RX_N52")
	)
	(via
		(at 160.10636 -222.294704)
		(size 0.508)
		(drill 0.254)
		(layers "F.Cu" "B.Cu")
		(net "PCIE_RX_N52")
	)
	(via
		(at 235.100114 -62.499748)
		(size 0.4572)
		(drill 0.2032)
		(layers "F.Cu" "B.Cu")
		(net "PCIE_RX_N52")
	)
	(segment
		(start 159.852614 -224.17278)
		(end 159.852614 -222.907352)
		(width 0.136652)
		(layer "B.Cu")
		(net "PCIE_RX_N52")
	)
	(segment
		(start 160.10001 -225.92538)
		(end 160.10001 -224.770188)
		(width 0.136652)
		(layer "B.Cu")
		(net "PCIE_RX_N52")
	)
	(arc
		(start 159.92983 -224.359216)
		(mid 159.872676 -224.273678)
		(end 159.852614 -224.17278)
		(width 0.136652)
		(layer "B.Cu")
		(net "PCIE_RX_N52")
	)
	(arc
		(start 160.10001 -224.770188)
		(mid 160.055772 -224.547791)
		(end 159.92983 -224.359216)
		(width 0.136652)
		(layer "B.Cu")
		(net "PCIE_RX_N52")
	)
	(arc
		(start 159.852614 -222.907352)
		(mid 159.918564 -222.575797)
		(end 160.10636 -222.294704)
		(width 0.136652)
		(layer "B.Cu")
		(net "PCIE_RX_N52")
	)
	(segment
		(start 160.274 -219.5576)
		(end 161.466784 -218.722194)
		(width 0.1397)
		(layer "In2.Cu")
		(net "PCIE_RX_N52")
	)
	(segment
		(start 159.86506 -221.712028)
		(end 159.86506 -220.141546)
		(width 0.1397)
		(layer "In2.Cu")
		(net "PCIE_RX_N52")
	)
	(segment
		(start 234.938316 -77.94752)
		(end 235.37418 -75.475084)
		(width 0.1397)
		(layer "In2.Cu")
		(net "PCIE_RX_N52")
	)
	(segment
		(start 164.248338 -218.23172)
		(end 164.57168 -218.005152)
		(width 0.1397)
		(layer "In2.Cu")
		(net "PCIE_RX_N52")
	)
	(segment
		(start 234.7722 -69.235574)
		(end 234.7722 -67.2338)
		(width 0.1397)
		(layer "In2.Cu")
		(net "PCIE_RX_N52")
	)
	(segment
		(start 164.57168 -218.005152)
		(end 167.14089 -216.20607)
		(width 0.1397)
		(layer "In2.Cu")
		(net "PCIE_RX_N52")
	)
	(segment
		(start 168.415716 -214.385652)
		(end 168.91 -211.582)
		(width 0.1397)
		(layer "In2.Cu")
		(net "PCIE_RX_N52")
	)
	(segment
		(start 168.630092 -209.9945)
		(end 170.288204 -200.59142)
		(width 0.1397)
		(layer "In2.Cu")
		(net "PCIE_RX_N52")
	)
	(segment
		(start 167.14089 -216.20607)
		(end 168.415716 -214.385652)
		(width 0.1397)
		(layer "In2.Cu")
		(net "PCIE_RX_N52")
	)
	(segment
		(start 234.523026 -70.648576)
		(end 234.7722 -69.235574)
		(width 0.1397)
		(layer "In2.Cu")
		(net "PCIE_RX_N52")
	)
	(segment
		(start 235.131356 -62.091316)
		(end 235.140246 -62.099952)
		(width 0.1016)
		(layer "In2.Cu")
		(net "PCIE_RX_N52")
	)
	(segment
		(start 234.77601 -62.111382)
		(end 234.77728 -62.110366)
		(width 0.1016)
		(layer "In2.Cu")
		(net "PCIE_RX_N52")
	)
	(segment
		(start 235.37418 -75.475084)
		(end 234.523026 -70.648576)
		(width 0.1397)
		(layer "In2.Cu")
		(net "PCIE_RX_N52")
	)
	(segment
		(start 234.7722 -67.2338)
		(end 234.697016 -67.158616)
		(width 0.1016)
		(layer "In2.Cu")
		(net "PCIE_RX_N52")
	)
	(segment
		(start 170.288204 -200.59142)
		(end 232.366058 -111.935768)
		(width 0.1397)
		(layer "In2.Cu")
		(net "PCIE_RX_N52")
	)
	(segment
		(start 234.697016 -67.158616)
		(end 234.697016 -62.301882)
		(width 0.1016)
		(layer "In2.Cu")
		(net "PCIE_RX_N52")
	)
	(segment
		(start 236.648752 -87.648288)
		(end 234.938316 -77.94752)
		(width 0.1397)
		(layer "In2.Cu")
		(net "PCIE_RX_N52")
	)
	(segment
		(start 161.466784 -218.722194)
		(end 164.248338 -218.23172)
		(width 0.1397)
		(layer "In2.Cu")
		(net "PCIE_RX_N52")
	)
	(segment
		(start 234.958382 -62.035182)
		(end 234.996228 -62.035182)
		(width 0.1016)
		(layer "In2.Cu")
		(net "PCIE_RX_N52")
	)
	(segment
		(start 159.86506 -220.141546)
		(end 160.274 -219.5576)
		(width 0.1397)
		(layer "In2.Cu")
		(net "PCIE_RX_N52")
	)
	(segment
		(start 168.91 -211.582)
		(end 168.630092 -209.9945)
		(width 0.1397)
		(layer "In2.Cu")
		(net "PCIE_RX_N52")
	)
	(segment
		(start 232.366058 -111.935768)
		(end 236.648752 -87.648288)
		(width 0.1397)
		(layer "In2.Cu")
		(net "PCIE_RX_N52")
	)
	(arc
		(start 235.140246 -62.099952)
		(mid 235.186655 -62.169408)
		(end 235.202984 -62.251336)
		(width 0.1016)
		(layer "In2.Cu")
		(net "PCIE_RX_N52")
	)
	(arc
		(start 234.996228 -62.035182)
		(mid 235.069367 -62.049824)
		(end 235.131356 -62.091316)
		(width 0.1016)
		(layer "In2.Cu")
		(net "PCIE_RX_N52")
	)
	(arc
		(start 160.10636 -222.294704)
		(mid 159.927733 -222.02737)
		(end 159.86506 -221.712028)
		(width 0.1397)
		(layer "In2.Cu")
		(net "PCIE_RX_N52")
	)
	(arc
		(start 234.725464 -62.181486)
		(mid 234.747906 -62.144392)
		(end 234.77601 -62.111382)
		(width 0.1016)
		(layer "In2.Cu")
		(net "PCIE_RX_N52")
	)
	(arc
		(start 235.202984 -62.251336)
		(mid 235.176244 -62.385766)
		(end 235.100114 -62.499748)
		(width 0.1016)
		(layer "In2.Cu")
		(net "PCIE_RX_N52")
	)
	(arc
		(start 234.77728 -62.110366)
		(mid 234.860355 -62.054764)
		(end 234.958382 -62.035182)
		(width 0.1016)
		(layer "In2.Cu")
		(net "PCIE_RX_N52")
	)
	(arc
		(start 234.697016 -62.301882)
		(mid 234.704261 -62.240037)
		(end 234.725464 -62.181486)
		(width 0.1016)
		(layer "In2.Cu")
		(net "PCIE_RX_N52")
	)
	(segment
		(start 236.599984 -62.999874)
		(end 236.100112 -63.499746)
		(width 0.136652)
		(layer "F.Cu")
		(net "PCIE_RX_N51")
	)
	(via
		(at 236.100112 -63.499746)
		(size 0.4572)
		(drill 0.2032)
		(layers "F.Cu" "B.Cu")
		(net "PCIE_RX_N51")
	)
	(via
		(at 165.706552 -222.294704)
		(size 0.508)
		(drill 0.254)
		(layers "F.Cu" "B.Cu")
		(net "PCIE_RX_N51")
	)
	(segment
		(start 165.452806 -224.17278)
		(end 165.452806 -222.907352)
		(width 0.136652)
		(layer "B.Cu")
		(net "PCIE_RX_N51")
	)
	(segment
		(start 165.700202 -225.92538)
		(end 165.700202 -224.770188)
		(width 0.136652)
		(layer "B.Cu")
		(net "PCIE_RX_N51")
	)
	(arc
		(start 165.452806 -222.907352)
		(mid 165.518756 -222.575797)
		(end 165.706552 -222.294704)
		(width 0.136652)
		(layer "B.Cu")
		(net "PCIE_RX_N51")
	)
	(arc
		(start 165.700202 -224.770188)
		(mid 165.655964 -224.547791)
		(end 165.530022 -224.359216)
		(width 0.136652)
		(layer "B.Cu")
		(net "PCIE_RX_N51")
	)
	(arc
		(start 165.530022 -224.359216)
		(mid 165.472868 -224.273678)
		(end 165.452806 -224.17278)
		(width 0.136652)
		(layer "B.Cu")
		(net "PCIE_RX_N51")
	)
	(segment
		(start 171.664884 -214.352632)
		(end 170.139106 -216.531698)
		(width 0.1397)
		(layer "In2.Cu")
		(net "PCIE_RX_N51")
	)
	(segment
		(start 236.87405 -75.538838)
		(end 236.22 -79.248)
		(width 0.1397)
		(layer "In2.Cu")
		(net "PCIE_RX_N51")
	)
	(segment
		(start 235.697014 -67.200018)
		(end 235.7628 -67.265804)
		(width 0.1016)
		(layer "In2.Cu")
		(net "PCIE_RX_N51")
	)
	(segment
		(start 235.7628 -69.235574)
		(end 236.87405 -75.538838)
		(width 0.1397)
		(layer "In2.Cu")
		(net "PCIE_RX_N51")
	)
	(segment
		(start 176.911508 -193.02603)
		(end 174.625 -205.994)
		(width 0.1397)
		(layer "In2.Cu")
		(net "PCIE_RX_N51")
	)
	(segment
		(start 236.22 -79.248)
		(end 237.776004 -88.07196)
		(width 0.1397)
		(layer "In2.Cu")
		(net "PCIE_RX_N51")
	)
	(segment
		(start 171.831 -213.4108)
		(end 171.664884 -214.352632)
		(width 0.1397)
		(layer "In2.Cu")
		(net "PCIE_RX_N51")
	)
	(segment
		(start 236.140244 -63.09995)
		(end 236.131354 -63.091314)
		(width 0.1016)
		(layer "In2.Cu")
		(net "PCIE_RX_N51")
	)
	(segment
		(start 165.465252 -220.559122)
		(end 165.465252 -221.712028)
		(width 0.1397)
		(layer "In2.Cu")
		(net "PCIE_RX_N51")
	)
	(segment
		(start 171.831 -209.98434)
		(end 171.831 -213.4108)
		(width 0.1397)
		(layer "In2.Cu")
		(net "PCIE_RX_N51")
	)
	(segment
		(start 235.996226 -63.03518)
		(end 235.95838 -63.03518)
		(width 0.1016)
		(layer "In2.Cu")
		(net "PCIE_RX_N51")
	)
	(segment
		(start 235.7628 -67.265804)
		(end 235.7628 -69.235574)
		(width 0.1397)
		(layer "In2.Cu")
		(net "PCIE_RX_N51")
	)
	(segment
		(start 237.776004 -88.07196)
		(end 233.526838 -112.171226)
		(width 0.1397)
		(layer "In2.Cu")
		(net "PCIE_RX_N51")
	)
	(segment
		(start 233.526838 -112.171226)
		(end 176.911508 -193.02603)
		(width 0.1397)
		(layer "In2.Cu")
		(net "PCIE_RX_N51")
	)
	(segment
		(start 235.697014 -63.30188)
		(end 235.697014 -67.200018)
		(width 0.1016)
		(layer "In2.Cu")
		(net "PCIE_RX_N51")
	)
	(segment
		(start 174.625 -205.994)
		(end 171.831 -209.98434)
		(width 0.1397)
		(layer "In2.Cu")
		(net "PCIE_RX_N51")
	)
	(segment
		(start 235.777278 -63.110364)
		(end 235.776008 -63.11138)
		(width 0.1016)
		(layer "In2.Cu")
		(net "PCIE_RX_N51")
	)
	(segment
		(start 166.50208 -219.078302)
		(end 165.465252 -220.559122)
		(width 0.1397)
		(layer "In2.Cu")
		(net "PCIE_RX_N51")
	)
	(segment
		(start 170.139106 -216.531698)
		(end 166.50208 -219.078302)
		(width 0.1397)
		(layer "In2.Cu")
		(net "PCIE_RX_N51")
	)
	(arc
		(start 236.100112 -63.499746)
		(mid 236.176266 -63.385774)
		(end 236.202982 -63.251334)
		(width 0.1016)
		(layer "In2.Cu")
		(net "PCIE_RX_N51")
	)
	(arc
		(start 235.725462 -63.181484)
		(mid 235.704227 -63.240027)
		(end 235.697014 -63.30188)
		(width 0.1016)
		(layer "In2.Cu")
		(net "PCIE_RX_N51")
	)
	(arc
		(start 236.131354 -63.091314)
		(mid 236.069372 -63.049806)
		(end 235.996226 -63.03518)
		(width 0.1016)
		(layer "In2.Cu")
		(net "PCIE_RX_N51")
	)
	(arc
		(start 235.95838 -63.03518)
		(mid 235.860357 -63.054772)
		(end 235.777278 -63.110364)
		(width 0.1016)
		(layer "In2.Cu")
		(net "PCIE_RX_N51")
	)
	(arc
		(start 165.465252 -221.712028)
		(mid 165.527973 -222.02735)
		(end 165.706552 -222.294704)
		(width 0.1397)
		(layer "In2.Cu")
		(net "PCIE_RX_N51")
	)
	(arc
		(start 235.776008 -63.11138)
		(mid 235.747916 -63.144399)
		(end 235.725462 -63.181484)
		(width 0.1016)
		(layer "In2.Cu")
		(net "PCIE_RX_N51")
	)
	(arc
		(start 236.202982 -63.251334)
		(mid 236.186683 -63.169393)
		(end 236.140244 -63.09995)
		(width 0.1016)
		(layer "In2.Cu")
		(net "PCIE_RX_N51")
	)
	(segment
		(start 237.599982 -61.999876)
		(end 237.10011 -62.499748)
		(width 0.136652)
		(layer "F.Cu")
		(net "PCIE_RX_N50")
	)
	(via
		(at 168.906444 -222.294704)
		(size 0.508)
		(drill 0.254)
		(layers "F.Cu" "B.Cu")
		(net "PCIE_RX_N50")
	)
	(via
		(at 237.10011 -62.499748)
		(size 0.4572)
		(drill 0.2032)
		(layers "F.Cu" "B.Cu")
		(net "PCIE_RX_N50")
	)
	(segment
		(start 168.652698 -224.17278)
		(end 168.652698 -222.907352)
		(width 0.136652)
		(layer "B.Cu")
		(net "PCIE_RX_N50")
	)
	(segment
		(start 168.900094 -225.92538)
		(end 168.900094 -224.770188)
		(width 0.136652)
		(layer "B.Cu")
		(net "PCIE_RX_N50")
	)
	(arc
		(start 168.900094 -224.770188)
		(mid 168.855856 -224.547791)
		(end 168.729914 -224.359216)
		(width 0.136652)
		(layer "B.Cu")
		(net "PCIE_RX_N50")
	)
	(arc
		(start 168.729914 -224.359216)
		(mid 168.67276 -224.273678)
		(end 168.652698 -224.17278)
		(width 0.136652)
		(layer "B.Cu")
		(net "PCIE_RX_N50")
	)
	(arc
		(start 168.652698 -222.907352)
		(mid 168.718648 -222.575797)
		(end 168.906444 -222.294704)
		(width 0.136652)
		(layer "B.Cu")
		(net "PCIE_RX_N50")
	)
	(segment
		(start 184.15 -196.977)
		(end 175.0568 -209.963258)
		(width 0.1397)
		(layer "In2.Cu")
		(net "PCIE_RX_N50")
	)
	(segment
		(start 173.52518 -216.49944)
		(end 169.50436 -219.314776)
		(width 0.1397)
		(layer "In2.Cu")
		(net "PCIE_RX_N50")
	)
	(segment
		(start 187.19419 -179.712112)
		(end 184.15 -196.977)
		(width 0.1397)
		(layer "In2.Cu")
		(net "PCIE_RX_N50")
	)
	(segment
		(start 236.7534 -69.235574)
		(end 237.812072 -75.239118)
		(width 0.1397)
		(layer "In2.Cu")
		(net "PCIE_RX_N50")
	)
	(segment
		(start 236.777276 -62.110366)
		(end 236.776006 -62.111382)
		(width 0.1016)
		(layer "In2.Cu")
		(net "PCIE_RX_N50")
	)
	(segment
		(start 236.697012 -67.228212)
		(end 236.7534 -67.2846)
		(width 0.1016)
		(layer "In2.Cu")
		(net "PCIE_RX_N50")
	)
	(segment
		(start 175.0568 -209.963258)
		(end 175.0568 -213.487)
		(width 0.1397)
		(layer "In2.Cu")
		(net "PCIE_RX_N50")
	)
	(segment
		(start 237.140242 -62.099952)
		(end 237.131352 -62.091316)
		(width 0.1016)
		(layer "In2.Cu")
		(net "PCIE_RX_N50")
	)
	(segment
		(start 168.665144 -220.513402)
		(end 168.665144 -221.712028)
		(width 0.1397)
		(layer "In2.Cu")
		(net "PCIE_RX_N50")
	)
	(segment
		(start 174.86249 -214.589614)
		(end 173.52518 -216.49944)
		(width 0.1397)
		(layer "In2.Cu")
		(net "PCIE_RX_N50")
	)
	(segment
		(start 238.724694 -88.270842)
		(end 234.518454 -112.126014)
		(width 0.1397)
		(layer "In2.Cu")
		(net "PCIE_RX_N50")
	)
	(segment
		(start 237.812072 -75.239118)
		(end 237.119414 -79.167736)
		(width 0.1397)
		(layer "In2.Cu")
		(net "PCIE_RX_N50")
	)
	(segment
		(start 236.697012 -62.301882)
		(end 236.697012 -67.228212)
		(width 0.1016)
		(layer "In2.Cu")
		(net "PCIE_RX_N50")
	)
	(segment
		(start 236.996224 -62.035182)
		(end 236.958378 -62.035182)
		(width 0.1016)
		(layer "In2.Cu")
		(net "PCIE_RX_N50")
	)
	(segment
		(start 175.0568 -213.487)
		(end 174.86249 -214.589614)
		(width 0.1397)
		(layer "In2.Cu")
		(net "PCIE_RX_N50")
	)
	(segment
		(start 237.119414 -79.167736)
		(end 238.724694 -88.270842)
		(width 0.1397)
		(layer "In2.Cu")
		(net "PCIE_RX_N50")
	)
	(segment
		(start 234.518454 -112.126014)
		(end 187.19419 -179.712112)
		(width 0.1397)
		(layer "In2.Cu")
		(net "PCIE_RX_N50")
	)
	(segment
		(start 236.7534 -67.2846)
		(end 236.7534 -69.235574)
		(width 0.1397)
		(layer "In2.Cu")
		(net "PCIE_RX_N50")
	)
	(segment
		(start 169.50436 -219.314776)
		(end 168.665144 -220.513402)
		(width 0.1397)
		(layer "In2.Cu")
		(net "PCIE_RX_N50")
	)
	(arc
		(start 236.72546 -62.181486)
		(mid 236.704225 -62.240029)
		(end 236.697012 -62.301882)
		(width 0.1016)
		(layer "In2.Cu")
		(net "PCIE_RX_N50")
	)
	(arc
		(start 236.776006 -62.111382)
		(mid 236.747914 -62.144401)
		(end 236.72546 -62.181486)
		(width 0.1016)
		(layer "In2.Cu")
		(net "PCIE_RX_N50")
	)
	(arc
		(start 237.20298 -62.251336)
		(mid 237.186681 -62.169395)
		(end 237.140242 -62.099952)
		(width 0.1016)
		(layer "In2.Cu")
		(net "PCIE_RX_N50")
	)
	(arc
		(start 237.131352 -62.091316)
		(mid 237.06937 -62.049808)
		(end 236.996224 -62.035182)
		(width 0.1016)
		(layer "In2.Cu")
		(net "PCIE_RX_N50")
	)
	(arc
		(start 237.10011 -62.499748)
		(mid 237.176264 -62.385776)
		(end 237.20298 -62.251336)
		(width 0.1016)
		(layer "In2.Cu")
		(net "PCIE_RX_N50")
	)
	(arc
		(start 236.958378 -62.035182)
		(mid 236.860355 -62.054774)
		(end 236.777276 -62.110366)
		(width 0.1016)
		(layer "In2.Cu")
		(net "PCIE_RX_N50")
	)
	(arc
		(start 168.665144 -221.712028)
		(mid 168.727865 -222.02735)
		(end 168.906444 -222.294704)
		(width 0.1397)
		(layer "In2.Cu")
		(net "PCIE_RX_N50")
	)
	(segment
		(start 247.599962 -30.999938)
		(end 248.099834 -30.500066)
		(width 0.136652)
		(layer "F.Cu")
		(net "PCIE_RX_N5")
	)
	(via
		(at 248.099834 -30.500066)
		(size 0.4572)
		(drill 0.2032)
		(layers "F.Cu" "B.Cu")
		(net "PCIE_RX_N5")
	)
	(segment
		(start 257.316478 -21.787358)
		(end 253.469394 -22.450552)
		(width 0.1397)
		(layer "In2.Cu")
		(net "PCIE_RX_N5")
	)
	(segment
		(start 294.291004 -19.207226)
		(end 293.977568 -20.983448)
		(width 0.1397)
		(layer "In2.Cu")
		(net "PCIE_RX_N5")
	)
	(segment
		(start 294.191182 -16.938498)
		(end 294.139112 -17.234154)
		(width 0.1397)
		(layer "In2.Cu")
		(net "PCIE_RX_N5")
	)
	(segment
		(start 292.593522 -22.313138)
		(end 289.89528 -22.78888)
		(width 0.1397)
		(layer "In2.Cu")
		(net "PCIE_RX_N5")
	)
	(segment
		(start 273.950684 -22.04212)
		(end 271.504664 -21.610828)
		(width 0.1397)
		(layer "In2.Cu")
		(net "PCIE_RX_N5")
	)
	(segment
		(start 294.139112 -17.234154)
		(end 294.041068 -17.789652)
		(width 0.1397)
		(layer "In2.Cu")
		(net "PCIE_RX_N5")
	)
	(segment
		(start 287.274 -22.3266)
		(end 284.403038 -22.832822)
		(width 0.1397)
		(layer "In2.Cu")
		(net "PCIE_RX_N5")
	)
	(segment
		(start 294.684958 -16.335248)
		(end 294.191182 -16.938498)
		(width 0.1397)
		(layer "In2.Cu")
		(net "PCIE_RX_N5")
	)
	(segment
		(start 298.311062 -15.20317)
		(end 297.565064 -15.042388)
		(width 0.1397)
		(layer "In2.Cu")
		(net "PCIE_RX_N5")
	)
	(segment
		(start 260.487414 -22.421342)
		(end 257.316478 -21.787358)
		(width 0.1397)
		(layer "In2.Cu")
		(net "PCIE_RX_N5")
	)
	(segment
		(start 266.869926 -22.4282)
		(end 263.661906 -21.786596)
		(width 0.1397)
		(layer "In2.Cu")
		(net "PCIE_RX_N5")
	)
	(segment
		(start 276.93493 -21.516086)
		(end 273.950684 -22.04212)
		(width 0.1397)
		(layer "In2.Cu")
		(net "PCIE_RX_N5")
	)
	(segment
		(start 289.89528 -22.78888)
		(end 287.274 -22.3266)
		(width 0.1397)
		(layer "In2.Cu")
		(net "PCIE_RX_N5")
	)
	(segment
		(start 298.654724 -15.431008)
		(end 298.311062 -15.20317)
		(width 0.1397)
		(layer "In2.Cu")
		(net "PCIE_RX_N5")
	)
	(segment
		(start 294.041068 -17.789652)
		(end 294.291004 -19.207226)
		(width 0.1397)
		(layer "In2.Cu")
		(net "PCIE_RX_N5")
	)
	(segment
		(start 297.565064 -15.042388)
		(end 294.684958 -16.335248)
		(width 0.1397)
		(layer "In2.Cu")
		(net "PCIE_RX_N5")
	)
	(segment
		(start 248.010172 -27.909774)
		(end 248.010172 -29.525976)
		(width 0.1397)
		(layer "In2.Cu")
		(net "PCIE_RX_N5")
	)
	(segment
		(start 284.403038 -22.832822)
		(end 276.93493 -21.516086)
		(width 0.1397)
		(layer "In2.Cu")
		(net "PCIE_RX_N5")
	)
	(segment
		(start 263.661906 -21.786596)
		(end 260.487414 -22.421342)
		(width 0.1397)
		(layer "In2.Cu")
		(net "PCIE_RX_N5")
	)
	(segment
		(start 293.977568 -20.983448)
		(end 293.482776 -21.690076)
		(width 0.1397)
		(layer "In2.Cu")
		(net "PCIE_RX_N5")
	)
	(segment
		(start 271.504664 -21.610828)
		(end 266.869926 -22.4282)
		(width 0.1397)
		(layer "In2.Cu")
		(net "PCIE_RX_N5")
	)
	(segment
		(start 253.469394 -22.450552)
		(end 248.010172 -27.909774)
		(width 0.1397)
		(layer "In2.Cu")
		(net "PCIE_RX_N5")
	)
	(segment
		(start 293.482776 -21.690076)
		(end 292.593522 -22.313138)
		(width 0.1397)
		(layer "In2.Cu")
		(net "PCIE_RX_N5")
	)
	(segment
		(start 299.377608 -16.472916)
		(end 299.377354 -16.472916)
		(width 0.1397)
		(layer "In2.Cu")
		(net "PCIE_RX_N5")
	)
	(arc
		(start 248.10974 -30.167072)
		(mid 248.133211 -30.334414)
		(end 248.099834 -30.500066)
		(width 0.1397)
		(layer "In2.Cu")
		(net "PCIE_RX_N5")
	)
	(arc
		(start 248.03862 -29.872178)
		(mid 248.068871 -30.020906)
		(end 248.10974 -30.167072)
		(width 0.1397)
		(layer "In2.Cu")
		(net "PCIE_RX_N5")
	)
	(arc
		(start 299.377354 -16.472916)
		(mid 299.11617 -15.882524)
		(end 298.654724 -15.431008)
		(width 0.1397)
		(layer "In2.Cu")
		(net "PCIE_RX_N5")
	)
	(arc
		(start 299.427646 -16.597376)
		(mid 299.397688 -16.537131)
		(end 299.377608 -16.472916)
		(width 0.1397)
		(layer "In2.Cu")
		(net "PCIE_RX_N5")
	)
	(arc
		(start 299.61078 -16.799052)
		(mid 299.509237 -16.707272)
		(end 299.427646 -16.597376)
		(width 0.1397)
		(layer "In2.Cu")
		(net "PCIE_RX_N5")
	)
	(arc
		(start 300.134274 -16.330168)
		(mid 300.063489 -16.777749)
		(end 299.61078 -16.799052)
		(width 0.1397)
		(layer "In2.Cu")
		(net "PCIE_RX_N5")
	)
	(arc
		(start 248.010172 -29.525976)
		(mid 248.017265 -29.699663)
		(end 248.03862 -29.872178)
		(width 0.1397)
		(layer "In2.Cu")
		(net "PCIE_RX_N5")
	)
	(segment
		(start 238.59998 -62.999874)
		(end 238.100108 -63.499746)
		(width 0.136652)
		(layer "F.Cu")
		(net "PCIE_RX_N49")
	)
	(via
		(at 172.10659 -222.294704)
		(size 0.508)
		(drill 0.254)
		(layers "F.Cu" "B.Cu")
		(net "PCIE_RX_N49")
	)
	(via
		(at 238.100108 -63.499746)
		(size 0.4572)
		(drill 0.2032)
		(layers "F.Cu" "B.Cu")
		(net "PCIE_RX_N49")
	)
	(segment
		(start 171.852844 -224.17278)
		(end 171.852844 -222.907352)
		(width 0.136652)
		(layer "B.Cu")
		(net "PCIE_RX_N49")
	)
	(segment
		(start 172.10024 -225.92538)
		(end 172.10024 -224.770188)
		(width 0.136652)
		(layer "B.Cu")
		(net "PCIE_RX_N49")
	)
	(arc
		(start 171.852844 -222.907352)
		(mid 171.918794 -222.575797)
		(end 172.10659 -222.294704)
		(width 0.136652)
		(layer "B.Cu")
		(net "PCIE_RX_N49")
	)
	(arc
		(start 171.93006 -224.359216)
		(mid 171.872906 -224.273678)
		(end 171.852844 -224.17278)
		(width 0.136652)
		(layer "B.Cu")
		(net "PCIE_RX_N49")
	)
	(arc
		(start 172.10024 -224.770188)
		(mid 172.056002 -224.547791)
		(end 171.93006 -224.359216)
		(width 0.136652)
		(layer "B.Cu")
		(net "PCIE_RX_N49")
	)
	(segment
		(start 187.476384 -205.252066)
		(end 187.084716 -205.492858)
		(width 0.1397)
		(layer "In2.Cu")
		(net "PCIE_RX_N49")
	)
	(segment
		(start 179.573682 -211.357972)
		(end 175.777398 -216.779348)
		(width 0.1397)
		(layer "In2.Cu")
		(net "PCIE_RX_N49")
	)
	(segment
		(start 175.777398 -216.779348)
		(end 172.659294 -218.962732)
		(width 0.1397)
		(layer "In2.Cu")
		(net "PCIE_RX_N49")
	)
	(segment
		(start 235.379768 -113.456974)
		(end 196.887084 -168.430956)
		(width 0.1397)
		(layer "In2.Cu")
		(net "PCIE_RX_N49")
	)
	(segment
		(start 187.084462 -205.493112)
		(end 183.689498 -207.579722)
		(width 0.1397)
		(layer "In2.Cu")
		(net "PCIE_RX_N49")
	)
	(segment
		(start 237.744 -69.67601)
		(end 238.76 -75.438)
		(width 0.1397)
		(layer "In2.Cu")
		(net "PCIE_RX_N49")
	)
	(segment
		(start 188.023754 -204.47)
		(end 187.861956 -204.701648)
		(width 0.1397)
		(layer "In2.Cu")
		(net "PCIE_RX_N49")
	)
	(segment
		(start 237.777274 -63.110364)
		(end 237.776004 -63.11138)
		(width 0.1016)
		(layer "In2.Cu")
		(net "PCIE_RX_N49")
	)
	(segment
		(start 183.689498 -207.579722)
		(end 179.586382 -211.339938)
		(width 0.1397)
		(layer "In2.Cu")
		(net "PCIE_RX_N49")
	)
	(segment
		(start 187.861956 -204.701648)
		(end 187.476384 -205.252066)
		(width 0.1397)
		(layer "In2.Cu")
		(net "PCIE_RX_N49")
	)
	(segment
		(start 238.14024 -63.09995)
		(end 238.13135 -63.091314)
		(width 0.1016)
		(layer "In2.Cu")
		(net "PCIE_RX_N49")
	)
	(segment
		(start 238.084106 -79.270606)
		(end 239.746028 -88.69553)
		(width 0.1397)
		(layer "In2.Cu")
		(net "PCIE_RX_N49")
	)
	(segment
		(start 239.746028 -88.69553)
		(end 235.379768 -113.456974)
		(width 0.1397)
		(layer "In2.Cu")
		(net "PCIE_RX_N49")
	)
	(segment
		(start 172.659294 -218.962732)
		(end 171.86529 -220.096588)
		(width 0.1397)
		(layer "In2.Cu")
		(net "PCIE_RX_N49")
	)
	(segment
		(start 196.887084 -168.430956)
		(end 191.376808 -199.681592)
		(width 0.1397)
		(layer "In2.Cu")
		(net "PCIE_RX_N49")
	)
	(segment
		(start 187.084716 -205.492858)
		(end 187.084462 -205.493112)
		(width 0.1397)
		(layer "In2.Cu")
		(net "PCIE_RX_N49")
	)
	(segment
		(start 237.69701 -67.26301)
		(end 237.744 -67.31)
		(width 0.1016)
		(layer "In2.Cu")
		(net "PCIE_RX_N49")
	)
	(segment
		(start 238.76 -75.438)
		(end 238.084106 -79.270606)
		(width 0.1397)
		(layer "In2.Cu")
		(net "PCIE_RX_N49")
	)
	(segment
		(start 237.69701 -63.30188)
		(end 237.69701 -67.26301)
		(width 0.1016)
		(layer "In2.Cu")
		(net "PCIE_RX_N49")
	)
	(segment
		(start 171.86529 -220.096588)
		(end 171.86529 -221.712028)
		(width 0.1397)
		(layer "In2.Cu")
		(net "PCIE_RX_N49")
	)
	(segment
		(start 237.996222 -63.03518)
		(end 237.958376 -63.03518)
		(width 0.1016)
		(layer "In2.Cu")
		(net "PCIE_RX_N49")
	)
	(segment
		(start 179.586382 -211.339938)
		(end 179.573682 -211.357972)
		(width 0.1397)
		(layer "In2.Cu")
		(net "PCIE_RX_N49")
	)
	(segment
		(start 191.376808 -199.681592)
		(end 188.023754 -204.47)
		(width 0.1397)
		(layer "In2.Cu")
		(net "PCIE_RX_N49")
	)
	(segment
		(start 237.744 -67.31)
		(end 237.744 -69.67601)
		(width 0.1397)
		(layer "In2.Cu")
		(net "PCIE_RX_N49")
	)
	(arc
		(start 237.958376 -63.03518)
		(mid 237.860353 -63.054772)
		(end 237.777274 -63.110364)
		(width 0.1016)
		(layer "In2.Cu")
		(net "PCIE_RX_N49")
	)
	(arc
		(start 238.202978 -63.251334)
		(mid 238.186679 -63.169393)
		(end 238.14024 -63.09995)
		(width 0.1016)
		(layer "In2.Cu")
		(net "PCIE_RX_N49")
	)
	(arc
		(start 237.776004 -63.11138)
		(mid 237.747912 -63.144399)
		(end 237.725458 -63.181484)
		(width 0.1016)
		(layer "In2.Cu")
		(net "PCIE_RX_N49")
	)
	(arc
		(start 238.100108 -63.499746)
		(mid 238.176262 -63.385774)
		(end 238.202978 -63.251334)
		(width 0.1016)
		(layer "In2.Cu")
		(net "PCIE_RX_N49")
	)
	(arc
		(start 171.86529 -221.712028)
		(mid 171.928011 -222.02735)
		(end 172.10659 -222.294704)
		(width 0.1397)
		(layer "In2.Cu")
		(net "PCIE_RX_N49")
	)
	(arc
		(start 238.13135 -63.091314)
		(mid 238.069368 -63.049806)
		(end 237.996222 -63.03518)
		(width 0.1016)
		(layer "In2.Cu")
		(net "PCIE_RX_N49")
	)
	(arc
		(start 237.725458 -63.181484)
		(mid 237.704223 -63.240027)
		(end 237.69701 -63.30188)
		(width 0.1016)
		(layer "In2.Cu")
		(net "PCIE_RX_N49")
	)
	(segment
		(start 239.599978 -61.999876)
		(end 239.100106 -62.499748)
		(width 0.136652)
		(layer "F.Cu")
		(net "PCIE_RX_N48")
	)
	(via
		(at 239.100106 -62.499748)
		(size 0.4572)
		(drill 0.2032)
		(layers "F.Cu" "B.Cu")
		(net "PCIE_RX_N48")
	)
	(via
		(at 175.306482 -222.294704)
		(size 0.508)
		(drill 0.254)
		(layers "F.Cu" "B.Cu")
		(net "PCIE_RX_N48")
	)
	(segment
		(start 175.300132 -225.92538)
		(end 175.300132 -224.770188)
		(width 0.136652)
		(layer "B.Cu")
		(net "PCIE_RX_N48")
	)
	(segment
		(start 175.052736 -224.17278)
		(end 175.052736 -222.907352)
		(width 0.136652)
		(layer "B.Cu")
		(net "PCIE_RX_N48")
	)
	(arc
		(start 175.129952 -224.359216)
		(mid 175.072798 -224.273678)
		(end 175.052736 -224.17278)
		(width 0.136652)
		(layer "B.Cu")
		(net "PCIE_RX_N48")
	)
	(arc
		(start 175.052736 -222.907352)
		(mid 175.118686 -222.575797)
		(end 175.306482 -222.294704)
		(width 0.136652)
		(layer "B.Cu")
		(net "PCIE_RX_N48")
	)
	(arc
		(start 175.300132 -224.770188)
		(mid 175.255894 -224.547791)
		(end 175.129952 -224.359216)
		(width 0.136652)
		(layer "B.Cu")
		(net "PCIE_RX_N48")
	)
	(segment
		(start 238.697008 -67.272408)
		(end 238.76 -67.3354)
		(width 0.1016)
		(layer "In2.Cu")
		(net "PCIE_RX_N48")
	)
	(segment
		(start 187.580524 -207.042004)
		(end 183.933084 -208.609184)
		(width 0.1397)
		(layer "In2.Cu")
		(net "PCIE_RX_N48")
	)
	(segment
		(start 197.788276 -169.6212)
		(end 192.405 -200.152)
		(width 0.1397)
		(layer "In2.Cu")
		(net "PCIE_RX_N48")
	)
	(segment
		(start 239.140238 -62.099952)
		(end 239.131348 -62.091316)
		(width 0.1016)
		(layer "In2.Cu")
		(net "PCIE_RX_N48")
	)
	(segment
		(start 238.76 -67.3354)
		(end 238.76 -69.235574)
		(width 0.1397)
		(layer "In2.Cu")
		(net "PCIE_RX_N48")
	)
	(segment
		(start 187.60059 -207.013302)
		(end 187.580524 -207.042004)
		(width 0.1397)
		(layer "In2.Cu")
		(net "PCIE_RX_N48")
	)
	(segment
		(start 180.829712 -211.741766)
		(end 180.81244 -211.766404)
		(width 0.1397)
		(layer "In2.Cu")
		(net "PCIE_RX_N48")
	)
	(segment
		(start 238.697008 -62.301882)
		(end 238.697008 -67.272408)
		(width 0.1016)
		(layer "In2.Cu")
		(net "PCIE_RX_N48")
	)
	(segment
		(start 175.065182 -219.974922)
		(end 175.065182 -221.712028)
		(width 0.1397)
		(layer "In2.Cu")
		(net "PCIE_RX_N48")
	)
	(segment
		(start 180.81244 -211.766404)
		(end 175.065182 -219.974922)
		(width 0.1397)
		(layer "In2.Cu")
		(net "PCIE_RX_N48")
	)
	(segment
		(start 238.76 -69.235574)
		(end 239.89284 -75.662028)
		(width 0.1397)
		(layer "In2.Cu")
		(net "PCIE_RX_N48")
	)
	(segment
		(start 239.89284 -75.662028)
		(end 239.16386 -79.796894)
		(width 0.1397)
		(layer "In2.Cu")
		(net "PCIE_RX_N48")
	)
	(segment
		(start 187.600844 -207.013048)
		(end 187.60059 -207.013302)
		(width 0.1397)
		(layer "In2.Cu")
		(net "PCIE_RX_N48")
	)
	(segment
		(start 236.242352 -114.703352)
		(end 197.788276 -169.6212)
		(width 0.1397)
		(layer "In2.Cu")
		(net "PCIE_RX_N48")
	)
	(segment
		(start 238.777272 -62.110366)
		(end 238.776002 -62.111382)
		(width 0.1016)
		(layer "In2.Cu")
		(net "PCIE_RX_N48")
	)
	(segment
		(start 192.405 -200.152)
		(end 187.600844 -207.013048)
		(width 0.1397)
		(layer "In2.Cu")
		(net "PCIE_RX_N48")
	)
	(segment
		(start 239.16386 -79.796894)
		(end 240.780062 -88.9635)
		(width 0.1397)
		(layer "In2.Cu")
		(net "PCIE_RX_N48")
	)
	(segment
		(start 183.933084 -208.609184)
		(end 180.829712 -211.741766)
		(width 0.1397)
		(layer "In2.Cu")
		(net "PCIE_RX_N48")
	)
	(segment
		(start 240.780062 -88.9635)
		(end 236.242352 -114.703352)
		(width 0.1397)
		(layer "In2.Cu")
		(net "PCIE_RX_N48")
	)
	(segment
		(start 238.99622 -62.035182)
		(end 238.958374 -62.035182)
		(width 0.1016)
		(layer "In2.Cu")
		(net "PCIE_RX_N48")
	)
	(arc
		(start 175.065182 -221.712028)
		(mid 175.127903 -222.02735)
		(end 175.306482 -222.294704)
		(width 0.1397)
		(layer "In2.Cu")
		(net "PCIE_RX_N48")
	)
	(arc
		(start 239.100106 -62.499748)
		(mid 239.17626 -62.385776)
		(end 239.202976 -62.251336)
		(width 0.1016)
		(layer "In2.Cu")
		(net "PCIE_RX_N48")
	)
	(arc
		(start 238.776002 -62.111382)
		(mid 238.74791 -62.144401)
		(end 238.725456 -62.181486)
		(width 0.1016)
		(layer "In2.Cu")
		(net "PCIE_RX_N48")
	)
	(arc
		(start 239.131348 -62.091316)
		(mid 239.069366 -62.049808)
		(end 238.99622 -62.035182)
		(width 0.1016)
		(layer "In2.Cu")
		(net "PCIE_RX_N48")
	)
	(arc
		(start 238.725456 -62.181486)
		(mid 238.704221 -62.240029)
		(end 238.697008 -62.301882)
		(width 0.1016)
		(layer "In2.Cu")
		(net "PCIE_RX_N48")
	)
	(arc
		(start 239.202976 -62.251336)
		(mid 239.186677 -62.169395)
		(end 239.140238 -62.099952)
		(width 0.1016)
		(layer "In2.Cu")
		(net "PCIE_RX_N48")
	)
	(arc
		(start 238.958374 -62.035182)
		(mid 238.860351 -62.054774)
		(end 238.777272 -62.110366)
		(width 0.1016)
		(layer "In2.Cu")
		(net "PCIE_RX_N48")
	)
	(segment
		(start 241.599974 -61.999876)
		(end 242.099846 -62.499748)
		(width 0.136652)
		(layer "F.Cu")
		(net "PCIE_RX_N47")
	)
	(via
		(at 242.099846 -62.499748)
		(size 0.4572)
		(drill 0.2032)
		(layers "F.Cu" "B.Cu")
		(net "PCIE_RX_N47")
	)
	(via
		(at 178.4096 -220.6752)
		(size 0.508)
		(drill 0.254)
		(layers "F.Cu" "B.Cu")
		(net "PCIE_RX_N47")
	)
	(segment
		(start 178.252628 -224.17278)
		(end 178.252628 -221.054168)
		(width 0.136652)
		(layer "B.Cu")
		(net "PCIE_RX_N47")
	)
	(segment
		(start 178.500024 -225.92538)
		(end 178.500024 -224.770188)
		(width 0.136652)
		(layer "B.Cu")
		(net "PCIE_RX_N47")
	)
	(arc
		(start 178.252628 -221.054168)
		(mid 178.293424 -220.849073)
		(end 178.4096 -220.6752)
		(width 0.136652)
		(layer "B.Cu")
		(net "PCIE_RX_N47")
	)
	(arc
		(start 178.500024 -224.770188)
		(mid 178.455786 -224.547791)
		(end 178.329844 -224.359216)
		(width 0.136652)
		(layer "B.Cu")
		(net "PCIE_RX_N47")
	)
	(arc
		(start 178.329844 -224.359216)
		(mid 178.27269 -224.273678)
		(end 178.252628 -224.17278)
		(width 0.136652)
		(layer "B.Cu")
		(net "PCIE_RX_N47")
	)
	(segment
		(start 241.7318 -71.29272)
		(end 240.247424 -79.710534)
		(width 0.1397)
		(layer "In2.Cu")
		(net "PCIE_RX_N47")
	)
	(segment
		(start 183.380126 -217.420952)
		(end 181.3814 -217.0684)
		(width 0.1397)
		(layer "In2.Cu")
		(net "PCIE_RX_N47")
	)
	(segment
		(start 185.351928 -217.072972)
		(end 183.380126 -217.420952)
		(width 0.1397)
		(layer "In2.Cu")
		(net "PCIE_RX_N47")
	)
	(segment
		(start 187.13958 -216.333578)
		(end 187.137548 -216.334594)
		(width 0.1397)
		(layer "In2.Cu")
		(net "PCIE_RX_N47")
	)
	(segment
		(start 240.247424 -79.710534)
		(end 241.935 -89.281)
		(width 0.1397)
		(layer "In2.Cu")
		(net "PCIE_RX_N47")
	)
	(segment
		(start 241.7318 -67.2338)
		(end 241.7318 -71.29272)
		(width 0.1397)
		(layer "In2.Cu")
		(net "PCIE_RX_N47")
	)
	(segment
		(start 179.370228 -217.422984)
		(end 178.634644 -217.938096)
		(width 0.1397)
		(layer "In2.Cu")
		(net "PCIE_RX_N47")
	)
	(segment
		(start 181.3814 -217.0684)
		(end 179.370228 -217.422984)
		(width 0.1397)
		(layer "In2.Cu")
		(net "PCIE_RX_N47")
	)
	(segment
		(start 178.1683 -218.604084)
		(end 178.1683 -220.092524)
		(width 0.1397)
		(layer "In2.Cu")
		(net "PCIE_RX_N47")
	)
	(segment
		(start 242.099846 -62.499748)
		(end 242.2525 -62.347094)
		(width 0.1016)
		(layer "In2.Cu")
		(net "PCIE_RX_N47")
	)
	(segment
		(start 187.137548 -216.334594)
		(end 185.351928 -217.072972)
		(width 0.1397)
		(layer "In2.Cu")
		(net "PCIE_RX_N47")
	)
	(segment
		(start 187.145168 -216.335864)
		(end 187.13958 -216.333578)
		(width 0.1397)
		(layer "In2.Cu")
		(net "PCIE_RX_N47")
	)
	(segment
		(start 242.2525 -62.1665)
		(end 242.162584 -62.076584)
		(width 0.1016)
		(layer "In2.Cu")
		(net "PCIE_RX_N47")
	)
	(segment
		(start 200.412604 -167.890444)
		(end 193.839592 -205.169008)
		(width 0.1397)
		(layer "In2.Cu")
		(net "PCIE_RX_N47")
	)
	(segment
		(start 242.062508 -62.035182)
		(end 241.958114 -62.035182)
		(width 0.1016)
		(layer "In2.Cu")
		(net "PCIE_RX_N47")
	)
	(segment
		(start 188.431424 -215.43518)
		(end 187.145168 -216.335864)
		(width 0.1397)
		(layer "In2.Cu")
		(net "PCIE_RX_N47")
	)
	(segment
		(start 178.634644 -217.938096)
		(end 178.1683 -218.604084)
		(width 0.1397)
		(layer "In2.Cu")
		(net "PCIE_RX_N47")
	)
	(segment
		(start 189.247272 -214.269828)
		(end 188.431424 -215.43518)
		(width 0.1397)
		(layer "In2.Cu")
		(net "PCIE_RX_N47")
	)
	(segment
		(start 241.714274 -67.216274)
		(end 241.7318 -67.2338)
		(width 0.1016)
		(layer "In2.Cu")
		(net "PCIE_RX_N47")
	)
	(segment
		(start 237.384336 -115.089686)
		(end 200.412604 -167.890444)
		(width 0.1397)
		(layer "In2.Cu")
		(net "PCIE_RX_N47")
	)
	(segment
		(start 241.777012 -62.110366)
		(end 241.775742 -62.111382)
		(width 0.1016)
		(layer "In2.Cu")
		(net "PCIE_RX_N47")
	)
	(segment
		(start 193.839592 -205.169008)
		(end 189.4078 -209.6008)
		(width 0.1397)
		(layer "In2.Cu")
		(net "PCIE_RX_N47")
	)
	(segment
		(start 189.4078 -209.6008)
		(end 189.4078 -213.36)
		(width 0.1397)
		(layer "In2.Cu")
		(net "PCIE_RX_N47")
	)
	(segment
		(start 241.696748 -62.301882)
		(end 241.696748 -67.173856)
		(width 0.1016)
		(layer "In2.Cu")
		(net "PCIE_RX_N47")
	)
	(segment
		(start 241.935 -89.281)
		(end 237.384336 -115.089686)
		(width 0.1397)
		(layer "In2.Cu")
		(net "PCIE_RX_N47")
	)
	(segment
		(start 189.4078 -213.36)
		(end 189.247272 -214.269828)
		(width 0.1397)
		(layer "In2.Cu")
		(net "PCIE_RX_N47")
	)
	(arc
		(start 241.725196 -62.181486)
		(mid 241.703961 -62.240029)
		(end 241.696748 -62.301882)
		(width 0.1016)
		(layer "In2.Cu")
		(net "PCIE_RX_N47")
	)
	(arc
		(start 241.696748 -67.173856)
		(mid 241.701296 -67.19681)
		(end 241.714274 -67.216274)
		(width 0.1016)
		(layer "In2.Cu")
		(net "PCIE_RX_N47")
	)
	(arc
		(start 241.958114 -62.035182)
		(mid 241.860091 -62.054774)
		(end 241.777012 -62.110366)
		(width 0.1016)
		(layer "In2.Cu")
		(net "PCIE_RX_N47")
	)
	(arc
		(start 242.162584 -62.076584)
		(mid 242.116655 -62.045958)
		(end 242.062508 -62.035182)
		(width 0.1016)
		(layer "In2.Cu")
		(net "PCIE_RX_N47")
	)
	(arc
		(start 178.1683 -220.092524)
		(mid 178.231021 -220.407846)
		(end 178.4096 -220.6752)
		(width 0.1397)
		(layer "In2.Cu")
		(net "PCIE_RX_N47")
	)
	(arc
		(start 242.2525 -62.347094)
		(mid 242.28985 -62.256834)
		(end 242.2525 -62.1665)
		(width 0.1016)
		(layer "In2.Cu")
		(net "PCIE_RX_N47")
	)
	(arc
		(start 241.775742 -62.111382)
		(mid 241.74765 -62.144401)
		(end 241.725196 -62.181486)
		(width 0.1016)
		(layer "In2.Cu")
		(net "PCIE_RX_N47")
	)
	(segment
		(start 242.599972 -62.999874)
		(end 243.099844 -63.499746)
		(width 0.136652)
		(layer "F.Cu")
		(net "PCIE_RX_N46")
	)
	(via
		(at 186.506358 -222.294704)
		(size 0.508)
		(drill 0.254)
		(layers "F.Cu" "B.Cu")
		(net "PCIE_RX_N46")
	)
	(via
		(at 243.099844 -63.499746)
		(size 0.4572)
		(drill 0.2032)
		(layers "F.Cu" "B.Cu")
		(net "PCIE_RX_N46")
	)
	(segment
		(start 186.500008 -225.92538)
		(end 186.500008 -224.770188)
		(width 0.136652)
		(layer "B.Cu")
		(net "PCIE_RX_N46")
	)
	(segment
		(start 186.252612 -224.17278)
		(end 186.252612 -222.907352)
		(width 0.136652)
		(layer "B.Cu")
		(net "PCIE_RX_N46")
	)
	(arc
		(start 186.329828 -224.359216)
		(mid 186.272674 -224.273678)
		(end 186.252612 -224.17278)
		(width 0.136652)
		(layer "B.Cu")
		(net "PCIE_RX_N46")
	)
	(arc
		(start 186.252612 -222.907352)
		(mid 186.318562 -222.575797)
		(end 186.506358 -222.294704)
		(width 0.136652)
		(layer "B.Cu")
		(net "PCIE_RX_N46")
	)
	(arc
		(start 186.500008 -224.770188)
		(mid 186.45577 -224.547791)
		(end 186.329828 -224.359216)
		(width 0.136652)
		(layer "B.Cu")
		(net "PCIE_RX_N46")
	)
	(segment
		(start 190.499238 -217.314526)
		(end 192.608962 -214.301324)
		(width 0.1397)
		(layer "In2.Cu")
		(net "PCIE_RX_N46")
	)
	(segment
		(start 192.73012 -209.738722)
		(end 194.844924 -206.718154)
		(width 0.1397)
		(layer "In2.Cu")
		(net "PCIE_RX_N46")
	)
	(segment
		(start 238.310928 -115.63223)
		(end 242.87988 -89.718896)
		(width 0.1397)
		(layer "In2.Cu")
		(net "PCIE_RX_N46")
	)
	(segment
		(start 242.958112 -63.03518)
		(end 242.995958 -63.03518)
		(width 0.1016)
		(layer "In2.Cu")
		(net "PCIE_RX_N46")
	)
	(segment
		(start 187.208668 -219.61856)
		(end 190.499238 -217.314526)
		(width 0.1397)
		(layer "In2.Cu")
		(net "PCIE_RX_N46")
	)
	(segment
		(start 194.844924 -206.718154)
		(end 201.681588 -167.942006)
		(width 0.1397)
		(layer "In2.Cu")
		(net "PCIE_RX_N46")
	)
	(segment
		(start 192.73012 -213.614)
		(end 192.73012 -209.738722)
		(width 0.1397)
		(layer "In2.Cu")
		(net "PCIE_RX_N46")
	)
	(segment
		(start 242.696746 -67.106546)
		(end 242.696746 -63.30188)
		(width 0.1016)
		(layer "In2.Cu")
		(net "PCIE_RX_N46")
	)
	(segment
		(start 242.77574 -63.11138)
		(end 242.77701 -63.110364)
		(width 0.1016)
		(layer "In2.Cu")
		(net "PCIE_RX_N46")
	)
	(segment
		(start 242.7732 -67.183)
		(end 242.696746 -67.106546)
		(width 0.1016)
		(layer "In2.Cu")
		(net "PCIE_RX_N46")
	)
	(segment
		(start 242.7732 -72.126602)
		(end 242.7732 -67.183)
		(width 0.1397)
		(layer "In2.Cu")
		(net "PCIE_RX_N46")
	)
	(segment
		(start 186.265058 -220.966284)
		(end 187.208668 -219.61856)
		(width 0.1397)
		(layer "In2.Cu")
		(net "PCIE_RX_N46")
	)
	(segment
		(start 243.131086 -63.091314)
		(end 243.139976 -63.09995)
		(width 0.1016)
		(layer "In2.Cu")
		(net "PCIE_RX_N46")
	)
	(segment
		(start 242.87988 -89.718896)
		(end 241.274346 -80.626712)
		(width 0.1397)
		(layer "In2.Cu")
		(net "PCIE_RX_N46")
	)
	(segment
		(start 241.274346 -80.626712)
		(end 242.7732 -72.126602)
		(width 0.1397)
		(layer "In2.Cu")
		(net "PCIE_RX_N46")
	)
	(segment
		(start 192.608962 -214.301324)
		(end 192.73012 -213.614)
		(width 0.1397)
		(layer "In2.Cu")
		(net "PCIE_RX_N46")
	)
	(segment
		(start 201.681588 -167.942006)
		(end 238.310928 -115.63223)
		(width 0.1397)
		(layer "In2.Cu")
		(net "PCIE_RX_N46")
	)
	(segment
		(start 186.265058 -221.712028)
		(end 186.265058 -220.966284)
		(width 0.1397)
		(layer "In2.Cu")
		(net "PCIE_RX_N46")
	)
	(arc
		(start 242.995958 -63.03518)
		(mid 243.069097 -63.049822)
		(end 243.131086 -63.091314)
		(width 0.1016)
		(layer "In2.Cu")
		(net "PCIE_RX_N46")
	)
	(arc
		(start 242.77701 -63.110364)
		(mid 242.860085 -63.054762)
		(end 242.958112 -63.03518)
		(width 0.1016)
		(layer "In2.Cu")
		(net "PCIE_RX_N46")
	)
	(arc
		(start 242.725194 -63.181484)
		(mid 242.747636 -63.14439)
		(end 242.77574 -63.11138)
		(width 0.1016)
		(layer "In2.Cu")
		(net "PCIE_RX_N46")
	)
	(arc
		(start 186.506358 -222.294704)
		(mid 186.327731 -222.02737)
		(end 186.265058 -221.712028)
		(width 0.1397)
		(layer "In2.Cu")
		(net "PCIE_RX_N46")
	)
	(arc
		(start 242.696746 -63.30188)
		(mid 242.703991 -63.240035)
		(end 242.725194 -63.181484)
		(width 0.1016)
		(layer "In2.Cu")
		(net "PCIE_RX_N46")
	)
	(arc
		(start 243.139976 -63.09995)
		(mid 243.186385 -63.169406)
		(end 243.202714 -63.251334)
		(width 0.1016)
		(layer "In2.Cu")
		(net "PCIE_RX_N46")
	)
	(arc
		(start 243.202714 -63.251334)
		(mid 243.175974 -63.385764)
		(end 243.099844 -63.499746)
		(width 0.1016)
		(layer "In2.Cu")
		(net "PCIE_RX_N46")
	)
	(segment
		(start 243.59997 -61.999876)
		(end 244.099842 -62.499748)
		(width 0.136652)
		(layer "F.Cu")
		(net "PCIE_RX_N45")
	)
	(via
		(at 189.706504 -222.294704)
		(size 0.508)
		(drill 0.254)
		(layers "F.Cu" "B.Cu")
		(net "PCIE_RX_N45")
	)
	(via
		(at 244.099842 -62.499748)
		(size 0.4572)
		(drill 0.2032)
		(layers "F.Cu" "B.Cu")
		(net "PCIE_RX_N45")
	)
	(segment
		(start 189.452758 -224.17278)
		(end 189.452758 -222.907352)
		(width 0.136652)
		(layer "B.Cu")
		(net "PCIE_RX_N45")
	)
	(segment
		(start 189.700154 -225.92538)
		(end 189.700154 -224.770188)
		(width 0.136652)
		(layer "B.Cu")
		(net "PCIE_RX_N45")
	)
	(arc
		(start 189.452758 -222.907352)
		(mid 189.518708 -222.575797)
		(end 189.706504 -222.294704)
		(width 0.136652)
		(layer "B.Cu")
		(net "PCIE_RX_N45")
	)
	(arc
		(start 189.700154 -224.770188)
		(mid 189.655916 -224.547791)
		(end 189.529974 -224.359216)
		(width 0.136652)
		(layer "B.Cu")
		(net "PCIE_RX_N45")
	)
	(arc
		(start 189.529974 -224.359216)
		(mid 189.47282 -224.273678)
		(end 189.452758 -224.17278)
		(width 0.136652)
		(layer "B.Cu")
		(net "PCIE_RX_N45")
	)
	(segment
		(start 195.60159 -215.24468)
		(end 194.699128 -216.533222)
		(width 0.1397)
		(layer "In2.Cu")
		(net "PCIE_RX_N45")
	)
	(segment
		(start 190.182754 -219.695522)
		(end 189.465204 -220.720158)
		(width 0.1397)
		(layer "In2.Cu")
		(net "PCIE_RX_N45")
	)
	(segment
		(start 243.995956 -62.035182)
		(end 243.95811 -62.035182)
		(width 0.1016)
		(layer "In2.Cu")
		(net "PCIE_RX_N45")
	)
	(segment
		(start 189.465204 -220.720158)
		(end 189.465204 -221.712028)
		(width 0.1397)
		(layer "In2.Cu")
		(net "PCIE_RX_N45")
	)
	(segment
		(start 202.746102 -168.72585)
		(end 195.752212 -208.391252)
		(width 0.1397)
		(layer "In2.Cu")
		(net "PCIE_RX_N45")
	)
	(segment
		(start 243.777008 -62.110366)
		(end 243.775738 -62.111382)
		(width 0.1016)
		(layer "In2.Cu")
		(net "PCIE_RX_N45")
	)
	(segment
		(start 195.8848 -213.6394)
		(end 195.60159 -215.24468)
		(width 0.1397)
		(layer "In2.Cu")
		(net "PCIE_RX_N45")
	)
	(segment
		(start 243.92001 -88.845644)
		(end 238.952786 -117.017038)
		(width 0.1397)
		(layer "In2.Cu")
		(net "PCIE_RX_N45")
	)
	(segment
		(start 195.8848 -209.1436)
		(end 195.8848 -213.6394)
		(width 0.1397)
		(layer "In2.Cu")
		(net "PCIE_RX_N45")
	)
	(segment
		(start 238.952786 -117.017038)
		(end 202.746102 -168.72585)
		(width 0.1397)
		(layer "In2.Cu")
		(net "PCIE_RX_N45")
	)
	(segment
		(start 195.752212 -208.391252)
		(end 195.8848 -209.1436)
		(width 0.1397)
		(layer "In2.Cu")
		(net "PCIE_RX_N45")
	)
	(segment
		(start 244.139974 -62.099952)
		(end 244.131084 -62.091316)
		(width 0.1016)
		(layer "In2.Cu")
		(net "PCIE_RX_N45")
	)
	(segment
		(start 243.696744 -62.301882)
		(end 243.696744 -67.110102)
		(width 0.1016)
		(layer "In2.Cu")
		(net "PCIE_RX_N45")
	)
	(segment
		(start 194.699128 -216.533222)
		(end 190.182754 -219.695522)
		(width 0.1397)
		(layer "In2.Cu")
		(net "PCIE_RX_N45")
	)
	(segment
		(start 243.981478 -73.573894)
		(end 242.60429 -81.384394)
		(width 0.1397)
		(layer "In2.Cu")
		(net "PCIE_RX_N45")
	)
	(segment
		(start 242.60429 -81.384394)
		(end 243.92001 -88.845644)
		(width 0.1397)
		(layer "In2.Cu")
		(net "PCIE_RX_N45")
	)
	(segment
		(start 243.769642 -72.371966)
		(end 243.981478 -73.573894)
		(width 0.1397)
		(layer "In2.Cu")
		(net "PCIE_RX_N45")
	)
	(segment
		(start 243.696744 -67.110102)
		(end 243.769642 -67.183)
		(width 0.1016)
		(layer "In2.Cu")
		(net "PCIE_RX_N45")
	)
	(segment
		(start 243.769642 -67.183)
		(end 243.769642 -72.371966)
		(width 0.1397)
		(layer "In2.Cu")
		(net "PCIE_RX_N45")
	)
	(arc
		(start 243.775738 -62.111382)
		(mid 243.747646 -62.144401)
		(end 243.725192 -62.181486)
		(width 0.1016)
		(layer "In2.Cu")
		(net "PCIE_RX_N45")
	)
	(arc
		(start 243.725192 -62.181486)
		(mid 243.703957 -62.240029)
		(end 243.696744 -62.301882)
		(width 0.1016)
		(layer "In2.Cu")
		(net "PCIE_RX_N45")
	)
	(arc
		(start 189.465204 -221.712028)
		(mid 189.527925 -222.02735)
		(end 189.706504 -222.294704)
		(width 0.1397)
		(layer "In2.Cu")
		(net "PCIE_RX_N45")
	)
	(arc
		(start 244.131084 -62.091316)
		(mid 244.069102 -62.049808)
		(end 243.995956 -62.035182)
		(width 0.1016)
		(layer "In2.Cu")
		(net "PCIE_RX_N45")
	)
	(arc
		(start 244.202712 -62.251336)
		(mid 244.186413 -62.169395)
		(end 244.139974 -62.099952)
		(width 0.1016)
		(layer "In2.Cu")
		(net "PCIE_RX_N45")
	)
	(arc
		(start 244.099842 -62.499748)
		(mid 244.175996 -62.385776)
		(end 244.202712 -62.251336)
		(width 0.1016)
		(layer "In2.Cu")
		(net "PCIE_RX_N45")
	)
	(arc
		(start 243.95811 -62.035182)
		(mid 243.860087 -62.054774)
		(end 243.777008 -62.110366)
		(width 0.1016)
		(layer "In2.Cu")
		(net "PCIE_RX_N45")
	)
	(segment
		(start 244.599968 -62.999874)
		(end 245.09984 -63.499746)
		(width 0.136652)
		(layer "F.Cu")
		(net "PCIE_RX_N44")
	)
	(via
		(at 245.09984 -63.499746)
		(size 0.4572)
		(drill 0.2032)
		(layers "F.Cu" "B.Cu")
		(net "PCIE_RX_N44")
	)
	(via
		(at 192.906396 -222.294704)
		(size 0.508)
		(drill 0.254)
		(layers "F.Cu" "B.Cu")
		(net "PCIE_RX_N44")
	)
	(segment
		(start 192.900046 -225.92538)
		(end 192.900046 -224.770188)
		(width 0.136652)
		(layer "B.Cu")
		(net "PCIE_RX_N44")
	)
	(segment
		(start 192.65265 -224.17278)
		(end 192.65265 -222.907352)
		(width 0.136652)
		(layer "B.Cu")
		(net "PCIE_RX_N44")
	)
	(arc
		(start 192.900046 -224.770188)
		(mid 192.855808 -224.547791)
		(end 192.729866 -224.359216)
		(width 0.136652)
		(layer "B.Cu")
		(net "PCIE_RX_N44")
	)
	(arc
		(start 192.65265 -222.907352)
		(mid 192.7186 -222.575797)
		(end 192.906396 -222.294704)
		(width 0.136652)
		(layer "B.Cu")
		(net "PCIE_RX_N44")
	)
	(arc
		(start 192.729866 -224.359216)
		(mid 192.672712 -224.273678)
		(end 192.65265 -224.17278)
		(width 0.136652)
		(layer "B.Cu")
		(net "PCIE_RX_N44")
	)
	(segment
		(start 199.39 -207.518)
		(end 199.114156 -205.954376)
		(width 0.1397)
		(layer "In2.Cu")
		(net "PCIE_RX_N44")
	)
	(segment
		(start 196.917056 -217.880184)
		(end 198.71182 -215.31707)
		(width 0.1397)
		(layer "In2.Cu")
		(net "PCIE_RX_N44")
	)
	(segment
		(start 240.083848 -117.277642)
		(end 245.11 -88.773)
		(width 0.1397)
		(layer "In2.Cu")
		(net "PCIE_RX_N44")
	)
	(segment
		(start 199.114156 -205.954376)
		(end 206.223616 -165.635178)
		(width 0.1397)
		(layer "In2.Cu")
		(net "PCIE_RX_N44")
	)
	(segment
		(start 192.665096 -221.591886)
		(end 193.67373 -220.151198)
		(width 0.1397)
		(layer "In2.Cu")
		(net "PCIE_RX_N44")
	)
	(segment
		(start 244.696742 -67.1195)
		(end 244.696742 -63.30188)
		(width 0.1016)
		(layer "In2.Cu")
		(net "PCIE_RX_N44")
	)
	(segment
		(start 199.023732 -209.59445)
		(end 199.39 -207.518)
		(width 0.1397)
		(layer "In2.Cu")
		(net "PCIE_RX_N44")
	)
	(segment
		(start 243.80317 -81.361534)
		(end 245.158006 -73.678288)
		(width 0.1397)
		(layer "In2.Cu")
		(net "PCIE_RX_N44")
	)
	(segment
		(start 245.11 -88.773)
		(end 243.80317 -81.361534)
		(width 0.1397)
		(layer "In2.Cu")
		(net "PCIE_RX_N44")
	)
	(segment
		(start 244.958108 -63.03518)
		(end 244.995954 -63.03518)
		(width 0.1016)
		(layer "In2.Cu")
		(net "PCIE_RX_N44")
	)
	(segment
		(start 244.775736 -63.11138)
		(end 244.777006 -63.110364)
		(width 0.1016)
		(layer "In2.Cu")
		(net "PCIE_RX_N44")
	)
	(segment
		(start 245.131082 -63.091314)
		(end 245.139972 -63.09995)
		(width 0.1016)
		(layer "In2.Cu")
		(net "PCIE_RX_N44")
	)
	(segment
		(start 244.760242 -71.42226)
		(end 244.760242 -67.183)
		(width 0.1397)
		(layer "In2.Cu")
		(net "PCIE_RX_N44")
	)
	(segment
		(start 199.023732 -213.548468)
		(end 199.023732 -209.59445)
		(width 0.1397)
		(layer "In2.Cu")
		(net "PCIE_RX_N44")
	)
	(segment
		(start 193.67373 -220.151198)
		(end 196.917056 -217.880184)
		(width 0.1397)
		(layer "In2.Cu")
		(net "PCIE_RX_N44")
	)
	(segment
		(start 198.71182 -215.31707)
		(end 199.023732 -213.548468)
		(width 0.1397)
		(layer "In2.Cu")
		(net "PCIE_RX_N44")
	)
	(segment
		(start 192.665096 -221.712028)
		(end 192.665096 -221.591886)
		(width 0.1397)
		(layer "In2.Cu")
		(net "PCIE_RX_N44")
	)
	(segment
		(start 245.158006 -73.678288)
		(end 244.760242 -71.42226)
		(width 0.1397)
		(layer "In2.Cu")
		(net "PCIE_RX_N44")
	)
	(segment
		(start 206.223616 -165.635178)
		(end 240.083848 -117.277642)
		(width 0.1397)
		(layer "In2.Cu")
		(net "PCIE_RX_N44")
	)
	(segment
		(start 244.760242 -67.183)
		(end 244.696742 -67.1195)
		(width 0.1016)
		(layer "In2.Cu")
		(net "PCIE_RX_N44")
	)
	(arc
		(start 245.20271 -63.251334)
		(mid 245.17597 -63.385764)
		(end 245.09984 -63.499746)
		(width 0.1016)
		(layer "In2.Cu")
		(net "PCIE_RX_N44")
	)
	(arc
		(start 244.72519 -63.181484)
		(mid 244.747632 -63.14439)
		(end 244.775736 -63.11138)
		(width 0.1016)
		(layer "In2.Cu")
		(net "PCIE_RX_N44")
	)
	(arc
		(start 244.995954 -63.03518)
		(mid 245.069093 -63.049822)
		(end 245.131082 -63.091314)
		(width 0.1016)
		(layer "In2.Cu")
		(net "PCIE_RX_N44")
	)
	(arc
		(start 244.777006 -63.110364)
		(mid 244.860081 -63.054762)
		(end 244.958108 -63.03518)
		(width 0.1016)
		(layer "In2.Cu")
		(net "PCIE_RX_N44")
	)
	(arc
		(start 192.906396 -222.294704)
		(mid 192.727769 -222.02737)
		(end 192.665096 -221.712028)
		(width 0.1397)
		(layer "In2.Cu")
		(net "PCIE_RX_N44")
	)
	(arc
		(start 245.139972 -63.09995)
		(mid 245.186381 -63.169406)
		(end 245.20271 -63.251334)
		(width 0.1016)
		(layer "In2.Cu")
		(net "PCIE_RX_N44")
	)
	(arc
		(start 244.696742 -63.30188)
		(mid 244.703987 -63.240035)
		(end 244.72519 -63.181484)
		(width 0.1016)
		(layer "In2.Cu")
		(net "PCIE_RX_N44")
	)
	(segment
		(start 245.599966 -61.999876)
		(end 246.099838 -62.499748)
		(width 0.136652)
		(layer "F.Cu")
		(net "PCIE_RX_N43")
	)
	(via
		(at 196.106542 -222.294704)
		(size 0.508)
		(drill 0.254)
		(layers "F.Cu" "B.Cu")
		(net "PCIE_RX_N43")
	)
	(via
		(at 246.099838 -62.499748)
		(size 0.4572)
		(drill 0.2032)
		(layers "F.Cu" "B.Cu")
		(net "PCIE_RX_N43")
	)
	(segment
		(start 195.852796 -224.17278)
		(end 195.852796 -222.907352)
		(width 0.136652)
		(layer "B.Cu")
		(net "PCIE_RX_N43")
	)
	(segment
		(start 196.100192 -225.92538)
		(end 196.100192 -224.770188)
		(width 0.136652)
		(layer "B.Cu")
		(net "PCIE_RX_N43")
	)
	(arc
		(start 195.930012 -224.359216)
		(mid 195.872858 -224.273678)
		(end 195.852796 -224.17278)
		(width 0.136652)
		(layer "B.Cu")
		(net "PCIE_RX_N43")
	)
	(arc
		(start 196.100192 -224.770188)
		(mid 196.055954 -224.547791)
		(end 195.930012 -224.359216)
		(width 0.136652)
		(layer "B.Cu")
		(net "PCIE_RX_N43")
	)
	(arc
		(start 195.852796 -222.907352)
		(mid 195.918746 -222.575797)
		(end 196.106542 -222.294704)
		(width 0.136652)
		(layer "B.Cu")
		(net "PCIE_RX_N43")
	)
	(segment
		(start 246.38 -73.787)
		(end 245.769638 -70.325488)
		(width 0.1397)
		(layer "In2.Cu")
		(net "PCIE_RX_N43")
	)
	(segment
		(start 201.807318 -208.509108)
		(end 200.89876 -203.354686)
		(width 0.1397)
		(layer "In2.Cu")
		(net "PCIE_RX_N43")
	)
	(segment
		(start 195.865242 -221.712028)
		(end 195.865242 -221.349062)
		(width 0.1397)
		(layer "In2.Cu")
		(net "PCIE_RX_N43")
	)
	(segment
		(start 202.274678 -209.17662)
		(end 201.807318 -208.509108)
		(width 0.1397)
		(layer "In2.Cu")
		(net "PCIE_RX_N43")
	)
	(segment
		(start 245.775734 -62.111382)
		(end 245.777004 -62.110366)
		(width 0.1016)
		(layer "In2.Cu")
		(net "PCIE_RX_N43")
	)
	(segment
		(start 245.69674 -67.10934)
		(end 245.69674 -62.301882)
		(width 0.1016)
		(layer "In2.Cu")
		(net "PCIE_RX_N43")
	)
	(segment
		(start 245.013988 -81.534)
		(end 246.38 -73.787)
		(width 0.1397)
		(layer "In2.Cu")
		(net "PCIE_RX_N43")
	)
	(segment
		(start 200.89876 -203.354686)
		(end 200.89876 -203.22413)
		(width 0.1397)
		(layer "In2.Cu")
		(net "PCIE_RX_N43")
	)
	(segment
		(start 199.632824 -218.22156)
		(end 202.06589 -214.746586)
		(width 0.1397)
		(layer "In2.Cu")
		(net "PCIE_RX_N43")
	)
	(segment
		(start 245.958106 -62.035182)
		(end 245.995952 -62.035182)
		(width 0.1016)
		(layer "In2.Cu")
		(net "PCIE_RX_N43")
	)
	(segment
		(start 207.522826 -165.658546)
		(end 241.458242 -117.194076)
		(width 0.1397)
		(layer "In2.Cu")
		(net "PCIE_RX_N43")
	)
	(segment
		(start 200.89876 -203.22413)
		(end 207.522826 -165.658546)
		(width 0.1397)
		(layer "In2.Cu")
		(net "PCIE_RX_N43")
	)
	(segment
		(start 195.865242 -221.349062)
		(end 196.537326 -220.388942)
		(width 0.1397)
		(layer "In2.Cu")
		(net "PCIE_RX_N43")
	)
	(segment
		(start 246.38 -89.281)
		(end 245.013988 -81.534)
		(width 0.1397)
		(layer "In2.Cu")
		(net "PCIE_RX_N43")
	)
	(segment
		(start 245.769638 -67.182238)
		(end 245.69674 -67.10934)
		(width 0.1016)
		(layer "In2.Cu")
		(net "PCIE_RX_N43")
	)
	(segment
		(start 196.537326 -220.388942)
		(end 199.632824 -218.22156)
		(width 0.1397)
		(layer "In2.Cu")
		(net "PCIE_RX_N43")
	)
	(segment
		(start 245.769638 -70.325488)
		(end 245.769638 -67.182238)
		(width 0.1397)
		(layer "In2.Cu")
		(net "PCIE_RX_N43")
	)
	(segment
		(start 202.274678 -213.5632)
		(end 202.274678 -209.17662)
		(width 0.1397)
		(layer "In2.Cu")
		(net "PCIE_RX_N43")
	)
	(segment
		(start 246.13108 -62.091316)
		(end 246.13997 -62.099952)
		(width 0.1016)
		(layer "In2.Cu")
		(net "PCIE_RX_N43")
	)
	(segment
		(start 202.06589 -214.746586)
		(end 202.274678 -213.5632)
		(width 0.1397)
		(layer "In2.Cu")
		(net "PCIE_RX_N43")
	)
	(segment
		(start 241.458242 -117.194076)
		(end 246.38 -89.281)
		(width 0.1397)
		(layer "In2.Cu")
		(net "PCIE_RX_N43")
	)
	(arc
		(start 245.995952 -62.035182)
		(mid 246.069091 -62.049824)
		(end 246.13108 -62.091316)
		(width 0.1016)
		(layer "In2.Cu")
		(net "PCIE_RX_N43")
	)
	(arc
		(start 246.13997 -62.099952)
		(mid 246.186379 -62.169408)
		(end 246.202708 -62.251336)
		(width 0.1016)
		(layer "In2.Cu")
		(net "PCIE_RX_N43")
	)
	(arc
		(start 246.202708 -62.251336)
		(mid 246.175968 -62.385766)
		(end 246.099838 -62.499748)
		(width 0.1016)
		(layer "In2.Cu")
		(net "PCIE_RX_N43")
	)
	(arc
		(start 245.777004 -62.110366)
		(mid 245.860079 -62.054764)
		(end 245.958106 -62.035182)
		(width 0.1016)
		(layer "In2.Cu")
		(net "PCIE_RX_N43")
	)
	(arc
		(start 245.725188 -62.181486)
		(mid 245.74763 -62.144392)
		(end 245.775734 -62.111382)
		(width 0.1016)
		(layer "In2.Cu")
		(net "PCIE_RX_N43")
	)
	(arc
		(start 196.106542 -222.294704)
		(mid 195.927915 -222.02737)
		(end 195.865242 -221.712028)
		(width 0.1397)
		(layer "In2.Cu")
		(net "PCIE_RX_N43")
	)
	(arc
		(start 245.69674 -62.301882)
		(mid 245.703985 -62.240037)
		(end 245.725188 -62.181486)
		(width 0.1016)
		(layer "In2.Cu")
		(net "PCIE_RX_N43")
	)
	(segment
		(start 246.599964 -62.999874)
		(end 247.099836 -63.499746)
		(width 0.136652)
		(layer "F.Cu")
		(net "PCIE_RX_N42")
	)
	(via
		(at 199.306434 -222.294704)
		(size 0.508)
		(drill 0.254)
		(layers "F.Cu" "B.Cu")
		(net "PCIE_RX_N42")
	)
	(via
		(at 247.099836 -63.499746)
		(size 0.4572)
		(drill 0.2032)
		(layers "F.Cu" "B.Cu")
		(net "PCIE_RX_N42")
	)
	(segment
		(start 199.052688 -224.17278)
		(end 199.052688 -222.907352)
		(width 0.136652)
		(layer "B.Cu")
		(net "PCIE_RX_N42")
	)
	(segment
		(start 199.300084 -225.92538)
		(end 199.300084 -224.770188)
		(width 0.136652)
		(layer "B.Cu")
		(net "PCIE_RX_N42")
	)
	(arc
		(start 199.129904 -224.359216)
		(mid 199.07275 -224.273678)
		(end 199.052688 -224.17278)
		(width 0.136652)
		(layer "B.Cu")
		(net "PCIE_RX_N42")
	)
	(arc
		(start 199.052688 -222.907352)
		(mid 199.118638 -222.575797)
		(end 199.306434 -222.294704)
		(width 0.136652)
		(layer "B.Cu")
		(net "PCIE_RX_N42")
	)
	(arc
		(start 199.300084 -224.770188)
		(mid 199.255846 -224.547791)
		(end 199.129904 -224.359216)
		(width 0.136652)
		(layer "B.Cu")
		(net "PCIE_RX_N42")
	)
	(segment
		(start 204.157326 -217.482166)
		(end 205.021434 -216.248234)
		(width 0.1397)
		(layer "In2.Cu")
		(net "PCIE_RX_N42")
	)
	(segment
		(start 246.760238 -67.233038)
		(end 246.696738 -67.169538)
		(width 0.1016)
		(layer "In2.Cu")
		(net "PCIE_RX_N42")
	)
	(segment
		(start 247.565418 -73.801986)
		(end 246.760238 -69.235574)
		(width 0.1397)
		(layer "In2.Cu")
		(net "PCIE_RX_N42")
	)
	(segment
		(start 208.668874 -166.89832)
		(end 242.992148 -117.878098)
		(width 0.1397)
		(layer "In2.Cu")
		(net "PCIE_RX_N42")
	)
	(segment
		(start 242.992148 -117.878098)
		(end 248.026428 -89.32672)
		(width 0.1397)
		(layer "In2.Cu")
		(net "PCIE_RX_N42")
	)
	(segment
		(start 205.021434 -216.248234)
		(end 205.486 -213.614)
		(width 0.1397)
		(layer "In2.Cu")
		(net "PCIE_RX_N42")
	)
	(segment
		(start 246.958104 -63.03518)
		(end 246.99595 -63.03518)
		(width 0.1016)
		(layer "In2.Cu")
		(net "PCIE_RX_N42")
	)
	(segment
		(start 247.131078 -63.091314)
		(end 247.139968 -63.09995)
		(width 0.1016)
		(layer "In2.Cu")
		(net "PCIE_RX_N42")
	)
	(segment
		(start 246.760238 -69.235574)
		(end 246.760238 -67.233038)
		(width 0.1397)
		(layer "In2.Cu")
		(net "PCIE_RX_N42")
	)
	(segment
		(start 248.026428 -89.32672)
		(end 246.427244 -80.257396)
		(width 0.1397)
		(layer "In2.Cu")
		(net "PCIE_RX_N42")
	)
	(segment
		(start 199.574658 -220.690948)
		(end 204.157326 -217.482166)
		(width 0.1397)
		(layer "In2.Cu")
		(net "PCIE_RX_N42")
	)
	(segment
		(start 199.065134 -221.712028)
		(end 199.065134 -221.418658)
		(width 0.1397)
		(layer "In2.Cu")
		(net "PCIE_RX_N42")
	)
	(segment
		(start 246.427244 -80.257396)
		(end 247.565418 -73.801986)
		(width 0.1397)
		(layer "In2.Cu")
		(net "PCIE_RX_N42")
	)
	(segment
		(start 205.486 -209.18678)
		(end 203.349606 -197.070218)
		(width 0.1397)
		(layer "In2.Cu")
		(net "PCIE_RX_N42")
	)
	(segment
		(start 199.065134 -221.418658)
		(end 199.574658 -220.690948)
		(width 0.1397)
		(layer "In2.Cu")
		(net "PCIE_RX_N42")
	)
	(segment
		(start 205.486 -213.614)
		(end 205.486 -209.18678)
		(width 0.1397)
		(layer "In2.Cu")
		(net "PCIE_RX_N42")
	)
	(segment
		(start 246.696738 -67.169538)
		(end 246.696738 -63.30188)
		(width 0.1016)
		(layer "In2.Cu")
		(net "PCIE_RX_N42")
	)
	(segment
		(start 246.775732 -63.11138)
		(end 246.777002 -63.110364)
		(width 0.1016)
		(layer "In2.Cu")
		(net "PCIE_RX_N42")
	)
	(segment
		(start 203.349606 -197.070218)
		(end 208.668874 -166.89832)
		(width 0.1397)
		(layer "In2.Cu")
		(net "PCIE_RX_N42")
	)
	(arc
		(start 246.99595 -63.03518)
		(mid 247.069089 -63.049822)
		(end 247.131078 -63.091314)
		(width 0.1016)
		(layer "In2.Cu")
		(net "PCIE_RX_N42")
	)
	(arc
		(start 246.777002 -63.110364)
		(mid 246.860077 -63.054762)
		(end 246.958104 -63.03518)
		(width 0.1016)
		(layer "In2.Cu")
		(net "PCIE_RX_N42")
	)
	(arc
		(start 246.696738 -63.30188)
		(mid 246.703983 -63.240035)
		(end 246.725186 -63.181484)
		(width 0.1016)
		(layer "In2.Cu")
		(net "PCIE_RX_N42")
	)
	(arc
		(start 247.139968 -63.09995)
		(mid 247.186377 -63.169406)
		(end 247.202706 -63.251334)
		(width 0.1016)
		(layer "In2.Cu")
		(net "PCIE_RX_N42")
	)
	(arc
		(start 246.725186 -63.181484)
		(mid 246.747628 -63.14439)
		(end 246.775732 -63.11138)
		(width 0.1016)
		(layer "In2.Cu")
		(net "PCIE_RX_N42")
	)
	(arc
		(start 199.306434 -222.294704)
		(mid 199.127807 -222.02737)
		(end 199.065134 -221.712028)
		(width 0.1397)
		(layer "In2.Cu")
		(net "PCIE_RX_N42")
	)
	(arc
		(start 247.202706 -63.251334)
		(mid 247.175966 -63.385764)
		(end 247.099836 -63.499746)
		(width 0.1016)
		(layer "In2.Cu")
		(net "PCIE_RX_N42")
	)
	(segment
		(start 247.599962 -61.999876)
		(end 248.099834 -62.499748)
		(width 0.136652)
		(layer "F.Cu")
		(net "PCIE_RX_N41")
	)
	(via
		(at 248.099834 -62.499748)
		(size 0.4572)
		(drill 0.2032)
		(layers "F.Cu" "B.Cu")
		(net "PCIE_RX_N41")
	)
	(via
		(at 202.50658 -222.294704)
		(size 0.508)
		(drill 0.254)
		(layers "F.Cu" "B.Cu")
		(net "PCIE_RX_N41")
	)
	(segment
		(start 202.50023 -225.92538)
		(end 202.50023 -224.770188)
		(width 0.136652)
		(layer "B.Cu")
		(net "PCIE_RX_N41")
	)
	(segment
		(start 202.252834 -224.17278)
		(end 202.252834 -222.907352)
		(width 0.136652)
		(layer "B.Cu")
		(net "PCIE_RX_N41")
	)
	(arc
		(start 202.33005 -224.359216)
		(mid 202.272896 -224.273678)
		(end 202.252834 -224.17278)
		(width 0.136652)
		(layer "B.Cu")
		(net "PCIE_RX_N41")
	)
	(arc
		(start 202.50023 -224.770188)
		(mid 202.455992 -224.547791)
		(end 202.33005 -224.359216)
		(width 0.136652)
		(layer "B.Cu")
		(net "PCIE_RX_N41")
	)
	(arc
		(start 202.252834 -222.907352)
		(mid 202.318784 -222.575797)
		(end 202.50658 -222.294704)
		(width 0.136652)
		(layer "B.Cu")
		(net "PCIE_RX_N41")
	)
	(segment
		(start 247.696736 -67.128136)
		(end 247.696736 -62.301882)
		(width 0.1016)
		(layer "In2.Cu")
		(net "PCIE_RX_N41")
	)
	(segment
		(start 206.375 -187.96)
		(end 209.88528 -168.052242)
		(width 0.1397)
		(layer "In2.Cu")
		(net "PCIE_RX_N41")
	)
	(segment
		(start 203.017374 -219.985844)
		(end 206.499968 -217.54719)
		(width 0.1397)
		(layer "In2.Cu")
		(net "PCIE_RX_N41")
	)
	(segment
		(start 243.701824 -119.756682)
		(end 249.037094 -89.499186)
		(width 0.1397)
		(layer "In2.Cu")
		(net "PCIE_RX_N41")
	)
	(segment
		(start 202.26528 -221.059756)
		(end 203.017374 -219.985844)
		(width 0.1397)
		(layer "In2.Cu")
		(net "PCIE_RX_N41")
	)
	(segment
		(start 247.77573 -62.111382)
		(end 247.777 -62.110366)
		(width 0.1016)
		(layer "In2.Cu")
		(net "PCIE_RX_N41")
	)
	(segment
		(start 248.131076 -62.091316)
		(end 248.139966 -62.099952)
		(width 0.1016)
		(layer "In2.Cu")
		(net "PCIE_RX_N41")
	)
	(segment
		(start 209.595466 -206.224886)
		(end 206.375 -187.96)
		(width 0.1397)
		(layer "In2.Cu")
		(net "PCIE_RX_N41")
	)
	(segment
		(start 249.037094 -89.499186)
		(end 247.4214 -80.335628)
		(width 0.1397)
		(layer "In2.Cu")
		(net "PCIE_RX_N41")
	)
	(segment
		(start 207.969104 -215.44915)
		(end 209.595466 -206.224886)
		(width 0.1397)
		(layer "In2.Cu")
		(net "PCIE_RX_N41")
	)
	(segment
		(start 206.499968 -217.54719)
		(end 207.969104 -215.44915)
		(width 0.1397)
		(layer "In2.Cu")
		(net "PCIE_RX_N41")
	)
	(segment
		(start 248.565162 -73.849484)
		(end 247.7516 -69.235574)
		(width 0.1397)
		(layer "In2.Cu")
		(net "PCIE_RX_N41")
	)
	(segment
		(start 202.26528 -221.712028)
		(end 202.26528 -221.059756)
		(width 0.1397)
		(layer "In2.Cu")
		(net "PCIE_RX_N41")
	)
	(segment
		(start 247.4214 -80.335628)
		(end 248.565162 -73.849484)
		(width 0.1397)
		(layer "In2.Cu")
		(net "PCIE_RX_N41")
	)
	(segment
		(start 247.7516 -69.235574)
		(end 247.7516 -67.183)
		(width 0.1397)
		(layer "In2.Cu")
		(net "PCIE_RX_N41")
	)
	(segment
		(start 209.88528 -168.052242)
		(end 243.701824 -119.756682)
		(width 0.1397)
		(layer "In2.Cu")
		(net "PCIE_RX_N41")
	)
	(segment
		(start 247.7516 -67.183)
		(end 247.696736 -67.128136)
		(width 0.1016)
		(layer "In2.Cu")
		(net "PCIE_RX_N41")
	)
	(segment
		(start 247.958102 -62.035182)
		(end 247.995948 -62.035182)
		(width 0.1016)
		(layer "In2.Cu")
		(net "PCIE_RX_N41")
	)
	(arc
		(start 247.725184 -62.181486)
		(mid 247.747626 -62.144392)
		(end 247.77573 -62.111382)
		(width 0.1016)
		(layer "In2.Cu")
		(net "PCIE_RX_N41")
	)
	(arc
		(start 247.696736 -62.301882)
		(mid 247.703981 -62.240037)
		(end 247.725184 -62.181486)
		(width 0.1016)
		(layer "In2.Cu")
		(net "PCIE_RX_N41")
	)
	(arc
		(start 247.995948 -62.035182)
		(mid 248.069087 -62.049824)
		(end 248.131076 -62.091316)
		(width 0.1016)
		(layer "In2.Cu")
		(net "PCIE_RX_N41")
	)
	(arc
		(start 248.139966 -62.099952)
		(mid 248.186375 -62.169408)
		(end 248.202704 -62.251336)
		(width 0.1016)
		(layer "In2.Cu")
		(net "PCIE_RX_N41")
	)
	(arc
		(start 248.202704 -62.251336)
		(mid 248.175964 -62.385766)
		(end 248.099834 -62.499748)
		(width 0.1016)
		(layer "In2.Cu")
		(net "PCIE_RX_N41")
	)
	(arc
		(start 202.50658 -222.294704)
		(mid 202.327953 -222.02737)
		(end 202.26528 -221.712028)
		(width 0.1397)
		(layer "In2.Cu")
		(net "PCIE_RX_N41")
	)
	(arc
		(start 247.777 -62.110366)
		(mid 247.860075 -62.054764)
		(end 247.958102 -62.035182)
		(width 0.1016)
		(layer "In2.Cu")
		(net "PCIE_RX_N41")
	)
	(segment
		(start 248.59996 -62.999874)
		(end 249.099832 -63.499746)
		(width 0.136652)
		(layer "F.Cu")
		(net "PCIE_RX_N40")
	)
	(via
		(at 205.706472 -222.294704)
		(size 0.508)
		(drill 0.254)
		(layers "F.Cu" "B.Cu")
		(net "PCIE_RX_N40")
	)
	(via
		(at 249.099832 -63.499746)
		(size 0.4572)
		(drill 0.2032)
		(layers "F.Cu" "B.Cu")
		(net "PCIE_RX_N40")
	)
	(segment
		(start 205.700122 -225.92538)
		(end 205.700122 -224.770188)
		(width 0.136652)
		(layer "B.Cu")
		(net "PCIE_RX_N40")
	)
	(segment
		(start 205.452726 -224.17278)
		(end 205.452726 -222.907352)
		(width 0.136652)
		(layer "B.Cu")
		(net "PCIE_RX_N40")
	)
	(arc
		(start 205.529942 -224.359216)
		(mid 205.472788 -224.273678)
		(end 205.452726 -224.17278)
		(width 0.136652)
		(layer "B.Cu")
		(net "PCIE_RX_N40")
	)
	(arc
		(start 205.700122 -224.770188)
		(mid 205.655884 -224.547791)
		(end 205.529942 -224.359216)
		(width 0.136652)
		(layer "B.Cu")
		(net "PCIE_RX_N40")
	)
	(arc
		(start 205.452726 -222.907352)
		(mid 205.518676 -222.575797)
		(end 205.706472 -222.294704)
		(width 0.136652)
		(layer "B.Cu")
		(net "PCIE_RX_N40")
	)
	(segment
		(start 244.364256 -121.151396)
		(end 210.725512 -169.192956)
		(width 0.1397)
		(layer "In2.Cu")
		(net "PCIE_RX_N40")
	)
	(segment
		(start 248.696734 -67.137534)
		(end 248.7676 -67.2084)
		(width 0.1016)
		(layer "In2.Cu")
		(net "PCIE_RX_N40")
	)
	(segment
		(start 248.995946 -63.03518)
		(end 248.9581 -63.03518)
		(width 0.1016)
		(layer "In2.Cu")
		(net "PCIE_RX_N40")
	)
	(segment
		(start 248.696734 -63.30188)
		(end 248.696734 -67.137534)
		(width 0.1016)
		(layer "In2.Cu")
		(net "PCIE_RX_N40")
	)
	(segment
		(start 249.139964 -63.09995)
		(end 249.131074 -63.091314)
		(width 0.1016)
		(layer "In2.Cu")
		(net "PCIE_RX_N40")
	)
	(segment
		(start 208.846166 -216.035636)
		(end 205.57998 -220.699838)
		(width 0.1397)
		(layer "In2.Cu")
		(net "PCIE_RX_N40")
	)
	(segment
		(start 210.589114 -206.151734)
		(end 208.846166 -216.035636)
		(width 0.1397)
		(layer "In2.Cu")
		(net "PCIE_RX_N40")
	)
	(segment
		(start 248.332244 -80.526382)
		(end 249.929904 -89.58707)
		(width 0.1397)
		(layer "In2.Cu")
		(net "PCIE_RX_N40")
	)
	(segment
		(start 207.398874 -188.058552)
		(end 210.589114 -206.151734)
		(width 0.1397)
		(layer "In2.Cu")
		(net "PCIE_RX_N40")
	)
	(segment
		(start 249.545348 -73.646538)
		(end 248.332244 -80.526382)
		(width 0.1397)
		(layer "In2.Cu")
		(net "PCIE_RX_N40")
	)
	(segment
		(start 205.465172 -221.064074)
		(end 205.465172 -221.712028)
		(width 0.1397)
		(layer "In2.Cu")
		(net "PCIE_RX_N40")
	)
	(segment
		(start 248.776998 -63.110364)
		(end 248.775728 -63.11138)
		(width 0.1016)
		(layer "In2.Cu")
		(net "PCIE_RX_N40")
	)
	(segment
		(start 248.7676 -67.2084)
		(end 248.7676 -69.235574)
		(width 0.1397)
		(layer "In2.Cu")
		(net "PCIE_RX_N40")
	)
	(segment
		(start 249.929904 -89.58707)
		(end 244.364256 -121.151396)
		(width 0.1397)
		(layer "In2.Cu")
		(net "PCIE_RX_N40")
	)
	(segment
		(start 210.725512 -169.192956)
		(end 207.398874 -188.058552)
		(width 0.1397)
		(layer "In2.Cu")
		(net "PCIE_RX_N40")
	)
	(segment
		(start 248.7676 -69.235574)
		(end 249.545348 -73.646538)
		(width 0.1397)
		(layer "In2.Cu")
		(net "PCIE_RX_N40")
	)
	(arc
		(start 248.9581 -63.03518)
		(mid 248.860077 -63.054772)
		(end 248.776998 -63.110364)
		(width 0.1016)
		(layer "In2.Cu")
		(net "PCIE_RX_N40")
	)
	(arc
		(start 205.57998 -220.699838)
		(mid 205.494529 -220.873118)
		(end 205.465172 -221.064074)
		(width 0.1397)
		(layer "In2.Cu")
		(net "PCIE_RX_N40")
	)
	(arc
		(start 248.725182 -63.181484)
		(mid 248.703947 -63.240027)
		(end 248.696734 -63.30188)
		(width 0.1016)
		(layer "In2.Cu")
		(net "PCIE_RX_N40")
	)
	(arc
		(start 249.099832 -63.499746)
		(mid 249.175986 -63.385774)
		(end 249.202702 -63.251334)
		(width 0.1016)
		(layer "In2.Cu")
		(net "PCIE_RX_N40")
	)
	(arc
		(start 249.131074 -63.091314)
		(mid 249.069092 -63.049806)
		(end 248.995946 -63.03518)
		(width 0.1016)
		(layer "In2.Cu")
		(net "PCIE_RX_N40")
	)
	(arc
		(start 249.202702 -63.251334)
		(mid 249.186403 -63.169393)
		(end 249.139964 -63.09995)
		(width 0.1016)
		(layer "In2.Cu")
		(net "PCIE_RX_N40")
	)
	(arc
		(start 248.775728 -63.11138)
		(mid 248.747636 -63.144399)
		(end 248.725182 -63.181484)
		(width 0.1016)
		(layer "In2.Cu")
		(net "PCIE_RX_N40")
	)
	(arc
		(start 205.465172 -221.712028)
		(mid 205.527893 -222.02735)
		(end 205.706472 -222.294704)
		(width 0.1397)
		(layer "In2.Cu")
		(net "PCIE_RX_N40")
	)
	(segment
		(start 246.599964 -29.99994)
		(end 247.099836 -29.500068)
		(width 0.136652)
		(layer "F.Cu")
		(net "PCIE_RX_N4")
	)
	(via
		(at 247.099836 -29.500068)
		(size 0.4572)
		(drill 0.2032)
		(layers "F.Cu" "B.Cu")
		(net "PCIE_RX_N4")
	)
	(via
		(at 282.6258 -20.4978)
		(size 0.508)
		(drill 0.254)
		(layers "F.Cu" "B.Cu")
		(net "PCIE_RX_N4")
	)
	(segment
		(start 281.8892 -21.880576)
		(end 281.8892 -21.9964)
		(width 0.136652)
		(layer "B.Cu")
		(net "PCIE_RX_N4")
	)
	(segment
		(start 294.437054 -20.658582)
		(end 295.251886 -18.635726)
		(width 0.136652)
		(layer "B.Cu")
		(net "PCIE_RX_N4")
	)
	(segment
		(start 282.10129 -21.34743)
		(end 282.098242 -21.350732)
		(width 0.136652)
		(layer "B.Cu")
		(net "PCIE_RX_N4")
	)
	(segment
		(start 292.554152 -22.684994)
		(end 294.156384 -21.083016)
		(width 0.136652)
		(layer "B.Cu")
		(net "PCIE_RX_N4")
	)
	(segment
		(start 291.947346 -22.9362)
		(end 291.9476 -22.936454)
		(width 0.136652)
		(layer "B.Cu")
		(net "PCIE_RX_N4")
	)
	(segment
		(start 298.069254 -15.406878)
		(end 299.76191 -15.047214)
		(width 0.136652)
		(layer "B.Cu")
		(net "PCIE_RX_N4")
	)
	(segment
		(start 282.829 -22.9362)
		(end 291.947346 -22.9362)
		(width 0.136652)
		(layer "B.Cu")
		(net "PCIE_RX_N4")
	)
	(segment
		(start 300.26737 -14.422882)
		(end 300.26737 -14.027912)
		(width 0.136652)
		(layer "B.Cu")
		(net "PCIE_RX_N4")
	)
	(segment
		(start 296.99585 -16.00327)
		(end 297.639994 -15.584678)
		(width 0.136652)
		(layer "B.Cu")
		(net "PCIE_RX_N4")
	)
	(segment
		(start 295.522142 -18.115788)
		(end 296.706036 -16.293084)
		(width 0.136652)
		(layer "B.Cu")
		(net "PCIE_RX_N4")
	)
	(segment
		(start 300.134274 -12.754864)
		(end 300.134274 -12.530074)
		(width 0.136652)
		(layer "B.Cu")
		(net "PCIE_RX_N4")
	)
	(segment
		(start 282.476956 -20.971764)
		(end 282.10129 -21.34743)
		(width 0.136652)
		(layer "B.Cu")
		(net "PCIE_RX_N4")
	)
	(arc
		(start 281.8892 -21.9964)
		(mid 282.164461 -22.660939)
		(end 282.829 -22.9362)
		(width 0.136652)
		(layer "B.Cu")
		(net "PCIE_RX_N4")
	)
	(arc
		(start 291.9476 -22.936454)
		(mid 292.275893 -22.871059)
		(end 292.554152 -22.684994)
		(width 0.136652)
		(layer "B.Cu")
		(net "PCIE_RX_N4")
	)
	(arc
		(start 300.26737 -14.027912)
		(mid 300.265366 -13.941582)
		(end 300.259242 -13.855446)
		(width 0.136652)
		(layer "B.Cu")
		(net "PCIE_RX_N4")
	)
	(arc
		(start 282.6258 -20.4978)
		(mid 282.587715 -20.746193)
		(end 282.476956 -20.971764)
		(width 0.136652)
		(layer "B.Cu")
		(net "PCIE_RX_N4")
	)
	(arc
		(start 282.098242 -21.350732)
		(mid 281.943325 -21.595768)
		(end 281.8892 -21.880576)
		(width 0.136652)
		(layer "B.Cu")
		(net "PCIE_RX_N4")
	)
	(arc
		(start 297.639994 -15.584678)
		(mid 297.846449 -15.476045)
		(end 298.069254 -15.406878)
		(width 0.136652)
		(layer "B.Cu")
		(net "PCIE_RX_N4")
	)
	(arc
		(start 295.251886 -18.635726)
		(mid 295.374464 -18.369234)
		(end 295.522142 -18.115788)
		(width 0.136652)
		(layer "B.Cu")
		(net "PCIE_RX_N4")
	)
	(arc
		(start 294.156384 -21.083016)
		(mid 294.318168 -20.884982)
		(end 294.437054 -20.658582)
		(width 0.136652)
		(layer "B.Cu")
		(net "PCIE_RX_N4")
	)
	(arc
		(start 300.228254 -13.653008)
		(mid 300.157819 -13.206389)
		(end 300.134274 -12.754864)
		(width 0.136652)
		(layer "B.Cu")
		(net "PCIE_RX_N4")
	)
	(arc
		(start 300.259242 -13.855446)
		(mid 300.246614 -13.753788)
		(end 300.228254 -13.653008)
		(width 0.136652)
		(layer "B.Cu")
		(net "PCIE_RX_N4")
	)
	(arc
		(start 296.706036 -16.293084)
		(mid 296.835721 -16.132955)
		(end 296.99585 -16.00327)
		(width 0.136652)
		(layer "B.Cu")
		(net "PCIE_RX_N4")
	)
	(arc
		(start 299.76191 -15.047214)
		(mid 300.125169 -14.824531)
		(end 300.26737 -14.422882)
		(width 0.136652)
		(layer "B.Cu")
		(net "PCIE_RX_N4")
	)
	(segment
		(start 260.670548 -20.567396)
		(end 259.082794 -20.249896)
		(width 0.1397)
		(layer "In2.Cu")
		(net "PCIE_RX_N4")
	)
	(segment
		(start 282.291536 -21.123656)
		(end 282.218384 -21.189442)
		(width 0.1397)
		(layer "In2.Cu")
		(net "PCIE_RX_N4")
	)
	(segment
		(start 253.675642 -20.574)
		(end 247.278144 -26.971498)
		(width 0.1397)
		(layer "In2.Cu")
		(net "PCIE_RX_N4")
	)
	(segment
		(start 247.278144 -26.971498)
		(end 247.278144 -29.04363)
		(width 0.1397)
		(layer "In2.Cu")
		(net "PCIE_RX_N4")
	)
	(segment
		(start 272.49247 -20.723606)
		(end 269.36573 -20.098258)
		(width 0.1397)
		(layer "In2.Cu")
		(net "PCIE_RX_N4")
	)
	(segment
		(start 278.275034 -20.114768)
		(end 277.167086 -19.919442)
		(width 0.1397)
		(layer "In2.Cu")
		(net "PCIE_RX_N4")
	)
	(segment
		(start 263.845548 -19.932396)
		(end 260.670548 -20.567396)
		(width 0.1397)
		(layer "In2.Cu")
		(net "PCIE_RX_N4")
	)
	(segment
		(start 279.430734 -20.318476)
		(end 278.275034 -20.114768)
		(width 0.1397)
		(layer "In2.Cu")
		(net "PCIE_RX_N4")
	)
	(segment
		(start 277.109936 -19.909282)
		(end 272.49247 -20.723606)
		(width 0.1397)
		(layer "In2.Cu")
		(net "PCIE_RX_N4")
	)
	(segment
		(start 277.167086 -19.919442)
		(end 277.167086 -19.919188)
		(width 0.1397)
		(layer "In2.Cu")
		(net "PCIE_RX_N4")
	)
	(segment
		(start 259.082794 -20.249896)
		(end 257.495548 -19.932396)
		(width 0.1397)
		(layer "In2.Cu")
		(net "PCIE_RX_N4")
	)
	(segment
		(start 267.020548 -20.567396)
		(end 263.845548 -19.932396)
		(width 0.1397)
		(layer "In2.Cu")
		(net "PCIE_RX_N4")
	)
	(segment
		(start 269.36573 -20.098258)
		(end 267.020548 -20.567396)
		(width 0.1397)
		(layer "In2.Cu")
		(net "PCIE_RX_N4")
	)
	(segment
		(start 277.167086 -19.919188)
		(end 277.109936 -19.909282)
		(width 0.1397)
		(layer "In2.Cu")
		(net "PCIE_RX_N4")
	)
	(segment
		(start 281.164538 -21.189442)
		(end 279.430734 -20.318476)
		(width 0.1397)
		(layer "In2.Cu")
		(net "PCIE_RX_N4")
	)
	(segment
		(start 282.218384 -21.189442)
		(end 281.164538 -21.189442)
		(width 0.1397)
		(layer "In2.Cu")
		(net "PCIE_RX_N4")
	)
	(segment
		(start 257.495548 -19.932396)
		(end 253.675642 -20.574)
		(width 0.1397)
		(layer "In2.Cu")
		(net "PCIE_RX_N4")
	)
	(arc
		(start 282.6258 -20.4978)
		(mid 282.537003 -20.852571)
		(end 282.291536 -21.123656)
		(width 0.1397)
		(layer "In2.Cu")
		(net "PCIE_RX_N4")
	)
	(arc
		(start 247.278144 -29.04363)
		(mid 247.231985 -29.288645)
		(end 247.099836 -29.500068)
		(width 0.1397)
		(layer "In2.Cu")
		(net "PCIE_RX_N4")
	)
	(segment
		(start 250.599956 -61.999876)
		(end 251.099828 -62.499748)
		(width 0.136652)
		(layer "F.Cu")
		(net "PCIE_RX_N39")
	)
	(via
		(at 212.10651 -222.294704)
		(size 0.508)
		(drill 0.254)
		(layers "F.Cu" "B.Cu")
		(net "PCIE_RX_N39")
	)
	(via
		(at 251.099828 -62.499748)
		(size 0.4572)
		(drill 0.2032)
		(layers "F.Cu" "B.Cu")
		(net "PCIE_RX_N39")
	)
	(segment
		(start 212.10016 -225.92538)
		(end 212.10016 -224.770188)
		(width 0.136652)
		(layer "B.Cu")
		(net "PCIE_RX_N39")
	)
	(segment
		(start 211.852764 -224.17278)
		(end 211.852764 -222.907352)
		(width 0.136652)
		(layer "B.Cu")
		(net "PCIE_RX_N39")
	)
	(arc
		(start 211.852764 -222.907352)
		(mid 211.918714 -222.575797)
		(end 212.10651 -222.294704)
		(width 0.136652)
		(layer "B.Cu")
		(net "PCIE_RX_N39")
	)
	(arc
		(start 212.10016 -224.770188)
		(mid 212.055922 -224.547791)
		(end 211.92998 -224.359216)
		(width 0.136652)
		(layer "B.Cu")
		(net "PCIE_RX_N39")
	)
	(arc
		(start 211.92998 -224.359216)
		(mid 211.872826 -224.273678)
		(end 211.852764 -224.17278)
		(width 0.136652)
		(layer "B.Cu")
		(net "PCIE_RX_N39")
	)
	(segment
		(start 211.950554 -169.728642)
		(end 245.349776 -122.02922)
		(width 0.1397)
		(layer "In2.Cu")
		(net "PCIE_RX_N39")
	)
	(segment
		(start 250.7488 -67.183)
		(end 250.69673 -67.13093)
		(width 0.1016)
		(layer "In2.Cu")
		(net "PCIE_RX_N39")
	)
	(segment
		(start 251.46 -87.376)
		(end 250.23953 -80.455008)
		(width 0.1397)
		(layer "In2.Cu")
		(net "PCIE_RX_N39")
	)
	(segment
		(start 250.7488 -69.49948)
		(end 250.7488 -67.183)
		(width 0.1397)
		(layer "In2.Cu")
		(net "PCIE_RX_N39")
	)
	(segment
		(start 211.86521 -219.629228)
		(end 212.306408 -217.127582)
		(width 0.1397)
		(layer "In2.Cu")
		(net "PCIE_RX_N39")
	)
	(segment
		(start 211.29625 -211.256372)
		(end 212.09 -206.756)
		(width 0.1397)
		(layer "In2.Cu")
		(net "PCIE_RX_N39")
	)
	(segment
		(start 208.755742 -187.846716)
		(end 211.950554 -169.728642)
		(width 0.1397)
		(layer "In2.Cu")
		(net "PCIE_RX_N39")
	)
	(segment
		(start 211.29625 -211.386928)
		(end 211.29625 -211.256372)
		(width 0.1397)
		(layer "In2.Cu")
		(net "PCIE_RX_N39")
	)
	(segment
		(start 212.306408 -217.127582)
		(end 211.29625 -211.386928)
		(width 0.1397)
		(layer "In2.Cu")
		(net "PCIE_RX_N39")
	)
	(segment
		(start 250.23953 -80.455008)
		(end 251.46 -73.533)
		(width 0.1397)
		(layer "In2.Cu")
		(net "PCIE_RX_N39")
	)
	(segment
		(start 250.958096 -62.035182)
		(end 250.995942 -62.035182)
		(width 0.1016)
		(layer "In2.Cu")
		(net "PCIE_RX_N39")
	)
	(segment
		(start 245.349776 -122.02922)
		(end 251.46 -87.376)
		(width 0.1397)
		(layer "In2.Cu")
		(net "PCIE_RX_N39")
	)
	(segment
		(start 251.13107 -62.091316)
		(end 251.13996 -62.099952)
		(width 0.1016)
		(layer "In2.Cu")
		(net "PCIE_RX_N39")
	)
	(segment
		(start 250.69673 -67.13093)
		(end 250.69673 -62.301882)
		(width 0.1016)
		(layer "In2.Cu")
		(net "PCIE_RX_N39")
	)
	(segment
		(start 251.46 -73.533)
		(end 250.7488 -69.49948)
		(width 0.1397)
		(layer "In2.Cu")
		(net "PCIE_RX_N39")
	)
	(segment
		(start 212.09 -206.756)
		(end 208.755742 -187.846716)
		(width 0.1397)
		(layer "In2.Cu")
		(net "PCIE_RX_N39")
	)
	(segment
		(start 250.775724 -62.111382)
		(end 250.776994 -62.110366)
		(width 0.1016)
		(layer "In2.Cu")
		(net "PCIE_RX_N39")
	)
	(segment
		(start 211.86521 -221.712028)
		(end 211.86521 -219.629228)
		(width 0.1397)
		(layer "In2.Cu")
		(net "PCIE_RX_N39")
	)
	(arc
		(start 212.10651 -222.294704)
		(mid 211.927883 -222.02737)
		(end 211.86521 -221.712028)
		(width 0.1397)
		(layer "In2.Cu")
		(net "PCIE_RX_N39")
	)
	(arc
		(start 250.725178 -62.181486)
		(mid 250.74762 -62.144392)
		(end 250.775724 -62.111382)
		(width 0.1016)
		(layer "In2.Cu")
		(net "PCIE_RX_N39")
	)
	(arc
		(start 250.995942 -62.035182)
		(mid 251.069081 -62.049824)
		(end 251.13107 -62.091316)
		(width 0.1016)
		(layer "In2.Cu")
		(net "PCIE_RX_N39")
	)
	(arc
		(start 251.202698 -62.251336)
		(mid 251.175958 -62.385766)
		(end 251.099828 -62.499748)
		(width 0.1016)
		(layer "In2.Cu")
		(net "PCIE_RX_N39")
	)
	(arc
		(start 250.776994 -62.110366)
		(mid 250.860069 -62.054764)
		(end 250.958096 -62.035182)
		(width 0.1016)
		(layer "In2.Cu")
		(net "PCIE_RX_N39")
	)
	(arc
		(start 251.13996 -62.099952)
		(mid 251.186369 -62.169408)
		(end 251.202698 -62.251336)
		(width 0.1016)
		(layer "In2.Cu")
		(net "PCIE_RX_N39")
	)
	(arc
		(start 250.69673 -62.301882)
		(mid 250.703975 -62.240037)
		(end 250.725178 -62.181486)
		(width 0.1016)
		(layer "In2.Cu")
		(net "PCIE_RX_N39")
	)
	(segment
		(start 251.599954 -62.999874)
		(end 252.099826 -63.499746)
		(width 0.136652)
		(layer "F.Cu")
		(net "PCIE_RX_N38")
	)
	(via
		(at 252.099826 -63.499746)
		(size 0.4572)
		(drill 0.2032)
		(layers "F.Cu" "B.Cu")
		(net "PCIE_RX_N38")
	)
	(via
		(at 215.306402 -222.294704)
		(size 0.508)
		(drill 0.254)
		(layers "F.Cu" "B.Cu")
		(net "PCIE_RX_N38")
	)
	(segment
		(start 215.052656 -224.17278)
		(end 215.052656 -222.907352)
		(width 0.136652)
		(layer "B.Cu")
		(net "PCIE_RX_N38")
	)
	(segment
		(start 215.300052 -225.92538)
		(end 215.300052 -224.770188)
		(width 0.136652)
		(layer "B.Cu")
		(net "PCIE_RX_N38")
	)
	(arc
		(start 215.300052 -224.770188)
		(mid 215.255814 -224.547791)
		(end 215.129872 -224.359216)
		(width 0.136652)
		(layer "B.Cu")
		(net "PCIE_RX_N38")
	)
	(arc
		(start 215.129872 -224.359216)
		(mid 215.072718 -224.273678)
		(end 215.052656 -224.17278)
		(width 0.136652)
		(layer "B.Cu")
		(net "PCIE_RX_N38")
	)
	(arc
		(start 215.052656 -222.907352)
		(mid 215.118606 -222.575797)
		(end 215.306402 -222.294704)
		(width 0.136652)
		(layer "B.Cu")
		(net "PCIE_RX_N38")
	)
	(segment
		(start 251.760736 -69.235574)
		(end 251.760736 -67.204336)
		(width 0.1397)
		(layer "In2.Cu")
		(net "PCIE_RX_N38")
	)
	(segment
		(start 214.685118 -207.447896)
		(end 213.465918 -205.706726)
		(width 0.1397)
		(layer "In2.Cu")
		(net "PCIE_RX_N38")
	)
	(segment
		(start 213.465918 -205.706726)
		(end 210.201764 -187.193682)
		(width 0.1397)
		(layer "In2.Cu")
		(net "PCIE_RX_N38")
	)
	(segment
		(start 210.201764 -187.193682)
		(end 213.137496 -170.543728)
		(width 0.1397)
		(layer "In2.Cu")
		(net "PCIE_RX_N38")
	)
	(segment
		(start 214.783162 -218.645994)
		(end 215.345264 -215.458548)
		(width 0.1397)
		(layer "In2.Cu")
		(net "PCIE_RX_N38")
	)
	(segment
		(start 251.329952 -80.099154)
		(end 252.503178 -73.445878)
		(width 0.1397)
		(layer "In2.Cu")
		(net "PCIE_RX_N38")
	)
	(segment
		(start 246.403876 -123.034806)
		(end 252.652276 -87.598504)
		(width 0.1397)
		(layer "In2.Cu")
		(net "PCIE_RX_N38")
	)
	(segment
		(start 215.065102 -221.712028)
		(end 215.065102 -220.24467)
		(width 0.1397)
		(layer "In2.Cu")
		(net "PCIE_RX_N38")
	)
	(segment
		(start 215.011 -209.296)
		(end 214.685118 -207.447896)
		(width 0.1397)
		(layer "In2.Cu")
		(net "PCIE_RX_N38")
	)
	(segment
		(start 252.652276 -87.598504)
		(end 251.329952 -80.099154)
		(width 0.1397)
		(layer "In2.Cu")
		(net "PCIE_RX_N38")
	)
	(segment
		(start 215.345264 -215.458548)
		(end 215.011 -213.5632)
		(width 0.1397)
		(layer "In2.Cu")
		(net "PCIE_RX_N38")
	)
	(segment
		(start 251.958094 -63.03518)
		(end 251.99594 -63.03518)
		(width 0.1016)
		(layer "In2.Cu")
		(net "PCIE_RX_N38")
	)
	(segment
		(start 251.696728 -67.140328)
		(end 251.696728 -63.30188)
		(width 0.1016)
		(layer "In2.Cu")
		(net "PCIE_RX_N38")
	)
	(segment
		(start 215.065102 -220.24467)
		(end 214.783162 -218.645994)
		(width 0.1397)
		(layer "In2.Cu")
		(net "PCIE_RX_N38")
	)
	(segment
		(start 251.760736 -67.204336)
		(end 251.696728 -67.140328)
		(width 0.1016)
		(layer "In2.Cu")
		(net "PCIE_RX_N38")
	)
	(segment
		(start 215.011 -213.5632)
		(end 215.011 -209.296)
		(width 0.1397)
		(layer "In2.Cu")
		(net "PCIE_RX_N38")
	)
	(segment
		(start 213.137496 -170.543728)
		(end 246.403876 -123.034806)
		(width 0.1397)
		(layer "In2.Cu")
		(net "PCIE_RX_N38")
	)
	(segment
		(start 251.775722 -63.11138)
		(end 251.776992 -63.110364)
		(width 0.1016)
		(layer "In2.Cu")
		(net "PCIE_RX_N38")
	)
	(segment
		(start 252.131068 -63.091314)
		(end 252.139958 -63.09995)
		(width 0.1016)
		(layer "In2.Cu")
		(net "PCIE_RX_N38")
	)
	(segment
		(start 252.503178 -73.445878)
		(end 251.760736 -69.235574)
		(width 0.1397)
		(layer "In2.Cu")
		(net "PCIE_RX_N38")
	)
	(arc
		(start 215.306402 -222.294704)
		(mid 215.127775 -222.02737)
		(end 215.065102 -221.712028)
		(width 0.1397)
		(layer "In2.Cu")
		(net "PCIE_RX_N38")
	)
	(arc
		(start 251.99594 -63.03518)
		(mid 252.069079 -63.049822)
		(end 252.131068 -63.091314)
		(width 0.1016)
		(layer "In2.Cu")
		(net "PCIE_RX_N38")
	)
	(arc
		(start 251.776992 -63.110364)
		(mid 251.860067 -63.054762)
		(end 251.958094 -63.03518)
		(width 0.1016)
		(layer "In2.Cu")
		(net "PCIE_RX_N38")
	)
	(arc
		(start 252.202696 -63.251334)
		(mid 252.175956 -63.385764)
		(end 252.099826 -63.499746)
		(width 0.1016)
		(layer "In2.Cu")
		(net "PCIE_RX_N38")
	)
	(arc
		(start 251.696728 -63.30188)
		(mid 251.703973 -63.240035)
		(end 251.725176 -63.181484)
		(width 0.1016)
		(layer "In2.Cu")
		(net "PCIE_RX_N38")
	)
	(arc
		(start 251.725176 -63.181484)
		(mid 251.747618 -63.14439)
		(end 251.775722 -63.11138)
		(width 0.1016)
		(layer "In2.Cu")
		(net "PCIE_RX_N38")
	)
	(arc
		(start 252.139958 -63.09995)
		(mid 252.186367 -63.169406)
		(end 252.202696 -63.251334)
		(width 0.1016)
		(layer "In2.Cu")
		(net "PCIE_RX_N38")
	)
	(segment
		(start 252.599952 -61.999876)
		(end 253.099824 -62.499748)
		(width 0.136652)
		(layer "F.Cu")
		(net "PCIE_RX_N37")
	)
	(via
		(at 253.099824 -62.499748)
		(size 0.4572)
		(drill 0.2032)
		(layers "F.Cu" "B.Cu")
		(net "PCIE_RX_N37")
	)
	(via
		(at 263.706356 -222.294704)
		(size 0.508)
		(drill 0.254)
		(layers "F.Cu" "B.Cu")
		(net "PCIE_RX_N37")
	)
	(segment
		(start 263.45261 -224.17278)
		(end 263.45261 -222.907352)
		(width 0.136652)
		(layer "B.Cu")
		(net "PCIE_RX_N37")
	)
	(segment
		(start 263.700006 -225.92538)
		(end 263.700006 -224.770188)
		(width 0.136652)
		(layer "B.Cu")
		(net "PCIE_RX_N37")
	)
	(arc
		(start 263.45261 -222.907352)
		(mid 263.51856 -222.575797)
		(end 263.706356 -222.294704)
		(width 0.136652)
		(layer "B.Cu")
		(net "PCIE_RX_N37")
	)
	(arc
		(start 263.529826 -224.359216)
		(mid 263.472672 -224.273678)
		(end 263.45261 -224.17278)
		(width 0.136652)
		(layer "B.Cu")
		(net "PCIE_RX_N37")
	)
	(arc
		(start 263.700006 -224.770188)
		(mid 263.655768 -224.547791)
		(end 263.529826 -224.359216)
		(width 0.136652)
		(layer "B.Cu")
		(net "PCIE_RX_N37")
	)
	(segment
		(start 263.706356 -222.294704)
		(end 263.649206 -222.237808)
		(width 0.1397)
		(layer "In2.Cu")
		(net "PCIE_RX_N37")
	)
	(segment
		(start 252.696726 -67.124326)
		(end 252.696726 -62.301882)
		(width 0.1016)
		(layer "In2.Cu")
		(net "PCIE_RX_N37")
	)
	(segment
		(start 252.781054 -67.208654)
		(end 252.696726 -67.124326)
		(width 0.1016)
		(layer "In2.Cu")
		(net "PCIE_RX_N37")
	)
	(segment
		(start 252.958092 -62.035182)
		(end 252.995938 -62.035182)
		(width 0.1016)
		(layer "In2.Cu")
		(net "PCIE_RX_N37")
	)
	(segment
		(start 272.1864 -156.845)
		(end 260.332728 -89.619836)
		(width 0.1397)
		(layer "In2.Cu")
		(net "PCIE_RX_N37")
	)
	(segment
		(start 263.465056 -219.116148)
		(end 262.335772 -212.71103)
		(width 0.1397)
		(layer "In2.Cu")
		(net "PCIE_RX_N37")
	)
	(segment
		(start 252.781054 -69.235574)
		(end 252.781054 -67.208654)
		(width 0.1397)
		(layer "In2.Cu")
		(net "PCIE_RX_N37")
	)
	(segment
		(start 263.465056 -221.7928)
		(end 263.465056 -219.116148)
		(width 0.1397)
		(layer "In2.Cu")
		(net "PCIE_RX_N37")
	)
	(segment
		(start 253.131066 -62.091316)
		(end 253.139956 -62.099952)
		(width 0.1016)
		(layer "In2.Cu")
		(net "PCIE_RX_N37")
	)
	(segment
		(start 252.77572 -62.111382)
		(end 252.77699 -62.110366)
		(width 0.1016)
		(layer "In2.Cu")
		(net "PCIE_RX_N37")
	)
	(segment
		(start 262.335772 -212.71103)
		(end 272.1864 -156.845)
		(width 0.1397)
		(layer "In2.Cu")
		(net "PCIE_RX_N37")
	)
	(segment
		(start 254.003302 -76.167742)
		(end 252.781054 -69.235574)
		(width 0.1397)
		(layer "In2.Cu")
		(net "PCIE_RX_N37")
	)
	(segment
		(start 260.332728 -89.619836)
		(end 254.003302 -76.167742)
		(width 0.1397)
		(layer "In2.Cu")
		(net "PCIE_RX_N37")
	)
	(arc
		(start 252.77699 -62.110366)
		(mid 252.860065 -62.054764)
		(end 252.958092 -62.035182)
		(width 0.1016)
		(layer "In2.Cu")
		(net "PCIE_RX_N37")
	)
	(arc
		(start 263.649206 -222.237808)
		(mid 263.512866 -222.033622)
		(end 263.465056 -221.7928)
		(width 0.1397)
		(layer "In2.Cu")
		(net "PCIE_RX_N37")
	)
	(arc
		(start 253.202694 -62.251336)
		(mid 253.175954 -62.385766)
		(end 253.099824 -62.499748)
		(width 0.1016)
		(layer "In2.Cu")
		(net "PCIE_RX_N37")
	)
	(arc
		(start 252.995938 -62.035182)
		(mid 253.069077 -62.049824)
		(end 253.131066 -62.091316)
		(width 0.1016)
		(layer "In2.Cu")
		(net "PCIE_RX_N37")
	)
	(arc
		(start 252.696726 -62.301882)
		(mid 252.703971 -62.240037)
		(end 252.725174 -62.181486)
		(width 0.1016)
		(layer "In2.Cu")
		(net "PCIE_RX_N37")
	)
	(arc
		(start 253.139956 -62.099952)
		(mid 253.186365 -62.169408)
		(end 253.202694 -62.251336)
		(width 0.1016)
		(layer "In2.Cu")
		(net "PCIE_RX_N37")
	)
	(arc
		(start 252.725174 -62.181486)
		(mid 252.747616 -62.144392)
		(end 252.77572 -62.111382)
		(width 0.1016)
		(layer "In2.Cu")
		(net "PCIE_RX_N37")
	)
	(segment
		(start 253.59995 -62.999874)
		(end 254.099822 -63.499746)
		(width 0.136652)
		(layer "F.Cu")
		(net "PCIE_RX_N36")
	)
	(via
		(at 266.906502 -222.294704)
		(size 0.508)
		(drill 0.254)
		(layers "F.Cu" "B.Cu")
		(net "PCIE_RX_N36")
	)
	(via
		(at 254.099822 -63.499746)
		(size 0.4572)
		(drill 0.2032)
		(layers "F.Cu" "B.Cu")
		(net "PCIE_RX_N36")
	)
	(segment
		(start 266.900152 -225.92538)
		(end 266.900152 -224.770188)
		(width 0.136652)
		(layer "B.Cu")
		(net "PCIE_RX_N36")
	)
	(segment
		(start 266.652756 -224.17278)
		(end 266.652756 -222.907352)
		(width 0.136652)
		(layer "B.Cu")
		(net "PCIE_RX_N36")
	)
	(arc
		(start 266.900152 -224.770188)
		(mid 266.855914 -224.547791)
		(end 266.729972 -224.359216)
		(width 0.136652)
		(layer "B.Cu")
		(net "PCIE_RX_N36")
	)
	(arc
		(start 266.652756 -222.907352)
		(mid 266.718706 -222.575797)
		(end 266.906502 -222.294704)
		(width 0.136652)
		(layer "B.Cu")
		(net "PCIE_RX_N36")
	)
	(arc
		(start 266.729972 -224.359216)
		(mid 266.672818 -224.273678)
		(end 266.652756 -224.17278)
		(width 0.136652)
		(layer "B.Cu")
		(net "PCIE_RX_N36")
	)
	(segment
		(start 266.6238 -208.661)
		(end 265.354562 -201.462386)
		(width 0.1397)
		(layer "In2.Cu")
		(net "PCIE_RX_N36")
	)
	(segment
		(start 253.696724 -67.166744)
		(end 253.696724 -63.30188)
		(width 0.1016)
		(layer "In2.Cu")
		(net "PCIE_RX_N36")
	)
	(segment
		(start 266.906502 -222.294704)
		(end 266.849352 -222.237808)
		(width 0.1397)
		(layer "In2.Cu")
		(net "PCIE_RX_N36")
	)
	(segment
		(start 255.406398 -75.310746)
		(end 254.413766 -72.894444)
		(width 0.1397)
		(layer "In2.Cu")
		(net "PCIE_RX_N36")
	)
	(segment
		(start 266.665202 -221.7928)
		(end 266.665202 -220.226128)
		(width 0.1397)
		(layer "In2.Cu")
		(net "PCIE_RX_N36")
	)
	(segment
		(start 266.07516 -216.878916)
		(end 266.6238 -213.7664)
		(width 0.1397)
		(layer "In2.Cu")
		(net "PCIE_RX_N36")
	)
	(segment
		(start 253.7841 -69.32168)
		(end 253.7841 -67.25412)
		(width 0.1397)
		(layer "In2.Cu")
		(net "PCIE_RX_N36")
	)
	(segment
		(start 266.665202 -220.226128)
		(end 266.07516 -216.878916)
		(width 0.1397)
		(layer "In2.Cu")
		(net "PCIE_RX_N36")
	)
	(segment
		(start 253.95809 -63.03518)
		(end 253.995936 -63.03518)
		(width 0.1016)
		(layer "In2.Cu")
		(net "PCIE_RX_N36")
	)
	(segment
		(start 254.131064 -63.091314)
		(end 254.139954 -63.09995)
		(width 0.1016)
		(layer "In2.Cu")
		(net "PCIE_RX_N36")
	)
	(segment
		(start 254.413766 -72.894444)
		(end 253.7841 -69.32168)
		(width 0.1397)
		(layer "In2.Cu")
		(net "PCIE_RX_N36")
	)
	(segment
		(start 253.775718 -63.11138)
		(end 253.776988 -63.110364)
		(width 0.1016)
		(layer "In2.Cu")
		(net "PCIE_RX_N36")
	)
	(segment
		(start 265.354562 -201.462386)
		(end 273.975068 -152.57526)
		(width 0.1397)
		(layer "In2.Cu")
		(net "PCIE_RX_N36")
	)
	(segment
		(start 266.6238 -213.7664)
		(end 266.6238 -208.661)
		(width 0.1397)
		(layer "In2.Cu")
		(net "PCIE_RX_N36")
	)
	(segment
		(start 253.7841 -67.25412)
		(end 253.696724 -67.166744)
		(width 0.1016)
		(layer "In2.Cu")
		(net "PCIE_RX_N36")
	)
	(segment
		(start 273.975068 -152.57526)
		(end 262.015986 -84.75091)
		(width 0.1397)
		(layer "In2.Cu")
		(net "PCIE_RX_N36")
	)
	(segment
		(start 262.015986 -84.75091)
		(end 255.406398 -75.310746)
		(width 0.1397)
		(layer "In2.Cu")
		(net "PCIE_RX_N36")
	)
	(arc
		(start 253.725172 -63.181484)
		(mid 253.747614 -63.14439)
		(end 253.775718 -63.11138)
		(width 0.1016)
		(layer "In2.Cu")
		(net "PCIE_RX_N36")
	)
	(arc
		(start 254.202692 -63.251334)
		(mid 254.175952 -63.385764)
		(end 254.099822 -63.499746)
		(width 0.1016)
		(layer "In2.Cu")
		(net "PCIE_RX_N36")
	)
	(arc
		(start 266.849352 -222.237808)
		(mid 266.713012 -222.033622)
		(end 266.665202 -221.7928)
		(width 0.1397)
		(layer "In2.Cu")
		(net "PCIE_RX_N36")
	)
	(arc
		(start 253.696724 -63.30188)
		(mid 253.703969 -63.240035)
		(end 253.725172 -63.181484)
		(width 0.1016)
		(layer "In2.Cu")
		(net "PCIE_RX_N36")
	)
	(arc
		(start 253.776988 -63.110364)
		(mid 253.860063 -63.054762)
		(end 253.95809 -63.03518)
		(width 0.1016)
		(layer "In2.Cu")
		(net "PCIE_RX_N36")
	)
	(arc
		(start 253.995936 -63.03518)
		(mid 254.069075 -63.049822)
		(end 254.131064 -63.091314)
		(width 0.1016)
		(layer "In2.Cu")
		(net "PCIE_RX_N36")
	)
	(arc
		(start 254.139954 -63.09995)
		(mid 254.186363 -63.169406)
		(end 254.202692 -63.251334)
		(width 0.1016)
		(layer "In2.Cu")
		(net "PCIE_RX_N36")
	)
	(segment
		(start 254.599948 -61.999876)
		(end 255.09982 -62.499748)
		(width 0.136652)
		(layer "F.Cu")
		(net "PCIE_RX_N35")
	)
	(via
		(at 273.30654 -222.294704)
		(size 0.508)
		(drill 0.254)
		(layers "F.Cu" "B.Cu")
		(net "PCIE_RX_N35")
	)
	(via
		(at 255.09982 -62.499748)
		(size 0.4572)
		(drill 0.2032)
		(layers "F.Cu" "B.Cu")
		(net "PCIE_RX_N35")
	)
	(segment
		(start 273.052794 -224.17278)
		(end 273.052794 -222.907352)
		(width 0.136652)
		(layer "B.Cu")
		(net "PCIE_RX_N35")
	)
	(segment
		(start 273.30019 -225.92538)
		(end 273.30019 -224.770188)
		(width 0.136652)
		(layer "B.Cu")
		(net "PCIE_RX_N35")
	)
	(arc
		(start 273.30019 -224.770188)
		(mid 273.255952 -224.547791)
		(end 273.13001 -224.359216)
		(width 0.136652)
		(layer "B.Cu")
		(net "PCIE_RX_N35")
	)
	(arc
		(start 273.052794 -222.907352)
		(mid 273.118744 -222.575797)
		(end 273.30654 -222.294704)
		(width 0.136652)
		(layer "B.Cu")
		(net "PCIE_RX_N35")
	)
	(arc
		(start 273.13001 -224.359216)
		(mid 273.072856 -224.273678)
		(end 273.052794 -224.17278)
		(width 0.136652)
		(layer "B.Cu")
		(net "PCIE_RX_N35")
	)
	(segment
		(start 254.696722 -67.117722)
		(end 254.696722 -62.301882)
		(width 0.1016)
		(layer "In2.Cu")
		(net "PCIE_RX_N35")
	)
	(segment
		(start 255.056386 -62.067186)
		(end 255.143 -62.1538)
		(width 0.1016)
		(layer "In2.Cu")
		(net "PCIE_RX_N35")
	)
	(segment
		(start 254.762 -69.235574)
		(end 254.762 -67.183)
		(width 0.1397)
		(layer "In2.Cu")
		(net "PCIE_RX_N35")
	)
	(segment
		(start 273.038824 -213.599776)
		(end 273.038824 -209.207354)
		(width 0.1397)
		(layer "In2.Cu")
		(net "PCIE_RX_N35")
	)
	(segment
		(start 273.2024 -208.28)
		(end 271.93113 -201.070464)
		(width 0.1397)
		(layer "In2.Cu")
		(net "PCIE_RX_N35")
	)
	(segment
		(start 255.143 -62.456568)
		(end 255.09982 -62.499748)
		(width 0.1016)
		(layer "In2.Cu")
		(net "PCIE_RX_N35")
	)
	(segment
		(start 273.336512 -218.30538)
		(end 272.772886 -215.108536)
		(width 0.1397)
		(layer "In2.Cu")
		(net "PCIE_RX_N35")
	)
	(segment
		(start 272.772886 -215.108536)
		(end 273.038824 -213.599776)
		(width 0.1397)
		(layer "In2.Cu")
		(net "PCIE_RX_N35")
	)
	(segment
		(start 254.958088 -62.035182)
		(end 254.97917 -62.035182)
		(width 0.1016)
		(layer "In2.Cu")
		(net "PCIE_RX_N35")
	)
	(segment
		(start 273.06524 -219.843858)
		(end 273.336512 -218.30538)
		(width 0.1397)
		(layer "In2.Cu")
		(net "PCIE_RX_N35")
	)
	(segment
		(start 254.762 -67.183)
		(end 254.696722 -67.117722)
		(width 0.1016)
		(layer "In2.Cu")
		(net "PCIE_RX_N35")
	)
	(segment
		(start 268.605 -91.44)
		(end 255.335786 -72.489822)
		(width 0.1397)
		(layer "In2.Cu")
		(net "PCIE_RX_N35")
	)
	(segment
		(start 273.038824 -209.207354)
		(end 273.2024 -208.28)
		(width 0.1397)
		(layer "In2.Cu")
		(net "PCIE_RX_N35")
	)
	(segment
		(start 255.335786 -72.489822)
		(end 254.762 -69.235574)
		(width 0.1397)
		(layer "In2.Cu")
		(net "PCIE_RX_N35")
	)
	(segment
		(start 273.06524 -221.9198)
		(end 273.06524 -219.843858)
		(width 0.1397)
		(layer "In2.Cu")
		(net "PCIE_RX_N35")
	)
	(segment
		(start 279.9334 -155.688284)
		(end 268.605 -91.44)
		(width 0.1397)
		(layer "In2.Cu")
		(net "PCIE_RX_N35")
	)
	(segment
		(start 271.93113 -201.070464)
		(end 279.9334 -155.688284)
		(width 0.1397)
		(layer "In2.Cu")
		(net "PCIE_RX_N35")
	)
	(segment
		(start 254.775716 -62.111382)
		(end 254.776986 -62.110366)
		(width 0.1016)
		(layer "In2.Cu")
		(net "PCIE_RX_N35")
	)
	(arc
		(start 254.72517 -62.181486)
		(mid 254.747612 -62.144392)
		(end 254.775716 -62.111382)
		(width 0.1016)
		(layer "In2.Cu")
		(net "PCIE_RX_N35")
	)
	(arc
		(start 273.30654 -222.294704)
		(mid 273.130818 -222.142708)
		(end 273.06524 -221.9198)
		(width 0.1397)
		(layer "In2.Cu")
		(net "PCIE_RX_N35")
	)
	(arc
		(start 254.776986 -62.110366)
		(mid 254.860061 -62.054764)
		(end 254.958088 -62.035182)
		(width 0.1016)
		(layer "In2.Cu")
		(net "PCIE_RX_N35")
	)
	(arc
		(start 255.143 -62.1538)
		(mid 255.205705 -62.305184)
		(end 255.143 -62.456568)
		(width 0.1016)
		(layer "In2.Cu")
		(net "PCIE_RX_N35")
	)
	(arc
		(start 254.696722 -62.301882)
		(mid 254.703967 -62.240037)
		(end 254.72517 -62.181486)
		(width 0.1016)
		(layer "In2.Cu")
		(net "PCIE_RX_N35")
	)
	(arc
		(start 254.97917 -62.035182)
		(mid 255.020967 -62.043496)
		(end 255.056386 -62.067186)
		(width 0.1016)
		(layer "In2.Cu")
		(net "PCIE_RX_N35")
	)
	(segment
		(start 255.599946 -62.999874)
		(end 256.099818 -63.499746)
		(width 0.136652)
		(layer "F.Cu")
		(net "PCIE_RX_N34")
	)
	(via
		(at 276.506432 -222.294704)
		(size 0.508)
		(drill 0.254)
		(layers "F.Cu" "B.Cu")
		(net "PCIE_RX_N34")
	)
	(via
		(at 256.099818 -63.499746)
		(size 0.4572)
		(drill 0.2032)
		(layers "F.Cu" "B.Cu")
		(net "PCIE_RX_N34")
	)
	(segment
		(start 276.500082 -225.92538)
		(end 276.500082 -224.770188)
		(width 0.136652)
		(layer "B.Cu")
		(net "PCIE_RX_N34")
	)
	(segment
		(start 276.252686 -224.17278)
		(end 276.252686 -222.907352)
		(width 0.136652)
		(layer "B.Cu")
		(net "PCIE_RX_N34")
	)
	(arc
		(start 276.329902 -224.359216)
		(mid 276.272748 -224.273678)
		(end 276.252686 -224.17278)
		(width 0.136652)
		(layer "B.Cu")
		(net "PCIE_RX_N34")
	)
	(arc
		(start 276.252686 -222.907352)
		(mid 276.318636 -222.575797)
		(end 276.506432 -222.294704)
		(width 0.136652)
		(layer "B.Cu")
		(net "PCIE_RX_N34")
	)
	(arc
		(start 276.500082 -224.770188)
		(mid 276.455844 -224.547791)
		(end 276.329902 -224.359216)
		(width 0.136652)
		(layer "B.Cu")
		(net "PCIE_RX_N34")
	)
	(segment
		(start 276.265132 -218.981782)
		(end 275.77415 -216.196926)
		(width 0.1397)
		(layer "In2.Cu")
		(net "PCIE_RX_N34")
	)
	(segment
		(start 256.206244 -71.665084)
		(end 255.778 -69.235574)
		(width 0.1397)
		(layer "In2.Cu")
		(net "PCIE_RX_N34")
	)
	(segment
		(start 276.506432 -222.294704)
		(end 276.449282 -222.237808)
		(width 0.1397)
		(layer "In2.Cu")
		(net "PCIE_RX_N34")
	)
	(segment
		(start 255.958086 -63.03518)
		(end 255.995932 -63.03518)
		(width 0.1016)
		(layer "In2.Cu")
		(net "PCIE_RX_N34")
	)
	(segment
		(start 276.225 -207.391254)
		(end 274.373594 -196.89191)
		(width 0.1397)
		(layer "In2.Cu")
		(net "PCIE_RX_N34")
	)
	(segment
		(start 275.77415 -216.196926)
		(end 276.225 -213.6394)
		(width 0.1397)
		(layer "In2.Cu")
		(net "PCIE_RX_N34")
	)
	(segment
		(start 255.775714 -63.11138)
		(end 255.776984 -63.110364)
		(width 0.1016)
		(layer "In2.Cu")
		(net "PCIE_RX_N34")
	)
	(segment
		(start 255.778 -69.235574)
		(end 255.778 -67.183)
		(width 0.1397)
		(layer "In2.Cu")
		(net "PCIE_RX_N34")
	)
	(segment
		(start 255.69672 -67.10172)
		(end 255.69672 -63.30188)
		(width 0.1016)
		(layer "In2.Cu")
		(net "PCIE_RX_N34")
	)
	(segment
		(start 281.445462 -156.786834)
		(end 269.875 -91.186)
		(width 0.1397)
		(layer "In2.Cu")
		(net "PCIE_RX_N34")
	)
	(segment
		(start 276.265132 -221.7928)
		(end 276.265132 -218.981782)
		(width 0.1397)
		(layer "In2.Cu")
		(net "PCIE_RX_N34")
	)
	(segment
		(start 256.13106 -63.091314)
		(end 256.13995 -63.09995)
		(width 0.1016)
		(layer "In2.Cu")
		(net "PCIE_RX_N34")
	)
	(segment
		(start 274.373594 -196.89191)
		(end 281.445462 -156.786834)
		(width 0.1397)
		(layer "In2.Cu")
		(net "PCIE_RX_N34")
	)
	(segment
		(start 276.225 -213.6394)
		(end 276.225 -207.391254)
		(width 0.1397)
		(layer "In2.Cu")
		(net "PCIE_RX_N34")
	)
	(segment
		(start 269.875 -91.186)
		(end 256.206244 -71.665084)
		(width 0.1397)
		(layer "In2.Cu")
		(net "PCIE_RX_N34")
	)
	(segment
		(start 255.778 -67.183)
		(end 255.69672 -67.10172)
		(width 0.1016)
		(layer "In2.Cu")
		(net "PCIE_RX_N34")
	)
	(arc
		(start 255.69672 -63.30188)
		(mid 255.703965 -63.240035)
		(end 255.725168 -63.181484)
		(width 0.1016)
		(layer "In2.Cu")
		(net "PCIE_RX_N34")
	)
	(arc
		(start 276.449282 -222.237808)
		(mid 276.312942 -222.033622)
		(end 276.265132 -221.7928)
		(width 0.1397)
		(layer "In2.Cu")
		(net "PCIE_RX_N34")
	)
	(arc
		(start 255.725168 -63.181484)
		(mid 255.74761 -63.14439)
		(end 255.775714 -63.11138)
		(width 0.1016)
		(layer "In2.Cu")
		(net "PCIE_RX_N34")
	)
	(arc
		(start 255.776984 -63.110364)
		(mid 255.860059 -63.054762)
		(end 255.958086 -63.03518)
		(width 0.1016)
		(layer "In2.Cu")
		(net "PCIE_RX_N34")
	)
	(arc
		(start 256.13995 -63.09995)
		(mid 256.186359 -63.169406)
		(end 256.202688 -63.251334)
		(width 0.1016)
		(layer "In2.Cu")
		(net "PCIE_RX_N34")
	)
	(arc
		(start 255.995932 -63.03518)
		(mid 256.069071 -63.049822)
		(end 256.13106 -63.091314)
		(width 0.1016)
		(layer "In2.Cu")
		(net "PCIE_RX_N34")
	)
	(arc
		(start 256.202688 -63.251334)
		(mid 256.175948 -63.385764)
		(end 256.099818 -63.499746)
		(width 0.1016)
		(layer "In2.Cu")
		(net "PCIE_RX_N34")
	)
	(segment
		(start 256.599944 -61.999876)
		(end 257.099816 -62.499748)
		(width 0.136652)
		(layer "F.Cu")
		(net "PCIE_RX_N33")
	)
	(via
		(at 279.706578 -222.294704)
		(size 0.508)
		(drill 0.254)
		(layers "F.Cu" "B.Cu")
		(net "PCIE_RX_N33")
	)
	(via
		(at 257.099816 -62.499748)
		(size 0.4572)
		(drill 0.2032)
		(layers "F.Cu" "B.Cu")
		(net "PCIE_RX_N33")
	)
	(segment
		(start 279.452832 -224.17278)
		(end 279.452832 -222.907352)
		(width 0.136652)
		(layer "B.Cu")
		(net "PCIE_RX_N33")
	)
	(segment
		(start 279.700228 -225.92538)
		(end 279.700228 -224.770188)
		(width 0.136652)
		(layer "B.Cu")
		(net "PCIE_RX_N33")
	)
	(arc
		(start 279.530048 -224.359216)
		(mid 279.472894 -224.273678)
		(end 279.452832 -224.17278)
		(width 0.136652)
		(layer "B.Cu")
		(net "PCIE_RX_N33")
	)
	(arc
		(start 279.452832 -222.907352)
		(mid 279.518782 -222.575797)
		(end 279.706578 -222.294704)
		(width 0.136652)
		(layer "B.Cu")
		(net "PCIE_RX_N33")
	)
	(arc
		(start 279.700228 -224.770188)
		(mid 279.65599 -224.547791)
		(end 279.530048 -224.359216)
		(width 0.136652)
		(layer "B.Cu")
		(net "PCIE_RX_N33")
	)
	(segment
		(start 256.7686 -67.183)
		(end 256.696718 -67.111118)
		(width 0.1016)
		(layer "In2.Cu")
		(net "PCIE_RX_N33")
	)
	(segment
		(start 278.806656 -206.8195)
		(end 285.204154 -170.537124)
		(width 0.1397)
		(layer "In2.Cu")
		(net "PCIE_RX_N33")
	)
	(segment
		(start 256.958084 -62.035182)
		(end 256.99593 -62.035182)
		(width 0.1016)
		(layer "In2.Cu")
		(net "PCIE_RX_N33")
	)
	(segment
		(start 279.706578 -222.294704)
		(end 279.649428 -222.237808)
		(width 0.1397)
		(layer "In2.Cu")
		(net "PCIE_RX_N33")
	)
	(segment
		(start 279.373584 -210.034124)
		(end 278.806656 -206.8195)
		(width 0.1397)
		(layer "In2.Cu")
		(net "PCIE_RX_N33")
	)
	(segment
		(start 271.145 -90.805)
		(end 257.013456 -70.623176)
		(width 0.1397)
		(layer "In2.Cu")
		(net "PCIE_RX_N33")
	)
	(segment
		(start 256.775712 -62.111382)
		(end 256.776982 -62.110366)
		(width 0.1016)
		(layer "In2.Cu")
		(net "PCIE_RX_N33")
	)
	(segment
		(start 256.7686 -69.235574)
		(end 256.7686 -67.183)
		(width 0.1397)
		(layer "In2.Cu")
		(net "PCIE_RX_N33")
	)
	(segment
		(start 285.204154 -170.537124)
		(end 271.145 -90.805)
		(width 0.1397)
		(layer "In2.Cu")
		(net "PCIE_RX_N33")
	)
	(segment
		(start 256.696718 -67.111118)
		(end 256.696718 -62.301882)
		(width 0.1016)
		(layer "In2.Cu")
		(net "PCIE_RX_N33")
	)
	(segment
		(start 278.83612 -216.640664)
		(end 279.373584 -213.592664)
		(width 0.1397)
		(layer "In2.Cu")
		(net "PCIE_RX_N33")
	)
	(segment
		(start 279.465278 -220.207078)
		(end 278.83612 -216.640664)
		(width 0.1397)
		(layer "In2.Cu")
		(net "PCIE_RX_N33")
	)
	(segment
		(start 279.465278 -221.7928)
		(end 279.465278 -220.207078)
		(width 0.1397)
		(layer "In2.Cu")
		(net "PCIE_RX_N33")
	)
	(segment
		(start 257.013456 -70.623176)
		(end 256.7686 -69.235574)
		(width 0.1397)
		(layer "In2.Cu")
		(net "PCIE_RX_N33")
	)
	(segment
		(start 257.131058 -62.091316)
		(end 257.139948 -62.099952)
		(width 0.1016)
		(layer "In2.Cu")
		(net "PCIE_RX_N33")
	)
	(segment
		(start 279.373584 -213.592664)
		(end 279.373584 -210.034124)
		(width 0.1397)
		(layer "In2.Cu")
		(net "PCIE_RX_N33")
	)
	(arc
		(start 256.696718 -62.301882)
		(mid 256.703963 -62.240037)
		(end 256.725166 -62.181486)
		(width 0.1016)
		(layer "In2.Cu")
		(net "PCIE_RX_N33")
	)
	(arc
		(start 257.202686 -62.251336)
		(mid 257.175946 -62.385766)
		(end 257.099816 -62.499748)
		(width 0.1016)
		(layer "In2.Cu")
		(net "PCIE_RX_N33")
	)
	(arc
		(start 256.725166 -62.181486)
		(mid 256.747608 -62.144392)
		(end 256.775712 -62.111382)
		(width 0.1016)
		(layer "In2.Cu")
		(net "PCIE_RX_N33")
	)
	(arc
		(start 256.99593 -62.035182)
		(mid 257.069069 -62.049824)
		(end 257.131058 -62.091316)
		(width 0.1016)
		(layer "In2.Cu")
		(net "PCIE_RX_N33")
	)
	(arc
		(start 257.139948 -62.099952)
		(mid 257.186357 -62.169408)
		(end 257.202686 -62.251336)
		(width 0.1016)
		(layer "In2.Cu")
		(net "PCIE_RX_N33")
	)
	(arc
		(start 279.649428 -222.237808)
		(mid 279.513088 -222.033622)
		(end 279.465278 -221.7928)
		(width 0.1397)
		(layer "In2.Cu")
		(net "PCIE_RX_N33")
	)
	(arc
		(start 256.776982 -62.110366)
		(mid 256.860057 -62.054764)
		(end 256.958084 -62.035182)
		(width 0.1016)
		(layer "In2.Cu")
		(net "PCIE_RX_N33")
	)
	(segment
		(start 257.599942 -62.999874)
		(end 258.099814 -63.499746)
		(width 0.136652)
		(layer "F.Cu")
		(net "PCIE_RX_N32")
	)
	(via
		(at 258.099814 -63.499746)
		(size 0.4572)
		(drill 0.2032)
		(layers "F.Cu" "B.Cu")
		(net "PCIE_RX_N32")
	)
	(via
		(at 282.90647 -222.294704)
		(size 0.508)
		(drill 0.254)
		(layers "F.Cu" "B.Cu")
		(net "PCIE_RX_N32")
	)
	(segment
		(start 282.652724 -224.17278)
		(end 282.652724 -222.907352)
		(width 0.136652)
		(layer "B.Cu")
		(net "PCIE_RX_N32")
	)
	(segment
		(start 282.90012 -225.92538)
		(end 282.90012 -224.770188)
		(width 0.136652)
		(layer "B.Cu")
		(net "PCIE_RX_N32")
	)
	(arc
		(start 282.90012 -224.770188)
		(mid 282.855882 -224.547791)
		(end 282.72994 -224.359216)
		(width 0.136652)
		(layer "B.Cu")
		(net "PCIE_RX_N32")
	)
	(arc
		(start 282.652724 -222.907352)
		(mid 282.718674 -222.575797)
		(end 282.90647 -222.294704)
		(width 0.136652)
		(layer "B.Cu")
		(net "PCIE_RX_N32")
	)
	(arc
		(start 282.72994 -224.359216)
		(mid 282.672786 -224.273678)
		(end 282.652724 -224.17278)
		(width 0.136652)
		(layer "B.Cu")
		(net "PCIE_RX_N32")
	)
	(segment
		(start 257.696716 -67.145916)
		(end 257.7846 -67.2338)
		(width 0.1016)
		(layer "In2.Cu")
		(net "PCIE_RX_N32")
	)
	(segment
		(start 287.162748 -173.216824)
		(end 281.699208 -204.202284)
		(width 0.1397)
		(layer "In2.Cu")
		(net "PCIE_RX_N32")
	)
	(segment
		(start 257.880104 -69.77761)
		(end 272.642584 -90.861642)
		(width 0.1397)
		(layer "In2.Cu")
		(net "PCIE_RX_N32")
	)
	(segment
		(start 257.7846 -67.2338)
		(end 257.7846 -69.235574)
		(width 0.1397)
		(layer "In2.Cu")
		(net "PCIE_RX_N32")
	)
	(segment
		(start 257.77698 -63.110364)
		(end 257.77571 -63.11138)
		(width 0.1016)
		(layer "In2.Cu")
		(net "PCIE_RX_N32")
	)
	(segment
		(start 282.84932 -222.237808)
		(end 282.90647 -222.294704)
		(width 0.1397)
		(layer "In2.Cu")
		(net "PCIE_RX_N32")
	)
	(segment
		(start 282.66517 -219.423488)
		(end 282.66517 -221.7928)
		(width 0.1397)
		(layer "In2.Cu")
		(net "PCIE_RX_N32")
	)
	(segment
		(start 272.642584 -90.861642)
		(end 287.162748 -173.216824)
		(width 0.1397)
		(layer "In2.Cu")
		(net "PCIE_RX_N32")
	)
	(segment
		(start 282.618942 -209.418174)
		(end 282.618942 -213.595458)
		(width 0.1397)
		(layer "In2.Cu")
		(net "PCIE_RX_N32")
	)
	(segment
		(start 258.139946 -63.09995)
		(end 258.131056 -63.091314)
		(width 0.1016)
		(layer "In2.Cu")
		(net "PCIE_RX_N32")
	)
	(segment
		(start 257.7846 -69.235574)
		(end 257.880104 -69.77761)
		(width 0.1397)
		(layer "In2.Cu")
		(net "PCIE_RX_N32")
	)
	(segment
		(start 257.995928 -63.03518)
		(end 257.958082 -63.03518)
		(width 0.1016)
		(layer "In2.Cu")
		(net "PCIE_RX_N32")
	)
	(segment
		(start 282.128214 -216.378536)
		(end 282.66517 -219.423488)
		(width 0.1397)
		(layer "In2.Cu")
		(net "PCIE_RX_N32")
	)
	(segment
		(start 282.618942 -213.595458)
		(end 282.128214 -216.378536)
		(width 0.1397)
		(layer "In2.Cu")
		(net "PCIE_RX_N32")
	)
	(segment
		(start 257.696716 -63.30188)
		(end 257.696716 -67.145916)
		(width 0.1016)
		(layer "In2.Cu")
		(net "PCIE_RX_N32")
	)
	(segment
		(start 281.699208 -204.202284)
		(end 282.618942 -209.418174)
		(width 0.1397)
		(layer "In2.Cu")
		(net "PCIE_RX_N32")
	)
	(arc
		(start 282.66517 -221.7928)
		(mid 282.712979 -222.033622)
		(end 282.84932 -222.237808)
		(width 0.1397)
		(layer "In2.Cu")
		(net "PCIE_RX_N32")
	)
	(arc
		(start 257.725164 -63.181484)
		(mid 257.703929 -63.240027)
		(end 257.696716 -63.30188)
		(width 0.1016)
		(layer "In2.Cu")
		(net "PCIE_RX_N32")
	)
	(arc
		(start 258.131056 -63.091314)
		(mid 258.069074 -63.049806)
		(end 257.995928 -63.03518)
		(width 0.1016)
		(layer "In2.Cu")
		(net "PCIE_RX_N32")
	)
	(arc
		(start 258.099814 -63.499746)
		(mid 258.175968 -63.385774)
		(end 258.202684 -63.251334)
		(width 0.1016)
		(layer "In2.Cu")
		(net "PCIE_RX_N32")
	)
	(arc
		(start 257.77571 -63.11138)
		(mid 257.747618 -63.144399)
		(end 257.725164 -63.181484)
		(width 0.1016)
		(layer "In2.Cu")
		(net "PCIE_RX_N32")
	)
	(arc
		(start 257.958082 -63.03518)
		(mid 257.860059 -63.054772)
		(end 257.77698 -63.110364)
		(width 0.1016)
		(layer "In2.Cu")
		(net "PCIE_RX_N32")
	)
	(arc
		(start 258.202684 -63.251334)
		(mid 258.186385 -63.169393)
		(end 258.139946 -63.09995)
		(width 0.1016)
		(layer "In2.Cu")
		(net "PCIE_RX_N32")
	)
	(segment
		(start 254.599948 -58.999882)
		(end 255.09982 -59.499754)
		(width 0.136652)
		(layer "F.Cu")
		(net "PCIE_RX_N31")
	)
	(via
		(at 255.09982 -59.499754)
		(size 0.4572)
		(drill 0.2032)
		(layers "F.Cu" "B.Cu")
		(net "PCIE_RX_N31")
	)
	(via
		(at 286.106362 -222.294704)
		(size 0.508)
		(drill 0.254)
		(layers "F.Cu" "B.Cu")
		(net "PCIE_RX_N31")
	)
	(segment
		(start 285.852616 -224.17278)
		(end 285.852616 -222.907352)
		(width 0.136652)
		(layer "B.Cu")
		(net "PCIE_RX_N31")
	)
	(segment
		(start 286.100012 -225.92538)
		(end 286.100012 -224.770188)
		(width 0.136652)
		(layer "B.Cu")
		(net "PCIE_RX_N31")
	)
	(arc
		(start 285.852616 -222.907352)
		(mid 285.918566 -222.575797)
		(end 286.106362 -222.294704)
		(width 0.136652)
		(layer "B.Cu")
		(net "PCIE_RX_N31")
	)
	(arc
		(start 286.100012 -224.770188)
		(mid 286.055774 -224.547791)
		(end 285.929832 -224.359216)
		(width 0.136652)
		(layer "B.Cu")
		(net "PCIE_RX_N31")
	)
	(arc
		(start 285.929832 -224.359216)
		(mid 285.872678 -224.273678)
		(end 285.852616 -224.17278)
		(width 0.136652)
		(layer "B.Cu")
		(net "PCIE_RX_N31")
	)
	(segment
		(start 289.92957 -175.831246)
		(end 285.628334 -200.223374)
		(width 0.1397)
		(layer "In2.Cu")
		(net "PCIE_RX_N31")
	)
	(segment
		(start 285.8516 -213.4616)
		(end 285.386272 -216.100152)
		(width 0.1397)
		(layer "In2.Cu")
		(net "PCIE_RX_N31")
	)
	(segment
		(start 285.386272 -216.100152)
		(end 285.865062 -218.815158)
		(width 0.1397)
		(layer "In2.Cu")
		(net "PCIE_RX_N31")
	)
	(segment
		(start 254.768096 -60.72505)
		(end 254.882396 -60.83935)
		(width 0.1016)
		(layer "In2.Cu")
		(net "PCIE_RX_N31")
	)
	(segment
		(start 266.911328 -65.94475)
		(end 271.78 -72.898)
		(width 0.1397)
		(layer "In2.Cu")
		(net "PCIE_RX_N31")
	)
	(segment
		(start 285.865062 -218.815158)
		(end 285.865062 -221.7928)
		(width 0.1397)
		(layer "In2.Cu")
		(net "PCIE_RX_N31")
	)
	(segment
		(start 259.78358 -60.893452)
		(end 259.820664 -60.930536)
		(width 0.1016)
		(layer "In2.Cu")
		(net "PCIE_RX_N31")
	)
	(segment
		(start 260.097778 -61.173614)
		(end 266.911328 -65.94475)
		(width 0.1397)
		(layer "In2.Cu")
		(net "PCIE_RX_N31")
	)
	(segment
		(start 286.604456 -205.764892)
		(end 285.8516 -210.035394)
		(width 0.1397)
		(layer "In2.Cu")
		(net "PCIE_RX_N31")
	)
	(segment
		(start 286.049212 -222.237808)
		(end 286.106362 -222.294704)
		(width 0.1397)
		(layer "In2.Cu")
		(net "PCIE_RX_N31")
	)
	(segment
		(start 255.09982 -59.499754)
		(end 254.867664 -59.732164)
		(width 0.1016)
		(layer "In2.Cu")
		(net "PCIE_RX_N31")
	)
	(segment
		(start 259.820664 -60.930536)
		(end 259.992368 -61.081412)
		(width 0.1016)
		(layer "In2.Cu")
		(net "PCIE_RX_N31")
	)
	(segment
		(start 271.78 -72.898)
		(end 289.92957 -175.831246)
		(width 0.1397)
		(layer "In2.Cu")
		(net "PCIE_RX_N31")
	)
	(segment
		(start 285.8516 -210.035394)
		(end 285.8516 -213.4616)
		(width 0.1397)
		(layer "In2.Cu")
		(net "PCIE_RX_N31")
	)
	(segment
		(start 259.992368 -61.081412)
		(end 260.097778 -61.173614)
		(width 0.1397)
		(layer "In2.Cu")
		(net "PCIE_RX_N31")
	)
	(segment
		(start 254.70612 -60.1218)
		(end 254.70612 -60.575444)
		(width 0.1016)
		(layer "In2.Cu")
		(net "PCIE_RX_N31")
	)
	(segment
		(start 255.012952 -60.893452)
		(end 259.78358 -60.893452)
		(width 0.1016)
		(layer "In2.Cu")
		(net "PCIE_RX_N31")
	)
	(segment
		(start 285.628334 -200.223374)
		(end 286.604456 -205.764892)
		(width 0.1397)
		(layer "In2.Cu")
		(net "PCIE_RX_N31")
	)
	(arc
		(start 254.882396 -60.83935)
		(mid 254.931886 -60.874474)
		(end 254.990092 -60.891674)
		(width 0.1016)
		(layer "In2.Cu")
		(net "PCIE_RX_N31")
	)
	(arc
		(start 254.70612 -60.575444)
		(mid 254.706567 -60.589189)
		(end 254.707898 -60.602876)
		(width 0.1016)
		(layer "In2.Cu")
		(net "PCIE_RX_N31")
	)
	(arc
		(start 254.990092 -60.891674)
		(mid 254.996178 -60.892408)
		(end 255.002284 -60.892944)
		(width 0.1016)
		(layer "In2.Cu")
		(net "PCIE_RX_N31")
	)
	(arc
		(start 255.002284 -60.892944)
		(mid 255.007614 -60.893279)
		(end 255.012952 -60.893452)
		(width 0.1016)
		(layer "In2.Cu")
		(net "PCIE_RX_N31")
	)
	(arc
		(start 285.865062 -221.7928)
		(mid 285.912871 -222.033622)
		(end 286.049212 -222.237808)
		(width 0.1397)
		(layer "In2.Cu")
		(net "PCIE_RX_N31")
	)
	(arc
		(start 254.867664 -59.732164)
		(mid 254.748133 -59.910915)
		(end 254.70612 -60.1218)
		(width 0.1016)
		(layer "In2.Cu")
		(net "PCIE_RX_N31")
	)
	(arc
		(start 254.707898 -60.602876)
		(mid 254.727891 -60.668944)
		(end 254.768096 -60.72505)
		(width 0.1016)
		(layer "In2.Cu")
		(net "PCIE_RX_N31")
	)
	(segment
		(start 255.599946 -57.999884)
		(end 256.099818 -58.499756)
		(width 0.136652)
		(layer "F.Cu")
		(net "PCIE_RX_N30")
	)
	(via
		(at 289.306508 -222.294704)
		(size 0.508)
		(drill 0.254)
		(layers "F.Cu" "B.Cu")
		(net "PCIE_RX_N30")
	)
	(via
		(at 256.099818 -58.499756)
		(size 0.4572)
		(drill 0.2032)
		(layers "F.Cu" "B.Cu")
		(net "PCIE_RX_N30")
	)
	(segment
		(start 289.052762 -224.17278)
		(end 289.052762 -222.907352)
		(width 0.136652)
		(layer "B.Cu")
		(net "PCIE_RX_N30")
	)
	(segment
		(start 289.300158 -225.92538)
		(end 289.300158 -224.770188)
		(width 0.136652)
		(layer "B.Cu")
		(net "PCIE_RX_N30")
	)
	(arc
		(start 289.052762 -222.907352)
		(mid 289.118712 -222.575797)
		(end 289.306508 -222.294704)
		(width 0.136652)
		(layer "B.Cu")
		(net "PCIE_RX_N30")
	)
	(arc
		(start 289.129978 -224.359216)
		(mid 289.072824 -224.273678)
		(end 289.052762 -224.17278)
		(width 0.136652)
		(layer "B.Cu")
		(net "PCIE_RX_N30")
	)
	(arc
		(start 289.300158 -224.770188)
		(mid 289.25592 -224.547791)
		(end 289.129978 -224.359216)
		(width 0.136652)
		(layer "B.Cu")
		(net "PCIE_RX_N30")
	)
	(segment
		(start 260.079744 -59.074812)
		(end 259.907786 -58.902854)
		(width 0.1016)
		(layer "In2.Cu")
		(net "PCIE_RX_N30")
	)
	(segment
		(start 274.407884 -72.862186)
		(end 268.842236 -64.913764)
		(width 0.1397)
		(layer "In2.Cu")
		(net "PCIE_RX_N30")
	)
	(segment
		(start 289.348164 -207.761078)
		(end 288.421572 -202.506072)
		(width 0.1397)
		(layer "In2.Cu")
		(net "PCIE_RX_N30")
	)
	(segment
		(start 255.8542 -58.747914)
		(end 255.8542 -58.745374)
		(width 0.1016)
		(layer "In2.Cu")
		(net "PCIE_RX_N30")
	)
	(segment
		(start 289.0774 -209.296)
		(end 289.348164 -207.761078)
		(width 0.1397)
		(layer "In2.Cu")
		(net "PCIE_RX_N30")
	)
	(segment
		(start 288.583116 -216.544906)
		(end 289.0774 -213.741)
		(width 0.1397)
		(layer "In2.Cu")
		(net "PCIE_RX_N30")
	)
	(segment
		(start 289.065208 -221.9452)
		(end 289.065208 -219.279724)
		(width 0.1397)
		(layer "In2.Cu")
		(net "PCIE_RX_N30")
	)
	(segment
		(start 289.065208 -219.279724)
		(end 288.583116 -216.544906)
		(width 0.1397)
		(layer "In2.Cu")
		(net "PCIE_RX_N30")
	)
	(segment
		(start 289.0774 -213.741)
		(end 289.0774 -209.296)
		(width 0.1397)
		(layer "In2.Cu")
		(net "PCIE_RX_N30")
	)
	(segment
		(start 263.197594 -60.961524)
		(end 260.079744 -59.074812)
		(width 0.1397)
		(layer "In2.Cu")
		(net "PCIE_RX_N30")
	)
	(segment
		(start 292.844474 -177.422048)
		(end 274.407884 -72.862186)
		(width 0.1397)
		(layer "In2.Cu")
		(net "PCIE_RX_N30")
	)
	(segment
		(start 268.842236 -64.913764)
		(end 263.197594 -60.961524)
		(width 0.1397)
		(layer "In2.Cu")
		(net "PCIE_RX_N30")
	)
	(segment
		(start 288.421572 -202.506072)
		(end 292.844474 -177.422048)
		(width 0.1397)
		(layer "In2.Cu")
		(net "PCIE_RX_N30")
	)
	(segment
		(start 259.907786 -58.902854)
		(end 256.00914 -58.902854)
		(width 0.1016)
		(layer "In2.Cu")
		(net "PCIE_RX_N30")
	)
	(segment
		(start 289.306508 -222.294704)
		(end 289.141662 -222.129858)
		(width 0.1397)
		(layer "In2.Cu")
		(net "PCIE_RX_N30")
	)
	(arc
		(start 255.873504 -58.822844)
		(mid 255.859114 -58.7866)
		(end 255.8542 -58.747914)
		(width 0.1016)
		(layer "In2.Cu")
		(net "PCIE_RX_N30")
	)
	(arc
		(start 289.141662 -222.129858)
		(mid 289.085053 -222.045136)
		(end 289.065208 -221.9452)
		(width 0.1397)
		(layer "In2.Cu")
		(net "PCIE_RX_N30")
	)
	(arc
		(start 256.00914 -58.902854)
		(mid 255.930406 -58.881358)
		(end 255.873504 -58.822844)
		(width 0.1016)
		(layer "In2.Cu")
		(net "PCIE_RX_N30")
	)
	(arc
		(start 255.8542 -58.745374)
		(mid 255.92614 -58.571696)
		(end 256.099818 -58.499756)
		(width 0.1016)
		(layer "In2.Cu")
		(net "PCIE_RX_N30")
	)
	(segment
		(start 245.599966 -30.999938)
		(end 246.099838 -30.500066)
		(width 0.136652)
		(layer "F.Cu")
		(net "PCIE_RX_N3")
	)
	(via
		(at 280.2382 -18.7706)
		(size 0.508)
		(drill 0.254)
		(layers "F.Cu" "B.Cu")
		(net "PCIE_RX_N3")
	)
	(via
		(at 246.099838 -30.500066)
		(size 0.4572)
		(drill 0.2032)
		(layers "F.Cu" "B.Cu")
		(net "PCIE_RX_N3")
	)
	(segment
		(start 291.166296 -15.11935)
		(end 291.142928 -15.142718)
		(width 0.136652)
		(layer "B.Cu")
		(net "PCIE_RX_N3")
	)
	(segment
		(start 282.423108 -18.310098)
		(end 282.290266 -18.39849)
		(width 0.136652)
		(layer "B.Cu")
		(net "PCIE_RX_N3")
	)
	(segment
		(start 282.44927 -18.29689)
		(end 282.423108 -18.310098)
		(width 0.136652)
		(layer "B.Cu")
		(net "PCIE_RX_N3")
	)
	(segment
		(start 291.384482 -12.530074)
		(end 291.384482 -14.592554)
		(width 0.136652)
		(layer "B.Cu")
		(net "PCIE_RX_N3")
	)
	(segment
		(start 285.22549 -15.52067)
		(end 282.44927 -18.29689)
		(width 0.136652)
		(layer "B.Cu")
		(net "PCIE_RX_N3")
	)
	(segment
		(start 282.105862 -18.47469)
		(end 281.841194 -18.527522)
		(width 0.136652)
		(layer "B.Cu")
		(net "PCIE_RX_N3")
	)
	(segment
		(start 281.841194 -18.527522)
		(end 280.82494 -18.527522)
		(width 0.136652)
		(layer "B.Cu")
		(net "PCIE_RX_N3")
	)
	(segment
		(start 290.6014 -15.367)
		(end 285.596584 -15.367)
		(width 0.136652)
		(layer "B.Cu")
		(net "PCIE_RX_N3")
	)
	(segment
		(start 282.290266 -18.39849)
		(end 282.105862 -18.47469)
		(width 0.136652)
		(layer "B.Cu")
		(net "PCIE_RX_N3")
	)
	(arc
		(start 291.142928 -15.142718)
		(mid 290.894473 -15.30873)
		(end 290.6014 -15.367)
		(width 0.136652)
		(layer "B.Cu")
		(net "PCIE_RX_N3")
	)
	(arc
		(start 285.596584 -15.367)
		(mid 285.395766 -15.406945)
		(end 285.22549 -15.52067)
		(width 0.136652)
		(layer "B.Cu")
		(net "PCIE_RX_N3")
	)
	(arc
		(start 280.82494 -18.527522)
		(mid 280.507382 -18.590688)
		(end 280.2382 -18.7706)
		(width 0.136652)
		(layer "B.Cu")
		(net "PCIE_RX_N3")
	)
	(arc
		(start 291.384482 -14.592554)
		(mid 291.327789 -14.87766)
		(end 291.166296 -15.11935)
		(width 0.136652)
		(layer "B.Cu")
		(net "PCIE_RX_N3")
	)
	(segment
		(start 273.701256 -19.424142)
		(end 270.109442 -18.70583)
		(width 0.1397)
		(layer "In2.Cu")
		(net "PCIE_RX_N3")
	)
	(segment
		(start 279.71242 -18.477738)
		(end 279.06853 -18.477738)
		(width 0.1397)
		(layer "In2.Cu")
		(net "PCIE_RX_N3")
	)
	(segment
		(start 258.73329 -19.202146)
		(end 257.205226 -18.896584)
		(width 0.1397)
		(layer "In2.Cu")
		(net "PCIE_RX_N3")
	)
	(segment
		(start 263.560306 -18.8976)
		(end 260.385306 -19.5326)
		(width 0.1397)
		(layer "In2.Cu")
		(net "PCIE_RX_N3")
	)
	(segment
		(start 257.205226 -18.896584)
		(end 253.549404 -19.510756)
		(width 0.1397)
		(layer "In2.Cu")
		(net "PCIE_RX_N3")
	)
	(segment
		(start 280.2382 -18.7706)
		(end 280.110184 -18.64233)
		(width 0.1397)
		(layer "In2.Cu")
		(net "PCIE_RX_N3")
	)
	(segment
		(start 266.355068 -19.456654)
		(end 263.560306 -18.8976)
		(width 0.1397)
		(layer "In2.Cu")
		(net "PCIE_RX_N3")
	)
	(segment
		(start 246.0498 -27.010106)
		(end 246.0498 -30.379162)
		(width 0.1397)
		(layer "In2.Cu")
		(net "PCIE_RX_N3")
	)
	(segment
		(start 270.109442 -18.70583)
		(end 266.355068 -19.456654)
		(width 0.1397)
		(layer "In2.Cu")
		(net "PCIE_RX_N3")
	)
	(segment
		(start 253.549404 -19.510756)
		(end 246.0498 -27.010106)
		(width 0.1397)
		(layer "In2.Cu")
		(net "PCIE_RX_N3")
	)
	(segment
		(start 279.06853 -18.477738)
		(end 273.701256 -19.424142)
		(width 0.1397)
		(layer "In2.Cu")
		(net "PCIE_RX_N3")
	)
	(segment
		(start 260.385306 -19.5326)
		(end 258.73329 -19.202146)
		(width 0.1397)
		(layer "In2.Cu")
		(net "PCIE_RX_N3")
	)
	(arc
		(start 246.0498 -30.379162)
		(mid 246.062812 -30.444579)
		(end 246.099838 -30.500066)
		(width 0.1397)
		(layer "In2.Cu")
		(net "PCIE_RX_N3")
	)
	(arc
		(start 280.110184 -18.64233)
		(mid 279.927673 -18.520473)
		(end 279.71242 -18.477738)
		(width 0.1397)
		(layer "In2.Cu")
		(net "PCIE_RX_N3")
	)
	(segment
		(start 254.599948 -56.999886)
		(end 255.09982 -57.499758)
		(width 0.136652)
		(layer "F.Cu")
		(net "PCIE_RX_N29")
	)
	(via
		(at 292.5064 -222.294704)
		(size 0.508)
		(drill 0.254)
		(layers "F.Cu" "B.Cu")
		(net "PCIE_RX_N29")
	)
	(via
		(at 255.09982 -57.499758)
		(size 0.4572)
		(drill 0.2032)
		(layers "F.Cu" "B.Cu")
		(net "PCIE_RX_N29")
	)
	(segment
		(start 292.252654 -224.17278)
		(end 292.252654 -222.907352)
		(width 0.136652)
		(layer "B.Cu")
		(net "PCIE_RX_N29")
	)
	(segment
		(start 292.50005 -225.92538)
		(end 292.50005 -224.770188)
		(width 0.136652)
		(layer "B.Cu")
		(net "PCIE_RX_N29")
	)
	(arc
		(start 292.50005 -224.770188)
		(mid 292.455812 -224.547791)
		(end 292.32987 -224.359216)
		(width 0.136652)
		(layer "B.Cu")
		(net "PCIE_RX_N29")
	)
	(arc
		(start 292.252654 -222.907352)
		(mid 292.318604 -222.575797)
		(end 292.5064 -222.294704)
		(width 0.136652)
		(layer "B.Cu")
		(net "PCIE_RX_N29")
	)
	(arc
		(start 292.32987 -224.359216)
		(mid 292.272716 -224.273678)
		(end 292.252654 -224.17278)
		(width 0.136652)
		(layer "B.Cu")
		(net "PCIE_RX_N29")
	)
	(segment
		(start 292.46068 -217.461846)
		(end 292.05428 -215.156542)
		(width 0.1397)
		(layer "In2.Cu")
		(net "PCIE_RX_N29")
	)
	(segment
		(start 291.853874 -203.33081)
		(end 295.425368 -183.07812)
		(width 0.1397)
		(layer "In2.Cu")
		(net "PCIE_RX_N29")
	)
	(segment
		(start 292.30828 -210.01863)
		(end 292.670738 -207.96377)
		(width 0.1397)
		(layer "In2.Cu")
		(net "PCIE_RX_N29")
	)
	(segment
		(start 259.520944 -57.902856)
		(end 255.009142 -57.902856)
		(width 0.1016)
		(layer "In2.Cu")
		(net "PCIE_RX_N29")
	)
	(segment
		(start 292.30828 -213.7156)
		(end 292.30828 -210.01863)
		(width 0.1397)
		(layer "In2.Cu")
		(net "PCIE_RX_N29")
	)
	(segment
		(start 262.601456 -58.25744)
		(end 260.208522 -57.8358)
		(width 0.1397)
		(layer "In2.Cu")
		(net "PCIE_RX_N29")
	)
	(segment
		(start 292.5064 -222.294704)
		(end 292.44925 -222.237808)
		(width 0.1397)
		(layer "In2.Cu")
		(net "PCIE_RX_N29")
	)
	(segment
		(start 292.05428 -215.156542)
		(end 292.30828 -213.7156)
		(width 0.1397)
		(layer "In2.Cu")
		(net "PCIE_RX_N29")
	)
	(segment
		(start 292.670738 -207.96377)
		(end 291.853874 -203.33081)
		(width 0.1397)
		(layer "In2.Cu")
		(net "PCIE_RX_N29")
	)
	(segment
		(start 270.112236 -63.516764)
		(end 262.601456 -58.25744)
		(width 0.1397)
		(layer "In2.Cu")
		(net "PCIE_RX_N29")
	)
	(segment
		(start 254.854202 -57.747916)
		(end 254.854202 -57.745376)
		(width 0.1016)
		(layer "In2.Cu")
		(net "PCIE_RX_N29")
	)
	(segment
		(start 259.588 -57.8358)
		(end 259.520944 -57.902856)
		(width 0.1016)
		(layer "In2.Cu")
		(net "PCIE_RX_N29")
	)
	(segment
		(start 295.425368 -183.07812)
		(end 275.767292 -71.592948)
		(width 0.1397)
		(layer "In2.Cu")
		(net "PCIE_RX_N29")
	)
	(segment
		(start 275.767292 -71.592948)
		(end 270.112236 -63.516764)
		(width 0.1397)
		(layer "In2.Cu")
		(net "PCIE_RX_N29")
	)
	(segment
		(start 292.2651 -218.57081)
		(end 292.46068 -217.461846)
		(width 0.1397)
		(layer "In2.Cu")
		(net "PCIE_RX_N29")
	)
	(segment
		(start 260.208522 -57.8358)
		(end 259.588 -57.8358)
		(width 0.1397)
		(layer "In2.Cu")
		(net "PCIE_RX_N29")
	)
	(segment
		(start 292.2651 -221.7928)
		(end 292.2651 -218.57081)
		(width 0.1397)
		(layer "In2.Cu")
		(net "PCIE_RX_N29")
	)
	(arc
		(start 292.44925 -222.237808)
		(mid 292.31291 -222.033622)
		(end 292.2651 -221.7928)
		(width 0.1397)
		(layer "In2.Cu")
		(net "PCIE_RX_N29")
	)
	(arc
		(start 254.873506 -57.822846)
		(mid 254.859116 -57.786602)
		(end 254.854202 -57.747916)
		(width 0.1016)
		(layer "In2.Cu")
		(net "PCIE_RX_N29")
	)
	(arc
		(start 254.854202 -57.745376)
		(mid 254.926142 -57.571698)
		(end 255.09982 -57.499758)
		(width 0.1016)
		(layer "In2.Cu")
		(net "PCIE_RX_N29")
	)
	(arc
		(start 255.009142 -57.902856)
		(mid 254.930408 -57.88136)
		(end 254.873506 -57.822846)
		(width 0.1016)
		(layer "In2.Cu")
		(net "PCIE_RX_N29")
	)
	(segment
		(start 255.599946 -55.999888)
		(end 256.099818 -56.49976)
		(width 0.136652)
		(layer "F.Cu")
		(net "PCIE_RX_N28")
	)
	(via
		(at 295.706546 -222.294704)
		(size 0.508)
		(drill 0.254)
		(layers "F.Cu" "B.Cu")
		(net "PCIE_RX_N28")
	)
	(via
		(at 256.099818 -56.49976)
		(size 0.4572)
		(drill 0.2032)
		(layers "F.Cu" "B.Cu")
		(net "PCIE_RX_N28")
	)
	(segment
		(start 295.4528 -224.17278)
		(end 295.4528 -222.907352)
		(width 0.136652)
		(layer "B.Cu")
		(net "PCIE_RX_N28")
	)
	(segment
		(start 295.700196 -225.92538)
		(end 295.700196 -224.770188)
		(width 0.136652)
		(layer "B.Cu")
		(net "PCIE_RX_N28")
	)
	(arc
		(start 295.530016 -224.359216)
		(mid 295.472862 -224.273678)
		(end 295.4528 -224.17278)
		(width 0.136652)
		(layer "B.Cu")
		(net "PCIE_RX_N28")
	)
	(arc
		(start 295.4528 -222.907352)
		(mid 295.51875 -222.575797)
		(end 295.706546 -222.294704)
		(width 0.136652)
		(layer "B.Cu")
		(net "PCIE_RX_N28")
	)
	(arc
		(start 295.700196 -224.770188)
		(mid 295.655958 -224.547791)
		(end 295.530016 -224.359216)
		(width 0.136652)
		(layer "B.Cu")
		(net "PCIE_RX_N28")
	)
	(segment
		(start 259.842 -56.8198)
		(end 260.404356 -56.8198)
		(width 0.1397)
		(layer "In2.Cu")
		(net "PCIE_RX_N28")
	)
	(segment
		(start 255.8542 -56.745378)
		(end 255.8542 -56.747918)
		(width 0.1016)
		(layer "In2.Cu")
		(net "PCIE_RX_N28")
	)
	(segment
		(start 264.457688 -57.534302)
		(end 271.608296 -62.54115)
		(width 0.1397)
		(layer "In2.Cu")
		(net "PCIE_RX_N28")
	)
	(segment
		(start 271.608296 -62.54115)
		(end 278.303736 -72.103488)
		(width 0.1397)
		(layer "In2.Cu")
		(net "PCIE_RX_N28")
	)
	(segment
		(start 296.9387 -212.396578)
		(end 295.465246 -220.752924)
		(width 0.1397)
		(layer "In2.Cu")
		(net "PCIE_RX_N28")
	)
	(segment
		(start 295.465246 -220.752924)
		(end 295.465246 -221.7928)
		(width 0.1397)
		(layer "In2.Cu")
		(net "PCIE_RX_N28")
	)
	(segment
		(start 295.649396 -222.237808)
		(end 295.706546 -222.294704)
		(width 0.1397)
		(layer "In2.Cu")
		(net "PCIE_RX_N28")
	)
	(segment
		(start 278.303736 -72.103488)
		(end 298.538138 -186.85891)
		(width 0.1397)
		(layer "In2.Cu")
		(net "PCIE_RX_N28")
	)
	(segment
		(start 298.538138 -186.85891)
		(end 295.48836 -204.15758)
		(width 0.1397)
		(layer "In2.Cu")
		(net "PCIE_RX_N28")
	)
	(segment
		(start 295.48836 -204.15758)
		(end 296.9387 -212.396578)
		(width 0.1397)
		(layer "In2.Cu")
		(net "PCIE_RX_N28")
	)
	(segment
		(start 259.758942 -56.902858)
		(end 259.842 -56.8198)
		(width 0.1016)
		(layer "In2.Cu")
		(net "PCIE_RX_N28")
	)
	(segment
		(start 256.00914 -56.902858)
		(end 259.758942 -56.902858)
		(width 0.1016)
		(layer "In2.Cu")
		(net "PCIE_RX_N28")
	)
	(segment
		(start 260.404356 -56.8198)
		(end 264.457688 -57.534302)
		(width 0.1397)
		(layer "In2.Cu")
		(net "PCIE_RX_N28")
	)
	(arc
		(start 256.099818 -56.49976)
		(mid 255.92614 -56.5717)
		(end 255.8542 -56.745378)
		(width 0.1016)
		(layer "In2.Cu")
		(net "PCIE_RX_N28")
	)
	(arc
		(start 255.8542 -56.747918)
		(mid 255.8591 -56.786608)
		(end 255.873504 -56.822848)
		(width 0.1016)
		(layer "In2.Cu")
		(net "PCIE_RX_N28")
	)
	(arc
		(start 295.465246 -221.7928)
		(mid 295.513055 -222.033622)
		(end 295.649396 -222.237808)
		(width 0.1397)
		(layer "In2.Cu")
		(net "PCIE_RX_N28")
	)
	(arc
		(start 255.873504 -56.822848)
		(mid 255.930398 -56.881377)
		(end 256.00914 -56.902858)
		(width 0.1016)
		(layer "In2.Cu")
		(net "PCIE_RX_N28")
	)
	(segment
		(start 254.599948 -54.99989)
		(end 255.09982 -55.499762)
		(width 0.136652)
		(layer "F.Cu")
		(net "PCIE_RX_N27")
	)
	(via
		(at 301.306484 -222.294704)
		(size 0.508)
		(drill 0.254)
		(layers "F.Cu" "B.Cu")
		(net "PCIE_RX_N27")
	)
	(via
		(at 255.09982 -55.499762)
		(size 0.4572)
		(drill 0.2032)
		(layers "F.Cu" "B.Cu")
		(net "PCIE_RX_N27")
	)
	(segment
		(start 301.052738 -224.17278)
		(end 301.052738 -222.907352)
		(width 0.136652)
		(layer "B.Cu")
		(net "PCIE_RX_N27")
	)
	(segment
		(start 301.300134 -225.92538)
		(end 301.300134 -224.770188)
		(width 0.136652)
		(layer "B.Cu")
		(net "PCIE_RX_N27")
	)
	(arc
		(start 301.052738 -222.907352)
		(mid 301.118688 -222.575797)
		(end 301.306484 -222.294704)
		(width 0.136652)
		(layer "B.Cu")
		(net "PCIE_RX_N27")
	)
	(arc
		(start 301.300134 -224.770188)
		(mid 301.255896 -224.547791)
		(end 301.129954 -224.359216)
		(width 0.136652)
		(layer "B.Cu")
		(net "PCIE_RX_N27")
	)
	(arc
		(start 301.129954 -224.359216)
		(mid 301.0728 -224.273678)
		(end 301.052738 -224.17278)
		(width 0.136652)
		(layer "B.Cu")
		(net "PCIE_RX_N27")
	)
	(segment
		(start 301.306484 -222.294704)
		(end 301.249334 -222.237808)
		(width 0.1397)
		(layer "In2.Cu")
		(net "PCIE_RX_N27")
	)
	(segment
		(start 259.7404 -55.8038)
		(end 259.64134 -55.90286)
		(width 0.1016)
		(layer "In2.Cu")
		(net "PCIE_RX_N27")
	)
	(segment
		(start 254.854202 -55.74792)
		(end 254.854202 -55.74538)
		(width 0.1016)
		(layer "In2.Cu")
		(net "PCIE_RX_N27")
	)
	(segment
		(start 264.987024 -56.609234)
		(end 260.417818 -55.8038)
		(width 0.1397)
		(layer "In2.Cu")
		(net "PCIE_RX_N27")
	)
	(segment
		(start 279.997662 -71.933816)
		(end 273.384264 -62.48908)
		(width 0.1397)
		(layer "In2.Cu")
		(net "PCIE_RX_N27")
	)
	(segment
		(start 300.37405 -205.166976)
		(end 301.932086 -196.330824)
		(width 0.1397)
		(layer "In2.Cu")
		(net "PCIE_RX_N27")
	)
	(segment
		(start 259.64134 -55.90286)
		(end 255.009142 -55.90286)
		(width 0.1016)
		(layer "In2.Cu")
		(net "PCIE_RX_N27")
	)
	(segment
		(start 300.996858 -208.698592)
		(end 300.37405 -205.166976)
		(width 0.1397)
		(layer "In2.Cu")
		(net "PCIE_RX_N27")
	)
	(segment
		(start 300.928786 -216.568528)
		(end 300.724824 -215.410796)
		(width 0.1397)
		(layer "In2.Cu")
		(net "PCIE_RX_N27")
	)
	(segment
		(start 301.932086 -196.330824)
		(end 279.997662 -71.933816)
		(width 0.1397)
		(layer "In2.Cu")
		(net "PCIE_RX_N27")
	)
	(segment
		(start 300.724824 -215.410796)
		(end 300.996858 -213.868)
		(width 0.1397)
		(layer "In2.Cu")
		(net "PCIE_RX_N27")
	)
	(segment
		(start 260.417818 -55.8038)
		(end 259.7404 -55.8038)
		(width 0.1397)
		(layer "In2.Cu")
		(net "PCIE_RX_N27")
	)
	(segment
		(start 301.102522 -217.553286)
		(end 300.928786 -216.568528)
		(width 0.1397)
		(layer "In2.Cu")
		(net "PCIE_RX_N27")
	)
	(segment
		(start 273.384264 -62.48908)
		(end 264.987024 -56.609234)
		(width 0.1397)
		(layer "In2.Cu")
		(net "PCIE_RX_N27")
	)
	(segment
		(start 300.820074 -219.155518)
		(end 301.102522 -217.553286)
		(width 0.1397)
		(layer "In2.Cu")
		(net "PCIE_RX_N27")
	)
	(segment
		(start 301.065184 -221.7928)
		(end 301.065184 -220.54693)
		(width 0.1397)
		(layer "In2.Cu")
		(net "PCIE_RX_N27")
	)
	(segment
		(start 301.065184 -220.54693)
		(end 300.820074 -219.155518)
		(width 0.1397)
		(layer "In2.Cu")
		(net "PCIE_RX_N27")
	)
	(segment
		(start 300.996858 -213.868)
		(end 300.996858 -208.698592)
		(width 0.1397)
		(layer "In2.Cu")
		(net "PCIE_RX_N27")
	)
	(arc
		(start 254.873506 -55.82285)
		(mid 254.859116 -55.786606)
		(end 254.854202 -55.74792)
		(width 0.1016)
		(layer "In2.Cu")
		(net "PCIE_RX_N27")
	)
	(arc
		(start 301.249334 -222.237808)
		(mid 301.112994 -222.033622)
		(end 301.065184 -221.7928)
		(width 0.1397)
		(layer "In2.Cu")
		(net "PCIE_RX_N27")
	)
	(arc
		(start 254.854202 -55.74538)
		(mid 254.926142 -55.571702)
		(end 255.09982 -55.499762)
		(width 0.1016)
		(layer "In2.Cu")
		(net "PCIE_RX_N27")
	)
	(arc
		(start 255.009142 -55.90286)
		(mid 254.930408 -55.881364)
		(end 254.873506 -55.82285)
		(width 0.1016)
		(layer "In2.Cu")
		(net "PCIE_RX_N27")
	)
	(segment
		(start 255.599946 -53.999892)
		(end 256.099818 -54.499764)
		(width 0.136652)
		(layer "F.Cu")
		(net "PCIE_RX_N26")
	)
	(via
		(at 256.099818 -54.499764)
		(size 0.4572)
		(drill 0.2032)
		(layers "F.Cu" "B.Cu")
		(net "PCIE_RX_N26")
	)
	(via
		(at 304.546 -220.2688)
		(size 0.508)
		(drill 0.254)
		(layers "F.Cu" "B.Cu")
		(net "PCIE_RX_N26")
	)
	(segment
		(start 304.500026 -225.92538)
		(end 304.500026 -224.770188)
		(width 0.136652)
		(layer "B.Cu")
		(net "PCIE_RX_N26")
	)
	(segment
		(start 304.25263 -224.17278)
		(end 304.25263 -220.8276)
		(width 0.136652)
		(layer "B.Cu")
		(net "PCIE_RX_N26")
	)
	(arc
		(start 304.500026 -224.770188)
		(mid 304.455788 -224.547791)
		(end 304.329846 -224.359216)
		(width 0.136652)
		(layer "B.Cu")
		(net "PCIE_RX_N26")
	)
	(arc
		(start 304.329846 -224.359216)
		(mid 304.272692 -224.273678)
		(end 304.25263 -224.17278)
		(width 0.136652)
		(layer "B.Cu")
		(net "PCIE_RX_N26")
	)
	(arc
		(start 304.25263 -220.8276)
		(mid 304.330425 -220.512029)
		(end 304.546 -220.2688)
		(width 0.136652)
		(layer "B.Cu")
		(net "PCIE_RX_N26")
	)
	(segment
		(start 274.398994 -61.185044)
		(end 281.679396 -71.58228)
		(width 0.1397)
		(layer "In2.Cu")
		(net "PCIE_RX_N26")
	)
	(segment
		(start 266.19454 -55.440326)
		(end 274.398994 -61.185044)
		(width 0.1397)
		(layer "In2.Cu")
		(net "PCIE_RX_N26")
	)
	(segment
		(start 262.785098 -54.839362)
		(end 266.19454 -55.440326)
		(width 0.1397)
		(layer "In2.Cu")
		(net "PCIE_RX_N26")
	)
	(segment
		(start 281.679396 -71.58228)
		(end 305.302666 -205.556866)
		(width 0.1397)
		(layer "In2.Cu")
		(net "PCIE_RX_N26")
	)
	(segment
		(start 255.8542 -54.745382)
		(end 255.8542 -54.747922)
		(width 0.1016)
		(layer "In2.Cu")
		(net "PCIE_RX_N26")
	)
	(segment
		(start 303.870614 -213.676992)
		(end 304.265076 -215.91524)
		(width 0.1397)
		(layer "In2.Cu")
		(net "PCIE_RX_N26")
	)
	(segment
		(start 256.00914 -54.902862)
		(end 259.7785 -54.902862)
		(width 0.1016)
		(layer "In2.Cu")
		(net "PCIE_RX_N26")
	)
	(segment
		(start 304.265076 -215.91524)
		(end 304.265076 -219.59062)
		(width 0.1397)
		(layer "In2.Cu")
		(net "PCIE_RX_N26")
	)
	(segment
		(start 305.302666 -205.556866)
		(end 303.870614 -213.676992)
		(width 0.1397)
		(layer "In2.Cu")
		(net "PCIE_RX_N26")
	)
	(segment
		(start 259.7785 -54.902862)
		(end 259.842 -54.839362)
		(width 0.1016)
		(layer "In2.Cu")
		(net "PCIE_RX_N26")
	)
	(segment
		(start 259.842 -54.839362)
		(end 262.785098 -54.839362)
		(width 0.1397)
		(layer "In2.Cu")
		(net "PCIE_RX_N26")
	)
	(arc
		(start 255.867916 -54.663848)
		(mid 255.86635 -54.668279)
		(end 255.864868 -54.672738)
		(width 0.1016)
		(layer "In2.Cu")
		(net "PCIE_RX_N26")
	)
	(arc
		(start 255.873504 -54.822852)
		(mid 255.930398 -54.881381)
		(end 256.00914 -54.902862)
		(width 0.1016)
		(layer "In2.Cu")
		(net "PCIE_RX_N26")
	)
	(arc
		(start 304.265076 -219.59062)
		(mid 304.338083 -219.957653)
		(end 304.546 -220.2688)
		(width 0.1397)
		(layer "In2.Cu")
		(net "PCIE_RX_N26")
	)
	(arc
		(start 255.854708 -54.727094)
		(mid 255.854283 -54.736233)
		(end 255.8542 -54.745382)
		(width 0.1016)
		(layer "In2.Cu")
		(net "PCIE_RX_N26")
	)
	(arc
		(start 255.868678 -54.661308)
		(mid 255.868294 -54.662577)
		(end 255.867916 -54.663848)
		(width 0.1016)
		(layer "In2.Cu")
		(net "PCIE_RX_N26")
	)
	(arc
		(start 255.862582 -54.680866)
		(mid 255.857534 -54.703791)
		(end 255.854708 -54.727094)
		(width 0.1016)
		(layer "In2.Cu")
		(net "PCIE_RX_N26")
	)
	(arc
		(start 255.8542 -54.747922)
		(mid 255.8591 -54.786612)
		(end 255.873504 -54.822852)
		(width 0.1016)
		(layer "In2.Cu")
		(net "PCIE_RX_N26")
	)
	(arc
		(start 255.864868 -54.672738)
		(mid 255.86369 -54.676792)
		(end 255.862582 -54.680866)
		(width 0.1016)
		(layer "In2.Cu")
		(net "PCIE_RX_N26")
	)
	(arc
		(start 256.099818 -54.499764)
		(mid 255.958821 -54.544153)
		(end 255.868678 -54.661308)
		(width 0.1016)
		(layer "In2.Cu")
		(net "PCIE_RX_N26")
	)
	(segment
		(start 254.599948 -52.999894)
		(end 255.09982 -53.499766)
		(width 0.136652)
		(layer "F.Cu")
		(net "PCIE_RX_N25")
	)
	(via
		(at 312.50636 -222.294704)
		(size 0.508)
		(drill 0.254)
		(layers "F.Cu" "B.Cu")
		(net "PCIE_RX_N25")
	)
	(via
		(at 255.09982 -53.499766)
		(size 0.4572)
		(drill 0.2032)
		(layers "F.Cu" "B.Cu")
		(net "PCIE_RX_N25")
	)
	(segment
		(start 312.252614 -224.17278)
		(end 312.252614 -222.907352)
		(width 0.136652)
		(layer "B.Cu")
		(net "PCIE_RX_N25")
	)
	(segment
		(start 312.50001 -225.92538)
		(end 312.50001 -224.770188)
		(width 0.136652)
		(layer "B.Cu")
		(net "PCIE_RX_N25")
	)
	(arc
		(start 312.50001 -224.770188)
		(mid 312.455772 -224.547791)
		(end 312.32983 -224.359216)
		(width 0.136652)
		(layer "B.Cu")
		(net "PCIE_RX_N25")
	)
	(arc
		(start 312.32983 -224.359216)
		(mid 312.272676 -224.273678)
		(end 312.252614 -224.17278)
		(width 0.136652)
		(layer "B.Cu")
		(net "PCIE_RX_N25")
	)
	(arc
		(start 312.252614 -222.907352)
		(mid 312.318564 -222.575797)
		(end 312.50636 -222.294704)
		(width 0.136652)
		(layer "B.Cu")
		(net "PCIE_RX_N25")
	)
	(segment
		(start 282.462986 -70.353682)
		(end 275.648928 -60.621926)
		(width 0.1397)
		(layer "In2.Cu")
		(net "PCIE_RX_N25")
	)
	(segment
		(start 254.854202 -53.747924)
		(end 254.854202 -53.745384)
		(width 0.1016)
		(layer "In2.Cu")
		(net "PCIE_RX_N25")
	)
	(segment
		(start 312.26506 -221.012766)
		(end 307.938678 -214.834216)
		(width 0.1397)
		(layer "In2.Cu")
		(net "PCIE_RX_N25")
	)
	(segment
		(start 266.7 -54.356)
		(end 263.675114 -53.8226)
		(width 0.1397)
		(layer "In2.Cu")
		(net "PCIE_RX_N25")
	)
	(segment
		(start 275.648928 -60.621926)
		(end 266.7 -54.356)
		(width 0.1397)
		(layer "In2.Cu")
		(net "PCIE_RX_N25")
	)
	(segment
		(start 259.7404 -53.8226)
		(end 259.660136 -53.902864)
		(width 0.1016)
		(layer "In2.Cu")
		(net "PCIE_RX_N25")
	)
	(segment
		(start 312.50636 -222.294704)
		(end 312.44921 -222.237808)
		(width 0.1397)
		(layer "In2.Cu")
		(net "PCIE_RX_N25")
	)
	(segment
		(start 259.660136 -53.902864)
		(end 255.009142 -53.902864)
		(width 0.1016)
		(layer "In2.Cu")
		(net "PCIE_RX_N25")
	)
	(segment
		(start 307.938678 -214.834216)
		(end 282.462986 -70.353682)
		(width 0.1397)
		(layer "In2.Cu")
		(net "PCIE_RX_N25")
	)
	(segment
		(start 263.675114 -53.8226)
		(end 259.7404 -53.8226)
		(width 0.1397)
		(layer "In2.Cu")
		(net "PCIE_RX_N25")
	)
	(segment
		(start 312.26506 -221.7928)
		(end 312.26506 -221.012766)
		(width 0.1397)
		(layer "In2.Cu")
		(net "PCIE_RX_N25")
	)
	(arc
		(start 254.854202 -53.745384)
		(mid 254.926142 -53.571706)
		(end 255.09982 -53.499766)
		(width 0.1016)
		(layer "In2.Cu")
		(net "PCIE_RX_N25")
	)
	(arc
		(start 312.44921 -222.237808)
		(mid 312.31287 -222.033622)
		(end 312.26506 -221.7928)
		(width 0.1397)
		(layer "In2.Cu")
		(net "PCIE_RX_N25")
	)
	(arc
		(start 255.009142 -53.902864)
		(mid 254.930408 -53.881368)
		(end 254.873506 -53.822854)
		(width 0.1016)
		(layer "In2.Cu")
		(net "PCIE_RX_N25")
	)
	(arc
		(start 254.873506 -53.822854)
		(mid 254.859116 -53.78661)
		(end 254.854202 -53.747924)
		(width 0.1016)
		(layer "In2.Cu")
		(net "PCIE_RX_N25")
	)
	(segment
		(start 255.599946 -51.999896)
		(end 256.099818 -52.499768)
		(width 0.136652)
		(layer "F.Cu")
		(net "PCIE_RX_N24")
	)
	(via
		(at 315.706506 -222.294704)
		(size 0.508)
		(drill 0.254)
		(layers "F.Cu" "B.Cu")
		(net "PCIE_RX_N24")
	)
	(via
		(at 256.099818 -52.499768)
		(size 0.4572)
		(drill 0.2032)
		(layers "F.Cu" "B.Cu")
		(net "PCIE_RX_N24")
	)
	(segment
		(start 315.45276 -224.17278)
		(end 315.45276 -222.907352)
		(width 0.136652)
		(layer "B.Cu")
		(net "PCIE_RX_N24")
	)
	(segment
		(start 315.700156 -225.92538)
		(end 315.700156 -224.770188)
		(width 0.136652)
		(layer "B.Cu")
		(net "PCIE_RX_N24")
	)
	(arc
		(start 315.529976 -224.359216)
		(mid 315.472822 -224.273678)
		(end 315.45276 -224.17278)
		(width 0.136652)
		(layer "B.Cu")
		(net "PCIE_RX_N24")
	)
	(arc
		(start 315.700156 -224.770188)
		(mid 315.655918 -224.547791)
		(end 315.529976 -224.359216)
		(width 0.136652)
		(layer "B.Cu")
		(net "PCIE_RX_N24")
	)
	(arc
		(start 315.45276 -222.907352)
		(mid 315.51871 -222.575797)
		(end 315.706506 -222.294704)
		(width 0.136652)
		(layer "B.Cu")
		(net "PCIE_RX_N24")
	)
	(segment
		(start 259.694934 -52.902866)
		(end 259.7404 -52.8574)
		(width 0.1016)
		(layer "In2.Cu")
		(net "PCIE_RX_N24")
	)
	(segment
		(start 264.597896 -52.8574)
		(end 267.335 -53.34)
		(width 0.1397)
		(layer "In2.Cu")
		(net "PCIE_RX_N24")
	)
	(segment
		(start 259.7404 -52.8574)
		(end 264.597896 -52.8574)
		(width 0.1397)
		(layer "In2.Cu")
		(net "PCIE_RX_N24")
	)
	(segment
		(start 308.89321 -214.146638)
		(end 310.380634 -216.271094)
		(width 0.1397)
		(layer "In2.Cu")
		(net "PCIE_RX_N24")
	)
	(segment
		(start 308.2036 -210.2358)
		(end 308.89321 -214.146638)
		(width 0.1397)
		(layer "In2.Cu")
		(net "PCIE_RX_N24")
	)
	(segment
		(start 315.465206 -220.707204)
		(end 315.465206 -221.7928)
		(width 0.1397)
		(layer "In2.Cu")
		(net "PCIE_RX_N24")
	)
	(segment
		(start 314.258706 -218.986354)
		(end 315.465206 -220.707204)
		(width 0.1397)
		(layer "In2.Cu")
		(net "PCIE_RX_N24")
	)
	(segment
		(start 308.361842 -209.338926)
		(end 308.2036 -210.2358)
		(width 0.1397)
		(layer "In2.Cu")
		(net "PCIE_RX_N24")
	)
	(segment
		(start 310.380634 -216.271094)
		(end 314.258706 -218.986354)
		(width 0.1397)
		(layer "In2.Cu")
		(net "PCIE_RX_N24")
	)
	(segment
		(start 256.00914 -52.902866)
		(end 259.694934 -52.902866)
		(width 0.1016)
		(layer "In2.Cu")
		(net "PCIE_RX_N24")
	)
	(segment
		(start 255.8542 -52.745386)
		(end 255.8542 -52.747926)
		(width 0.1016)
		(layer "In2.Cu")
		(net "PCIE_RX_N24")
	)
	(segment
		(start 267.335 -53.34)
		(end 276.582124 -59.814968)
		(width 0.1397)
		(layer "In2.Cu")
		(net "PCIE_RX_N24")
	)
	(segment
		(start 283.818838 -70.150228)
		(end 308.361842 -209.338926)
		(width 0.1397)
		(layer "In2.Cu")
		(net "PCIE_RX_N24")
	)
	(segment
		(start 276.582124 -59.814968)
		(end 283.818838 -70.150228)
		(width 0.1397)
		(layer "In2.Cu")
		(net "PCIE_RX_N24")
	)
	(segment
		(start 315.649356 -222.237808)
		(end 315.706506 -222.294704)
		(width 0.1397)
		(layer "In2.Cu")
		(net "PCIE_RX_N24")
	)
	(arc
		(start 256.099818 -52.499768)
		(mid 255.92614 -52.571708)
		(end 255.8542 -52.745386)
		(width 0.1016)
		(layer "In2.Cu")
		(net "PCIE_RX_N24")
	)
	(arc
		(start 315.465206 -221.7928)
		(mid 315.513015 -222.033622)
		(end 315.649356 -222.237808)
		(width 0.1397)
		(layer "In2.Cu")
		(net "PCIE_RX_N24")
	)
	(arc
		(start 255.873504 -52.822856)
		(mid 255.930398 -52.881385)
		(end 256.00914 -52.902866)
		(width 0.1016)
		(layer "In2.Cu")
		(net "PCIE_RX_N24")
	)
	(arc
		(start 255.8542 -52.747926)
		(mid 255.8591 -52.786616)
		(end 255.873504 -52.822856)
		(width 0.1016)
		(layer "In2.Cu")
		(net "PCIE_RX_N24")
	)
	(segment
		(start 254.599948 -49.9999)
		(end 255.09982 -50.499772)
		(width 0.136652)
		(layer "F.Cu")
		(net "PCIE_RX_N23")
	)
	(via
		(at 255.09982 -50.499772)
		(size 0.4572)
		(drill 0.2032)
		(layers "F.Cu" "B.Cu")
		(net "PCIE_RX_N23")
	)
	(via
		(at 318.906398 -222.294704)
		(size 0.508)
		(drill 0.254)
		(layers "F.Cu" "B.Cu")
		(net "PCIE_RX_N23")
	)
	(segment
		(start 318.900048 -225.92538)
		(end 318.900048 -224.770188)
		(width 0.136652)
		(layer "B.Cu")
		(net "PCIE_RX_N23")
	)
	(segment
		(start 318.652652 -224.17278)
		(end 318.652652 -222.907352)
		(width 0.136652)
		(layer "B.Cu")
		(net "PCIE_RX_N23")
	)
	(arc
		(start 318.652652 -222.907352)
		(mid 318.718602 -222.575797)
		(end 318.906398 -222.294704)
		(width 0.136652)
		(layer "B.Cu")
		(net "PCIE_RX_N23")
	)
	(arc
		(start 318.900048 -224.770188)
		(mid 318.85581 -224.547791)
		(end 318.729868 -224.359216)
		(width 0.136652)
		(layer "B.Cu")
		(net "PCIE_RX_N23")
	)
	(arc
		(start 318.729868 -224.359216)
		(mid 318.672714 -224.273678)
		(end 318.652652 -224.17278)
		(width 0.136652)
		(layer "B.Cu")
		(net "PCIE_RX_N23")
	)
	(segment
		(start 259.68833 -50.90287)
		(end 255.009142 -50.90287)
		(width 0.1016)
		(layer "In2.Cu")
		(net "PCIE_RX_N23")
	)
	(segment
		(start 259.7658 -50.8254)
		(end 259.68833 -50.90287)
		(width 0.1016)
		(layer "In2.Cu")
		(net "PCIE_RX_N23")
	)
	(segment
		(start 268.266164 -52.208938)
		(end 260.417818 -50.8254)
		(width 0.1397)
		(layer "In2.Cu")
		(net "PCIE_RX_N23")
	)
	(segment
		(start 307.81498 -196.551804)
		(end 285.528512 -70.157848)
		(width 0.1397)
		(layer "In2.Cu")
		(net "PCIE_RX_N23")
	)
	(segment
		(start 315.494416 -209.924396)
		(end 315.494416 -209.78749)
		(width 0.1397)
		(layer "In2.Cu")
		(net "PCIE_RX_N23")
	)
	(segment
		(start 315.494416 -209.78749)
		(end 314.96 -206.756)
		(width 0.1397)
		(layer "In2.Cu")
		(net "PCIE_RX_N23")
	)
	(segment
		(start 285.528512 -70.157848)
		(end 277.47595 -58.657744)
		(width 0.1397)
		(layer "In2.Cu")
		(net "PCIE_RX_N23")
	)
	(segment
		(start 254.854202 -50.74793)
		(end 254.854202 -50.74539)
		(width 0.1016)
		(layer "In2.Cu")
		(net "PCIE_RX_N23")
	)
	(segment
		(start 277.47595 -58.657744)
		(end 268.266164 -52.208938)
		(width 0.1397)
		(layer "In2.Cu")
		(net "PCIE_RX_N23")
	)
	(segment
		(start 318.665098 -221.7928)
		(end 318.665098 -219.587318)
		(width 0.1397)
		(layer "In2.Cu")
		(net "PCIE_RX_N23")
	)
	(segment
		(start 315.491622 -214.496142)
		(end 315.491622 -209.92719)
		(width 0.1397)
		(layer "In2.Cu")
		(net "PCIE_RX_N23")
	)
	(segment
		(start 318.665098 -219.587318)
		(end 315.623448 -215.24341)
		(width 0.1397)
		(layer "In2.Cu")
		(net "PCIE_RX_N23")
	)
	(segment
		(start 314.96 -206.756)
		(end 307.81498 -196.551804)
		(width 0.1397)
		(layer "In2.Cu")
		(net "PCIE_RX_N23")
	)
	(segment
		(start 315.491622 -209.92719)
		(end 315.494416 -209.924396)
		(width 0.1397)
		(layer "In2.Cu")
		(net "PCIE_RX_N23")
	)
	(segment
		(start 315.623448 -215.24341)
		(end 315.491622 -214.496142)
		(width 0.1397)
		(layer "In2.Cu")
		(net "PCIE_RX_N23")
	)
	(segment
		(start 260.417818 -50.8254)
		(end 259.7658 -50.8254)
		(width 0.1397)
		(layer "In2.Cu")
		(net "PCIE_RX_N23")
	)
	(segment
		(start 318.906398 -222.294704)
		(end 318.849248 -222.237808)
		(width 0.1397)
		(layer "In2.Cu")
		(net "PCIE_RX_N23")
	)
	(arc
		(start 318.849248 -222.237808)
		(mid 318.712908 -222.033622)
		(end 318.665098 -221.7928)
		(width 0.1397)
		(layer "In2.Cu")
		(net "PCIE_RX_N23")
	)
	(arc
		(start 254.854202 -50.74539)
		(mid 254.926142 -50.571712)
		(end 255.09982 -50.499772)
		(width 0.1016)
		(layer "In2.Cu")
		(net "PCIE_RX_N23")
	)
	(arc
		(start 254.873506 -50.82286)
		(mid 254.859116 -50.786616)
		(end 254.854202 -50.74793)
		(width 0.1016)
		(layer "In2.Cu")
		(net "PCIE_RX_N23")
	)
	(arc
		(start 255.009142 -50.90287)
		(mid 254.930408 -50.881374)
		(end 254.873506 -50.82286)
		(width 0.1016)
		(layer "In2.Cu")
		(net "PCIE_RX_N23")
	)
	(segment
		(start 255.599946 -48.999902)
		(end 256.099818 -49.499774)
		(width 0.136652)
		(layer "F.Cu")
		(net "PCIE_RX_N22")
	)
	(via
		(at 322.106544 -222.294704)
		(size 0.508)
		(drill 0.254)
		(layers "F.Cu" "B.Cu")
		(net "PCIE_RX_N22")
	)
	(via
		(at 256.099818 -49.499774)
		(size 0.4572)
		(drill 0.2032)
		(layers "F.Cu" "B.Cu")
		(net "PCIE_RX_N22")
	)
	(segment
		(start 322.100194 -225.92538)
		(end 322.100194 -224.770188)
		(width 0.136652)
		(layer "B.Cu")
		(net "PCIE_RX_N22")
	)
	(segment
		(start 321.852798 -224.17278)
		(end 321.852798 -222.907352)
		(width 0.136652)
		(layer "B.Cu")
		(net "PCIE_RX_N22")
	)
	(arc
		(start 321.930014 -224.359216)
		(mid 321.87286 -224.273678)
		(end 321.852798 -224.17278)
		(width 0.136652)
		(layer "B.Cu")
		(net "PCIE_RX_N22")
	)
	(arc
		(start 322.100194 -224.770188)
		(mid 322.055956 -224.547791)
		(end 321.930014 -224.359216)
		(width 0.136652)
		(layer "B.Cu")
		(net "PCIE_RX_N22")
	)
	(arc
		(start 321.852798 -222.907352)
		(mid 321.918748 -222.575797)
		(end 322.106544 -222.294704)
		(width 0.136652)
		(layer "B.Cu")
		(net "PCIE_RX_N22")
	)
	(segment
		(start 260.417818 -49.8348)
		(end 268.958314 -51.340512)
		(width 0.1397)
		(layer "In2.Cu")
		(net "PCIE_RX_N22")
	)
	(segment
		(start 319.377314 -216.169748)
		(end 321.865244 -219.723208)
		(width 0.1397)
		(layer "In2.Cu")
		(net "PCIE_RX_N22")
	)
	(segment
		(start 308.113176 -191.173354)
		(end 318.135 -205.486)
		(width 0.1397)
		(layer "In2.Cu")
		(net "PCIE_RX_N22")
	)
	(segment
		(start 278.512016 -58.03011)
		(end 286.697674 -69.72046)
		(width 0.1397)
		(layer "In2.Cu")
		(net "PCIE_RX_N22")
	)
	(segment
		(start 318.544194 -211.445094)
		(end 318.545972 -211.455)
		(width 0.1397)
		(layer "In2.Cu")
		(net "PCIE_RX_N22")
	)
	(segment
		(start 318.135 -205.486)
		(end 318.769746 -209.08518)
		(width 0.1397)
		(layer "In2.Cu")
		(net "PCIE_RX_N22")
	)
	(segment
		(start 321.865244 -219.723208)
		(end 321.865244 -221.7928)
		(width 0.1397)
		(layer "In2.Cu")
		(net "PCIE_RX_N22")
	)
	(segment
		(start 259.646928 -49.902872)
		(end 259.715 -49.8348)
		(width 0.1016)
		(layer "In2.Cu")
		(net "PCIE_RX_N22")
	)
	(segment
		(start 259.715 -49.8348)
		(end 260.417818 -49.8348)
		(width 0.1397)
		(layer "In2.Cu")
		(net "PCIE_RX_N22")
	)
	(segment
		(start 318.545972 -211.455)
		(end 319.377314 -216.169748)
		(width 0.1397)
		(layer "In2.Cu")
		(net "PCIE_RX_N22")
	)
	(segment
		(start 318.769746 -209.08518)
		(end 318.769746 -209.085942)
		(width 0.1397)
		(layer "In2.Cu")
		(net "PCIE_RX_N22")
	)
	(segment
		(start 286.697674 -69.72046)
		(end 308.113176 -191.173354)
		(width 0.1397)
		(layer "In2.Cu")
		(net "PCIE_RX_N22")
	)
	(segment
		(start 318.797432 -209.243168)
		(end 318.765428 -209.52333)
		(width 0.1397)
		(layer "In2.Cu")
		(net "PCIE_RX_N22")
	)
	(segment
		(start 256.00914 -49.902872)
		(end 259.646928 -49.902872)
		(width 0.1016)
		(layer "In2.Cu")
		(net "PCIE_RX_N22")
	)
	(segment
		(start 255.8542 -49.745392)
		(end 255.8542 -49.747932)
		(width 0.1016)
		(layer "In2.Cu")
		(net "PCIE_RX_N22")
	)
	(segment
		(start 322.049394 -222.237808)
		(end 322.106544 -222.294704)
		(width 0.1397)
		(layer "In2.Cu")
		(net "PCIE_RX_N22")
	)
	(segment
		(start 318.765174 -209.524854)
		(end 318.544194 -211.445094)
		(width 0.1397)
		(layer "In2.Cu")
		(net "PCIE_RX_N22")
	)
	(segment
		(start 318.769746 -209.085942)
		(end 318.797432 -209.243168)
		(width 0.1397)
		(layer "In2.Cu")
		(net "PCIE_RX_N22")
	)
	(segment
		(start 268.958314 -51.340512)
		(end 278.512016 -58.03011)
		(width 0.1397)
		(layer "In2.Cu")
		(net "PCIE_RX_N22")
	)
	(segment
		(start 318.765428 -209.52333)
		(end 318.765174 -209.524854)
		(width 0.1397)
		(layer "In2.Cu")
		(net "PCIE_RX_N22")
	)
	(arc
		(start 255.873504 -49.822862)
		(mid 255.930398 -49.881391)
		(end 256.00914 -49.902872)
		(width 0.1016)
		(layer "In2.Cu")
		(net "PCIE_RX_N22")
	)
	(arc
		(start 321.865244 -221.7928)
		(mid 321.913053 -222.033622)
		(end 322.049394 -222.237808)
		(width 0.1397)
		(layer "In2.Cu")
		(net "PCIE_RX_N22")
	)
	(arc
		(start 255.8542 -49.747932)
		(mid 255.8591 -49.786622)
		(end 255.873504 -49.822862)
		(width 0.1016)
		(layer "In2.Cu")
		(net "PCIE_RX_N22")
	)
	(arc
		(start 256.099818 -49.499774)
		(mid 255.92614 -49.571714)
		(end 255.8542 -49.745392)
		(width 0.1016)
		(layer "In2.Cu")
		(net "PCIE_RX_N22")
	)
	(segment
		(start 254.599948 -47.999904)
		(end 255.09982 -48.499776)
		(width 0.136652)
		(layer "F.Cu")
		(net "PCIE_RX_N21")
	)
	(via
		(at 325.306436 -222.294704)
		(size 0.508)
		(drill 0.254)
		(layers "F.Cu" "B.Cu")
		(net "PCIE_RX_N21")
	)
	(via
		(at 255.09982 -48.499776)
		(size 0.4572)
		(drill 0.2032)
		(layers "F.Cu" "B.Cu")
		(net "PCIE_RX_N21")
	)
	(segment
		(start 325.05269 -224.17278)
		(end 325.05269 -222.907352)
		(width 0.136652)
		(layer "B.Cu")
		(net "PCIE_RX_N21")
	)
	(segment
		(start 325.300086 -225.92538)
		(end 325.300086 -224.770188)
		(width 0.136652)
		(layer "B.Cu")
		(net "PCIE_RX_N21")
	)
	(arc
		(start 325.05269 -222.907352)
		(mid 325.11864 -222.575797)
		(end 325.306436 -222.294704)
		(width 0.136652)
		(layer "B.Cu")
		(net "PCIE_RX_N21")
	)
	(arc
		(start 325.129906 -224.359216)
		(mid 325.072752 -224.273678)
		(end 325.05269 -224.17278)
		(width 0.136652)
		(layer "B.Cu")
		(net "PCIE_RX_N21")
	)
	(arc
		(start 325.300086 -224.770188)
		(mid 325.255848 -224.547791)
		(end 325.129906 -224.359216)
		(width 0.136652)
		(layer "B.Cu")
		(net "PCIE_RX_N21")
	)
	(segment
		(start 325.249286 -222.237808)
		(end 325.306436 -222.294704)
		(width 0.1397)
		(layer "In2.Cu")
		(net "PCIE_RX_N21")
	)
	(segment
		(start 259.503926 -48.902874)
		(end 259.588 -48.8188)
		(width 0.1016)
		(layer "In2.Cu")
		(net "PCIE_RX_N21")
	)
	(segment
		(start 321.945 -207.518)
		(end 321.945 -213.469982)
		(width 0.1397)
		(layer "In2.Cu")
		(net "PCIE_RX_N21")
	)
	(segment
		(start 259.588 -48.8188)
		(end 260.388862 -48.8188)
		(width 0.1397)
		(layer "In2.Cu")
		(net "PCIE_RX_N21")
	)
	(segment
		(start 308.58968 -188.444632)
		(end 321.945 -207.518)
		(width 0.1397)
		(layer "In2.Cu")
		(net "PCIE_RX_N21")
	)
	(segment
		(start 254.854202 -48.745394)
		(end 254.854202 -48.747934)
		(width 0.1016)
		(layer "In2.Cu")
		(net "PCIE_RX_N21")
	)
	(segment
		(start 255.009142 -48.902874)
		(end 259.503926 -48.902874)
		(width 0.1016)
		(layer "In2.Cu")
		(net "PCIE_RX_N21")
	)
	(segment
		(start 279.144476 -57.242964)
		(end 287.579054 -69.288914)
		(width 0.1397)
		(layer "In2.Cu")
		(net "PCIE_RX_N21")
	)
	(segment
		(start 325.065136 -220.651324)
		(end 325.065136 -221.7928)
		(width 0.1397)
		(layer "In2.Cu")
		(net "PCIE_RX_N21")
	)
	(segment
		(start 324.77964 -219.655898)
		(end 325.065136 -220.651324)
		(width 0.1397)
		(layer "In2.Cu")
		(net "PCIE_RX_N21")
	)
	(segment
		(start 269.37716 -50.40376)
		(end 279.144476 -57.242964)
		(width 0.1397)
		(layer "In2.Cu")
		(net "PCIE_RX_N21")
	)
	(segment
		(start 287.579054 -69.288914)
		(end 308.58968 -188.444632)
		(width 0.1397)
		(layer "In2.Cu")
		(net "PCIE_RX_N21")
	)
	(segment
		(start 321.945 -213.469982)
		(end 322.448428 -216.32545)
		(width 0.1397)
		(layer "In2.Cu")
		(net "PCIE_RX_N21")
	)
	(segment
		(start 260.388862 -48.8188)
		(end 269.37716 -50.40376)
		(width 0.1397)
		(layer "In2.Cu")
		(net "PCIE_RX_N21")
	)
	(segment
		(start 322.448428 -216.32545)
		(end 324.77964 -219.655898)
		(width 0.1397)
		(layer "In2.Cu")
		(net "PCIE_RX_N21")
	)
	(arc
		(start 255.09982 -48.499776)
		(mid 254.926142 -48.571716)
		(end 254.854202 -48.745394)
		(width 0.1016)
		(layer "In2.Cu")
		(net "PCIE_RX_N21")
	)
	(arc
		(start 254.873506 -48.822864)
		(mid 254.9304 -48.881393)
		(end 255.009142 -48.902874)
		(width 0.1016)
		(layer "In2.Cu")
		(net "PCIE_RX_N21")
	)
	(arc
		(start 325.065136 -221.7928)
		(mid 325.112945 -222.033622)
		(end 325.249286 -222.237808)
		(width 0.1397)
		(layer "In2.Cu")
		(net "PCIE_RX_N21")
	)
	(arc
		(start 254.854202 -48.747934)
		(mid 254.859102 -48.786624)
		(end 254.873506 -48.822864)
		(width 0.1016)
		(layer "In2.Cu")
		(net "PCIE_RX_N21")
	)
	(segment
		(start 255.599946 -46.999906)
		(end 256.099818 -46.500034)
		(width 0.136652)
		(layer "F.Cu")
		(net "PCIE_RX_N20")
	)
	(via
		(at 256.099818 -46.500034)
		(size 0.4572)
		(drill 0.2032)
		(layers "F.Cu" "B.Cu")
		(net "PCIE_RX_N20")
	)
	(via
		(at 328.506582 -222.294704)
		(size 0.508)
		(drill 0.254)
		(layers "F.Cu" "B.Cu")
		(net "PCIE_RX_N20")
	)
	(segment
		(start 328.500232 -225.92538)
		(end 328.500232 -224.770188)
		(width 0.136652)
		(layer "B.Cu")
		(net "PCIE_RX_N20")
	)
	(segment
		(start 328.252836 -224.17278)
		(end 328.252836 -222.907352)
		(width 0.136652)
		(layer "B.Cu")
		(net "PCIE_RX_N20")
	)
	(arc
		(start 328.252836 -222.907352)
		(mid 328.318786 -222.575797)
		(end 328.506582 -222.294704)
		(width 0.136652)
		(layer "B.Cu")
		(net "PCIE_RX_N20")
	)
	(arc
		(start 328.500232 -224.770188)
		(mid 328.455994 -224.547791)
		(end 328.330052 -224.359216)
		(width 0.136652)
		(layer "B.Cu")
		(net "PCIE_RX_N20")
	)
	(arc
		(start 328.330052 -224.359216)
		(mid 328.272898 -224.273678)
		(end 328.252836 -224.17278)
		(width 0.136652)
		(layer "B.Cu")
		(net "PCIE_RX_N20")
	)
	(segment
		(start 260.388862 -47.37354)
		(end 256.163572 -47.37354)
		(width 0.1397)
		(layer "In2.Cu")
		(net "PCIE_RX_N20")
	)
	(segment
		(start 325.12 -208.80578)
		(end 309.73141 -186.828684)
		(width 0.1397)
		(layer "In2.Cu")
		(net "PCIE_RX_N20")
	)
	(segment
		(start 309.73141 -186.828684)
		(end 288.885122 -68.603114)
		(width 0.1397)
		(layer "In2.Cu")
		(net "PCIE_RX_N20")
	)
	(segment
		(start 328.265282 -218.952318)
		(end 327.533 -217.9066)
		(width 0.1397)
		(layer "In2.Cu")
		(net "PCIE_RX_N20")
	)
	(segment
		(start 255.764792 -46.83506)
		(end 256.099818 -46.500034)
		(width 0.1397)
		(layer "In2.Cu")
		(net "PCIE_RX_N20")
	)
	(segment
		(start 270.044672 -49.076102)
		(end 260.388862 -47.37354)
		(width 0.1397)
		(layer "In2.Cu")
		(net "PCIE_RX_N20")
	)
	(segment
		(start 325.12 -213.6902)
		(end 325.12 -208.80578)
		(width 0.1397)
		(layer "In2.Cu")
		(net "PCIE_RX_N20")
	)
	(segment
		(start 325.470012 -215.67521)
		(end 325.12 -213.6902)
		(width 0.1397)
		(layer "In2.Cu")
		(net "PCIE_RX_N20")
	)
	(segment
		(start 256.163572 -47.37354)
		(end 255.764792 -46.97476)
		(width 0.1397)
		(layer "In2.Cu")
		(net "PCIE_RX_N20")
	)
	(segment
		(start 326.551036 -217.219022)
		(end 325.470012 -215.67521)
		(width 0.1397)
		(layer "In2.Cu")
		(net "PCIE_RX_N20")
	)
	(segment
		(start 255.764792 -46.97476)
		(end 255.764792 -46.83506)
		(width 0.1397)
		(layer "In2.Cu")
		(net "PCIE_RX_N20")
	)
	(segment
		(start 280.183844 -56.175656)
		(end 270.044672 -49.076102)
		(width 0.1397)
		(layer "In2.Cu")
		(net "PCIE_RX_N20")
	)
	(segment
		(start 328.506582 -222.294704)
		(end 328.449432 -222.237808)
		(width 0.1397)
		(layer "In2.Cu")
		(net "PCIE_RX_N20")
	)
	(segment
		(start 288.885122 -68.603114)
		(end 280.183844 -56.175656)
		(width 0.1397)
		(layer "In2.Cu")
		(net "PCIE_RX_N20")
	)
	(segment
		(start 328.265282 -221.7928)
		(end 328.265282 -218.952318)
		(width 0.1397)
		(layer "In2.Cu")
		(net "PCIE_RX_N20")
	)
	(segment
		(start 327.533 -217.9066)
		(end 326.551036 -217.219022)
		(width 0.1397)
		(layer "In2.Cu")
		(net "PCIE_RX_N20")
	)
	(arc
		(start 328.449432 -222.237808)
		(mid 328.313092 -222.033622)
		(end 328.265282 -221.7928)
		(width 0.1397)
		(layer "In2.Cu")
		(net "PCIE_RX_N20")
	)
	(segment
		(start 244.599968 -29.99994)
		(end 245.09984 -29.500068)
		(width 0.136652)
		(layer "F.Cu")
		(net "PCIE_RX_N2")
	)
	(via
		(at 245.09984 -29.500068)
		(size 0.4572)
		(drill 0.2032)
		(layers "F.Cu" "B.Cu")
		(net "PCIE_RX_N2")
	)
	(segment
		(start 277.835614 -17.483582)
		(end 273.10207 -18.318226)
		(width 0.1397)
		(layer "In2.Cu")
		(net "PCIE_RX_N2")
	)
	(segment
		(start 286.058102 -18.996914)
		(end 282.169616 -16.274034)
		(width 0.1397)
		(layer "In2.Cu")
		(net "PCIE_RX_N2")
	)
	(segment
		(start 256.816352 -17.601184)
		(end 253.16053 -18.215356)
		(width 0.1397)
		(layer "In2.Cu")
		(net "PCIE_RX_N2")
	)
	(segment
		(start 290.227258 -19.3802)
		(end 288.23158 -19.3802)
		(width 0.1397)
		(layer "In2.Cu")
		(net "PCIE_RX_N2")
	)
	(segment
		(start 245.237 -26.138632)
		(end 245.237 -29.168852)
		(width 0.1397)
		(layer "In2.Cu")
		(net "PCIE_RX_N2")
	)
	(segment
		(start 253.16053 -18.215356)
		(end 245.237 -26.138632)
		(width 0.1397)
		(layer "In2.Cu")
		(net "PCIE_RX_N2")
	)
	(segment
		(start 259.996432 -18.2372)
		(end 256.816352 -17.601184)
		(width 0.1397)
		(layer "In2.Cu")
		(net "PCIE_RX_N2")
	)
	(segment
		(start 266.346432 -18.2372)
		(end 263.171432 -17.6022)
		(width 0.1397)
		(layer "In2.Cu")
		(net "PCIE_RX_N2")
	)
	(segment
		(start 273.10207 -18.318226)
		(end 269.521432 -17.6022)
		(width 0.1397)
		(layer "In2.Cu")
		(net "PCIE_RX_N2")
	)
	(segment
		(start 282.169616 -16.274034)
		(end 280.881074 -16.046958)
		(width 0.1397)
		(layer "In2.Cu")
		(net "PCIE_RX_N2")
	)
	(segment
		(start 279.5524 -16.2814)
		(end 277.835614 -17.483582)
		(width 0.1397)
		(layer "In2.Cu")
		(net "PCIE_RX_N2")
	)
	(segment
		(start 288.23158 -19.3802)
		(end 286.058102 -18.996914)
		(width 0.1397)
		(layer "In2.Cu")
		(net "PCIE_RX_N2")
	)
	(segment
		(start 291.384482 -16.330168)
		(end 291.384482 -18.288)
		(width 0.1397)
		(layer "In2.Cu")
		(net "PCIE_RX_N2")
	)
	(segment
		(start 280.881074 -16.046958)
		(end 279.5524 -16.2814)
		(width 0.1397)
		(layer "In2.Cu")
		(net "PCIE_RX_N2")
	)
	(segment
		(start 269.521432 -17.6022)
		(end 266.346432 -18.2372)
		(width 0.1397)
		(layer "In2.Cu")
		(net "PCIE_RX_N2")
	)
	(segment
		(start 263.171432 -17.6022)
		(end 259.996432 -18.2372)
		(width 0.1397)
		(layer "In2.Cu")
		(net "PCIE_RX_N2")
	)
	(segment
		(start 291.201856 -18.728944)
		(end 290.7792 -19.1516)
		(width 0.1397)
		(layer "In2.Cu")
		(net "PCIE_RX_N2")
	)
	(arc
		(start 290.672266 -19.241008)
		(mid 290.460403 -19.344645)
		(end 290.227258 -19.3802)
		(width 0.1397)
		(layer "In2.Cu")
		(net "PCIE_RX_N2")
	)
	(arc
		(start 291.384482 -18.288)
		(mid 291.337016 -18.52663)
		(end 291.201856 -18.728944)
		(width 0.1397)
		(layer "In2.Cu")
		(net "PCIE_RX_N2")
	)
	(arc
		(start 245.237 -29.168852)
		(mid 245.201347 -29.348092)
		(end 245.09984 -29.500068)
		(width 0.1397)
		(layer "In2.Cu")
		(net "PCIE_RX_N2")
	)
	(arc
		(start 290.7792 -19.1516)
		(mid 290.727736 -19.1987)
		(end 290.672266 -19.241008)
		(width 0.1397)
		(layer "In2.Cu")
		(net "PCIE_RX_N2")
	)
	(segment
		(start 254.599948 -45.999908)
		(end 255.09982 -45.500036)
		(width 0.136652)
		(layer "F.Cu")
		(net "PCIE_RX_N19")
	)
	(via
		(at 331.706474 -222.294704)
		(size 0.508)
		(drill 0.254)
		(layers "F.Cu" "B.Cu")
		(net "PCIE_RX_N19")
	)
	(via
		(at 255.09982 -45.500036)
		(size 0.4572)
		(drill 0.2032)
		(layers "F.Cu" "B.Cu")
		(net "PCIE_RX_N19")
	)
	(segment
		(start 331.700124 -225.92538)
		(end 331.700124 -224.770188)
		(width 0.136652)
		(layer "B.Cu")
		(net "PCIE_RX_N19")
	)
	(segment
		(start 331.452728 -224.17278)
		(end 331.452728 -222.907352)
		(width 0.136652)
		(layer "B.Cu")
		(net "PCIE_RX_N19")
	)
	(arc
		(start 331.700124 -224.770188)
		(mid 331.655886 -224.547791)
		(end 331.529944 -224.359216)
		(width 0.136652)
		(layer "B.Cu")
		(net "PCIE_RX_N19")
	)
	(arc
		(start 331.529944 -224.359216)
		(mid 331.47279 -224.273678)
		(end 331.452728 -224.17278)
		(width 0.136652)
		(layer "B.Cu")
		(net "PCIE_RX_N19")
	)
	(arc
		(start 331.452728 -222.907352)
		(mid 331.518678 -222.575797)
		(end 331.706474 -222.294704)
		(width 0.136652)
		(layer "B.Cu")
		(net "PCIE_RX_N19")
	)
	(segment
		(start 331.465174 -219.936568)
		(end 329.7809 -210.384136)
		(width 0.1397)
		(layer "In2.Cu")
		(net "PCIE_RX_N19")
	)
	(segment
		(start 260.417818 -45.8216)
		(end 259.6388 -45.8216)
		(width 0.1397)
		(layer "In2.Cu")
		(net "PCIE_RX_N19")
	)
	(segment
		(start 329.7809 -210.384136)
		(end 309.862474 -181.937914)
		(width 0.1397)
		(layer "In2.Cu")
		(net "PCIE_RX_N19")
	)
	(segment
		(start 280.881328 -54.755034)
		(end 270.716502 -47.637446)
		(width 0.1397)
		(layer "In2.Cu")
		(net "PCIE_RX_N19")
	)
	(segment
		(start 254.854202 -45.748194)
		(end 254.854202 -45.745654)
		(width 0.1016)
		(layer "In2.Cu")
		(net "PCIE_RX_N19")
	)
	(segment
		(start 309.862474 -181.937914)
		(end 289.643058 -67.268344)
		(width 0.1397)
		(layer "In2.Cu")
		(net "PCIE_RX_N19")
	)
	(segment
		(start 259.44195 -45.903134)
		(end 255.009142 -45.903134)
		(width 0.1016)
		(layer "In2.Cu")
		(net "PCIE_RX_N19")
	)
	(segment
		(start 331.706474 -222.294704)
		(end 331.649324 -222.237808)
		(width 0.1397)
		(layer "In2.Cu")
		(net "PCIE_RX_N19")
	)
	(segment
		(start 331.465174 -221.7928)
		(end 331.465174 -219.936568)
		(width 0.1397)
		(layer "In2.Cu")
		(net "PCIE_RX_N19")
	)
	(segment
		(start 289.643058 -67.268344)
		(end 280.881328 -54.755034)
		(width 0.1397)
		(layer "In2.Cu")
		(net "PCIE_RX_N19")
	)
	(segment
		(start 270.716502 -47.637446)
		(end 260.417818 -45.8216)
		(width 0.1397)
		(layer "In2.Cu")
		(net "PCIE_RX_N19")
	)
	(arc
		(start 259.6388 -45.8216)
		(mid 259.548484 -45.881947)
		(end 259.44195 -45.903134)
		(width 0.1016)
		(layer "In2.Cu")
		(net "PCIE_RX_N19")
	)
	(arc
		(start 254.854202 -45.745654)
		(mid 254.926142 -45.571976)
		(end 255.09982 -45.500036)
		(width 0.1016)
		(layer "In2.Cu")
		(net "PCIE_RX_N19")
	)
	(arc
		(start 255.009142 -45.903134)
		(mid 254.930408 -45.881638)
		(end 254.873506 -45.823124)
		(width 0.1016)
		(layer "In2.Cu")
		(net "PCIE_RX_N19")
	)
	(arc
		(start 331.649324 -222.237808)
		(mid 331.512984 -222.033622)
		(end 331.465174 -221.7928)
		(width 0.1397)
		(layer "In2.Cu")
		(net "PCIE_RX_N19")
	)
	(arc
		(start 254.873506 -45.823124)
		(mid 254.859116 -45.78688)
		(end 254.854202 -45.748194)
		(width 0.1016)
		(layer "In2.Cu")
		(net "PCIE_RX_N19")
	)
	(segment
		(start 255.599946 -44.99991)
		(end 256.099818 -44.500038)
		(width 0.136652)
		(layer "F.Cu")
		(net "PCIE_RX_N18")
	)
	(via
		(at 256.099818 -44.500038)
		(size 0.4572)
		(drill 0.2032)
		(layers "F.Cu" "B.Cu")
		(net "PCIE_RX_N18")
	)
	(via
		(at 334.906366 -222.294704)
		(size 0.508)
		(drill 0.254)
		(layers "F.Cu" "B.Cu")
		(net "PCIE_RX_N18")
	)
	(segment
		(start 334.65262 -224.17278)
		(end 334.65262 -222.907352)
		(width 0.136652)
		(layer "B.Cu")
		(net "PCIE_RX_N18")
	)
	(segment
		(start 334.900016 -225.92538)
		(end 334.900016 -224.770188)
		(width 0.136652)
		(layer "B.Cu")
		(net "PCIE_RX_N18")
	)
	(arc
		(start 334.729836 -224.359216)
		(mid 334.672682 -224.273678)
		(end 334.65262 -224.17278)
		(width 0.136652)
		(layer "B.Cu")
		(net "PCIE_RX_N18")
	)
	(arc
		(start 334.900016 -224.770188)
		(mid 334.855778 -224.547791)
		(end 334.729836 -224.359216)
		(width 0.136652)
		(layer "B.Cu")
		(net "PCIE_RX_N18")
	)
	(arc
		(start 334.65262 -222.907352)
		(mid 334.71857 -222.575797)
		(end 334.906366 -222.294704)
		(width 0.136652)
		(layer "B.Cu")
		(net "PCIE_RX_N18")
	)
	(segment
		(start 290.378388 -66.375788)
		(end 281.867864 -54.221126)
		(width 0.1397)
		(layer "In2.Cu")
		(net "PCIE_RX_N18")
	)
	(segment
		(start 281.867864 -54.221126)
		(end 271.161002 -46.724062)
		(width 0.1397)
		(layer "In2.Cu")
		(net "PCIE_RX_N18")
	)
	(segment
		(start 259.715 -44.830238)
		(end 259.642102 -44.903136)
		(width 0.1016)
		(layer "In2.Cu")
		(net "PCIE_RX_N18")
	)
	(segment
		(start 334.906366 -222.294704)
		(end 334.849216 -222.237808)
		(width 0.1397)
		(layer "In2.Cu")
		(net "PCIE_RX_N18")
	)
	(segment
		(start 330.99121 -209.968592)
		(end 310.561482 -180.791866)
		(width 0.1397)
		(layer "In2.Cu")
		(net "PCIE_RX_N18")
	)
	(segment
		(start 259.642102 -44.903136)
		(end 256.00914 -44.903136)
		(width 0.1016)
		(layer "In2.Cu")
		(net "PCIE_RX_N18")
	)
	(segment
		(start 334.665066 -221.7928)
		(end 334.665066 -219.273374)
		(width 0.1397)
		(layer "In2.Cu")
		(net "PCIE_RX_N18")
	)
	(segment
		(start 271.161002 -46.724062)
		(end 260.417818 -44.830238)
		(width 0.1397)
		(layer "In2.Cu")
		(net "PCIE_RX_N18")
	)
	(segment
		(start 334.665066 -219.273374)
		(end 334.490822 -218.284806)
		(width 0.1397)
		(layer "In2.Cu")
		(net "PCIE_RX_N18")
	)
	(segment
		(start 260.417818 -44.830238)
		(end 259.715 -44.830238)
		(width 0.1397)
		(layer "In2.Cu")
		(net "PCIE_RX_N18")
	)
	(segment
		(start 255.8542 -44.748196)
		(end 255.8542 -44.745656)
		(width 0.1016)
		(layer "In2.Cu")
		(net "PCIE_RX_N18")
	)
	(segment
		(start 310.561482 -180.791866)
		(end 290.378388 -66.375788)
		(width 0.1397)
		(layer "In2.Cu")
		(net "PCIE_RX_N18")
	)
	(segment
		(start 331.772768 -214.402924)
		(end 330.99121 -209.968592)
		(width 0.1397)
		(layer "In2.Cu")
		(net "PCIE_RX_N18")
	)
	(segment
		(start 334.490822 -218.284806)
		(end 331.772768 -214.402924)
		(width 0.1397)
		(layer "In2.Cu")
		(net "PCIE_RX_N18")
	)
	(arc
		(start 256.00914 -44.903136)
		(mid 255.930406 -44.88164)
		(end 255.873504 -44.823126)
		(width 0.1016)
		(layer "In2.Cu")
		(net "PCIE_RX_N18")
	)
	(arc
		(start 255.873504 -44.823126)
		(mid 255.859114 -44.786882)
		(end 255.8542 -44.748196)
		(width 0.1016)
		(layer "In2.Cu")
		(net "PCIE_RX_N18")
	)
	(arc
		(start 334.849216 -222.237808)
		(mid 334.712876 -222.033622)
		(end 334.665066 -221.7928)
		(width 0.1397)
		(layer "In2.Cu")
		(net "PCIE_RX_N18")
	)
	(arc
		(start 255.8542 -44.745656)
		(mid 255.92614 -44.571978)
		(end 256.099818 -44.500038)
		(width 0.1016)
		(layer "In2.Cu")
		(net "PCIE_RX_N18")
	)
	(segment
		(start 254.599948 -43.999912)
		(end 255.09982 -43.50004)
		(width 0.136652)
		(layer "F.Cu")
		(net "PCIE_RX_N17")
	)
	(via
		(at 338.106512 -222.294704)
		(size 0.508)
		(drill 0.254)
		(layers "F.Cu" "B.Cu")
		(net "PCIE_RX_N17")
	)
	(via
		(at 255.09982 -43.50004)
		(size 0.4572)
		(drill 0.2032)
		(layers "F.Cu" "B.Cu")
		(net "PCIE_RX_N17")
	)
	(segment
		(start 338.100162 -225.92538)
		(end 338.100162 -224.770188)
		(width 0.136652)
		(layer "B.Cu")
		(net "PCIE_RX_N17")
	)
	(segment
		(start 337.852766 -224.17278)
		(end 337.852766 -222.907352)
		(width 0.136652)
		(layer "B.Cu")
		(net "PCIE_RX_N17")
	)
	(arc
		(start 337.929982 -224.359216)
		(mid 337.872828 -224.273678)
		(end 337.852766 -224.17278)
		(width 0.136652)
		(layer "B.Cu")
		(net "PCIE_RX_N17")
	)
	(arc
		(start 338.100162 -224.770188)
		(mid 338.055924 -224.547791)
		(end 337.929982 -224.359216)
		(width 0.136652)
		(layer "B.Cu")
		(net "PCIE_RX_N17")
	)
	(arc
		(start 337.852766 -222.907352)
		(mid 337.918716 -222.575797)
		(end 338.106512 -222.294704)
		(width 0.136652)
		(layer "B.Cu")
		(net "PCIE_RX_N17")
	)
	(segment
		(start 334.772 -214.5792)
		(end 334.6704 -214.002874)
		(width 0.1397)
		(layer "In2.Cu")
		(net "PCIE_RX_N17")
	)
	(segment
		(start 282.448762 -53.699664)
		(end 282.392628 -53.643276)
		(width 0.1397)
		(layer "In2.Cu")
		(net "PCIE_RX_N17")
	)
	(segment
		(start 260.418072 -43.83024)
		(end 259.847588 -43.83024)
		(width 0.1397)
		(layer "In2.Cu")
		(net "PCIE_RX_N17")
	)
	(segment
		(start 329.640184 -205.906624)
		(end 311.650888 -180.222398)
		(width 0.1397)
		(layer "In2.Cu")
		(net "PCIE_RX_N17")
	)
	(segment
		(start 254.854202 -43.748198)
		(end 254.854202 -43.745658)
		(width 0.1016)
		(layer "In2.Cu")
		(net "PCIE_RX_N17")
	)
	(segment
		(start 259.77469 -43.903138)
		(end 255.009142 -43.903138)
		(width 0.1016)
		(layer "In2.Cu")
		(net "PCIE_RX_N17")
	)
	(segment
		(start 334.03032 -208.980532)
		(end 329.640184 -205.906624)
		(width 0.1397)
		(layer "In2.Cu")
		(net "PCIE_RX_N17")
	)
	(segment
		(start 337.865212 -221.7928)
		(end 337.865212 -218.996514)
		(width 0.1397)
		(layer "In2.Cu")
		(net "PCIE_RX_N17")
	)
	(segment
		(start 334.6704 -209.620612)
		(end 334.03032 -208.980532)
		(width 0.1397)
		(layer "In2.Cu")
		(net "PCIE_RX_N17")
	)
	(segment
		(start 311.650888 -180.222398)
		(end 291.301424 -66.34226)
		(width 0.1397)
		(layer "In2.Cu")
		(net "PCIE_RX_N17")
	)
	(segment
		(start 291.301424 -66.34226)
		(end 282.448762 -53.699664)
		(width 0.1397)
		(layer "In2.Cu")
		(net "PCIE_RX_N17")
	)
	(segment
		(start 338.106512 -222.294704)
		(end 338.049362 -222.237808)
		(width 0.1397)
		(layer "In2.Cu")
		(net "PCIE_RX_N17")
	)
	(segment
		(start 337.865212 -218.996514)
		(end 334.772 -214.5792)
		(width 0.1397)
		(layer "In2.Cu")
		(net "PCIE_RX_N17")
	)
	(segment
		(start 259.847588 -43.83024)
		(end 259.77469 -43.903138)
		(width 0.1016)
		(layer "In2.Cu")
		(net "PCIE_RX_N17")
	)
	(segment
		(start 271.983454 -45.869098)
		(end 260.418072 -43.83024)
		(width 0.1397)
		(layer "In2.Cu")
		(net "PCIE_RX_N17")
	)
	(segment
		(start 334.6704 -214.002874)
		(end 334.6704 -209.620612)
		(width 0.1397)
		(layer "In2.Cu")
		(net "PCIE_RX_N17")
	)
	(segment
		(start 282.392628 -53.643276)
		(end 271.983454 -45.869098)
		(width 0.1397)
		(layer "In2.Cu")
		(net "PCIE_RX_N17")
	)
	(arc
		(start 255.009142 -43.903138)
		(mid 254.930408 -43.881642)
		(end 254.873506 -43.823128)
		(width 0.1016)
		(layer "In2.Cu")
		(net "PCIE_RX_N17")
	)
	(arc
		(start 338.049362 -222.237808)
		(mid 337.913022 -222.033622)
		(end 337.865212 -221.7928)
		(width 0.1397)
		(layer "In2.Cu")
		(net "PCIE_RX_N17")
	)
	(arc
		(start 254.854202 -43.745658)
		(mid 254.926142 -43.57198)
		(end 255.09982 -43.50004)
		(width 0.1016)
		(layer "In2.Cu")
		(net "PCIE_RX_N17")
	)
	(arc
		(start 254.873506 -43.823128)
		(mid 254.859116 -43.786884)
		(end 254.854202 -43.748198)
		(width 0.1016)
		(layer "In2.Cu")
		(net "PCIE_RX_N17")
	)
	(segment
		(start 255.599946 -42.999914)
		(end 256.099818 -42.500042)
		(width 0.136652)
		(layer "F.Cu")
		(net "PCIE_RX_N16")
	)
	(via
		(at 341.306404 -222.294704)
		(size 0.508)
		(drill 0.254)
		(layers "F.Cu" "B.Cu")
		(net "PCIE_RX_N16")
	)
	(via
		(at 256.099818 -42.500042)
		(size 0.4572)
		(drill 0.2032)
		(layers "F.Cu" "B.Cu")
		(net "PCIE_RX_N16")
	)
	(segment
		(start 341.300054 -225.92538)
		(end 341.300054 -224.770188)
		(width 0.136652)
		(layer "B.Cu")
		(net "PCIE_RX_N16")
	)
	(segment
		(start 341.052658 -224.17278)
		(end 341.052658 -222.907352)
		(width 0.136652)
		(layer "B.Cu")
		(net "PCIE_RX_N16")
	)
	(arc
		(start 341.300054 -224.770188)
		(mid 341.255816 -224.547791)
		(end 341.129874 -224.359216)
		(width 0.136652)
		(layer "B.Cu")
		(net "PCIE_RX_N16")
	)
	(arc
		(start 341.129874 -224.359216)
		(mid 341.07272 -224.273678)
		(end 341.052658 -224.17278)
		(width 0.136652)
		(layer "B.Cu")
		(net "PCIE_RX_N16")
	)
	(arc
		(start 341.052658 -222.907352)
		(mid 341.118608 -222.575797)
		(end 341.306404 -222.294704)
		(width 0.136652)
		(layer "B.Cu")
		(net "PCIE_RX_N16")
	)
	(segment
		(start 272.091912 -44.897802)
		(end 282.177236 -51.959764)
		(width 0.1397)
		(layer "In2.Cu")
		(net "PCIE_RX_N16")
	)
	(segment
		(start 334.7212 -206.7306)
		(end 337.363054 -208.580228)
		(width 0.1397)
		(layer "In2.Cu")
		(net "PCIE_RX_N16")
	)
	(segment
		(start 259.67436 -42.83964)
		(end 260.417818 -42.83964)
		(width 0.1397)
		(layer "In2.Cu")
		(net "PCIE_RX_N16")
	)
	(segment
		(start 292.01999 -65.97142)
		(end 313.628532 -180.02377)
		(width 0.1397)
		(layer "In2.Cu")
		(net "PCIE_RX_N16")
	)
	(segment
		(start 341.249254 -222.237808)
		(end 341.306404 -222.294704)
		(width 0.1397)
		(layer "In2.Cu")
		(net "PCIE_RX_N16")
	)
	(segment
		(start 330.835254 -204.597)
		(end 333.600298 -206.532988)
		(width 0.1397)
		(layer "In2.Cu")
		(net "PCIE_RX_N16")
	)
	(segment
		(start 341.065104 -220.541342)
		(end 341.065104 -221.7928)
		(width 0.1397)
		(layer "In2.Cu")
		(net "PCIE_RX_N16")
	)
	(segment
		(start 338.400136 -216.730072)
		(end 341.065104 -220.541342)
		(width 0.1397)
		(layer "In2.Cu")
		(net "PCIE_RX_N16")
	)
	(segment
		(start 282.177236 -51.959764)
		(end 292.01999 -65.97142)
		(width 0.1397)
		(layer "In2.Cu")
		(net "PCIE_RX_N16")
	)
	(segment
		(start 313.628532 -180.02377)
		(end 330.835254 -204.597)
		(width 0.1397)
		(layer "In2.Cu")
		(net "PCIE_RX_N16")
	)
	(segment
		(start 333.600298 -206.532988)
		(end 334.7212 -206.7306)
		(width 0.1397)
		(layer "In2.Cu")
		(net "PCIE_RX_N16")
	)
	(segment
		(start 260.417818 -42.83964)
		(end 272.091912 -44.897802)
		(width 0.1397)
		(layer "In2.Cu")
		(net "PCIE_RX_N16")
	)
	(segment
		(start 259.61086 -42.90314)
		(end 259.67436 -42.83964)
		(width 0.1016)
		(layer "In2.Cu")
		(net "PCIE_RX_N16")
	)
	(segment
		(start 337.865212 -213.695788)
		(end 338.400136 -216.730072)
		(width 0.1397)
		(layer "In2.Cu")
		(net "PCIE_RX_N16")
	)
	(segment
		(start 337.363054 -208.580228)
		(end 337.865212 -209.29727)
		(width 0.1397)
		(layer "In2.Cu")
		(net "PCIE_RX_N16")
	)
	(segment
		(start 255.8542 -42.74566)
		(end 255.8542 -42.7482)
		(width 0.1016)
		(layer "In2.Cu")
		(net "PCIE_RX_N16")
	)
	(segment
		(start 256.00914 -42.90314)
		(end 259.61086 -42.90314)
		(width 0.1016)
		(layer "In2.Cu")
		(net "PCIE_RX_N16")
	)
	(segment
		(start 337.865212 -209.29727)
		(end 337.865212 -213.695788)
		(width 0.1397)
		(layer "In2.Cu")
		(net "PCIE_RX_N16")
	)
	(arc
		(start 255.8542 -42.7482)
		(mid 255.899581 -42.857759)
		(end 256.00914 -42.90314)
		(width 0.1016)
		(layer "In2.Cu")
		(net "PCIE_RX_N16")
	)
	(arc
		(start 256.099818 -42.500042)
		(mid 255.92614 -42.571982)
		(end 255.8542 -42.74566)
		(width 0.1016)
		(layer "In2.Cu")
		(net "PCIE_RX_N16")
	)
	(arc
		(start 341.065104 -221.7928)
		(mid 341.112913 -222.033622)
		(end 341.249254 -222.237808)
		(width 0.1397)
		(layer "In2.Cu")
		(net "PCIE_RX_N16")
	)
	(segment
		(start 254.599948 -40.999918)
		(end 255.09982 -40.500046)
		(width 0.136652)
		(layer "F.Cu")
		(net "PCIE_RX_N15")
	)
	(via
		(at 255.09982 -40.500046)
		(size 0.4572)
		(drill 0.2032)
		(layers "F.Cu" "B.Cu")
		(net "PCIE_RX_N15")
	)
	(segment
		(start 329.249786 -27.66822)
		(end 330.70419 -34.514282)
		(width 0.1397)
		(layer "In2.Cu")
		(net "PCIE_RX_N15")
	)
	(segment
		(start 324.384416 -12.530074)
		(end 324.384416 -13.344906)
		(width 0.1397)
		(layer "In2.Cu")
		(net "PCIE_RX_N15")
	)
	(segment
		(start 287.822386 -42.28211)
		(end 287.82264 -42.281348)
		(width 0.1397)
		(layer "In2.Cu")
		(net "PCIE_RX_N15")
	)
	(segment
		(start 330.344018 -36.209986)
		(end 325.358506 -39.448232)
		(width 0.1397)
		(layer "In2.Cu")
		(net "PCIE_RX_N15")
	)
	(segment
		(start 259.1308 -40.7162)
		(end 258.520946 -40.106346)
		(width 0.1016)
		(layer "In2.Cu")
		(net "PCIE_RX_N15")
	)
	(segment
		(start 276.01037 -42.440352)
		(end 269.887192 -43.401488)
		(width 0.1397)
		(layer "In2.Cu")
		(net "PCIE_RX_N15")
	)
	(segment
		(start 325.358506 -39.448232)
		(end 300.53788 -44.723812)
		(width 0.1397)
		(layer "In2.Cu")
		(net "PCIE_RX_N15")
	)
	(segment
		(start 281.715464 -43.497246)
		(end 276.01037 -42.440352)
		(width 0.1397)
		(layer "In2.Cu")
		(net "PCIE_RX_N15")
	)
	(segment
		(start 282.679648 -43.676062)
		(end 281.715464 -43.497246)
		(width 0.1397)
		(layer "In2.Cu")
		(net "PCIE_RX_N15")
	)
	(segment
		(start 324.6374 -13.967968)
		(end 324.6374 -14.950694)
		(width 0.1397)
		(layer "In2.Cu")
		(net "PCIE_RX_N15")
	)
	(segment
		(start 287.82264 -42.281348)
		(end 282.679648 -43.676062)
		(width 0.1397)
		(layer "In2.Cu")
		(net "PCIE_RX_N15")
	)
	(segment
		(start 328.225658 -18.538698)
		(end 329.707748 -25.511506)
		(width 0.1397)
		(layer "In2.Cu")
		(net "PCIE_RX_N15")
	)
	(segment
		(start 269.887192 -43.401488)
		(end 261.769352 -40.7162)
		(width 0.1397)
		(layer "In2.Cu")
		(net "PCIE_RX_N15")
	)
	(segment
		(start 330.70419 -34.514282)
		(end 330.344018 -36.209986)
		(width 0.1397)
		(layer "In2.Cu")
		(net "PCIE_RX_N15")
	)
	(segment
		(start 259.2832 -40.7162)
		(end 259.1308 -40.7162)
		(width 0.1016)
		(layer "In2.Cu")
		(net "PCIE_RX_N15")
	)
	(segment
		(start 261.769352 -40.7162)
		(end 259.2832 -40.7162)
		(width 0.1397)
		(layer "In2.Cu")
		(net "PCIE_RX_N15")
	)
	(segment
		(start 329.707748 -25.511506)
		(end 329.249786 -27.66822)
		(width 0.1397)
		(layer "In2.Cu")
		(net "PCIE_RX_N15")
	)
	(segment
		(start 258.520946 -40.106346)
		(end 255.651 -40.106346)
		(width 0.1016)
		(layer "In2.Cu")
		(net "PCIE_RX_N15")
	)
	(segment
		(start 255.382014 -40.217598)
		(end 255.09982 -40.500046)
		(width 0.1016)
		(layer "In2.Cu")
		(net "PCIE_RX_N15")
	)
	(segment
		(start 324.6374 -14.950694)
		(end 328.225658 -18.538698)
		(width 0.1397)
		(layer "In2.Cu")
		(net "PCIE_RX_N15")
	)
	(segment
		(start 294.14724 -43.496484)
		(end 287.822386 -42.28211)
		(width 0.1397)
		(layer "In2.Cu")
		(net "PCIE_RX_N15")
	)
	(segment
		(start 300.53788 -44.723812)
		(end 294.14724 -43.496484)
		(width 0.1397)
		(layer "In2.Cu")
		(net "PCIE_RX_N15")
	)
	(arc
		(start 255.651 -40.106346)
		(mid 255.505436 -40.135207)
		(end 255.382014 -40.217598)
		(width 0.1016)
		(layer "In2.Cu")
		(net "PCIE_RX_N15")
	)
	(arc
		(start 324.637146 -13.950442)
		(mid 324.63715 -13.952601)
		(end 324.637146 -13.95476)
		(width 0.1397)
		(layer "In2.Cu")
		(net "PCIE_RX_N15")
	)
	(arc
		(start 324.460362 -13.528294)
		(mid 324.462006 -13.529952)
		(end 324.463664 -13.531596)
		(width 0.1397)
		(layer "In2.Cu")
		(net "PCIE_RX_N15")
	)
	(arc
		(start 324.463664 -13.531596)
		(mid 324.588763 -13.725129)
		(end 324.637146 -13.950442)
		(width 0.1397)
		(layer "In2.Cu")
		(net "PCIE_RX_N15")
	)
	(arc
		(start 324.384416 -13.344906)
		(mid 324.404157 -13.444149)
		(end 324.460362 -13.528294)
		(width 0.1397)
		(layer "In2.Cu")
		(net "PCIE_RX_N15")
	)
	(arc
		(start 324.637146 -13.95476)
		(mid 324.637306 -13.961363)
		(end 324.6374 -13.967968)
		(width 0.1397)
		(layer "In2.Cu")
		(net "PCIE_RX_N15")
	)
	(segment
		(start 255.599946 -39.99992)
		(end 256.099818 -39.500048)
		(width 0.136652)
		(layer "F.Cu")
		(net "PCIE_RX_N14")
	)
	(via
		(at 256.099818 -39.500048)
		(size 0.4572)
		(drill 0.2032)
		(layers "F.Cu" "B.Cu")
		(net "PCIE_RX_N14")
	)
	(segment
		(start 259.36575 -39.09695)
		(end 256.667 -39.09695)
		(width 0.1016)
		(layer "In2.Cu")
		(net "PCIE_RX_N14")
	)
	(segment
		(start 276.369272 -40.744648)
		(end 270.023336 -42.013886)
		(width 0.1397)
		(layer "In2.Cu")
		(net "PCIE_RX_N14")
	)
	(segment
		(start 324.384416 -16.330168)
		(end 324.384416 -17.144746)
		(width 0.1397)
		(layer "In2.Cu")
		(net "PCIE_RX_N14")
	)
	(segment
		(start 324.6374 -17.767808)
		(end 324.6374 -18.35531)
		(width 0.1397)
		(layer "In2.Cu")
		(net "PCIE_RX_N14")
	)
	(segment
		(start 321.512692 -37.544248)
		(end 320.80835 -38.601142)
		(width 0.1397)
		(layer "In2.Cu")
		(net "PCIE_RX_N14")
	)
	(segment
		(start 261.836154 -39.535354)
		(end 260.0325 -39.535354)
		(width 0.1397)
		(layer "In2.Cu")
		(net "PCIE_RX_N14")
	)
	(segment
		(start 324.6374 -18.35531)
		(end 324.827646 -18.62709)
		(width 0.1397)
		(layer "In2.Cu")
		(net "PCIE_RX_N14")
	)
	(segment
		(start 299.432218 -43.208194)
		(end 293.414958 -42.146982)
		(width 0.1397)
		(layer "In2.Cu")
		(net "PCIE_RX_N14")
	)
	(segment
		(start 327.09739 -29.873702)
		(end 326.103742 -30.51937)
		(width 0.1397)
		(layer "In2.Cu")
		(net "PCIE_RX_N14")
	)
	(segment
		(start 327.589134 -29.118306)
		(end 327.09739 -29.873702)
		(width 0.1397)
		(layer "In2.Cu")
		(net "PCIE_RX_N14")
	)
	(segment
		(start 319.037208 -39.751)
		(end 299.432218 -43.208194)
		(width 0.1397)
		(layer "In2.Cu")
		(net "PCIE_RX_N14")
	)
	(segment
		(start 259.804154 -39.535354)
		(end 259.36575 -39.09695)
		(width 0.1016)
		(layer "In2.Cu")
		(net "PCIE_RX_N14")
	)
	(segment
		(start 320.80835 -38.601142)
		(end 319.037208 -39.751)
		(width 0.1397)
		(layer "In2.Cu")
		(net "PCIE_RX_N14")
	)
	(segment
		(start 327.708514 -20.739608)
		(end 328.52868 -24.599392)
		(width 0.1397)
		(layer "In2.Cu")
		(net "PCIE_RX_N14")
	)
	(segment
		(start 287.39846 -41.086024)
		(end 282.737306 -42.018204)
		(width 0.1397)
		(layer "In2.Cu")
		(net "PCIE_RX_N14")
	)
	(segment
		(start 260.0325 -39.535354)
		(end 259.804154 -39.535354)
		(width 0.1016)
		(layer "In2.Cu")
		(net "PCIE_RX_N14")
	)
	(segment
		(start 282.737306 -42.018204)
		(end 276.369272 -40.744648)
		(width 0.1397)
		(layer "In2.Cu")
		(net "PCIE_RX_N14")
	)
	(segment
		(start 256.386838 -39.213028)
		(end 256.099818 -39.500048)
		(width 0.1016)
		(layer "In2.Cu")
		(net "PCIE_RX_N14")
	)
	(segment
		(start 323.158104 -31.145226)
		(end 322.734432 -31.797498)
		(width 0.1397)
		(layer "In2.Cu")
		(net "PCIE_RX_N14")
	)
	(segment
		(start 328.52868 -24.599392)
		(end 327.589134 -29.118306)
		(width 0.1397)
		(layer "In2.Cu")
		(net "PCIE_RX_N14")
	)
	(segment
		(start 270.023336 -42.013886)
		(end 261.836154 -39.535354)
		(width 0.1397)
		(layer "In2.Cu")
		(net "PCIE_RX_N14")
	)
	(segment
		(start 322.734432 -31.797498)
		(end 321.512692 -37.544248)
		(width 0.1397)
		(layer "In2.Cu")
		(net "PCIE_RX_N14")
	)
	(segment
		(start 293.414958 -42.146982)
		(end 287.39846 -41.086024)
		(width 0.1397)
		(layer "In2.Cu")
		(net "PCIE_RX_N14")
	)
	(segment
		(start 324.827646 -18.62709)
		(end 327.708514 -20.739608)
		(width 0.1397)
		(layer "In2.Cu")
		(net "PCIE_RX_N14")
	)
	(segment
		(start 326.103742 -30.51937)
		(end 323.158104 -31.145226)
		(width 0.1397)
		(layer "In2.Cu")
		(net "PCIE_RX_N14")
	)
	(arc
		(start 324.463664 -17.331436)
		(mid 324.588763 -17.524969)
		(end 324.637146 -17.750282)
		(width 0.1397)
		(layer "In2.Cu")
		(net "PCIE_RX_N14")
	)
	(arc
		(start 324.460362 -17.328134)
		(mid 324.462006 -17.329792)
		(end 324.463664 -17.331436)
		(width 0.1397)
		(layer "In2.Cu")
		(net "PCIE_RX_N14")
	)
	(arc
		(start 324.384416 -17.144746)
		(mid 324.404157 -17.243989)
		(end 324.460362 -17.328134)
		(width 0.1397)
		(layer "In2.Cu")
		(net "PCIE_RX_N14")
	)
	(arc
		(start 324.637146 -17.7546)
		(mid 324.637306 -17.761203)
		(end 324.6374 -17.767808)
		(width 0.1397)
		(layer "In2.Cu")
		(net "PCIE_RX_N14")
	)
	(arc
		(start 256.667 -39.09695)
		(mid 256.515366 -39.127112)
		(end 256.386838 -39.213028)
		(width 0.1016)
		(layer "In2.Cu")
		(net "PCIE_RX_N14")
	)
	(arc
		(start 324.637146 -17.750282)
		(mid 324.63715 -17.752441)
		(end 324.637146 -17.7546)
		(width 0.1397)
		(layer "In2.Cu")
		(net "PCIE_RX_N14")
	)
	(segment
		(start 254.599948 -38.999922)
		(end 255.09982 -38.50005)
		(width 0.136652)
		(layer "F.Cu")
		(net "PCIE_RX_N13")
	)
	(via
		(at 255.09982 -38.50005)
		(size 0.4572)
		(drill 0.2032)
		(layers "F.Cu" "B.Cu")
		(net "PCIE_RX_N13")
	)
	(segment
		(start 310.078374 -38.054788)
		(end 313.722004 -38.829234)
		(width 0.1397)
		(layer "In2.Cu")
		(net "PCIE_RX_N13")
	)
	(segment
		(start 318.450976 -26.894028)
		(end 317.9318 -24.299164)
		(width 0.1397)
		(layer "In2.Cu")
		(net "PCIE_RX_N13")
	)
	(segment
		(start 318.17691 -31.345632)
		(end 318.36614 -30.271974)
		(width 0.1397)
		(layer "In2.Cu")
		(net "PCIE_RX_N13")
	)
	(segment
		(start 270.646906 -40.773604)
		(end 276.996906 -39.503604)
		(width 0.1397)
		(layer "In2.Cu")
		(net "PCIE_RX_N13")
	)
	(segment
		(start 297.869102 -42.072052)
		(end 301.833534 -41.229534)
		(width 0.1397)
		(layer "In2.Cu")
		(net "PCIE_RX_N13")
	)
	(segment
		(start 262.769096 -38.168072)
		(end 270.646906 -40.773604)
		(width 0.1397)
		(layer "In2.Cu")
		(net "PCIE_RX_N13")
	)
	(segment
		(start 322.416932 -17.940528)
		(end 322.416932 -17.690846)
		(width 0.1397)
		(layer "In2.Cu")
		(net "PCIE_RX_N13")
	)
	(segment
		(start 314.804806 -38.59911)
		(end 316.287912 -37.635942)
		(width 0.1397)
		(layer "In2.Cu")
		(net "PCIE_RX_N13")
	)
	(segment
		(start 317.9318 -24.299164)
		(end 317.9318 -20.364196)
		(width 0.1397)
		(layer "In2.Cu")
		(net "PCIE_RX_N13")
	)
	(segment
		(start 276.996906 -39.503604)
		(end 283.346906 -40.773604)
		(width 0.1397)
		(layer "In2.Cu")
		(net "PCIE_RX_N13")
	)
	(segment
		(start 301.833534 -41.229534)
		(end 305.50612 -38.844474)
		(width 0.1397)
		(layer "In2.Cu")
		(net "PCIE_RX_N13")
	)
	(segment
		(start 259.334 -38.1)
		(end 259.402072 -38.168072)
		(width 0.1016)
		(layer "In2.Cu")
		(net "PCIE_RX_N13")
	)
	(segment
		(start 309.935626 -38.06317)
		(end 309.93715 -38.061646)
		(width 0.1397)
		(layer "In2.Cu")
		(net "PCIE_RX_N13")
	)
	(segment
		(start 316.287912 -37.635942)
		(end 317.554102 -35.686238)
		(width 0.1397)
		(layer "In2.Cu")
		(net "PCIE_RX_N13")
	)
	(segment
		(start 317.416688 -33.25749)
		(end 317.610744 -32.154114)
		(width 0.1397)
		(layer "In2.Cu")
		(net "PCIE_RX_N13")
	)
	(segment
		(start 259.402072 -38.168072)
		(end 262.769096 -38.168072)
		(width 0.1397)
		(layer "In2.Cu")
		(net "PCIE_RX_N13")
	)
	(segment
		(start 309.93715 -38.061646)
		(end 309.938674 -38.061646)
		(width 0.1397)
		(layer "In2.Cu")
		(net "PCIE_RX_N13")
	)
	(segment
		(start 305.50612 -38.844474)
		(end 309.935626 -38.06317)
		(width 0.1397)
		(layer "In2.Cu")
		(net "PCIE_RX_N13")
	)
	(segment
		(start 317.610744 -32.154114)
		(end 318.17691 -31.345632)
		(width 0.1397)
		(layer "In2.Cu")
		(net "PCIE_RX_N13")
	)
	(segment
		(start 318.344296 -30.161738)
		(end 318.266826 -29.775404)
		(width 0.1397)
		(layer "In2.Cu")
		(net "PCIE_RX_N13")
	)
	(segment
		(start 317.743586 -34.794952)
		(end 317.416688 -33.25749)
		(width 0.1397)
		(layer "In2.Cu")
		(net "PCIE_RX_N13")
	)
	(segment
		(start 283.346906 -40.773604)
		(end 287.481772 -39.94658)
		(width 0.1397)
		(layer "In2.Cu")
		(net "PCIE_RX_N13")
	)
	(segment
		(start 313.722004 -38.829234)
		(end 314.804806 -38.59911)
		(width 0.1397)
		(layer "In2.Cu")
		(net "PCIE_RX_N13")
	)
	(segment
		(start 318.266826 -29.775404)
		(end 318.186054 -29.372052)
		(width 0.1397)
		(layer "In2.Cu")
		(net "PCIE_RX_N13")
	)
	(segment
		(start 318.186054 -28.217368)
		(end 318.450976 -26.894028)
		(width 0.1397)
		(layer "In2.Cu")
		(net "PCIE_RX_N13")
	)
	(segment
		(start 317.554102 -35.686238)
		(end 317.743586 -34.794952)
		(width 0.1397)
		(layer "In2.Cu")
		(net "PCIE_RX_N13")
	)
	(segment
		(start 319.331848 -18.964148)
		(end 321.393312 -18.964148)
		(width 0.1397)
		(layer "In2.Cu")
		(net "PCIE_RX_N13")
	)
	(segment
		(start 310.07812 -38.054788)
		(end 310.078374 -38.054788)
		(width 0.1397)
		(layer "In2.Cu")
		(net "PCIE_RX_N13")
	)
	(segment
		(start 287.481772 -39.94658)
		(end 297.869102 -42.072052)
		(width 0.1397)
		(layer "In2.Cu")
		(net "PCIE_RX_N13")
	)
	(segment
		(start 254.914146 -38.1)
		(end 259.334 -38.1)
		(width 0.1016)
		(layer "In2.Cu")
		(net "PCIE_RX_N13")
	)
	(segment
		(start 318.186054 -29.372052)
		(end 318.186054 -28.217368)
		(width 0.1397)
		(layer "In2.Cu")
		(net "PCIE_RX_N13")
	)
	(segment
		(start 309.938674 -38.061646)
		(end 310.07812 -38.054788)
		(width 0.1397)
		(layer "In2.Cu")
		(net "PCIE_RX_N13")
	)
	(segment
		(start 318.36614 -30.271974)
		(end 318.344296 -30.161738)
		(width 0.1397)
		(layer "In2.Cu")
		(net "PCIE_RX_N13")
	)
	(arc
		(start 317.9318 -20.364196)
		(mid 318.341865 -19.374213)
		(end 319.331848 -18.964148)
		(width 0.1397)
		(layer "In2.Cu")
		(net "PCIE_RX_N13")
	)
	(arc
		(start 322.416932 -17.690846)
		(mid 322.400887 -17.523273)
		(end 322.352924 -17.361916)
		(width 0.1397)
		(layer "In2.Cu")
		(net "PCIE_RX_N13")
	)
	(arc
		(start 254.759968 -38.254178)
		(mid 254.805126 -38.145158)
		(end 254.914146 -38.1)
		(width 0.1016)
		(layer "In2.Cu")
		(net "PCIE_RX_N13")
	)
	(arc
		(start 255.09982 -38.50005)
		(mid 254.867067 -38.463933)
		(end 254.759968 -38.254178)
		(width 0.1016)
		(layer "In2.Cu")
		(net "PCIE_RX_N13")
	)
	(arc
		(start 321.393312 -18.964148)
		(mid 322.117121 -18.664337)
		(end 322.416932 -17.940528)
		(width 0.1397)
		(layer "In2.Cu")
		(net "PCIE_RX_N13")
	)
	(arc
		(start 322.352924 -17.361916)
		(mid 322.198023 -16.855715)
		(end 322.134484 -16.330168)
		(width 0.1397)
		(layer "In2.Cu")
		(net "PCIE_RX_N13")
	)
	(segment
		(start 255.599946 -37.999924)
		(end 256.099818 -37.500052)
		(width 0.136652)
		(layer "F.Cu")
		(net "PCIE_RX_N12")
	)
	(via
		(at 256.099818 -37.500052)
		(size 0.4572)
		(drill 0.2032)
		(layers "F.Cu" "B.Cu")
		(net "PCIE_RX_N12")
	)
	(segment
		(start 317.600838 -15.807436)
		(end 316.734952 -17.044162)
		(width 0.1397)
		(layer "In2.Cu")
		(net "PCIE_RX_N12")
	)
	(segment
		(start 298.178982 -41.065196)
		(end 287.56483 -38.898576)
		(width 0.1397)
		(layer "In2.Cu")
		(net "PCIE_RX_N12")
	)
	(segment
		(start 316.550548 -23.75535)
		(end 317.052706 -26.603706)
		(width 0.1397)
		(layer "In2.Cu")
		(net "PCIE_RX_N12")
	)
	(segment
		(start 259.6642 -37.160454)
		(end 259.511546 -37.160454)
		(width 0.1016)
		(layer "In2.Cu")
		(net "PCIE_RX_N12")
	)
	(segment
		(start 283.778706 -39.656004)
		(end 277.428706 -38.386004)
		(width 0.1397)
		(layer "In2.Cu")
		(net "PCIE_RX_N12")
	)
	(segment
		(start 255.851914 -37.500052)
		(end 256.099818 -37.500052)
		(width 0.1016)
		(layer "In2.Cu")
		(net "PCIE_RX_N12")
	)
	(segment
		(start 271.078706 -39.656004)
		(end 262.864854 -37.160454)
		(width 0.1397)
		(layer "In2.Cu")
		(net "PCIE_RX_N12")
	)
	(segment
		(start 316.734952 -17.044162)
		(end 316.550548 -18.088864)
		(width 0.1397)
		(layer "In2.Cu")
		(net "PCIE_RX_N12")
	)
	(segment
		(start 316.550548 -18.088864)
		(end 316.550548 -23.75535)
		(width 0.1397)
		(layer "In2.Cu")
		(net "PCIE_RX_N12")
	)
	(segment
		(start 277.428706 -38.386004)
		(end 271.078706 -39.656004)
		(width 0.1397)
		(layer "In2.Cu")
		(net "PCIE_RX_N12")
	)
	(segment
		(start 259.454396 -37.103304)
		(end 255.849882 -37.103304)
		(width 0.1016)
		(layer "In2.Cu")
		(net "PCIE_RX_N12")
	)
	(segment
		(start 309.76062 -32.043624)
		(end 306.64912 -36.759388)
		(width 0.1397)
		(layer "In2.Cu")
		(net "PCIE_RX_N12")
	)
	(segment
		(start 319.370202 -14.9606)
		(end 317.600838 -15.807436)
		(width 0.1397)
		(layer "In2.Cu")
		(net "PCIE_RX_N12")
	)
	(segment
		(start 311.489598 -31.676086)
		(end 309.76062 -32.043624)
		(width 0.1397)
		(layer "In2.Cu")
		(net "PCIE_RX_N12")
	)
	(segment
		(start 301.183802 -40.42664)
		(end 298.178982 -41.065196)
		(width 0.1397)
		(layer "In2.Cu")
		(net "PCIE_RX_N12")
	)
	(segment
		(start 259.511546 -37.160454)
		(end 259.454396 -37.103304)
		(width 0.1016)
		(layer "In2.Cu")
		(net "PCIE_RX_N12")
	)
	(segment
		(start 321.600068 -14.9606)
		(end 319.370202 -14.9606)
		(width 0.1397)
		(layer "In2.Cu")
		(net "PCIE_RX_N12")
	)
	(segment
		(start 322.387468 -13.816076)
		(end 322.387468 -14.1732)
		(width 0.1397)
		(layer "In2.Cu")
		(net "PCIE_RX_N12")
	)
	(segment
		(start 287.56483 -38.898576)
		(end 283.778706 -39.656004)
		(width 0.1397)
		(layer "In2.Cu")
		(net "PCIE_RX_N12")
	)
	(segment
		(start 316.815724 -27.946604)
		(end 311.489598 -31.676086)
		(width 0.1397)
		(layer "In2.Cu")
		(net "PCIE_RX_N12")
	)
	(segment
		(start 306.64912 -36.759388)
		(end 301.183802 -40.42664)
		(width 0.1397)
		(layer "In2.Cu")
		(net "PCIE_RX_N12")
	)
	(segment
		(start 317.052706 -26.603706)
		(end 316.815724 -27.946604)
		(width 0.1397)
		(layer "In2.Cu")
		(net "PCIE_RX_N12")
	)
	(segment
		(start 262.864854 -37.160454)
		(end 259.6642 -37.160454)
		(width 0.1397)
		(layer "In2.Cu")
		(net "PCIE_RX_N12")
	)
	(arc
		(start 255.849882 -37.103304)
		(mid 255.727212 -37.154116)
		(end 255.6764 -37.276786)
		(width 0.1016)
		(layer "In2.Cu")
		(net "PCIE_RX_N12")
	)
	(arc
		(start 255.6764 -37.276786)
		(mid 255.725522 -37.418809)
		(end 255.851914 -37.500052)
		(width 0.1016)
		(layer "In2.Cu")
		(net "PCIE_RX_N12")
	)
	(arc
		(start 322.387468 -14.1732)
		(mid 322.156844 -14.729976)
		(end 321.600068 -14.9606)
		(width 0.1397)
		(layer "In2.Cu")
		(net "PCIE_RX_N12")
	)
	(arc
		(start 322.313554 -13.485622)
		(mid 322.368796 -13.646759)
		(end 322.387468 -13.816076)
		(width 0.1397)
		(layer "In2.Cu")
		(net "PCIE_RX_N12")
	)
	(arc
		(start 322.134484 -12.530074)
		(mid 322.162714 -13.019337)
		(end 322.313554 -13.485622)
		(width 0.1397)
		(layer "In2.Cu")
		(net "PCIE_RX_N12")
	)
	(segment
		(start 254.599948 -36.999926)
		(end 255.09982 -36.500054)
		(width 0.136652)
		(layer "F.Cu")
		(net "PCIE_RX_N11")
	)
	(via
		(at 255.09982 -36.500054)
		(size 0.4572)
		(drill 0.2032)
		(layers "F.Cu" "B.Cu")
		(net "PCIE_RX_N11")
	)
	(segment
		(start 313.796426 -15.05712)
		(end 314.973716 -16.23441)
		(width 0.1397)
		(layer "In2.Cu")
		(net "PCIE_RX_N11")
	)
	(segment
		(start 287.166812 -31.97479)
		(end 285.09849 -31.609538)
		(width 0.1397)
		(layer "In2.Cu")
		(net "PCIE_RX_N11")
	)
	(segment
		(start 315.608462 -25.73909)
		(end 315.32576 -27.265884)
		(width 0.1397)
		(layer "In2.Cu")
		(net "PCIE_RX_N11")
	)
	(segment
		(start 258.397756 -36.096956)
		(end 255.790954 -36.096956)
		(width 0.1016)
		(layer "In2.Cu")
		(net "PCIE_RX_N11")
	)
	(segment
		(start 266.672822 -36.867592)
		(end 265.009376 -36.365434)
		(width 0.1397)
		(layer "In2.Cu")
		(net "PCIE_RX_N11")
	)
	(segment
		(start 312.487056 -29.058616)
		(end 310.110632 -30.722824)
		(width 0.1397)
		(layer "In2.Cu")
		(net "PCIE_RX_N11")
	)
	(segment
		(start 310.110632 -30.722824)
		(end 301.151544 -32.30245)
		(width 0.1397)
		(layer "In2.Cu")
		(net "PCIE_RX_N11")
	)
	(segment
		(start 282.61691 -32.126428)
		(end 279.513284 -34.299398)
		(width 0.1397)
		(layer "In2.Cu")
		(net "PCIE_RX_N11")
	)
	(segment
		(start 258.557776 -36.256976)
		(end 258.397756 -36.096956)
		(width 0.1016)
		(layer "In2.Cu")
		(net "PCIE_RX_N11")
	)
	(segment
		(start 289.134296 -31.62808)
		(end 287.166812 -31.97479)
		(width 0.1397)
		(layer "In2.Cu")
		(net "PCIE_RX_N11")
	)
	(segment
		(start 279.513284 -34.299398)
		(end 266.672822 -36.867592)
		(width 0.1397)
		(layer "In2.Cu")
		(net "PCIE_RX_N11")
	)
	(segment
		(start 315.214 -23.767034)
		(end 315.608462 -25.73909)
		(width 0.1397)
		(layer "In2.Cu")
		(net "PCIE_RX_N11")
	)
	(segment
		(start 263.471406 -35.901122)
		(end 259.958078 -35.901122)
		(width 0.1397)
		(layer "In2.Cu")
		(net "PCIE_RX_N11")
	)
	(segment
		(start 315.214 -16.814546)
		(end 315.214 -23.767034)
		(width 0.1397)
		(layer "In2.Cu")
		(net "PCIE_RX_N11")
	)
	(segment
		(start 291.474906 -32.03575)
		(end 289.134296 -31.62808)
		(width 0.1397)
		(layer "In2.Cu")
		(net "PCIE_RX_N11")
	)
	(segment
		(start 314.950094 -27.997658)
		(end 313.754008 -28.83535)
		(width 0.1397)
		(layer "In2.Cu")
		(net "PCIE_RX_N11")
	)
	(segment
		(start 265.009376 -36.365434)
		(end 263.471406 -35.901122)
		(width 0.1397)
		(layer "In2.Cu")
		(net "PCIE_RX_N11")
	)
	(segment
		(start 295.962832 -32.105346)
		(end 293.929562 -32.463486)
		(width 0.1397)
		(layer "In2.Cu")
		(net "PCIE_RX_N11")
	)
	(segment
		(start 285.09849 -31.609538)
		(end 282.61691 -32.126428)
		(width 0.1397)
		(layer "In2.Cu")
		(net "PCIE_RX_N11")
	)
	(segment
		(start 313.637422 -13.967968)
		(end 313.637422 -14.673326)
		(width 0.1397)
		(layer "In2.Cu")
		(net "PCIE_RX_N11")
	)
	(segment
		(start 255.29921 -36.300664)
		(end 255.09982 -36.500054)
		(width 0.1016)
		(layer "In2.Cu")
		(net "PCIE_RX_N11")
	)
	(segment
		(start 258.7244 -36.256976)
		(end 258.557776 -36.256976)
		(width 0.1016)
		(layer "In2.Cu")
		(net "PCIE_RX_N11")
	)
	(segment
		(start 293.529766 -32.39389)
		(end 291.474906 -32.03575)
		(width 0.1397)
		(layer "In2.Cu")
		(net "PCIE_RX_N11")
	)
	(segment
		(start 301.151544 -32.30245)
		(end 297.99788 -31.746444)
		(width 0.1397)
		(layer "In2.Cu")
		(net "PCIE_RX_N11")
	)
	(segment
		(start 313.754008 -28.83535)
		(end 312.487056 -29.058616)
		(width 0.1397)
		(layer "In2.Cu")
		(net "PCIE_RX_N11")
	)
	(segment
		(start 259.958078 -35.901122)
		(end 259.602224 -36.256976)
		(width 0.1397)
		(layer "In2.Cu")
		(net "PCIE_RX_N11")
	)
	(segment
		(start 259.602224 -36.256976)
		(end 258.7244 -36.256976)
		(width 0.1397)
		(layer "In2.Cu")
		(net "PCIE_RX_N11")
	)
	(segment
		(start 315.32576 -27.265884)
		(end 314.950094 -27.997658)
		(width 0.1397)
		(layer "In2.Cu")
		(net "PCIE_RX_N11")
	)
	(segment
		(start 313.384438 -12.530074)
		(end 313.384438 -13.344906)
		(width 0.1397)
		(layer "In2.Cu")
		(net "PCIE_RX_N11")
	)
	(segment
		(start 297.99788 -31.746444)
		(end 295.962832 -32.105346)
		(width 0.1397)
		(layer "In2.Cu")
		(net "PCIE_RX_N11")
	)
	(segment
		(start 293.929562 -32.463486)
		(end 293.529766 -32.39389)
		(width 0.1397)
		(layer "In2.Cu")
		(net "PCIE_RX_N11")
	)
	(arc
		(start 313.637422 -14.673326)
		(mid 313.67874 -14.881046)
		(end 313.796426 -15.05712)
		(width 0.1397)
		(layer "In2.Cu")
		(net "PCIE_RX_N11")
	)
	(arc
		(start 313.637168 -13.950442)
		(mid 313.637172 -13.952601)
		(end 313.637168 -13.95476)
		(width 0.1397)
		(layer "In2.Cu")
		(net "PCIE_RX_N11")
	)
	(arc
		(start 314.973716 -16.23441)
		(mid 315.151511 -16.500593)
		(end 315.214 -16.814546)
		(width 0.1397)
		(layer "In2.Cu")
		(net "PCIE_RX_N11")
	)
	(arc
		(start 255.790954 -36.096956)
		(mid 255.524816 -36.149894)
		(end 255.29921 -36.300664)
		(width 0.1016)
		(layer "In2.Cu")
		(net "PCIE_RX_N11")
	)
	(arc
		(start 313.463686 -13.531596)
		(mid 313.588785 -13.725129)
		(end 313.637168 -13.950442)
		(width 0.1397)
		(layer "In2.Cu")
		(net "PCIE_RX_N11")
	)
	(arc
		(start 313.637168 -13.95476)
		(mid 313.637328 -13.961363)
		(end 313.637422 -13.967968)
		(width 0.1397)
		(layer "In2.Cu")
		(net "PCIE_RX_N11")
	)
	(arc
		(start 313.460384 -13.528294)
		(mid 313.462028 -13.529952)
		(end 313.463686 -13.531596)
		(width 0.1397)
		(layer "In2.Cu")
		(net "PCIE_RX_N11")
	)
	(arc
		(start 313.384438 -13.344906)
		(mid 313.404179 -13.444149)
		(end 313.460384 -13.528294)
		(width 0.1397)
		(layer "In2.Cu")
		(net "PCIE_RX_N11")
	)
	(segment
		(start 255.599946 -35.999928)
		(end 256.099818 -35.500056)
		(width 0.136652)
		(layer "F.Cu")
		(net "PCIE_RX_N10")
	)
	(via
		(at 256.099818 -35.500056)
		(size 0.4572)
		(drill 0.2032)
		(layers "F.Cu" "B.Cu")
		(net "PCIE_RX_N10")
	)
	(segment
		(start 307.180488 -23.377144)
		(end 306.466494 -24.396954)
		(width 0.1397)
		(layer "In2.Cu")
		(net "PCIE_RX_N10")
	)
	(segment
		(start 313.545728 -17.482312)
		(end 313.580526 -17.56664)
		(width 0.1397)
		(layer "In2.Cu")
		(net "PCIE_RX_N10")
	)
	(segment
		(start 278.200104 -33.43529)
		(end 267.218668 -35.370262)
		(width 0.1397)
		(layer "In2.Cu")
		(net "PCIE_RX_N10")
	)
	(segment
		(start 302.134524 -31.059628)
		(end 298.3357 -30.38983)
		(width 0.1397)
		(layer "In2.Cu")
		(net "PCIE_RX_N10")
	)
	(segment
		(start 313.637422 -17.853914)
		(end 313.637422 -18.407634)
		(width 0.1397)
		(layer "In2.Cu")
		(net "PCIE_RX_N10")
	)
	(segment
		(start 289.343846 -30.804104)
		(end 287.386014 -31.148782)
		(width 0.1397)
		(layer "In2.Cu")
		(net "PCIE_RX_N10")
	)
	(segment
		(start 296.928794 -30.637734)
		(end 295.955466 -31.319216)
		(width 0.1397)
		(layer "In2.Cu")
		(net "PCIE_RX_N10")
	)
	(segment
		(start 295.955466 -31.319216)
		(end 294.110918 -31.644336)
		(width 0.1397)
		(layer "In2.Cu")
		(net "PCIE_RX_N10")
	)
	(segment
		(start 312.532014 -19.431)
		(end 308.434232 -19.431)
		(width 0.1397)
		(layer "In2.Cu")
		(net "PCIE_RX_N10")
	)
	(segment
		(start 307.438298 -21.914104)
		(end 307.180488 -23.377144)
		(width 0.1397)
		(layer "In2.Cu")
		(net "PCIE_RX_N10")
	)
	(segment
		(start 306.466494 -24.396954)
		(end 306.390548 -24.827992)
		(width 0.1397)
		(layer "In2.Cu")
		(net "PCIE_RX_N10")
	)
	(segment
		(start 267.218668 -35.370262)
		(end 263.974834 -34.7218)
		(width 0.1397)
		(layer "In2.Cu")
		(net "PCIE_RX_N10")
	)
	(segment
		(start 307.345334 -21.3868)
		(end 307.438298 -21.914104)
		(width 0.1397)
		(layer "In2.Cu")
		(net "PCIE_RX_N10")
	)
	(segment
		(start 313.384438 -16.330168)
		(end 313.384438 -17.144746)
		(width 0.1397)
		(layer "In2.Cu")
		(net "PCIE_RX_N10")
	)
	(segment
		(start 305.704494 -29.865066)
		(end 304.62601 -30.620208)
		(width 0.1397)
		(layer "In2.Cu")
		(net "PCIE_RX_N10")
	)
	(segment
		(start 281.069542 -31.666434)
		(end 278.200104 -33.43529)
		(width 0.1397)
		(layer "In2.Cu")
		(net "PCIE_RX_N10")
	)
	(segment
		(start 258.7244 -35.106356)
		(end 256.325116 -35.106356)
		(width 0.1016)
		(layer "In2.Cu")
		(net "PCIE_RX_N10")
	)
	(segment
		(start 287.32607 -31.157926)
		(end 284.449266 -30.666182)
		(width 0.1397)
		(layer "In2.Cu")
		(net "PCIE_RX_N10")
	)
	(segment
		(start 306.535074 -28.67914)
		(end 305.704494 -29.865066)
		(width 0.1397)
		(layer "In2.Cu")
		(net "PCIE_RX_N10")
	)
	(segment
		(start 308.434232 -19.431)
		(end 307.853588 -19.93392)
		(width 0.1397)
		(layer "In2.Cu")
		(net "PCIE_RX_N10")
	)
	(segment
		(start 256.099818 -35.331654)
		(end 256.099818 -35.500056)
		(width 0.1016)
		(layer "In2.Cu")
		(net "PCIE_RX_N10")
	)
	(segment
		(start 307.853588 -19.93392)
		(end 307.51653 -20.41525)
		(width 0.1397)
		(layer "In2.Cu")
		(net "PCIE_RX_N10")
	)
	(segment
		(start 304.62601 -30.620208)
		(end 302.134524 -31.059628)
		(width 0.1397)
		(layer "In2.Cu")
		(net "PCIE_RX_N10")
	)
	(segment
		(start 307.51653 -20.41525)
		(end 307.345334 -21.3868)
		(width 0.1397)
		(layer "In2.Cu")
		(net "PCIE_RX_N10")
	)
	(segment
		(start 306.802282 -27.163776)
		(end 306.535074 -28.67914)
		(width 0.1397)
		(layer "In2.Cu")
		(net "PCIE_RX_N10")
	)
	(segment
		(start 313.455558 -17.323308)
		(end 313.449716 -17.328134)
		(width 0.1397)
		(layer "In2.Cu")
		(net "PCIE_RX_N10")
	)
	(segment
		(start 284.448758 -30.666436)
		(end 284.448758 -30.666182)
		(width 0.1397)
		(layer "In2.Cu")
		(net "PCIE_RX_N10")
	)
	(segment
		(start 284.449266 -30.666182)
		(end 284.448758 -30.666436)
		(width 0.1397)
		(layer "In2.Cu")
		(net "PCIE_RX_N10")
	)
	(segment
		(start 284.448758 -30.666182)
		(end 281.069542 -31.666434)
		(width 0.1397)
		(layer "In2.Cu")
		(net "PCIE_RX_N10")
	)
	(segment
		(start 259.21716 -34.7218)
		(end 258.909058 -35.029902)
		(width 0.1397)
		(layer "In2.Cu")
		(net "PCIE_RX_N10")
	)
	(segment
		(start 294.110918 -31.644336)
		(end 289.343846 -30.804104)
		(width 0.1397)
		(layer "In2.Cu")
		(net "PCIE_RX_N10")
	)
	(segment
		(start 306.390548 -24.827992)
		(end 306.802282 -27.163776)
		(width 0.1397)
		(layer "In2.Cu")
		(net "PCIE_RX_N10")
	)
	(segment
		(start 287.386014 -31.148782)
		(end 287.32607 -31.157926)
		(width 0.1397)
		(layer "In2.Cu")
		(net "PCIE_RX_N10")
	)
	(segment
		(start 263.974834 -34.7218)
		(end 259.21716 -34.7218)
		(width 0.1397)
		(layer "In2.Cu")
		(net "PCIE_RX_N10")
	)
	(segment
		(start 298.3357 -30.38983)
		(end 296.928794 -30.637734)
		(width 0.1397)
		(layer "In2.Cu")
		(net "PCIE_RX_N10")
	)
	(arc
		(start 313.449716 -17.328134)
		(mid 313.504136 -17.401229)
		(end 313.545728 -17.482312)
		(width 0.1397)
		(layer "In2.Cu")
		(net "PCIE_RX_N10")
	)
	(arc
		(start 313.437524 -17.302226)
		(mid 313.446252 -17.313014)
		(end 313.455558 -17.323308)
		(width 0.1397)
		(layer "In2.Cu")
		(net "PCIE_RX_N10")
	)
	(arc
		(start 313.580526 -17.56664)
		(mid 313.623075 -17.707484)
		(end 313.637422 -17.853914)
		(width 0.1397)
		(layer "In2.Cu")
		(net "PCIE_RX_N10")
	)
	(arc
		(start 313.637422 -18.407634)
		(mid 313.564064 -18.777082)
		(end 313.354974 -19.090386)
		(width 0.1397)
		(layer "In2.Cu")
		(net "PCIE_RX_N10")
	)
	(arc
		(start 313.409076 -17.25549)
		(mid 313.412164 -17.261757)
		(end 313.415426 -17.267936)
		(width 0.1397)
		(layer "In2.Cu")
		(net "PCIE_RX_N10")
	)
	(arc
		(start 256.325116 -35.106356)
		(mid 256.165806 -35.172344)
		(end 256.099818 -35.331654)
		(width 0.1016)
		(layer "In2.Cu")
		(net "PCIE_RX_N10")
	)
	(arc
		(start 313.408568 -17.25422)
		(mid 313.408821 -17.254855)
		(end 313.409076 -17.25549)
		(width 0.1397)
		(layer "In2.Cu")
		(net "PCIE_RX_N10")
	)
	(arc
		(start 313.384438 -17.144746)
		(mid 313.390513 -17.200804)
		(end 313.408568 -17.25422)
		(width 0.1397)
		(layer "In2.Cu")
		(net "PCIE_RX_N10")
	)
	(arc
		(start 313.41949 -17.275302)
		(mid 313.428086 -17.289046)
		(end 313.437524 -17.302226)
		(width 0.1397)
		(layer "In2.Cu")
		(net "PCIE_RX_N10")
	)
	(arc
		(start 313.415426 -17.267936)
		(mid 313.417429 -17.271635)
		(end 313.41949 -17.275302)
		(width 0.1397)
		(layer "In2.Cu")
		(net "PCIE_RX_N10")
	)
	(arc
		(start 313.354974 -19.090386)
		(mid 312.977382 -19.342592)
		(end 312.532014 -19.431)
		(width 0.1397)
		(layer "In2.Cu")
		(net "PCIE_RX_N10")
	)
	(arc
		(start 258.909058 -35.029902)
		(mid 258.824336 -35.086511)
		(end 258.7244 -35.106356)
		(width 0.1016)
		(layer "In2.Cu")
		(net "PCIE_RX_N10")
	)
	(segment
		(start 243.59997 -30.999938)
		(end 244.099842 -30.500066)
		(width 0.136652)
		(layer "F.Cu")
		(net "PCIE_RX_N1")
	)
	(via
		(at 244.099842 -30.500066)
		(size 0.4572)
		(drill 0.2032)
		(layers "F.Cu" "B.Cu")
		(net "PCIE_RX_N1")
	)
	(segment
		(start 282.507944 -14.066012)
		(end 282.381198 -13.885164)
		(width 0.1397)
		(layer "In2.Cu")
		(net "PCIE_RX_N1")
	)
	(segment
		(start 244.303042 -30.898338)
		(end 244.201442 -30.898338)
		(width 0.1016)
		(layer "In2.Cu")
		(net "PCIE_RX_N1")
	)
	(segment
		(start 284.361636 -14.43228)
		(end 283.845 -14.523466)
		(width 0.1397)
		(layer "In2.Cu")
		(net "PCIE_RX_N1")
	)
	(segment
		(start 274.578318 -16.721328)
		(end 273.372834 -16.93418)
		(width 0.1397)
		(layer "In2.Cu")
		(net "PCIE_RX_N1")
	)
	(segment
		(start 280.97861 -8.730996)
		(end 279.677368 -8.960358)
		(width 0.1397)
		(layer "In2.Cu")
		(net "PCIE_RX_N1")
	)
	(segment
		(start 244.16258 -29.842206)
		(end 244.320314 -30.000194)
		(width 0.1016)
		(layer "In2.Cu")
		(net "PCIE_RX_N1")
	)
	(segment
		(start 282.332684 -13.60932)
		(end 282.417266 -13.130022)
		(width 0.1397)
		(layer "In2.Cu")
		(net "PCIE_RX_N1")
	)
	(segment
		(start 286.860742 -14.873224)
		(end 284.361636 -14.43228)
		(width 0.1397)
		(layer "In2.Cu")
		(net "PCIE_RX_N1")
	)
	(segment
		(start 283.274516 -9.75995)
		(end 282.082748 -8.92556)
		(width 0.1397)
		(layer "In2.Cu")
		(net "PCIE_RX_N1")
	)
	(segment
		(start 244.470936 -30.318964)
		(end 244.515894 -30.655514)
		(width 0.1016)
		(layer "In2.Cu")
		(net "PCIE_RX_N1")
	)
	(segment
		(start 282.931362 -14.36243)
		(end 282.507944 -14.066012)
		(width 0.1397)
		(layer "In2.Cu")
		(net "PCIE_RX_N1")
	)
	(segment
		(start 244.1575 -25.080468)
		(end 244.1575 -28.316936)
		(width 0.1397)
		(layer "In2.Cu")
		(net "PCIE_RX_N1")
	)
	(segment
		(start 244.236748 -28.80614)
		(end 244.16258 -28.880308)
		(width 0.1016)
		(layer "In2.Cu")
		(net "PCIE_RX_N1")
	)
	(segment
		(start 252.651768 -16.5862)
		(end 244.1575 -25.080468)
		(width 0.1397)
		(layer "In2.Cu")
		(net "PCIE_RX_N1")
	)
	(segment
		(start 278.050244 -10.698734)
		(end 278.03729 -10.771124)
		(width 0.1397)
		(layer "In2.Cu")
		(net "PCIE_RX_N1")
	)
	(segment
		(start 283.845 -14.523466)
		(end 282.931362 -14.36243)
		(width 0.1397)
		(layer "In2.Cu")
		(net "PCIE_RX_N1")
	)
	(segment
		(start 278.872696 -9.523984)
		(end 278.050244 -10.698734)
		(width 0.1397)
		(layer "In2.Cu")
		(net "PCIE_RX_N1")
	)
	(segment
		(start 259.646674 -16.579596)
		(end 256.471674 -15.944596)
		(width 0.1397)
		(layer "In2.Cu")
		(net "PCIE_RX_N1")
	)
	(segment
		(start 244.236748 -28.396184)
		(end 244.236748 -28.80614)
		(width 0.1016)
		(layer "In2.Cu")
		(net "PCIE_RX_N1")
	)
	(segment
		(start 277.453852 -14.080998)
		(end 276.592284 -15.31112)
		(width 0.1397)
		(layer "In2.Cu")
		(net "PCIE_RX_N1")
	)
	(segment
		(start 244.099842 -30.796738)
		(end 244.099842 -30.500066)
		(width 0.1016)
		(layer "In2.Cu")
		(net "PCIE_RX_N1")
	)
	(segment
		(start 283.56052 -10.168636)
		(end 283.274516 -9.75995)
		(width 0.1397)
		(layer "In2.Cu")
		(net "PCIE_RX_N1")
	)
	(segment
		(start 273.372834 -16.93418)
		(end 268.798294 -16.019272)
		(width 0.1397)
		(layer "In2.Cu")
		(net "PCIE_RX_N1")
	)
	(segment
		(start 282.417266 -13.130022)
		(end 283.60116 -11.439144)
		(width 0.1397)
		(layer "In2.Cu")
		(net "PCIE_RX_N1")
	)
	(segment
		(start 244.16258 -28.880308)
		(end 244.16258 -29.842206)
		(width 0.1016)
		(layer "In2.Cu")
		(net "PCIE_RX_N1")
	)
	(segment
		(start 278.037544 -10.771124)
		(end 277.453852 -14.080998)
		(width 0.1397)
		(layer "In2.Cu")
		(net "PCIE_RX_N1")
	)
	(segment
		(start 283.60116 -11.439144)
		(end 283.692854 -10.919206)
		(width 0.1397)
		(layer "In2.Cu")
		(net "PCIE_RX_N1")
	)
	(segment
		(start 262.821674 -15.944596)
		(end 259.646674 -16.579596)
		(width 0.1397)
		(layer "In2.Cu")
		(net "PCIE_RX_N1")
	)
	(segment
		(start 256.471674 -15.944596)
		(end 252.651768 -16.5862)
		(width 0.1397)
		(layer "In2.Cu")
		(net "PCIE_RX_N1")
	)
	(segment
		(start 282.381198 -13.885164)
		(end 282.332684 -13.60932)
		(width 0.1397)
		(layer "In2.Cu")
		(net "PCIE_RX_N1")
	)
	(segment
		(start 265.996674 -16.579596)
		(end 262.821674 -15.944596)
		(width 0.1397)
		(layer "In2.Cu")
		(net "PCIE_RX_N1")
	)
	(segment
		(start 278.03729 -10.771124)
		(end 278.037544 -10.771124)
		(width 0.1397)
		(layer "In2.Cu")
		(net "PCIE_RX_N1")
	)
	(segment
		(start 279.677368 -8.960358)
		(end 278.872696 -9.523984)
		(width 0.1397)
		(layer "In2.Cu")
		(net "PCIE_RX_N1")
	)
	(segment
		(start 268.798294 -16.019272)
		(end 265.996674 -16.579596)
		(width 0.1397)
		(layer "In2.Cu")
		(net "PCIE_RX_N1")
	)
	(segment
		(start 288.40811 -16.420338)
		(end 286.860742 -14.873224)
		(width 0.1397)
		(layer "In2.Cu")
		(net "PCIE_RX_N1")
	)
	(segment
		(start 244.1575 -28.316936)
		(end 244.236748 -28.396184)
		(width 0.1016)
		(layer "In2.Cu")
		(net "PCIE_RX_N1")
	)
	(segment
		(start 276.592284 -15.31112)
		(end 274.578318 -16.721328)
		(width 0.1397)
		(layer "In2.Cu")
		(net "PCIE_RX_N1")
	)
	(segment
		(start 282.082748 -8.92556)
		(end 280.97861 -8.730996)
		(width 0.1397)
		(layer "In2.Cu")
		(net "PCIE_RX_N1")
	)
	(segment
		(start 283.692854 -10.919206)
		(end 283.56052 -10.168636)
		(width 0.1397)
		(layer "In2.Cu")
		(net "PCIE_RX_N1")
	)
	(arc
		(start 244.320314 -30.000194)
		(mid 244.420354 -30.147894)
		(end 244.470936 -30.318964)
		(width 0.1016)
		(layer "In2.Cu")
		(net "PCIE_RX_N1")
	)
	(arc
		(start 244.201442 -30.898338)
		(mid 244.1296 -30.86858)
		(end 244.099842 -30.796738)
		(width 0.1016)
		(layer "In2.Cu")
		(net "PCIE_RX_N1")
	)
	(arc
		(start 244.515894 -30.655514)
		(mid 244.464526 -30.825213)
		(end 244.303042 -30.898338)
		(width 0.1016)
		(layer "In2.Cu")
		(net "PCIE_RX_N1")
	)
	(arc
		(start 289.134296 -16.330168)
		(mid 288.793216 -16.552719)
		(end 288.40811 -16.420338)
		(width 0.1397)
		(layer "In2.Cu")
		(net "PCIE_RX_N1")
	)
	(segment
		(start 242.599972 -29.99994)
		(end 243.099844 -29.500068)
		(width 0.136652)
		(layer "F.Cu")
		(net "PCIE_RX_N0")
	)
	(via
		(at 243.099844 -29.500068)
		(size 0.4572)
		(drill 0.2032)
		(layers "F.Cu" "B.Cu")
		(net "PCIE_RX_N0")
	)
	(segment
		(start 242.711732 -28.704032)
		(end 242.711732 -29.916628)
		(width 0.1016)
		(layer "In2.Cu")
		(net "PCIE_RX_N0")
	)
	(segment
		(start 274.506182 -8.531352)
		(end 268.473936 -12.814046)
		(width 0.1397)
		(layer "In2.Cu")
		(net "PCIE_RX_N0")
	)
	(segment
		(start 290.185602 -14.52118)
		(end 290.185856 -14.520926)
		(width 0.1397)
		(layer "In2.Cu")
		(net "PCIE_RX_N0")
	)
	(segment
		(start 280.047192 -7.348982)
		(end 278.727662 -8.273288)
		(width 0.1397)
		(layer "In2.Cu")
		(net "PCIE_RX_N0")
	)
	(segment
		(start 293.558976 -12.32535)
		(end 293.558976 -8.727694)
		(width 0.1397)
		(layer "In2.Cu")
		(net "PCIE_RX_N0")
	)
	(segment
		(start 278.727662 -8.273288)
		(end 278.637746 -8.33628)
		(width 0.1397)
		(layer "In2.Cu")
		(net "PCIE_RX_N0")
	)
	(segment
		(start 243.73205 -26.94305)
		(end 243.73205 -27.863292)
		(width 0.1397)
		(layer "In2.Cu")
		(net "PCIE_RX_N0")
	)
	(segment
		(start 292.61054 -7.373366)
		(end 290.9316 -6.1976)
		(width 0.1397)
		(layer "In2.Cu")
		(net "PCIE_RX_N0")
	)
	(segment
		(start 258.99364 -15.950946)
		(end 255.800606 -15.312136)
		(width 0.1397)
		(layer "In2.Cu")
		(net "PCIE_RX_N0")
	)
	(segment
		(start 243.12626 -28.289504)
		(end 242.711732 -28.704032)
		(width 0.1016)
		(layer "In2.Cu")
		(net "PCIE_RX_N0")
	)
	(segment
		(start 288.75482 -5.813806)
		(end 280.047192 -7.348982)
		(width 0.1397)
		(layer "In2.Cu")
		(net "PCIE_RX_N0")
	)
	(segment
		(start 293.558976 -8.727694)
		(end 292.61054 -7.373366)
		(width 0.1397)
		(layer "In2.Cu")
		(net "PCIE_RX_N0")
	)
	(segment
		(start 264.143998 -14.748002)
		(end 258.99364 -15.950946)
		(width 0.1397)
		(layer "In2.Cu")
		(net "PCIE_RX_N0")
	)
	(segment
		(start 289.62731 -14.178534)
		(end 290.185602 -14.52118)
		(width 0.1397)
		(layer "In2.Cu")
		(net "PCIE_RX_N0")
	)
	(segment
		(start 290.185856 -14.520926)
		(end 290.81857 -14.782546)
		(width 0.1397)
		(layer "In2.Cu")
		(net "PCIE_RX_N0")
	)
	(segment
		(start 291.903404 -14.518894)
		(end 293.17823 -13.244068)
		(width 0.1397)
		(layer "In2.Cu")
		(net "PCIE_RX_N0")
	)
	(segment
		(start 255.800606 -15.312136)
		(end 251.975366 -15.954756)
		(width 0.1397)
		(layer "In2.Cu")
		(net "PCIE_RX_N0")
	)
	(segment
		(start 251.975366 -15.954756)
		(end 243.3066 -24.623268)
		(width 0.1397)
		(layer "In2.Cu")
		(net "PCIE_RX_N0")
	)
	(segment
		(start 288.585148 -13.147548)
		(end 289.497262 -14.059662)
		(width 0.1397)
		(layer "In2.Cu")
		(net "PCIE_RX_N0")
	)
	(segment
		(start 290.9316 -6.1976)
		(end 288.75482 -5.813806)
		(width 0.1397)
		(layer "In2.Cu")
		(net "PCIE_RX_N0")
	)
	(segment
		(start 243.73205 -27.863292)
		(end 243.305838 -28.289504)
		(width 0.1397)
		(layer "In2.Cu")
		(net "PCIE_RX_N0")
	)
	(segment
		(start 278.637746 -8.33628)
		(end 278.487886 -8.440928)
		(width 0.1397)
		(layer "In2.Cu")
		(net "PCIE_RX_N0")
	)
	(segment
		(start 243.3066 -26.5176)
		(end 243.73205 -26.94305)
		(width 0.1397)
		(layer "In2.Cu")
		(net "PCIE_RX_N0")
	)
	(segment
		(start 291.267388 -14.782546)
		(end 291.903404 -14.518894)
		(width 0.1397)
		(layer "In2.Cu")
		(net "PCIE_RX_N0")
	)
	(segment
		(start 268.473936 -12.814046)
		(end 265.564874 -13.327126)
		(width 0.1397)
		(layer "In2.Cu")
		(net "PCIE_RX_N0")
	)
	(segment
		(start 289.558476 -14.118336)
		(end 289.62731 -14.178534)
		(width 0.1397)
		(layer "In2.Cu")
		(net "PCIE_RX_N0")
	)
	(segment
		(start 243.305838 -28.289504)
		(end 243.12626 -28.289504)
		(width 0.1016)
		(layer "In2.Cu")
		(net "PCIE_RX_N0")
	)
	(segment
		(start 290.81857 -14.782546)
		(end 291.267388 -14.782546)
		(width 0.1397)
		(layer "In2.Cu")
		(net "PCIE_RX_N0")
	)
	(segment
		(start 276.239986 -8.837422)
		(end 274.506182 -8.531352)
		(width 0.1397)
		(layer "In2.Cu")
		(net "PCIE_RX_N0")
	)
	(segment
		(start 243.099844 -29.916628)
		(end 243.099844 -29.500068)
		(width 0.1016)
		(layer "In2.Cu")
		(net "PCIE_RX_N0")
	)
	(segment
		(start 243.3066 -24.623268)
		(end 243.3066 -26.5176)
		(width 0.1397)
		(layer "In2.Cu")
		(net "PCIE_RX_N0")
	)
	(segment
		(start 278.487886 -8.440928)
		(end 276.239986 -8.837422)
		(width 0.1397)
		(layer "In2.Cu")
		(net "PCIE_RX_N0")
	)
	(segment
		(start 265.564874 -13.327126)
		(end 264.143998 -14.748002)
		(width 0.1397)
		(layer "In2.Cu")
		(net "PCIE_RX_N0")
	)
	(segment
		(start 293.17823 -13.244068)
		(end 293.558976 -12.32535)
		(width 0.1397)
		(layer "In2.Cu")
		(net "PCIE_RX_N0")
	)
	(arc
		(start 242.711732 -29.916628)
		(mid 242.729641 -29.998053)
		(end 242.780058 -30.064456)
		(width 0.1016)
		(layer "In2.Cu")
		(net "PCIE_RX_N0")
	)
	(arc
		(start 289.497262 -14.059662)
		(mid 289.527577 -14.089304)
		(end 289.558476 -14.118336)
		(width 0.1397)
		(layer "In2.Cu")
		(net "PCIE_RX_N0")
	)
	(arc
		(start 242.780058 -30.064456)
		(mid 242.987217 -30.092783)
		(end 243.099844 -29.916628)
		(width 0.1016)
		(layer "In2.Cu")
		(net "PCIE_RX_N0")
	)
	(arc
		(start 289.134296 -12.530074)
		(mid 288.568442 -12.579848)
		(end 288.585148 -13.147548)
		(width 0.1397)
		(layer "In2.Cu")
		(net "PCIE_RX_N0")
	)
	(segment
		(start 235.599986 -34.99993)
		(end 235.100114 -34.500058)
		(width 0.136652)
		(layer "F.Cu")
		(net "PCIE_REFCLK_S5_P")
	)
	(segment
		(start 27.912822 -109.02442)
		(end 28.255214 -108.682028)
		(width 0.136652)
		(layer "F.Cu")
		(net "PCIE_REFCLK_S5_P")
	)
	(segment
		(start 27.635708 -109.02442)
		(end 27.912822 -109.02442)
		(width 0.136652)
		(layer "F.Cu")
		(net "PCIE_REFCLK_S5_P")
	)
	(segment
		(start 28.772612 -106.664506)
		(end 28.833572 -106.725466)
		(width 0.136652)
		(layer "F.Cu")
		(net "PCIE_REFCLK_S5_P")
	)
	(segment
		(start 28.255214 -108.682028)
		(end 28.255214 -106.830876)
		(width 0.136652)
		(layer "F.Cu")
		(net "PCIE_REFCLK_S5_P")
	)
	(segment
		(start 28.294838 -106.735118)
		(end 28.365196 -106.664506)
		(width 0.136652)
		(layer "F.Cu")
		(net "PCIE_REFCLK_S5_P")
	)
	(segment
		(start 27.333448 -109.32668)
		(end 27.635708 -109.02442)
		(width 0.136652)
		(layer "F.Cu")
		(net "PCIE_REFCLK_S5_P")
	)
	(via
		(at 28.833572 -106.725466)
		(size 0.508)
		(drill 0.254)
		(layers "F.Cu" "B.Cu")
		(net "PCIE_REFCLK_S5_P")
	)
	(via
		(at 235.100114 -34.500058)
		(size 0.4572)
		(drill 0.2032)
		(layers "F.Cu" "B.Cu")
		(net "PCIE_REFCLK_S5_P")
	)
	(arc
		(start 28.365196 -106.664506)
		(mid 28.568904 -106.580127)
		(end 28.772612 -106.664506)
		(width 0.136652)
		(layer "F.Cu")
		(net "PCIE_REFCLK_S5_P")
	)
	(arc
		(start 28.255214 -106.830876)
		(mid 28.265504 -106.779053)
		(end 28.294838 -106.735118)
		(width 0.136652)
		(layer "F.Cu")
		(net "PCIE_REFCLK_S5_P")
	)
	(segment
		(start 172.081698 -101.664008)
		(end 174.428912 -100.020374)
		(width 0.1397)
		(layer "In2.Cu")
		(net "PCIE_REFCLK_S5_P")
	)
	(segment
		(start 192.98539 -56.24449)
		(end 196.583554 -51.1048)
		(width 0.1397)
		(layer "In2.Cu")
		(net "PCIE_REFCLK_S5_P")
	)
	(segment
		(start 116.74094 -107.8484)
		(end 121.661936 -106.802428)
		(width 0.1397)
		(layer "In2.Cu")
		(net "PCIE_REFCLK_S5_P")
	)
	(segment
		(start 235.218732 -34.38144)
		(end 235.100114 -34.500058)
		(width 0.1016)
		(layer "In2.Cu")
		(net "PCIE_REFCLK_S5_P")
	)
	(segment
		(start 234.851702 -34.006028)
		(end 234.851702 -34.005774)
		(width 0.1016)
		(layer "In2.Cu")
		(net "PCIE_REFCLK_S5_P")
	)
	(segment
		(start 87.08136 -102.653592)
		(end 116.673884 -107.8611)
		(width 0.1397)
		(layer "In2.Cu")
		(net "PCIE_REFCLK_S5_P")
	)
	(segment
		(start 233.697018 -42.747946)
		(end 233.697018 -34.212022)
		(width 0.1016)
		(layer "In2.Cu")
		(net "PCIE_REFCLK_S5_P")
	)
	(segment
		(start 141.571726 -101.712776)
		(end 148.594318 -100.474526)
		(width 0.1397)
		(layer "In2.Cu")
		(net "PCIE_REFCLK_S5_P")
	)
	(segment
		(start 222.924624 -43.1673)
		(end 222.988124 -43.1038)
		(width 0.1016)
		(layer "In2.Cu")
		(net "PCIE_REFCLK_S5_P")
	)
	(segment
		(start 222.988124 -43.1038)
		(end 233.341164 -43.1038)
		(width 0.1016)
		(layer "In2.Cu")
		(net "PCIE_REFCLK_S5_P")
	)
	(segment
		(start 233.341164 -43.1038)
		(end 233.697018 -42.747946)
		(width 0.1016)
		(layer "In2.Cu")
		(net "PCIE_REFCLK_S5_P")
	)
	(segment
		(start 134.193788 -106.504232)
		(end 141.571726 -101.712776)
		(width 0.1397)
		(layer "In2.Cu")
		(net "PCIE_REFCLK_S5_P")
	)
	(segment
		(start 37.424868 -100.836984)
		(end 41.828974 -99.900994)
		(width 0.1397)
		(layer "In2.Cu")
		(net "PCIE_REFCLK_S5_P")
	)
	(segment
		(start 174.428912 -100.020374)
		(end 191.504062 -75.633834)
		(width 0.1397)
		(layer "In2.Cu")
		(net "PCIE_REFCLK_S5_P")
	)
	(segment
		(start 193.159634 -66.2432)
		(end 192.2018 -60.695586)
		(width 0.1397)
		(layer "In2.Cu")
		(net "PCIE_REFCLK_S5_P")
	)
	(segment
		(start 148.594318 -100.474526)
		(end 163.71062 -103.140002)
		(width 0.1397)
		(layer "In2.Cu")
		(net "PCIE_REFCLK_S5_P")
	)
	(segment
		(start 163.71062 -103.140002)
		(end 172.081698 -101.664008)
		(width 0.1397)
		(layer "In2.Cu")
		(net "PCIE_REFCLK_S5_P")
	)
	(segment
		(start 28.833572 -106.167936)
		(end 31.82239 -103.179118)
		(width 0.1397)
		(layer "In2.Cu")
		(net "PCIE_REFCLK_S5_P")
	)
	(segment
		(start 116.673884 -107.8611)
		(end 116.74094 -107.8484)
		(width 0.1397)
		(layer "In2.Cu")
		(net "PCIE_REFCLK_S5_P")
	)
	(segment
		(start 191.504062 -75.633834)
		(end 193.159634 -66.2432)
		(width 0.1397)
		(layer "In2.Cu")
		(net "PCIE_REFCLK_S5_P")
	)
	(segment
		(start 210.9343 -44.418504)
		(end 218.029028 -43.1673)
		(width 0.1397)
		(layer "In2.Cu")
		(net "PCIE_REFCLK_S5_P")
	)
	(segment
		(start 60.041282 -100.509578)
		(end 63.711328 -99.862132)
		(width 0.1397)
		(layer "In2.Cu")
		(net "PCIE_REFCLK_S5_P")
	)
	(segment
		(start 206.369158 -47.383446)
		(end 210.9343 -44.418504)
		(width 0.1397)
		(layer "In2.Cu")
		(net "PCIE_REFCLK_S5_P")
	)
	(segment
		(start 234.52836 -34.101532)
		(end 234.851702 -34.006028)
		(width 0.1016)
		(layer "In2.Cu")
		(net "PCIE_REFCLK_S5_P")
	)
	(segment
		(start 199.949562 -48.74768)
		(end 206.369158 -47.383446)
		(width 0.1397)
		(layer "In2.Cu")
		(net "PCIE_REFCLK_S5_P")
	)
	(segment
		(start 218.029028 -43.1673)
		(end 222.911924 -43.1673)
		(width 0.1397)
		(layer "In2.Cu")
		(net "PCIE_REFCLK_S5_P")
	)
	(segment
		(start 233.697018 -34.212022)
		(end 233.807762 -34.101532)
		(width 0.1016)
		(layer "In2.Cu")
		(net "PCIE_REFCLK_S5_P")
	)
	(segment
		(start 41.828974 -99.900994)
		(end 44.696126 -100.50018)
		(width 0.1397)
		(layer "In2.Cu")
		(net "PCIE_REFCLK_S5_P")
	)
	(segment
		(start 121.661936 -106.802428)
		(end 127.227076 -107.98556)
		(width 0.1397)
		(layer "In2.Cu")
		(net "PCIE_REFCLK_S5_P")
	)
	(segment
		(start 233.807762 -34.101532)
		(end 234.52836 -34.101532)
		(width 0.1016)
		(layer "In2.Cu")
		(net "PCIE_REFCLK_S5_P")
	)
	(segment
		(start 127.227076 -107.98556)
		(end 134.193788 -106.504232)
		(width 0.1397)
		(layer "In2.Cu")
		(net "PCIE_REFCLK_S5_P")
	)
	(segment
		(start 83.298284 -103.321358)
		(end 87.08136 -102.653592)
		(width 0.1397)
		(layer "In2.Cu")
		(net "PCIE_REFCLK_S5_P")
	)
	(segment
		(start 33.025842 -101.771704)
		(end 37.424868 -100.836984)
		(width 0.1397)
		(layer "In2.Cu")
		(net "PCIE_REFCLK_S5_P")
	)
	(segment
		(start 51.630834 -99.025964)
		(end 60.041282 -100.509578)
		(width 0.1397)
		(layer "In2.Cu")
		(net "PCIE_REFCLK_S5_P")
	)
	(segment
		(start 222.911924 -43.1673)
		(end 222.924624 -43.1673)
		(width 0.1016)
		(layer "In2.Cu")
		(net "PCIE_REFCLK_S5_P")
	)
	(segment
		(start 31.82239 -103.179118)
		(end 32.55899 -102.086918)
		(width 0.1397)
		(layer "In2.Cu")
		(net "PCIE_REFCLK_S5_P")
	)
	(segment
		(start 196.583554 -51.1048)
		(end 199.949562 -48.74768)
		(width 0.1397)
		(layer "In2.Cu")
		(net "PCIE_REFCLK_S5_P")
	)
	(segment
		(start 192.2018 -60.695586)
		(end 192.98539 -56.24449)
		(width 0.1397)
		(layer "In2.Cu")
		(net "PCIE_REFCLK_S5_P")
	)
	(segment
		(start 32.55899 -102.086918)
		(end 33.025842 -101.771704)
		(width 0.1397)
		(layer "In2.Cu")
		(net "PCIE_REFCLK_S5_P")
	)
	(segment
		(start 63.711328 -99.862132)
		(end 83.298284 -103.321358)
		(width 0.1397)
		(layer "In2.Cu")
		(net "PCIE_REFCLK_S5_P")
	)
	(segment
		(start 44.696126 -100.50018)
		(end 51.630834 -99.025964)
		(width 0.1397)
		(layer "In2.Cu")
		(net "PCIE_REFCLK_S5_P")
	)
	(arc
		(start 28.833572 -106.725466)
		(mid 28.718231 -106.446738)
		(end 28.833572 -106.167936)
		(width 0.1397)
		(layer "In2.Cu")
		(net "PCIE_REFCLK_S5_P")
	)
	(arc
		(start 234.851702 -34.005774)
		(mid 235.042775 -33.997928)
		(end 235.212382 -34.086292)
		(width 0.1016)
		(layer "In2.Cu")
		(net "PCIE_REFCLK_S5_P")
	)
	(arc
		(start 235.212382 -34.086292)
		(mid 235.278642 -34.232513)
		(end 235.218732 -34.38144)
		(width 0.1016)
		(layer "In2.Cu")
		(net "PCIE_REFCLK_S5_P")
	)
	(segment
		(start 28.078684 -106.519726)
		(end 28.14955 -106.44886)
		(width 0.136652)
		(layer "F.Cu")
		(net "PCIE_REFCLK_S5_N")
	)
	(segment
		(start 27.593036 -108.71962)
		(end 27.78633 -108.71962)
		(width 0.136652)
		(layer "F.Cu")
		(net "PCIE_REFCLK_S5_N")
	)
	(segment
		(start 27.78633 -108.71962)
		(end 27.950414 -108.555536)
		(width 0.136652)
		(layer "F.Cu")
		(net "PCIE_REFCLK_S5_N")
	)
	(segment
		(start 27.950414 -108.555536)
		(end 27.950414 -106.830876)
		(width 0.136652)
		(layer "F.Cu")
		(net "PCIE_REFCLK_S5_N")
	)
	(segment
		(start 28.14955 -106.041444)
		(end 28.043124 -105.935018)
		(width 0.136652)
		(layer "F.Cu")
		(net "PCIE_REFCLK_S5_N")
	)
	(segment
		(start 235.599986 -33.999932)
		(end 235.100114 -33.50006)
		(width 0.136652)
		(layer "F.Cu")
		(net "PCIE_REFCLK_S5_N")
	)
	(segment
		(start 27.332432 -108.459016)
		(end 27.593036 -108.71962)
		(width 0.136652)
		(layer "F.Cu")
		(net "PCIE_REFCLK_S5_N")
	)
	(via
		(at 28.043124 -105.935018)
		(size 0.508)
		(drill 0.254)
		(layers "F.Cu" "B.Cu")
		(net "PCIE_REFCLK_S5_N")
	)
	(via
		(at 235.100114 -33.50006)
		(size 0.4572)
		(drill 0.2032)
		(layers "F.Cu" "B.Cu")
		(net "PCIE_REFCLK_S5_N")
	)
	(arc
		(start 28.14955 -106.44886)
		(mid 28.233929 -106.245152)
		(end 28.14955 -106.041444)
		(width 0.136652)
		(layer "F.Cu")
		(net "PCIE_REFCLK_S5_N")
	)
	(arc
		(start 27.950414 -106.830876)
		(mid 27.983637 -106.662553)
		(end 28.078684 -106.519726)
		(width 0.136652)
		(layer "F.Cu")
		(net "PCIE_REFCLK_S5_N")
	)
	(segment
		(start 222.9866 -42.8371)
		(end 223.0501 -42.9006)
		(width 0.1016)
		(layer "In2.Cu")
		(net "PCIE_REFCLK_S5_N")
	)
	(segment
		(start 191.191388 -75.504294)
		(end 192.824354 -66.242692)
		(width 0.1397)
		(layer "In2.Cu")
		(net "PCIE_REFCLK_S5_N")
	)
	(segment
		(start 233.493818 -34.127694)
		(end 233.723688 -33.898332)
		(width 0.1016)
		(layer "In2.Cu")
		(net "PCIE_REFCLK_S5_N")
	)
	(segment
		(start 206.240634 -47.073058)
		(end 210.810602 -44.104814)
		(width 0.1397)
		(layer "In2.Cu")
		(net "PCIE_REFCLK_S5_N")
	)
	(segment
		(start 234.498642 -33.898332)
		(end 234.781598 -33.814512)
		(width 0.1016)
		(layer "In2.Cu")
		(net "PCIE_REFCLK_S5_N")
	)
	(segment
		(start 158.12897 -101.626924)
		(end 158.283402 -101.847396)
		(width 0.1397)
		(layer "In2.Cu")
		(net "PCIE_REFCLK_S5_N")
	)
	(segment
		(start 191.86652 -60.695078)
		(end 192.672716 -56.11495)
		(width 0.1397)
		(layer "In2.Cu")
		(net "PCIE_REFCLK_S5_N")
	)
	(segment
		(start 41.828466 -99.563428)
		(end 44.695618 -100.162614)
		(width 0.1397)
		(layer "In2.Cu")
		(net "PCIE_REFCLK_S5_N")
	)
	(segment
		(start 157.71622 -101.554026)
		(end 158.12897 -101.626924)
		(width 0.1397)
		(layer "In2.Cu")
		(net "PCIE_REFCLK_S5_N")
	)
	(segment
		(start 234.813348 -33.786318)
		(end 234.813602 -33.786318)
		(width 0.1016)
		(layer "In2.Cu")
		(net "PCIE_REFCLK_S5_N")
	)
	(segment
		(start 60.041282 -100.174044)
		(end 63.711328 -99.526598)
		(width 0.1397)
		(layer "In2.Cu")
		(net "PCIE_REFCLK_S5_N")
	)
	(segment
		(start 83.298284 -102.985824)
		(end 87.08136 -102.318058)
		(width 0.1397)
		(layer "In2.Cu")
		(net "PCIE_REFCLK_S5_N")
	)
	(segment
		(start 116.67617 -107.52455)
		(end 121.661936 -106.464608)
		(width 0.1397)
		(layer "In2.Cu")
		(net "PCIE_REFCLK_S5_N")
	)
	(segment
		(start 233.493818 -42.663618)
		(end 233.493818 -34.127694)
		(width 0.1016)
		(layer "In2.Cu")
		(net "PCIE_REFCLK_S5_N")
	)
	(segment
		(start 210.810602 -44.104814)
		(end 217.971878 -42.841926)
		(width 0.1397)
		(layer "In2.Cu")
		(net "PCIE_REFCLK_S5_N")
	)
	(segment
		(start 155.094178 -101.28504)
		(end 155.314904 -101.130354)
		(width 0.1397)
		(layer "In2.Cu")
		(net "PCIE_REFCLK_S5_N")
	)
	(segment
		(start 121.661936 -106.464608)
		(end 127.227076 -107.64774)
		(width 0.1397)
		(layer "In2.Cu")
		(net "PCIE_REFCLK_S5_N")
	)
	(segment
		(start 233.723688 -33.898332)
		(end 234.498642 -33.898332)
		(width 0.1016)
		(layer "In2.Cu")
		(net "PCIE_REFCLK_S5_N")
	)
	(segment
		(start 192.824354 -66.242692)
		(end 191.86652 -60.695078)
		(width 0.1397)
		(layer "In2.Cu")
		(net "PCIE_REFCLK_S5_N")
	)
	(segment
		(start 223.0501 -42.9006)
		(end 233.256836 -42.9006)
		(width 0.1016)
		(layer "In2.Cu")
		(net "PCIE_REFCLK_S5_N")
	)
	(segment
		(start 199.815196 -48.438562)
		(end 206.240634 -47.073058)
		(width 0.1397)
		(layer "In2.Cu")
		(net "PCIE_REFCLK_S5_N")
	)
	(segment
		(start 44.696126 -100.16236)
		(end 51.624992 -98.689414)
		(width 0.1397)
		(layer "In2.Cu")
		(net "PCIE_REFCLK_S5_N")
	)
	(segment
		(start 148.594318 -100.138992)
		(end 155.094178 -101.28504)
		(width 0.1397)
		(layer "In2.Cu")
		(net "PCIE_REFCLK_S5_N")
	)
	(segment
		(start 28.618434 -105.915968)
		(end 31.566358 -102.968044)
		(width 0.1397)
		(layer "In2.Cu")
		(net "PCIE_REFCLK_S5_N")
	)
	(segment
		(start 158.283402 -101.847396)
		(end 163.71062 -102.804468)
		(width 0.1397)
		(layer "In2.Cu")
		(net "PCIE_REFCLK_S5_N")
	)
	(segment
		(start 155.727654 -101.203252)
		(end 155.882086 -101.423978)
		(width 0.1397)
		(layer "In2.Cu")
		(net "PCIE_REFCLK_S5_N")
	)
	(segment
		(start 32.320992 -101.849174)
		(end 32.783272 -101.537008)
		(width 0.1397)
		(layer "In2.Cu")
		(net "PCIE_REFCLK_S5_N")
	)
	(segment
		(start 156.928312 -101.415088)
		(end 157.082744 -101.63556)
		(width 0.1397)
		(layer "In2.Cu")
		(net "PCIE_REFCLK_S5_N")
	)
	(segment
		(start 196.346318 -50.867564)
		(end 199.815196 -48.438562)
		(width 0.1397)
		(layer "In2.Cu")
		(net "PCIE_REFCLK_S5_N")
	)
	(segment
		(start 234.813602 -33.786318)
		(end 234.813602 -33.786064)
		(width 0.1016)
		(layer "In2.Cu")
		(net "PCIE_REFCLK_S5_N")
	)
	(segment
		(start 32.89427 -101.462078)
		(end 41.828466 -99.563428)
		(width 0.1397)
		(layer "In2.Cu")
		(net "PCIE_REFCLK_S5_N")
	)
	(segment
		(start 134.065264 -106.193844)
		(end 141.448028 -101.399086)
		(width 0.1397)
		(layer "In2.Cu")
		(net "PCIE_REFCLK_S5_N")
	)
	(segment
		(start 155.314904 -101.130354)
		(end 155.727654 -101.203252)
		(width 0.1397)
		(layer "In2.Cu")
		(net "PCIE_REFCLK_S5_N")
	)
	(segment
		(start 192.672716 -56.11495)
		(end 196.346318 -50.867564)
		(width 0.1397)
		(layer "In2.Cu")
		(net "PCIE_REFCLK_S5_N")
	)
	(segment
		(start 51.624992 -98.689414)
		(end 60.041282 -100.174044)
		(width 0.1397)
		(layer "In2.Cu")
		(net "PCIE_REFCLK_S5_N")
	)
	(segment
		(start 233.256836 -42.9006)
		(end 233.493818 -42.663618)
		(width 0.1016)
		(layer "In2.Cu")
		(net "PCIE_REFCLK_S5_N")
	)
	(segment
		(start 174.191676 -99.783138)
		(end 191.191388 -75.504294)
		(width 0.1397)
		(layer "In2.Cu")
		(net "PCIE_REFCLK_S5_N")
	)
	(segment
		(start 155.882086 -101.423978)
		(end 156.294836 -101.496622)
		(width 0.1397)
		(layer "In2.Cu")
		(net "PCIE_REFCLK_S5_N")
	)
	(segment
		(start 32.783272 -101.537008)
		(end 32.89427 -101.462078)
		(width 0.1397)
		(layer "In2.Cu")
		(net "PCIE_REFCLK_S5_N")
	)
	(segment
		(start 141.448028 -101.399086)
		(end 148.594318 -100.138992)
		(width 0.1397)
		(layer "In2.Cu")
		(net "PCIE_REFCLK_S5_N")
	)
	(segment
		(start 217.971878 -42.841926)
		(end 217.976704 -42.8371)
		(width 0.1397)
		(layer "In2.Cu")
		(net "PCIE_REFCLK_S5_N")
	)
	(segment
		(start 171.952158 -101.351334)
		(end 174.191676 -99.783138)
		(width 0.1397)
		(layer "In2.Cu")
		(net "PCIE_REFCLK_S5_N")
	)
	(segment
		(start 156.294836 -101.496622)
		(end 156.515562 -101.34219)
		(width 0.1397)
		(layer "In2.Cu")
		(net "PCIE_REFCLK_S5_N")
	)
	(segment
		(start 127.227076 -107.64774)
		(end 134.065264 -106.193844)
		(width 0.1397)
		(layer "In2.Cu")
		(net "PCIE_REFCLK_S5_N")
	)
	(segment
		(start 63.711328 -99.526598)
		(end 83.298284 -102.985824)
		(width 0.1397)
		(layer "In2.Cu")
		(net "PCIE_REFCLK_S5_N")
	)
	(segment
		(start 116.672106 -107.525312)
		(end 116.67617 -107.52455)
		(width 0.1397)
		(layer "In2.Cu")
		(net "PCIE_REFCLK_S5_N")
	)
	(segment
		(start 222.9612 -42.8371)
		(end 222.9866 -42.8371)
		(width 0.1016)
		(layer "In2.Cu")
		(net "PCIE_REFCLK_S5_N")
	)
	(segment
		(start 156.515562 -101.34219)
		(end 156.928312 -101.415088)
		(width 0.1397)
		(layer "In2.Cu")
		(net "PCIE_REFCLK_S5_N")
	)
	(segment
		(start 28.599892 -105.934256)
		(end 28.618434 -105.915968)
		(width 0.1397)
		(layer "In2.Cu")
		(net "PCIE_REFCLK_S5_N")
	)
	(segment
		(start 157.082744 -101.63556)
		(end 157.495494 -101.708458)
		(width 0.1397)
		(layer "In2.Cu")
		(net "PCIE_REFCLK_S5_N")
	)
	(segment
		(start 163.71062 -102.804468)
		(end 171.952158 -101.351334)
		(width 0.1397)
		(layer "In2.Cu")
		(net "PCIE_REFCLK_S5_N")
	)
	(segment
		(start 31.566358 -102.968044)
		(end 32.320992 -101.849174)
		(width 0.1397)
		(layer "In2.Cu")
		(net "PCIE_REFCLK_S5_N")
	)
	(segment
		(start 44.695618 -100.162614)
		(end 44.696126 -100.16236)
		(width 0.1397)
		(layer "In2.Cu")
		(net "PCIE_REFCLK_S5_N")
	)
	(segment
		(start 157.495494 -101.708458)
		(end 157.71622 -101.554026)
		(width 0.1397)
		(layer "In2.Cu")
		(net "PCIE_REFCLK_S5_N")
	)
	(segment
		(start 217.976704 -42.8371)
		(end 222.9612 -42.8371)
		(width 0.1397)
		(layer "In2.Cu")
		(net "PCIE_REFCLK_S5_N")
	)
	(segment
		(start 87.08136 -102.318058)
		(end 116.672106 -107.525312)
		(width 0.1397)
		(layer "In2.Cu")
		(net "PCIE_REFCLK_S5_N")
	)
	(segment
		(start 234.813602 -33.786064)
		(end 235.100114 -33.50006)
		(width 0.1016)
		(layer "In2.Cu")
		(net "PCIE_REFCLK_S5_N")
	)
	(arc
		(start 28.043124 -105.935018)
		(mid 28.316673 -106.050197)
		(end 28.59278 -105.941368)
		(width 0.1397)
		(layer "In2.Cu")
		(net "PCIE_REFCLK_S5_N")
	)
	(arc
		(start 28.59278 -105.941368)
		(mid 28.596324 -105.9378)
		(end 28.599892 -105.934256)
		(width 0.1397)
		(layer "In2.Cu")
		(net "PCIE_REFCLK_S5_N")
	)
	(arc
		(start 234.781598 -33.814512)
		(mid 234.797867 -33.800859)
		(end 234.813348 -33.786318)
		(width 0.1016)
		(layer "In2.Cu")
		(net "PCIE_REFCLK_S5_N")
	)
	(segment
		(start 46.134274 -222.863918)
		(end 46.134274 -211.599018)
		(width 0.136652)
		(layer "F.Cu")
		(net "PCIE_REFCLK_S4_P")
	)
	(segment
		(start 58.5978 -198.724266)
		(end 58.5978 -196.90969)
		(width 0.136652)
		(layer "F.Cu")
		(net "PCIE_REFCLK_S4_P")
	)
	(segment
		(start 46.488858 -223.323658)
		(end 46.208696 -223.043496)
		(width 0.136652)
		(layer "F.Cu")
		(net "PCIE_REFCLK_S4_P")
	)
	(segment
		(start 46.863 -224.282)
		(end 46.689518 -224.108518)
		(width 0.136652)
		(layer "F.Cu")
		(net "PCIE_REFCLK_S4_P")
	)
	(segment
		(start 46.900084 -225.54438)
		(end 46.900084 -224.371662)
		(width 0.136652)
		(layer "F.Cu")
		(net "PCIE_REFCLK_S4_P")
	)
	(segment
		(start 46.134274 -211.599018)
		(end 58.307224 -199.426068)
		(width 0.136652)
		(layer "F.Cu")
		(net "PCIE_REFCLK_S4_P")
	)
	(segment
		(start 46.652434 -224.018856)
		(end 46.652434 -223.718628)
		(width 0.136652)
		(layer "F.Cu")
		(net "PCIE_REFCLK_S4_P")
	)
	(segment
		(start 236.599984 -34.99993)
		(end 236.100112 -34.500058)
		(width 0.136652)
		(layer "F.Cu")
		(net "PCIE_REFCLK_S4_P")
	)
	(via
		(at 58.8645 -196.2658)
		(size 0.508)
		(drill 0.254)
		(layers "F.Cu" "B.Cu")
		(net "PCIE_REFCLK_S4_P")
	)
	(via
		(at 236.100112 -34.500058)
		(size 0.4572)
		(drill 0.2032)
		(layers "F.Cu" "B.Cu")
		(net "PCIE_REFCLK_S4_P")
	)
	(via
		(at 173.6344 -96.194372)
		(size 0.508)
		(drill 0.254)
		(layers "F.Cu" "B.Cu")
		(net "PCIE_REFCLK_S4_P")
	)
	(arc
		(start 46.208696 -223.043496)
		(mid 46.153644 -222.961105)
		(end 46.134274 -222.863918)
		(width 0.136652)
		(layer "F.Cu")
		(net "PCIE_REFCLK_S4_P")
	)
	(arc
		(start 46.689518 -224.108518)
		(mid 46.662085 -224.067367)
		(end 46.652434 -224.018856)
		(width 0.136652)
		(layer "F.Cu")
		(net "PCIE_REFCLK_S4_P")
	)
	(arc
		(start 58.5978 -196.90969)
		(mid 58.667115 -196.561222)
		(end 58.8645 -196.2658)
		(width 0.136652)
		(layer "F.Cu")
		(net "PCIE_REFCLK_S4_P")
	)
	(arc
		(start 46.900084 -224.371662)
		(mid 46.890451 -224.323144)
		(end 46.863 -224.282)
		(width 0.136652)
		(layer "F.Cu")
		(net "PCIE_REFCLK_S4_P")
	)
	(arc
		(start 58.307224 -199.426068)
		(mid 58.522288 -199.104063)
		(end 58.5978 -198.724266)
		(width 0.136652)
		(layer "F.Cu")
		(net "PCIE_REFCLK_S4_P")
	)
	(arc
		(start 46.652434 -223.718628)
		(mid 46.609932 -223.504867)
		(end 46.488858 -223.323658)
		(width 0.136652)
		(layer "F.Cu")
		(net "PCIE_REFCLK_S4_P")
	)
	(segment
		(start 209.386678 -43.162728)
		(end 209.597498 -43.299634)
		(width 0.1397)
		(layer "In2.Cu")
		(net "PCIE_REFCLK_S4_P")
	)
	(segment
		(start 235.494068 -33.286192)
		(end 235.494068 -33.782508)
		(width 0.1016)
		(layer "In2.Cu")
		(net "PCIE_REFCLK_S4_P")
	)
	(segment
		(start 180.991764 -88.90508)
		(end 180.991764 -88.905334)
		(width 0.1397)
		(layer "In2.Cu")
		(net "PCIE_REFCLK_S4_P")
	)
	(segment
		(start 211.311998 -42.75328)
		(end 211.721954 -42.666158)
		(width 0.1397)
		(layer "In2.Cu")
		(net "PCIE_REFCLK_S4_P")
	)
	(segment
		(start 221.604078 -42.169842)
		(end 221.629478 -42.169842)
		(width 0.1016)
		(layer "In2.Cu")
		(net "PCIE_REFCLK_S4_P")
	)
	(segment
		(start 221.629478 -42.169842)
		(end 221.692978 -42.106342)
		(width 0.1016)
		(layer "In2.Cu")
		(net "PCIE_REFCLK_S4_P")
	)
	(segment
		(start 232.734104 -33.254696)
		(end 232.845356 -33.143444)
		(width 0.1016)
		(layer "In2.Cu")
		(net "PCIE_REFCLK_S4_P")
	)
	(segment
		(start 180.991764 -88.905334)
		(end 181.039516 -88.871806)
		(width 0.1397)
		(layer "In2.Cu")
		(net "PCIE_REFCLK_S4_P")
	)
	(segment
		(start 221.692978 -42.106342)
		(end 232.149904 -42.106342)
		(width 0.1016)
		(layer "In2.Cu")
		(net "PCIE_REFCLK_S4_P")
	)
	(segment
		(start 236.101128 -34.250122)
		(end 236.101128 -34.499042)
		(width 0.1016)
		(layer "In2.Cu")
		(net "PCIE_REFCLK_S4_P")
	)
	(segment
		(start 199.394318 -47.768256)
		(end 203.00061 -47.001684)
		(width 0.1397)
		(layer "In2.Cu")
		(net "PCIE_REFCLK_S4_P")
	)
	(segment
		(start 214.057484 -42.169842)
		(end 221.604078 -42.169842)
		(width 0.1397)
		(layer "In2.Cu")
		(net "PCIE_REFCLK_S4_P")
	)
	(segment
		(start 235.851954 -34.14014)
		(end 235.991146 -34.14014)
		(width 0.1016)
		(layer "In2.Cu")
		(net "PCIE_REFCLK_S4_P")
	)
	(segment
		(start 173.6344 -96.194372)
		(end 173.355 -95.914972)
		(width 0.1397)
		(layer "In2.Cu")
		(net "PCIE_REFCLK_S4_P")
	)
	(segment
		(start 213.100666 -42.554906)
		(end 213.510622 -42.467784)
		(width 0.1397)
		(layer "In2.Cu")
		(net "PCIE_REFCLK_S4_P")
	)
	(segment
		(start 232.473246 -41.972484)
		(end 232.563162 -41.882568)
		(width 0.1016)
		(layer "In2.Cu")
		(net "PCIE_REFCLK_S4_P")
	)
	(segment
		(start 173.355 -95.914972)
		(end 173.355 -94.905322)
		(width 0.1397)
		(layer "In2.Cu")
		(net "PCIE_REFCLK_S4_P")
	)
	(segment
		(start 192.033652 -55.764176)
		(end 195.93687 -50.188876)
		(width 0.1397)
		(layer "In2.Cu")
		(net "PCIE_REFCLK_S4_P")
	)
	(segment
		(start 212.47989 -42.505122)
		(end 212.889846 -42.418)
		(width 0.1397)
		(layer "In2.Cu")
		(net "PCIE_REFCLK_S4_P")
	)
	(segment
		(start 191.134746 -60.863226)
		(end 192.033652 -55.764176)
		(width 0.1397)
		(layer "In2.Cu")
		(net "PCIE_REFCLK_S4_P")
	)
	(segment
		(start 213.647528 -42.256964)
		(end 214.057484 -42.169842)
		(width 0.1397)
		(layer "In2.Cu")
		(net "PCIE_REFCLK_S4_P")
	)
	(segment
		(start 232.935018 -33.10636)
		(end 235.313982 -33.10636)
		(width 0.1016)
		(layer "In2.Cu")
		(net "PCIE_REFCLK_S4_P")
	)
	(segment
		(start 203.00061 -47.001684)
		(end 208.681066 -43.312588)
		(width 0.1397)
		(layer "In2.Cu")
		(net "PCIE_REFCLK_S4_P")
	)
	(segment
		(start 190.416942 -75.479656)
		(end 192.051686 -66.207386)
		(width 0.1397)
		(layer "In2.Cu")
		(net "PCIE_REFCLK_S4_P")
	)
	(segment
		(start 236.101128 -34.499042)
		(end 236.100112 -34.500058)
		(width 0.1016)
		(layer "In2.Cu")
		(net "PCIE_REFCLK_S4_P")
	)
	(segment
		(start 211.175092 -42.964354)
		(end 211.311998 -42.75328)
		(width 0.1397)
		(layer "In2.Cu")
		(net "PCIE_REFCLK_S4_P")
	)
	(segment
		(start 212.342984 -42.715942)
		(end 212.47989 -42.505122)
		(width 0.1397)
		(layer "In2.Cu")
		(net "PCIE_REFCLK_S4_P")
	)
	(segment
		(start 191.134746 -61.007498)
		(end 191.134746 -60.863226)
		(width 0.1397)
		(layer "In2.Cu")
		(net "PCIE_REFCLK_S4_P")
	)
	(segment
		(start 212.889846 -42.418)
		(end 213.100666 -42.554906)
		(width 0.1397)
		(layer "In2.Cu")
		(net "PCIE_REFCLK_S4_P")
	)
	(segment
		(start 208.681066 -43.312588)
		(end 209.386678 -43.162728)
		(width 0.1397)
		(layer "In2.Cu")
		(net "PCIE_REFCLK_S4_P")
	)
	(segment
		(start 209.597498 -43.299634)
		(end 210.007454 -43.212512)
		(width 0.1397)
		(layer "In2.Cu")
		(net "PCIE_REFCLK_S4_P")
	)
	(segment
		(start 192.051686 -66.207386)
		(end 191.134746 -61.007498)
		(width 0.1397)
		(layer "In2.Cu")
		(net "PCIE_REFCLK_S4_P")
	)
	(segment
		(start 235.403644 -33.143444)
		(end 235.456984 -33.196784)
		(width 0.1016)
		(layer "In2.Cu")
		(net "PCIE_REFCLK_S4_P")
	)
	(segment
		(start 210.554316 -42.91457)
		(end 210.765136 -43.051476)
		(width 0.1397)
		(layer "In2.Cu")
		(net "PCIE_REFCLK_S4_P")
	)
	(segment
		(start 173.355 -94.905322)
		(end 174.25162 -93.624654)
		(width 0.1397)
		(layer "In2.Cu")
		(net "PCIE_REFCLK_S4_P")
	)
	(segment
		(start 210.765136 -43.051476)
		(end 211.175092 -42.964354)
		(width 0.1397)
		(layer "In2.Cu")
		(net "PCIE_REFCLK_S4_P")
	)
	(segment
		(start 211.721954 -42.666158)
		(end 211.933028 -42.803318)
		(width 0.1397)
		(layer "In2.Cu")
		(net "PCIE_REFCLK_S4_P")
	)
	(segment
		(start 211.933028 -42.803318)
		(end 212.342984 -42.715942)
		(width 0.1397)
		(layer "In2.Cu")
		(net "PCIE_REFCLK_S4_P")
	)
	(segment
		(start 174.25162 -93.624654)
		(end 180.991764 -88.90508)
		(width 0.1397)
		(layer "In2.Cu")
		(net "PCIE_REFCLK_S4_P")
	)
	(segment
		(start 232.69702 -33.344104)
		(end 232.697274 -33.344104)
		(width 0.1016)
		(layer "In2.Cu")
		(net "PCIE_REFCLK_S4_P")
	)
	(segment
		(start 195.93687 -50.188876)
		(end 199.394318 -47.768256)
		(width 0.1397)
		(layer "In2.Cu")
		(net "PCIE_REFCLK_S4_P")
	)
	(segment
		(start 232.69702 -41.559226)
		(end 232.69702 -33.344104)
		(width 0.1016)
		(layer "In2.Cu")
		(net "PCIE_REFCLK_S4_P")
	)
	(segment
		(start 181.039516 -88.871806)
		(end 190.416942 -75.479656)
		(width 0.1397)
		(layer "In2.Cu")
		(net "PCIE_REFCLK_S4_P")
	)
	(segment
		(start 210.007454 -43.212512)
		(end 210.14436 -43.001692)
		(width 0.1397)
		(layer "In2.Cu")
		(net "PCIE_REFCLK_S4_P")
	)
	(segment
		(start 213.510622 -42.467784)
		(end 213.647528 -42.256964)
		(width 0.1397)
		(layer "In2.Cu")
		(net "PCIE_REFCLK_S4_P")
	)
	(segment
		(start 210.14436 -43.001692)
		(end 210.554316 -42.91457)
		(width 0.1397)
		(layer "In2.Cu")
		(net "PCIE_REFCLK_S4_P")
	)
	(segment
		(start 235.598208 -34.035238)
		(end 235.598716 -34.035746)
		(width 0.1016)
		(layer "In2.Cu")
		(net "PCIE_REFCLK_S4_P")
	)
	(arc
		(start 235.313982 -33.10636)
		(mid 235.3625 -33.115993)
		(end 235.403644 -33.143444)
		(width 0.1016)
		(layer "In2.Cu")
		(net "PCIE_REFCLK_S4_P")
	)
	(arc
		(start 232.697274 -33.344104)
		(mid 232.706838 -33.295752)
		(end 232.734104 -33.254696)
		(width 0.1016)
		(layer "In2.Cu")
		(net "PCIE_REFCLK_S4_P")
	)
	(arc
		(start 235.991146 -34.14014)
		(mid 236.068915 -34.172353)
		(end 236.101128 -34.250122)
		(width 0.1016)
		(layer "In2.Cu")
		(net "PCIE_REFCLK_S4_P")
	)
	(arc
		(start 235.456984 -33.196784)
		(mid 235.484369 -33.237818)
		(end 235.494068 -33.286192)
		(width 0.1016)
		(layer "In2.Cu")
		(net "PCIE_REFCLK_S4_P")
	)
	(arc
		(start 232.845356 -33.143444)
		(mid 232.886507 -33.116011)
		(end 232.935018 -33.10636)
		(width 0.1016)
		(layer "In2.Cu")
		(net "PCIE_REFCLK_S4_P")
	)
	(arc
		(start 232.149904 -42.106342)
		(mid 232.324921 -42.071623)
		(end 232.473246 -41.972484)
		(width 0.1016)
		(layer "In2.Cu")
		(net "PCIE_REFCLK_S4_P")
	)
	(arc
		(start 235.494068 -33.782508)
		(mid 235.52109 -33.919187)
		(end 235.598208 -34.035238)
		(width 0.1016)
		(layer "In2.Cu")
		(net "PCIE_REFCLK_S4_P")
	)
	(arc
		(start 232.563162 -41.882568)
		(mid 232.662204 -41.734202)
		(end 232.69702 -41.559226)
		(width 0.1016)
		(layer "In2.Cu")
		(net "PCIE_REFCLK_S4_P")
	)
	(arc
		(start 235.598716 -34.035746)
		(mid 235.71496 -34.113136)
		(end 235.851954 -34.14014)
		(width 0.1016)
		(layer "In2.Cu")
		(net "PCIE_REFCLK_S4_P")
	)
	(segment
		(start 99.403662 -174.556674)
		(end 90.022934 -176.210722)
		(width 0.1397)
		(layer "In5.Cu")
		(net "PCIE_REFCLK_S4_P")
	)
	(segment
		(start 58.775854 -196.177154)
		(end 58.8645 -196.2658)
		(width 0.1397)
		(layer "In5.Cu")
		(net "PCIE_REFCLK_S4_P")
	)
	(segment
		(start 162.364166 -117.145308)
		(end 155.920948 -121.656602)
		(width 0.1397)
		(layer "In5.Cu")
		(net "PCIE_REFCLK_S4_P")
	)
	(segment
		(start 61.40704 -178.132486)
		(end 59.744864 -180.506624)
		(width 0.1397)
		(layer "In5.Cu")
		(net "PCIE_REFCLK_S4_P")
	)
	(segment
		(start 172.475398 -102.748842)
		(end 162.364166 -117.145308)
		(width 0.1397)
		(layer "In5.Cu")
		(net "PCIE_REFCLK_S4_P")
	)
	(segment
		(start 63.893446 -176.391316)
		(end 61.40704 -178.132486)
		(width 0.1397)
		(layer "In5.Cu")
		(net "PCIE_REFCLK_S4_P")
	)
	(segment
		(start 145.8849 -135.92556)
		(end 127.020066 -149.134576)
		(width 0.1397)
		(layer "In5.Cu")
		(net "PCIE_REFCLK_S4_P")
	)
	(segment
		(start 59.72175 -180.56225)
		(end 59.72175 -180.562504)
		(width 0.1397)
		(layer "In5.Cu")
		(net "PCIE_REFCLK_S4_P")
	)
	(segment
		(start 58.6232 -186.85129)
		(end 58.6232 -195.8086)
		(width 0.1397)
		(layer "In5.Cu")
		(net "PCIE_REFCLK_S4_P")
	)
	(segment
		(start 173.6344 -96.194372)
		(end 173.355 -96.473772)
		(width 0.1397)
		(layer "In5.Cu")
		(net "PCIE_REFCLK_S4_P")
	)
	(segment
		(start 126.985776 -149.168866)
		(end 118.614698 -161.124138)
		(width 0.1397)
		(layer "In5.Cu")
		(net "PCIE_REFCLK_S4_P")
	)
	(segment
		(start 118.499382 -161.239454)
		(end 99.591622 -174.47895)
		(width 0.1397)
		(layer "In5.Cu")
		(net "PCIE_REFCLK_S4_P")
	)
	(segment
		(start 58.617612 -186.81954)
		(end 58.6232 -186.85129)
		(width 0.1397)
		(layer "In5.Cu")
		(net "PCIE_REFCLK_S4_P")
	)
	(segment
		(start 89.859866 -176.210722)
		(end 82.075274 -174.838106)
		(width 0.1397)
		(layer "In5.Cu")
		(net "PCIE_REFCLK_S4_P")
	)
	(segment
		(start 173.355 -98.01352)
		(end 172.553122 -102.561136)
		(width 0.1397)
		(layer "In5.Cu")
		(net "PCIE_REFCLK_S4_P")
	)
	(segment
		(start 173.355 -96.473772)
		(end 173.355 -98.01352)
		(width 0.1397)
		(layer "In5.Cu")
		(net "PCIE_REFCLK_S4_P")
	)
	(segment
		(start 67.995546 -175.654716)
		(end 63.949326 -176.368202)
		(width 0.1397)
		(layer "In5.Cu")
		(net "PCIE_REFCLK_S4_P")
	)
	(segment
		(start 82.026506 -174.838106)
		(end 72.801734 -176.464722)
		(width 0.1397)
		(layer "In5.Cu")
		(net "PCIE_REFCLK_S4_P")
	)
	(segment
		(start 72.638666 -176.464722)
		(end 68.044314 -175.654716)
		(width 0.1397)
		(layer "In5.Cu")
		(net "PCIE_REFCLK_S4_P")
	)
	(segment
		(start 59.72175 -180.562504)
		(end 58.617612 -186.81954)
		(width 0.1397)
		(layer "In5.Cu")
		(net "PCIE_REFCLK_S4_P")
	)
	(segment
		(start 155.886658 -121.690892)
		(end 146.000216 -135.810244)
		(width 0.1397)
		(layer "In5.Cu")
		(net "PCIE_REFCLK_S4_P")
	)
	(arc
		(start 59.744864 -180.506624)
		(mid 59.730289 -180.533181)
		(end 59.72175 -180.56225)
		(width 0.1397)
		(layer "In5.Cu")
		(net "PCIE_REFCLK_S4_P")
	)
	(arc
		(start 72.801734 -176.464722)
		(mid 72.7202 -176.471849)
		(end 72.638666 -176.464722)
		(width 0.1397)
		(layer "In5.Cu")
		(net "PCIE_REFCLK_S4_P")
	)
	(arc
		(start 82.075274 -174.838106)
		(mid 82.05089 -174.835963)
		(end 82.026506 -174.838106)
		(width 0.1397)
		(layer "In5.Cu")
		(net "PCIE_REFCLK_S4_P")
	)
	(arc
		(start 127.020066 -149.134576)
		(mid 127.001424 -149.150224)
		(end 126.985776 -149.168866)
		(width 0.1397)
		(layer "In5.Cu")
		(net "PCIE_REFCLK_S4_P")
	)
	(arc
		(start 58.6232 -195.8086)
		(mid 58.662875 -196.008058)
		(end 58.775854 -196.177154)
		(width 0.1397)
		(layer "In5.Cu")
		(net "PCIE_REFCLK_S4_P")
	)
	(arc
		(start 172.553122 -102.561136)
		(mid 172.524552 -102.659254)
		(end 172.475398 -102.748842)
		(width 0.1397)
		(layer "In5.Cu")
		(net "PCIE_REFCLK_S4_P")
	)
	(arc
		(start 68.044314 -175.654716)
		(mid 68.01993 -175.652573)
		(end 67.995546 -175.654716)
		(width 0.1397)
		(layer "In5.Cu")
		(net "PCIE_REFCLK_S4_P")
	)
	(arc
		(start 90.022934 -176.210722)
		(mid 89.9414 -176.217849)
		(end 89.859866 -176.210722)
		(width 0.1397)
		(layer "In5.Cu")
		(net "PCIE_REFCLK_S4_P")
	)
	(arc
		(start 146.000216 -135.810244)
		(mid 145.9476 -135.872944)
		(end 145.8849 -135.92556)
		(width 0.1397)
		(layer "In5.Cu")
		(net "PCIE_REFCLK_S4_P")
	)
	(arc
		(start 99.591622 -174.47895)
		(mid 99.501896 -174.528097)
		(end 99.403662 -174.556674)
		(width 0.1397)
		(layer "In5.Cu")
		(net "PCIE_REFCLK_S4_P")
	)
	(arc
		(start 118.614698 -161.124138)
		(mid 118.562082 -161.186838)
		(end 118.499382 -161.239454)
		(width 0.1397)
		(layer "In5.Cu")
		(net "PCIE_REFCLK_S4_P")
	)
	(arc
		(start 63.949326 -176.368202)
		(mid 63.920112 -176.376684)
		(end 63.893446 -176.391316)
		(width 0.1397)
		(layer "In5.Cu")
		(net "PCIE_REFCLK_S4_P")
	)
	(arc
		(start 155.920948 -121.656602)
		(mid 155.902306 -121.67225)
		(end 155.886658 -121.690892)
		(width 0.1397)
		(layer "In5.Cu")
		(net "PCIE_REFCLK_S4_P")
	)
	(segment
		(start 45.829474 -222.864172)
		(end 45.829474 -211.472526)
		(width 0.136652)
		(layer "F.Cu")
		(net "PCIE_REFCLK_S4_N")
	)
	(segment
		(start 46.273212 -223.539304)
		(end 45.99305 -223.259142)
		(width 0.136652)
		(layer "F.Cu")
		(net "PCIE_REFCLK_S4_N")
	)
	(segment
		(start 236.599984 -33.999932)
		(end 236.100112 -33.50006)
		(width 0.136652)
		(layer "F.Cu")
		(net "PCIE_REFCLK_S4_N")
	)
	(segment
		(start 46.099984 -225.54438)
		(end 46.099984 -224.386394)
		(width 0.136652)
		(layer "F.Cu")
		(net "PCIE_REFCLK_S4_N")
	)
	(segment
		(start 45.829474 -211.472526)
		(end 58.091578 -199.210422)
		(width 0.136652)
		(layer "F.Cu")
		(net "PCIE_REFCLK_S4_N")
	)
	(segment
		(start 58.117994 -196.332094)
		(end 58.0517 -196.2658)
		(width 0.136652)
		(layer "F.Cu")
		(net "PCIE_REFCLK_S4_N")
	)
	(segment
		(start 58.293 -198.724266)
		(end 58.293 -196.75475)
		(width 0.136652)
		(layer "F.Cu")
		(net "PCIE_REFCLK_S4_N")
	)
	(segment
		(start 46.137068 -224.296732)
		(end 46.31055 -224.12325)
		(width 0.136652)
		(layer "F.Cu")
		(net "PCIE_REFCLK_S4_N")
	)
	(segment
		(start 46.347634 -224.033588)
		(end 46.347634 -223.718882)
		(width 0.136652)
		(layer "F.Cu")
		(net "PCIE_REFCLK_S4_N")
	)
	(via
		(at 172.7454 -96.194372)
		(size 0.508)
		(drill 0.254)
		(layers "F.Cu" "B.Cu")
		(net "PCIE_REFCLK_S4_N")
	)
	(via
		(at 236.100112 -33.50006)
		(size 0.4572)
		(drill 0.2032)
		(layers "F.Cu" "B.Cu")
		(net "PCIE_REFCLK_S4_N")
	)
	(via
		(at 58.0517 -196.2658)
		(size 0.508)
		(drill 0.254)
		(layers "F.Cu" "B.Cu")
		(net "PCIE_REFCLK_S4_N")
	)
	(arc
		(start 58.091578 -199.210422)
		(mid 58.240669 -198.987386)
		(end 58.293 -198.724266)
		(width 0.136652)
		(layer "F.Cu")
		(net "PCIE_REFCLK_S4_N")
	)
	(arc
		(start 46.099984 -224.386394)
		(mid 46.109617 -224.337876)
		(end 46.137068 -224.296732)
		(width 0.136652)
		(layer "F.Cu")
		(net "PCIE_REFCLK_S4_N")
	)
	(arc
		(start 45.99305 -223.259142)
		(mid 45.872021 -223.077914)
		(end 45.829474 -222.864172)
		(width 0.136652)
		(layer "F.Cu")
		(net "PCIE_REFCLK_S4_N")
	)
	(arc
		(start 58.293 -196.75475)
		(mid 58.247521 -196.52602)
		(end 58.117994 -196.332094)
		(width 0.136652)
		(layer "F.Cu")
		(net "PCIE_REFCLK_S4_N")
	)
	(arc
		(start 46.347634 -223.718882)
		(mid 46.328299 -223.62168)
		(end 46.273212 -223.539304)
		(width 0.136652)
		(layer "F.Cu")
		(net "PCIE_REFCLK_S4_N")
	)
	(arc
		(start 46.31055 -224.12325)
		(mid 46.337983 -224.082099)
		(end 46.347634 -224.033588)
		(width 0.136652)
		(layer "F.Cu")
		(net "PCIE_REFCLK_S4_N")
	)
	(segment
		(start 235.601002 -33.05302)
		(end 235.547408 -32.999426)
		(width 0.1016)
		(layer "In2.Cu")
		(net "PCIE_REFCLK_S4_N")
	)
	(segment
		(start 221.629478 -41.839642)
		(end 221.604078 -41.839642)
		(width 0.1016)
		(layer "In2.Cu")
		(net "PCIE_REFCLK_S4_N")
	)
	(segment
		(start 191.716152 -66.207386)
		(end 190.104268 -75.350116)
		(width 0.1397)
		(layer "In2.Cu")
		(net "PCIE_REFCLK_S4_N")
	)
	(segment
		(start 232.419398 -41.738804)
		(end 232.329482 -41.82872)
		(width 0.1016)
		(layer "In2.Cu")
		(net "PCIE_REFCLK_S4_N")
	)
	(segment
		(start 235.313982 -32.90316)
		(end 232.935018 -32.90316)
		(width 0.1016)
		(layer "In2.Cu")
		(net "PCIE_REFCLK_S4_N")
	)
	(segment
		(start 221.604078 -41.839642)
		(end 213.996016 -41.839642)
		(width 0.1397)
		(layer "In2.Cu")
		(net "PCIE_REFCLK_S4_N")
	)
	(segment
		(start 199.259952 -47.459138)
		(end 195.699634 -49.95164)
		(width 0.1397)
		(layer "In2.Cu")
		(net "PCIE_REFCLK_S4_N")
	)
	(segment
		(start 174.014384 -93.387418)
		(end 173.0248 -94.801182)
		(width 0.1397)
		(layer "In2.Cu")
		(net "PCIE_REFCLK_S4_N")
	)
	(segment
		(start 221.692978 -41.903142)
		(end 221.629478 -41.839642)
		(width 0.1016)
		(layer "In2.Cu")
		(net "PCIE_REFCLK_S4_N")
	)
	(segment
		(start 202.872086 -46.691296)
		(end 199.259952 -47.459138)
		(width 0.1397)
		(layer "In2.Cu")
		(net "PCIE_REFCLK_S4_N")
	)
	(segment
		(start 173.0248 -95.914972)
		(end 172.7454 -96.194372)
		(width 0.1397)
		(layer "In2.Cu")
		(net "PCIE_REFCLK_S4_N")
	)
	(segment
		(start 208.552542 -43.0022)
		(end 202.872086 -46.691296)
		(width 0.1397)
		(layer "In2.Cu")
		(net "PCIE_REFCLK_S4_N")
	)
	(segment
		(start 235.697268 -33.782508)
		(end 235.697268 -33.286446)
		(width 0.1016)
		(layer "In2.Cu")
		(net "PCIE_REFCLK_S4_N")
	)
	(segment
		(start 190.804546 -61.036454)
		(end 191.716152 -66.207386)
		(width 0.1397)
		(layer "In2.Cu")
		(net "PCIE_REFCLK_S4_N")
	)
	(segment
		(start 232.149904 -41.903142)
		(end 221.692978 -41.903142)
		(width 0.1016)
		(layer "In2.Cu")
		(net "PCIE_REFCLK_S4_N")
	)
	(segment
		(start 232.49382 -33.344358)
		(end 232.49382 -41.559226)
		(width 0.1016)
		(layer "In2.Cu")
		(net "PCIE_REFCLK_S4_N")
	)
	(segment
		(start 177.431954 -90.994484)
		(end 174.014384 -93.387418)
		(width 0.1397)
		(layer "In2.Cu")
		(net "PCIE_REFCLK_S4_N")
	)
	(segment
		(start 232.701592 -32.999426)
		(end 232.590086 -33.110932)
		(width 0.1016)
		(layer "In2.Cu")
		(net "PCIE_REFCLK_S4_N")
	)
	(segment
		(start 235.961682 -33.93694)
		(end 235.851954 -33.93694)
		(width 0.1016)
		(layer "In2.Cu")
		(net "PCIE_REFCLK_S4_N")
	)
	(segment
		(start 236.101128 -33.501076)
		(end 236.101128 -33.744154)
		(width 0.1016)
		(layer "In2.Cu")
		(net "PCIE_REFCLK_S4_N")
	)
	(segment
		(start 173.0248 -94.801182)
		(end 173.0248 -95.914972)
		(width 0.1397)
		(layer "In2.Cu")
		(net "PCIE_REFCLK_S4_N")
	)
	(segment
		(start 236.100112 -33.50006)
		(end 236.101128 -33.501076)
		(width 0.1016)
		(layer "In2.Cu")
		(net "PCIE_REFCLK_S4_N")
	)
	(segment
		(start 235.74248 -33.891728)
		(end 235.742226 -33.891474)
		(width 0.1016)
		(layer "In2.Cu")
		(net "PCIE_REFCLK_S4_N")
	)
	(segment
		(start 195.699634 -49.95164)
		(end 191.720978 -55.634636)
		(width 0.1397)
		(layer "In2.Cu")
		(net "PCIE_REFCLK_S4_N")
	)
	(segment
		(start 213.988904 -41.846754)
		(end 208.552542 -43.0022)
		(width 0.1397)
		(layer "In2.Cu")
		(net "PCIE_REFCLK_S4_N")
	)
	(segment
		(start 180.80228 -88.63457)
		(end 177.431954 -90.994484)
		(width 0.1397)
		(layer "In2.Cu")
		(net "PCIE_REFCLK_S4_N")
	)
	(segment
		(start 191.720978 -55.634636)
		(end 190.804546 -60.83427)
		(width 0.1397)
		(layer "In2.Cu")
		(net "PCIE_REFCLK_S4_N")
	)
	(segment
		(start 190.804546 -60.83427)
		(end 190.804546 -61.036454)
		(width 0.1397)
		(layer "In2.Cu")
		(net "PCIE_REFCLK_S4_N")
	)
	(segment
		(start 213.996016 -41.839642)
		(end 213.988904 -41.846754)
		(width 0.1397)
		(layer "In2.Cu")
		(net "PCIE_REFCLK_S4_N")
	)
	(segment
		(start 190.104268 -75.350116)
		(end 180.80228 -88.63457)
		(width 0.1397)
		(layer "In2.Cu")
		(net "PCIE_REFCLK_S4_N")
	)
	(arc
		(start 235.547408 -32.999426)
		(mid 235.440268 -32.928056)
		(end 235.313982 -32.90316)
		(width 0.1016)
		(layer "In2.Cu")
		(net "PCIE_REFCLK_S4_N")
	)
	(arc
		(start 232.935018 -32.90316)
		(mid 232.808768 -32.928143)
		(end 232.701592 -32.999426)
		(width 0.1016)
		(layer "In2.Cu")
		(net "PCIE_REFCLK_S4_N")
	)
	(arc
		(start 232.329482 -41.82872)
		(mid 232.247105 -41.883826)
		(end 232.149904 -41.903142)
		(width 0.1016)
		(layer "In2.Cu")
		(net "PCIE_REFCLK_S4_N")
	)
	(arc
		(start 232.590086 -33.110932)
		(mid 232.518716 -33.218072)
		(end 232.49382 -33.344358)
		(width 0.1016)
		(layer "In2.Cu")
		(net "PCIE_REFCLK_S4_N")
	)
	(arc
		(start 235.851954 -33.93694)
		(mid 235.79273 -33.925195)
		(end 235.74248 -33.891728)
		(width 0.1016)
		(layer "In2.Cu")
		(net "PCIE_REFCLK_S4_N")
	)
	(arc
		(start 235.742226 -33.891474)
		(mid 235.708928 -33.841452)
		(end 235.697268 -33.782508)
		(width 0.1016)
		(layer "In2.Cu")
		(net "PCIE_REFCLK_S4_N")
	)
	(arc
		(start 232.49382 -41.559226)
		(mid 232.47447 -41.656413)
		(end 232.419398 -41.738804)
		(width 0.1016)
		(layer "In2.Cu")
		(net "PCIE_REFCLK_S4_N")
	)
	(arc
		(start 235.697268 -33.286446)
		(mid 235.672285 -33.160196)
		(end 235.601002 -33.05302)
		(width 0.1016)
		(layer "In2.Cu")
		(net "PCIE_REFCLK_S4_N")
	)
	(arc
		(start 236.101128 -33.744154)
		(mid 236.062609 -33.863112)
		(end 235.961682 -33.93694)
		(width 0.1016)
		(layer "In2.Cu")
		(net "PCIE_REFCLK_S4_N")
	)
	(segment
		(start 58.292238 -186.76239)
		(end 59.396376 -180.5051)
		(width 0.1397)
		(layer "In5.Cu")
		(net "PCIE_REFCLK_S4_N")
	)
	(segment
		(start 68.101718 -175.329342)
		(end 72.69607 -176.139348)
		(width 0.1397)
		(layer "In5.Cu")
		(net "PCIE_REFCLK_S4_N")
	)
	(segment
		(start 61.217556 -177.861976)
		(end 63.703962 -176.120552)
		(width 0.1397)
		(layer "In5.Cu")
		(net "PCIE_REFCLK_S4_N")
	)
	(segment
		(start 82.132678 -174.512732)
		(end 89.91727 -175.885348)
		(width 0.1397)
		(layer "In5.Cu")
		(net "PCIE_REFCLK_S4_N")
	)
	(segment
		(start 155.731464 -121.386092)
		(end 162.127184 -116.908072)
		(width 0.1397)
		(layer "In5.Cu")
		(net "PCIE_REFCLK_S4_N")
	)
	(segment
		(start 89.96553 -175.885348)
		(end 99.346258 -174.2313)
		(width 0.1397)
		(layer "In5.Cu")
		(net "PCIE_REFCLK_S4_N")
	)
	(segment
		(start 118.344188 -160.934654)
		(end 126.715266 -148.979382)
		(width 0.1397)
		(layer "In5.Cu")
		(net "PCIE_REFCLK_S4_N")
	)
	(segment
		(start 99.402138 -174.208186)
		(end 118.309898 -160.968944)
		(width 0.1397)
		(layer "In5.Cu")
		(net "PCIE_REFCLK_S4_N")
	)
	(segment
		(start 58.293 -186.7662)
		(end 58.292238 -186.76239)
		(width 0.1397)
		(layer "In5.Cu")
		(net "PCIE_REFCLK_S4_N")
	)
	(segment
		(start 61.136276 -177.942748)
		(end 61.217048 -177.861976)
		(width 0.1397)
		(layer "In5.Cu")
		(net "PCIE_REFCLK_S4_N")
	)
	(segment
		(start 126.830582 -148.864066)
		(end 145.695416 -135.65505)
		(width 0.1397)
		(layer "In5.Cu")
		(net "PCIE_REFCLK_S4_N")
	)
	(segment
		(start 58.293 -195.742814)
		(end 58.293 -186.7662)
		(width 0.1397)
		(layer "In5.Cu")
		(net "PCIE_REFCLK_S4_N")
	)
	(segment
		(start 72.74433 -176.139348)
		(end 81.969102 -174.512732)
		(width 0.1397)
		(layer "In5.Cu")
		(net "PCIE_REFCLK_S4_N")
	)
	(segment
		(start 145.729706 -135.62076)
		(end 155.616148 -121.501408)
		(width 0.1397)
		(layer "In5.Cu")
		(net "PCIE_REFCLK_S4_N")
	)
	(segment
		(start 173.0248 -97.984564)
		(end 173.0248 -96.473772)
		(width 0.1397)
		(layer "In5.Cu")
		(net "PCIE_REFCLK_S4_N")
	)
	(segment
		(start 172.227748 -102.503732)
		(end 173.0248 -97.984564)
		(width 0.1397)
		(layer "In5.Cu")
		(net "PCIE_REFCLK_S4_N")
	)
	(segment
		(start 59.4741 -180.31714)
		(end 61.136276 -177.942748)
		(width 0.1397)
		(layer "In5.Cu")
		(net "PCIE_REFCLK_S4_N")
	)
	(segment
		(start 61.217048 -177.861976)
		(end 61.217556 -177.861976)
		(width 0.1397)
		(layer "In5.Cu")
		(net "PCIE_REFCLK_S4_N")
	)
	(segment
		(start 173.0248 -96.473772)
		(end 172.7454 -96.194372)
		(width 0.1397)
		(layer "In5.Cu")
		(net "PCIE_REFCLK_S4_N")
	)
	(segment
		(start 162.127184 -116.908072)
		(end 172.204888 -102.559358)
		(width 0.1397)
		(layer "In5.Cu")
		(net "PCIE_REFCLK_S4_N")
	)
	(segment
		(start 63.891922 -176.042828)
		(end 67.938142 -175.329342)
		(width 0.1397)
		(layer "In5.Cu")
		(net "PCIE_REFCLK_S4_N")
	)
	(arc
		(start 81.969102 -174.512732)
		(mid 82.05089 -174.505564)
		(end 82.132678 -174.512732)
		(width 0.1397)
		(layer "In5.Cu")
		(net "PCIE_REFCLK_S4_N")
	)
	(arc
		(start 72.69607 -176.139348)
		(mid 72.7202 -176.141451)
		(end 72.74433 -176.139348)
		(width 0.1397)
		(layer "In5.Cu")
		(net "PCIE_REFCLK_S4_N")
	)
	(arc
		(start 145.695416 -135.65505)
		(mid 145.714062 -135.639406)
		(end 145.729706 -135.62076)
		(width 0.1397)
		(layer "In5.Cu")
		(net "PCIE_REFCLK_S4_N")
	)
	(arc
		(start 126.715266 -148.979382)
		(mid 126.767886 -148.916686)
		(end 126.830582 -148.864066)
		(width 0.1397)
		(layer "In5.Cu")
		(net "PCIE_REFCLK_S4_N")
	)
	(arc
		(start 155.616148 -121.501408)
		(mid 155.668768 -121.438712)
		(end 155.731464 -121.386092)
		(width 0.1397)
		(layer "In5.Cu")
		(net "PCIE_REFCLK_S4_N")
	)
	(arc
		(start 58.0517 -196.2658)
		(mid 58.229786 -196.030804)
		(end 58.293 -195.742814)
		(width 0.1397)
		(layer "In5.Cu")
		(net "PCIE_REFCLK_S4_N")
	)
	(arc
		(start 59.396376 -180.5051)
		(mid 59.424939 -180.40686)
		(end 59.4741 -180.31714)
		(width 0.1397)
		(layer "In5.Cu")
		(net "PCIE_REFCLK_S4_N")
	)
	(arc
		(start 89.91727 -175.885348)
		(mid 89.9414 -175.887451)
		(end 89.96553 -175.885348)
		(width 0.1397)
		(layer "In5.Cu")
		(net "PCIE_REFCLK_S4_N")
	)
	(arc
		(start 63.703962 -176.120552)
		(mid 63.793683 -176.071383)
		(end 63.891922 -176.042828)
		(width 0.1397)
		(layer "In5.Cu")
		(net "PCIE_REFCLK_S4_N")
	)
	(arc
		(start 172.204888 -102.559358)
		(mid 172.219336 -102.532787)
		(end 172.227748 -102.503732)
		(width 0.1397)
		(layer "In5.Cu")
		(net "PCIE_REFCLK_S4_N")
	)
	(arc
		(start 67.938142 -175.329342)
		(mid 68.01993 -175.322174)
		(end 68.101718 -175.329342)
		(width 0.1397)
		(layer "In5.Cu")
		(net "PCIE_REFCLK_S4_N")
	)
	(arc
		(start 118.309898 -160.968944)
		(mid 118.328544 -160.9533)
		(end 118.344188 -160.934654)
		(width 0.1397)
		(layer "In5.Cu")
		(net "PCIE_REFCLK_S4_N")
	)
	(arc
		(start 99.346258 -174.2313)
		(mid 99.375464 -174.222805)
		(end 99.402138 -174.208186)
		(width 0.1397)
		(layer "In5.Cu")
		(net "PCIE_REFCLK_S4_N")
	)
	(segment
		(start 238.59998 -34.99993)
		(end 238.100108 -34.500058)
		(width 0.136652)
		(layer "F.Cu")
		(net "PCIE_REFCLK_S3_P")
	)
	(via
		(at 238.100108 -34.500058)
		(size 0.4572)
		(drill 0.2032)
		(layers "F.Cu" "B.Cu")
		(net "PCIE_REFCLK_S3_P")
	)
	(via
		(at 50.95748 -208.712054)
		(size 0.508)
		(drill 0.254)
		(layers "F.Cu" "B.Cu")
		(net "PCIE_REFCLK_S3_P")
	)
	(segment
		(start 48.25238 -223.2152)
		(end 48.252634 -223.2152)
		(width 0.136652)
		(layer "B.Cu")
		(net "PCIE_REFCLK_S3_P")
	)
	(segment
		(start 47.371 -210.489038)
		(end 47.371 -221.476062)
		(width 0.136652)
		(layer "B.Cu")
		(net "PCIE_REFCLK_S3_P")
	)
	(segment
		(start 50.723546 -209.175604)
		(end 50.723546 -209.24012)
		(width 0.136652)
		(layer "B.Cu")
		(net "PCIE_REFCLK_S3_P")
	)
	(segment
		(start 48.20793 -222.834708)
		(end 48.207676 -222.834708)
		(width 0.136652)
		(layer "B.Cu")
		(net "PCIE_REFCLK_S3_P")
	)
	(segment
		(start 49.611534 -210.11896)
		(end 47.565056 -210.11896)
		(width 0.136652)
		(layer "B.Cu")
		(net "PCIE_REFCLK_S3_P")
	)
	(segment
		(start 48.25238 -223.138746)
		(end 48.25238 -223.2152)
		(width 0.136652)
		(layer "B.Cu")
		(net "PCIE_REFCLK_S3_P")
	)
	(segment
		(start 50.95748 -208.712054)
		(end 50.863754 -208.80578)
		(width 0.136652)
		(layer "B.Cu")
		(net "PCIE_REFCLK_S3_P")
	)
	(segment
		(start 50.7238 -209.1436)
		(end 50.7238 -209.175096)
		(width 0.136652)
		(layer "B.Cu")
		(net "PCIE_REFCLK_S3_P")
	)
	(segment
		(start 47.613316 -222.061024)
		(end 47.942246 -222.389954)
		(width 0.136652)
		(layer "B.Cu")
		(net "PCIE_REFCLK_S3_P")
	)
	(segment
		(start 48.252634 -223.2152)
		(end 48.252634 -224.62998)
		(width 0.136652)
		(layer "B.Cu")
		(net "PCIE_REFCLK_S3_P")
	)
	(segment
		(start 50.682144 -209.45094)
		(end 50.66284 -209.49793)
		(width 0.136652)
		(layer "B.Cu")
		(net "PCIE_REFCLK_S3_P")
	)
	(segment
		(start 48.50003 -225.227388)
		(end 48.50003 -225.92538)
		(width 0.136652)
		(layer "B.Cu")
		(net "PCIE_REFCLK_S3_P")
	)
	(arc
		(start 50.863754 -208.80578)
		(mid 50.760191 -208.960773)
		(end 50.7238 -209.1436)
		(width 0.136652)
		(layer "B.Cu")
		(net "PCIE_REFCLK_S3_P")
	)
	(arc
		(start 50.66284 -209.49793)
		(mid 50.429882 -209.834282)
		(end 50.078132 -210.043268)
		(width 0.136652)
		(layer "B.Cu")
		(net "PCIE_REFCLK_S3_P")
	)
	(arc
		(start 48.32985 -224.816416)
		(mid 48.455839 -225.004972)
		(end 48.50003 -225.227388)
		(width 0.136652)
		(layer "B.Cu")
		(net "PCIE_REFCLK_S3_P")
	)
	(arc
		(start 50.723546 -209.24012)
		(mid 50.71314 -209.34755)
		(end 50.682144 -209.45094)
		(width 0.136652)
		(layer "B.Cu")
		(net "PCIE_REFCLK_S3_P")
	)
	(arc
		(start 50.7238 -209.175096)
		(mid 50.723673 -209.17535)
		(end 50.723546 -209.175604)
		(width 0.136652)
		(layer "B.Cu")
		(net "PCIE_REFCLK_S3_P")
	)
	(arc
		(start 47.942246 -222.389954)
		(mid 48.102667 -222.595852)
		(end 48.20793 -222.834708)
		(width 0.136652)
		(layer "B.Cu")
		(net "PCIE_REFCLK_S3_P")
	)
	(arc
		(start 50.05197 -210.05165)
		(mid 49.834309 -210.102041)
		(end 49.611534 -210.11896)
		(width 0.136652)
		(layer "B.Cu")
		(net "PCIE_REFCLK_S3_P")
	)
	(arc
		(start 47.565056 -210.11896)
		(mid 47.494474 -210.138599)
		(end 47.444152 -210.191858)
		(width 0.136652)
		(layer "B.Cu")
		(net "PCIE_REFCLK_S3_P")
	)
	(arc
		(start 50.078132 -210.043268)
		(mid 50.065081 -210.047552)
		(end 50.05197 -210.05165)
		(width 0.136652)
		(layer "B.Cu")
		(net "PCIE_REFCLK_S3_P")
	)
	(arc
		(start 48.252634 -224.62998)
		(mid 48.272703 -224.730875)
		(end 48.32985 -224.816416)
		(width 0.136652)
		(layer "B.Cu")
		(net "PCIE_REFCLK_S3_P")
	)
	(arc
		(start 47.371 -221.476062)
		(mid 47.433973 -221.792648)
		(end 47.613316 -222.061024)
		(width 0.136652)
		(layer "B.Cu")
		(net "PCIE_REFCLK_S3_P")
	)
	(arc
		(start 48.207676 -222.834708)
		(mid 48.241124 -222.985096)
		(end 48.25238 -223.138746)
		(width 0.136652)
		(layer "B.Cu")
		(net "PCIE_REFCLK_S3_P")
	)
	(arc
		(start 47.444152 -210.191858)
		(mid 47.389566 -210.336014)
		(end 47.371 -210.489038)
		(width 0.136652)
		(layer "B.Cu")
		(net "PCIE_REFCLK_S3_P")
	)
	(segment
		(start 88.275668 -191.132714)
		(end 94.708218 -186.628278)
		(width 0.1397)
		(layer "In2.Cu")
		(net "PCIE_REFCLK_S3_P")
	)
	(segment
		(start 87.410544 -191.285368)
		(end 88.275668 -191.132714)
		(width 0.1397)
		(layer "In2.Cu")
		(net "PCIE_REFCLK_S3_P")
	)
	(segment
		(start 50.902108 -205.968092)
		(end 56.040274 -200.829926)
		(width 0.1397)
		(layer "In2.Cu")
		(net "PCIE_REFCLK_S3_P")
	)
	(segment
		(start 97.155 -183.134)
		(end 97.488756 -181.2417)
		(width 0.1397)
		(layer "In2.Cu")
		(net "PCIE_REFCLK_S3_P")
	)
	(segment
		(start 221.342712 -45.096938)
		(end 235.266484 -45.096938)
		(width 0.1016)
		(layer "In2.Cu")
		(net "PCIE_REFCLK_S3_P")
	)
	(segment
		(start 94.708218 -186.628278)
		(end 97.155 -183.134)
		(width 0.1397)
		(layer "In2.Cu")
		(net "PCIE_REFCLK_S3_P")
	)
	(segment
		(start 206.015844 -52.59324)
		(end 208.652364 -48.84547)
		(width 0.1397)
		(layer "In2.Cu")
		(net "PCIE_REFCLK_S3_P")
	)
	(segment
		(start 150.55469 -124.604018)
		(end 150.600664 -124.342398)
		(width 0.1397)
		(layer "In2.Cu")
		(net "PCIE_REFCLK_S3_P")
	)
	(segment
		(start 148.61159 -125.73508)
		(end 148.954998 -125.494796)
		(width 0.1397)
		(layer "In2.Cu")
		(net "PCIE_REFCLK_S3_P")
	)
	(segment
		(start 148.222208 -126.237238)
		(end 148.565616 -125.996954)
		(width 0.1397)
		(layer "In2.Cu")
		(net "PCIE_REFCLK_S3_P")
	)
	(segment
		(start 56.040274 -200.829926)
		(end 66.94805 -193.192146)
		(width 0.1397)
		(layer "In2.Cu")
		(net "PCIE_REFCLK_S3_P")
	)
	(segment
		(start 218.820238 -45.124878)
		(end 221.314772 -45.124878)
		(width 0.1397)
		(layer "In2.Cu")
		(net "PCIE_REFCLK_S3_P")
	)
	(segment
		(start 208.652364 -48.84547)
		(end 212.332062 -46.268894)
		(width 0.1397)
		(layer "In2.Cu")
		(net "PCIE_REFCLK_S3_P")
	)
	(segment
		(start 173.903894 -108.025184)
		(end 195.449698 -77.263244)
		(width 0.1397)
		(layer "In2.Cu")
		(net "PCIE_REFCLK_S3_P")
	)
	(segment
		(start 74.93254 -190.558674)
		(end 77.11059 -190.174626)
		(width 0.1397)
		(layer "In2.Cu")
		(net "PCIE_REFCLK_S3_P")
	)
	(segment
		(start 81.312512 -190.209932)
		(end 87.410544 -191.285368)
		(width 0.1397)
		(layer "In2.Cu")
		(net "PCIE_REFCLK_S3_P")
	)
	(segment
		(start 150.600664 -124.342144)
		(end 173.903894 -108.025184)
		(width 0.1397)
		(layer "In2.Cu")
		(net "PCIE_REFCLK_S3_P")
	)
	(segment
		(start 66.94805 -193.192146)
		(end 72.5932 -192.19672)
		(width 0.1397)
		(layer "In2.Cu")
		(net "PCIE_REFCLK_S3_P")
	)
	(segment
		(start 221.314772 -45.124878)
		(end 221.342712 -45.096938)
		(width 0.1016)
		(layer "In2.Cu")
		(net "PCIE_REFCLK_S3_P")
	)
	(segment
		(start 150.211282 -124.844556)
		(end 150.55469 -124.604018)
		(width 0.1397)
		(layer "In2.Cu")
		(net "PCIE_REFCLK_S3_P")
	)
	(segment
		(start 212.332062 -46.268894)
		(end 218.820238 -45.124878)
		(width 0.1397)
		(layer "In2.Cu")
		(net "PCIE_REFCLK_S3_P")
	)
	(segment
		(start 236.697012 -35.71621)
		(end 236.697012 -35.388042)
		(width 0.1016)
		(layer "In2.Cu")
		(net "PCIE_REFCLK_S3_P")
	)
	(segment
		(start 196.768212 -58.258964)
		(end 197.541896 -57.067958)
		(width 0.1397)
		(layer "In2.Cu")
		(net "PCIE_REFCLK_S3_P")
	)
	(segment
		(start 149.949408 -124.798328)
		(end 150.211282 -124.844556)
		(width 0.1397)
		(layer "In2.Cu")
		(net "PCIE_REFCLK_S3_P")
	)
	(segment
		(start 77.11059 -190.174626)
		(end 79.310992 -190.562484)
		(width 0.1397)
		(layer "In2.Cu")
		(net "PCIE_REFCLK_S3_P")
	)
	(segment
		(start 202.931268 -54.752748)
		(end 206.015844 -52.59324)
		(width 0.1397)
		(layer "In2.Cu")
		(net "PCIE_REFCLK_S3_P")
	)
	(segment
		(start 235.697014 -44.666408)
		(end 235.697014 -36.313364)
		(width 0.1016)
		(layer "In2.Cu")
		(net "PCIE_REFCLK_S3_P")
	)
	(segment
		(start 237.565692 -35.01009)
		(end 237.600998 -34.974784)
		(width 0.1016)
		(layer "In2.Cu")
		(net "PCIE_REFCLK_S3_P")
	)
	(segment
		(start 197.541896 -57.067958)
		(end 200.219564 -55.329074)
		(width 0.1397)
		(layer "In2.Cu")
		(net "PCIE_REFCLK_S3_P")
	)
	(segment
		(start 196.347842 -60.689998)
		(end 196.768212 -58.258964)
		(width 0.1397)
		(layer "In2.Cu")
		(net "PCIE_REFCLK_S3_P")
	)
	(segment
		(start 148.954998 -125.494796)
		(end 149.216618 -125.54077)
		(width 0.1397)
		(layer "In2.Cu")
		(net "PCIE_REFCLK_S3_P")
	)
	(segment
		(start 79.310992 -190.562484)
		(end 81.312512 -190.209932)
		(width 0.1397)
		(layer "In2.Cu")
		(net "PCIE_REFCLK_S3_P")
	)
	(segment
		(start 237.81766 -34.106866)
		(end 237.962186 -34.106866)
		(width 0.1016)
		(layer "In2.Cu")
		(net "PCIE_REFCLK_S3_P")
	)
	(segment
		(start 200.219564 -55.329074)
		(end 202.931268 -54.752748)
		(width 0.1397)
		(layer "In2.Cu")
		(net "PCIE_REFCLK_S3_P")
	)
	(segment
		(start 195.449698 -77.263244)
		(end 197.360286 -66.433954)
		(width 0.1397)
		(layer "In2.Cu")
		(net "PCIE_REFCLK_S3_P")
	)
	(segment
		(start 236.72673 -35.31616)
		(end 236.90707 -35.136074)
		(width 0.1016)
		(layer "In2.Cu")
		(net "PCIE_REFCLK_S3_P")
	)
	(segment
		(start 236.39653 -36.06927)
		(end 236.659928 -35.805872)
		(width 0.1016)
		(layer "In2.Cu")
		(net "PCIE_REFCLK_S3_P")
	)
	(segment
		(start 235.49991 -45.000672)
		(end 235.600748 -44.899834)
		(width 0.1016)
		(layer "In2.Cu")
		(net "PCIE_REFCLK_S3_P")
	)
	(segment
		(start 72.5932 -192.19672)
		(end 74.93254 -190.558674)
		(width 0.1397)
		(layer "In2.Cu")
		(net "PCIE_REFCLK_S3_P")
	)
	(segment
		(start 50.71618 -208.1784)
		(end 50.71618 -206.417164)
		(width 0.1397)
		(layer "In2.Cu")
		(net "PCIE_REFCLK_S3_P")
	)
	(segment
		(start 197.360286 -66.433954)
		(end 196.347842 -60.689998)
		(width 0.1397)
		(layer "In2.Cu")
		(net "PCIE_REFCLK_S3_P")
	)
	(segment
		(start 237.697264 -34.741358)
		(end 237.697264 -34.227008)
		(width 0.1016)
		(layer "In2.Cu")
		(net "PCIE_REFCLK_S3_P")
	)
	(segment
		(start 235.734098 -36.223702)
		(end 235.814362 -36.143438)
		(width 0.1016)
		(layer "In2.Cu")
		(net "PCIE_REFCLK_S3_P")
	)
	(segment
		(start 235.904024 -36.106354)
		(end 236.306868 -36.106354)
		(width 0.1016)
		(layer "In2.Cu")
		(net "PCIE_REFCLK_S3_P")
	)
	(segment
		(start 149.560026 -125.300486)
		(end 149.606254 -125.038612)
		(width 0.1397)
		(layer "In2.Cu")
		(net "PCIE_REFCLK_S3_P")
	)
	(segment
		(start 147.960334 -126.19101)
		(end 148.222208 -126.237238)
		(width 0.1397)
		(layer "In2.Cu")
		(net "PCIE_REFCLK_S3_P")
	)
	(segment
		(start 124.564648 -142.572994)
		(end 147.960334 -126.19101)
		(width 0.1397)
		(layer "In2.Cu")
		(net "PCIE_REFCLK_S3_P")
	)
	(segment
		(start 149.606254 -125.038612)
		(end 149.949408 -124.798328)
		(width 0.1397)
		(layer "In2.Cu")
		(net "PCIE_REFCLK_S3_P")
	)
	(segment
		(start 97.488756 -181.2417)
		(end 124.564648 -142.572994)
		(width 0.1397)
		(layer "In2.Cu")
		(net "PCIE_REFCLK_S3_P")
	)
	(segment
		(start 148.565616 -125.996954)
		(end 148.61159 -125.73508)
		(width 0.1397)
		(layer "In2.Cu")
		(net "PCIE_REFCLK_S3_P")
	)
	(segment
		(start 236.978952 -35.106356)
		(end 237.332266 -35.106356)
		(width 0.1016)
		(layer "In2.Cu")
		(net "PCIE_REFCLK_S3_P")
	)
	(segment
		(start 149.216618 -125.54077)
		(end 149.560026 -125.300486)
		(width 0.1397)
		(layer "In2.Cu")
		(net "PCIE_REFCLK_S3_P")
	)
	(segment
		(start 150.600664 -124.342398)
		(end 150.600664 -124.342144)
		(width 0.1397)
		(layer "In2.Cu")
		(net "PCIE_REFCLK_S3_P")
	)
	(arc
		(start 237.732316 -34.142172)
		(mid 237.771486 -34.116062)
		(end 237.81766 -34.106866)
		(width 0.1016)
		(layer "In2.Cu")
		(net "PCIE_REFCLK_S3_P")
	)
	(arc
		(start 238.1504 -34.2138)
		(mid 238.178508 -34.366299)
		(end 238.100108 -34.500058)
		(width 0.1016)
		(layer "In2.Cu")
		(net "PCIE_REFCLK_S3_P")
	)
	(arc
		(start 236.306868 -36.106354)
		(mid 236.355386 -36.096721)
		(end 236.39653 -36.06927)
		(width 0.1016)
		(layer "In2.Cu")
		(net "PCIE_REFCLK_S3_P")
	)
	(arc
		(start 237.600998 -34.974784)
		(mid 237.672368 -34.867644)
		(end 237.697264 -34.741358)
		(width 0.1016)
		(layer "In2.Cu")
		(net "PCIE_REFCLK_S3_P")
	)
	(arc
		(start 235.697014 -36.313364)
		(mid 235.706647 -36.264846)
		(end 235.734098 -36.223702)
		(width 0.1016)
		(layer "In2.Cu")
		(net "PCIE_REFCLK_S3_P")
	)
	(arc
		(start 236.697012 -35.388042)
		(mid 236.704731 -35.349147)
		(end 236.72673 -35.31616)
		(width 0.1016)
		(layer "In2.Cu")
		(net "PCIE_REFCLK_S3_P")
	)
	(arc
		(start 50.71618 -206.417164)
		(mid 50.764516 -206.17416)
		(end 50.902108 -205.968092)
		(width 0.1397)
		(layer "In2.Cu")
		(net "PCIE_REFCLK_S3_P")
	)
	(arc
		(start 237.332266 -35.106356)
		(mid 237.458516 -35.081373)
		(end 237.565692 -35.01009)
		(width 0.1016)
		(layer "In2.Cu")
		(net "PCIE_REFCLK_S3_P")
	)
	(arc
		(start 50.95748 -208.712054)
		(mid 50.779292 -208.471241)
		(end 50.71618 -208.1784)
		(width 0.1397)
		(layer "In2.Cu")
		(net "PCIE_REFCLK_S3_P")
	)
	(arc
		(start 237.697264 -34.227008)
		(mid 237.706375 -34.181115)
		(end 237.732316 -34.142172)
		(width 0.1016)
		(layer "In2.Cu")
		(net "PCIE_REFCLK_S3_P")
	)
	(arc
		(start 237.962186 -34.106866)
		(mid 238.070433 -34.135458)
		(end 238.1504 -34.2138)
		(width 0.1016)
		(layer "In2.Cu")
		(net "PCIE_REFCLK_S3_P")
	)
	(arc
		(start 235.266484 -45.096938)
		(mid 235.392734 -45.071955)
		(end 235.49991 -45.000672)
		(width 0.1016)
		(layer "In2.Cu")
		(net "PCIE_REFCLK_S3_P")
	)
	(arc
		(start 235.814362 -36.143438)
		(mid 235.855513 -36.116005)
		(end 235.904024 -36.106354)
		(width 0.1016)
		(layer "In2.Cu")
		(net "PCIE_REFCLK_S3_P")
	)
	(arc
		(start 236.659928 -35.805872)
		(mid 236.687361 -35.764721)
		(end 236.697012 -35.71621)
		(width 0.1016)
		(layer "In2.Cu")
		(net "PCIE_REFCLK_S3_P")
	)
	(arc
		(start 236.90707 -35.136074)
		(mid 236.940064 -35.114091)
		(end 236.978952 -35.106356)
		(width 0.1016)
		(layer "In2.Cu")
		(net "PCIE_REFCLK_S3_P")
	)
	(arc
		(start 235.600748 -44.899834)
		(mid 235.672118 -44.792694)
		(end 235.697014 -44.666408)
		(width 0.1016)
		(layer "In2.Cu")
		(net "PCIE_REFCLK_S3_P")
	)
	(segment
		(start 238.59998 -33.999932)
		(end 238.100108 -33.50006)
		(width 0.136652)
		(layer "F.Cu")
		(net "PCIE_REFCLK_S3_N")
	)
	(via
		(at 50.14468 -208.712054)
		(size 0.508)
		(drill 0.254)
		(layers "F.Cu" "B.Cu")
		(net "PCIE_REFCLK_S3_N")
	)
	(via
		(at 238.100108 -33.50006)
		(size 0.4572)
		(drill 0.2032)
		(layers "F.Cu" "B.Cu")
		(net "PCIE_REFCLK_S3_N")
	)
	(segment
		(start 50.418746 -209.175604)
		(end 50.418746 -209.24012)
		(width 0.136652)
		(layer "B.Cu")
		(net "PCIE_REFCLK_S3_N")
	)
	(segment
		(start 49.981612 -209.753962)
		(end 49.981104 -209.753962)
		(width 0.136652)
		(layer "B.Cu")
		(net "PCIE_REFCLK_S3_N")
	)
	(segment
		(start 47.94758 -223.139)
		(end 47.94758 -224.0534)
		(width 0.136652)
		(layer "B.Cu")
		(net "PCIE_REFCLK_S3_N")
	)
	(segment
		(start 47.389542 -222.268542)
		(end 47.7266 -222.6056)
		(width 0.136652)
		(layer "B.Cu")
		(net "PCIE_REFCLK_S3_N")
	)
	(segment
		(start 47.94758 -224.0534)
		(end 47.947834 -224.053654)
		(width 0.136652)
		(layer "B.Cu")
		(net "PCIE_REFCLK_S3_N")
	)
	(segment
		(start 47.947834 -224.053654)
		(end 47.947834 -224.644712)
		(width 0.136652)
		(layer "B.Cu")
		(net "PCIE_REFCLK_S3_N")
	)
	(segment
		(start 47.700184 -225.170746)
		(end 47.700184 -225.92538)
		(width 0.136652)
		(layer "B.Cu")
		(net "PCIE_REFCLK_S3_N")
	)
	(segment
		(start 49.61128 -209.81416)
		(end 47.565056 -209.81416)
		(width 0.136652)
		(layer "B.Cu")
		(net "PCIE_REFCLK_S3_N")
	)
	(segment
		(start 50.39995 -209.335116)
		(end 50.3809 -209.381598)
		(width 0.136652)
		(layer "B.Cu")
		(net "PCIE_REFCLK_S3_N")
	)
	(segment
		(start 50.14468 -208.712054)
		(end 50.285142 -208.852516)
		(width 0.136652)
		(layer "B.Cu")
		(net "PCIE_REFCLK_S3_N")
	)
	(segment
		(start 47.890938 -224.782126)
		(end 47.840138 -224.832926)
		(width 0.136652)
		(layer "B.Cu")
		(net "PCIE_REFCLK_S3_N")
	)
	(segment
		(start 47.0662 -210.489038)
		(end 47.0662 -221.488)
		(width 0.136652)
		(layer "B.Cu")
		(net "PCIE_REFCLK_S3_N")
	)
	(arc
		(start 47.840138 -224.832926)
		(mid 47.736575 -224.987919)
		(end 47.700184 -225.170746)
		(width 0.136652)
		(layer "B.Cu")
		(net "PCIE_REFCLK_S3_N")
	)
	(arc
		(start 47.91583 -222.922338)
		(mid 47.939624 -223.02951)
		(end 47.94758 -223.139)
		(width 0.136652)
		(layer "B.Cu")
		(net "PCIE_REFCLK_S3_N")
	)
	(arc
		(start 49.960784 -209.760566)
		(mid 49.788069 -209.800647)
		(end 49.61128 -209.81416)
		(width 0.136652)
		(layer "B.Cu")
		(net "PCIE_REFCLK_S3_N")
	)
	(arc
		(start 47.947834 -224.644712)
		(mid 47.933043 -224.719071)
		(end 47.890938 -224.782126)
		(width 0.136652)
		(layer "B.Cu")
		(net "PCIE_REFCLK_S3_N")
	)
	(arc
		(start 47.17415 -210.049872)
		(mid 47.093516 -210.262903)
		(end 47.0662 -210.489038)
		(width 0.136652)
		(layer "B.Cu")
		(net "PCIE_REFCLK_S3_N")
	)
	(arc
		(start 47.0662 -221.488)
		(mid 47.150228 -221.910438)
		(end 47.389542 -222.268542)
		(width 0.136652)
		(layer "B.Cu")
		(net "PCIE_REFCLK_S3_N")
	)
	(arc
		(start 50.418746 -209.24012)
		(mid 50.414001 -209.288539)
		(end 50.39995 -209.335116)
		(width 0.136652)
		(layer "B.Cu")
		(net "PCIE_REFCLK_S3_N")
	)
	(arc
		(start 49.981104 -209.753962)
		(mid 49.970959 -209.75731)
		(end 49.960784 -209.760566)
		(width 0.136652)
		(layer "B.Cu")
		(net "PCIE_REFCLK_S3_N")
	)
	(arc
		(start 47.565056 -209.81416)
		(mid 47.336765 -209.877576)
		(end 47.17415 -210.049872)
		(width 0.136652)
		(layer "B.Cu")
		(net "PCIE_REFCLK_S3_N")
	)
	(arc
		(start 50.285142 -208.852516)
		(mid 50.384052 -209.000779)
		(end 50.418746 -209.175604)
		(width 0.136652)
		(layer "B.Cu")
		(net "PCIE_REFCLK_S3_N")
	)
	(arc
		(start 50.3809 -209.381598)
		(mid 50.221819 -209.611272)
		(end 49.981612 -209.753962)
		(width 0.136652)
		(layer "B.Cu")
		(net "PCIE_REFCLK_S3_N")
	)
	(arc
		(start 47.7266 -222.6056)
		(mid 47.840891 -222.752216)
		(end 47.91583 -222.922338)
		(width 0.136652)
		(layer "B.Cu")
		(net "PCIE_REFCLK_S3_N")
	)
	(segment
		(start 200.09104 -55.018686)
		(end 202.796902 -54.44363)
		(width 0.1397)
		(layer "In2.Cu")
		(net "PCIE_REFCLK_S3_N")
	)
	(segment
		(start 197.024752 -66.433954)
		(end 196.012562 -60.691014)
		(width 0.1397)
		(layer "In2.Cu")
		(net "PCIE_REFCLK_S3_N")
	)
	(segment
		(start 236.493812 -35.642296)
		(end 236.493812 -35.388042)
		(width 0.1016)
		(layer "In2.Cu")
		(net "PCIE_REFCLK_S3_N")
	)
	(segment
		(start 196.012562 -60.689998)
		(end 196.454268 -58.136028)
		(width 0.1397)
		(layer "In2.Cu")
		(net "PCIE_REFCLK_S3_N")
	)
	(segment
		(start 236.582712 -35.172396)
		(end 236.763052 -34.99231)
		(width 0.1016)
		(layer "In2.Cu")
		(net "PCIE_REFCLK_S3_N")
	)
	(segment
		(start 235.904024 -35.903154)
		(end 236.232954 -35.903154)
		(width 0.1016)
		(layer "In2.Cu")
		(net "PCIE_REFCLK_S3_N")
	)
	(segment
		(start 237.816136 -33.903666)
		(end 237.899194 -33.903666)
		(width 0.1016)
		(layer "In2.Cu")
		(net "PCIE_REFCLK_S3_N")
	)
	(segment
		(start 173.666658 -107.787948)
		(end 195.137024 -77.133704)
		(width 0.1397)
		(layer "In2.Cu")
		(net "PCIE_REFCLK_S3_N")
	)
	(segment
		(start 74.803 -190.246)
		(end 77.11059 -189.839092)
		(width 0.1397)
		(layer "In2.Cu")
		(net "PCIE_REFCLK_S3_N")
	)
	(segment
		(start 238.040926 -33.844992)
		(end 238.04118 -33.844738)
		(width 0.1016)
		(layer "In2.Cu")
		(net "PCIE_REFCLK_S3_N")
	)
	(segment
		(start 236.763052 -34.99231)
		(end 236.763306 -34.99231)
		(width 0.1016)
		(layer "In2.Cu")
		(net "PCIE_REFCLK_S3_N")
	)
	(segment
		(start 77.11059 -189.839092)
		(end 79.310992 -190.22695)
		(width 0.1397)
		(layer "In2.Cu")
		(net "PCIE_REFCLK_S3_N")
	)
	(segment
		(start 221.451678 -44.794678)
		(end 221.550738 -44.893738)
		(width 0.1016)
		(layer "In2.Cu")
		(net "PCIE_REFCLK_S3_N")
	)
	(segment
		(start 221.550738 -44.893738)
		(end 235.266484 -44.893738)
		(width 0.1016)
		(layer "In2.Cu")
		(net "PCIE_REFCLK_S3_N")
	)
	(segment
		(start 218.791282 -44.794678)
		(end 221.451678 -44.794678)
		(width 0.1397)
		(layer "In2.Cu")
		(net "PCIE_REFCLK_S3_N")
	)
	(segment
		(start 50.668682 -205.734412)
		(end 55.827168 -200.575926)
		(width 0.1397)
		(layer "In2.Cu")
		(net "PCIE_REFCLK_S3_N")
	)
	(segment
		(start 94.470982 -186.391042)
		(end 96.842326 -183.00446)
		(width 0.1397)
		(layer "In2.Cu")
		(net "PCIE_REFCLK_S3_N")
	)
	(segment
		(start 236.905038 -34.903156)
		(end 237.332266 -34.903156)
		(width 0.1016)
		(layer "In2.Cu")
		(net "PCIE_REFCLK_S3_N")
	)
	(segment
		(start 205.778862 -52.35575)
		(end 208.415382 -48.60798)
		(width 0.1397)
		(layer "In2.Cu")
		(net "PCIE_REFCLK_S3_N")
	)
	(segment
		(start 237.421928 -34.866072)
		(end 237.45698 -34.83102)
		(width 0.1016)
		(layer "In2.Cu")
		(net "PCIE_REFCLK_S3_N")
	)
	(segment
		(start 196.454268 -58.136028)
		(end 197.303136 -56.829198)
		(width 0.1397)
		(layer "In2.Cu")
		(net "PCIE_REFCLK_S3_N")
	)
	(segment
		(start 237.58779 -33.998916)
		(end 237.58906 -33.997646)
		(width 0.1016)
		(layer "In2.Cu")
		(net "PCIE_REFCLK_S3_N")
	)
	(segment
		(start 88.146128 -190.82004)
		(end 94.470982 -186.391042)
		(width 0.1397)
		(layer "In2.Cu")
		(net "PCIE_REFCLK_S3_N")
	)
	(segment
		(start 87.410544 -190.949834)
		(end 88.146128 -190.82004)
		(width 0.1397)
		(layer "In2.Cu")
		(net "PCIE_REFCLK_S3_N")
	)
	(segment
		(start 50.38598 -208.129378)
		(end 50.38598 -206.41691)
		(width 0.1397)
		(layer "In2.Cu")
		(net "PCIE_REFCLK_S3_N")
	)
	(segment
		(start 81.312512 -189.874398)
		(end 87.410544 -190.949834)
		(width 0.1397)
		(layer "In2.Cu")
		(net "PCIE_REFCLK_S3_N")
	)
	(segment
		(start 236.763306 -34.99231)
		(end 236.815376 -34.94024)
		(width 0.1016)
		(layer "In2.Cu")
		(net "PCIE_REFCLK_S3_N")
	)
	(segment
		(start 237.58906 -33.997646)
		(end 237.589314 -33.997646)
		(width 0.1016)
		(layer "In2.Cu")
		(net "PCIE_REFCLK_S3_N")
	)
	(segment
		(start 212.202522 -45.95622)
		(end 218.791282 -44.794678)
		(width 0.1397)
		(layer "In2.Cu")
		(net "PCIE_REFCLK_S3_N")
	)
	(segment
		(start 66.81851 -192.879472)
		(end 72.46366 -191.884046)
		(width 0.1397)
		(layer "In2.Cu")
		(net "PCIE_REFCLK_S3_N")
	)
	(segment
		(start 196.012562 -60.691014)
		(end 196.012562 -60.689998)
		(width 0.1397)
		(layer "In2.Cu")
		(net "PCIE_REFCLK_S3_N")
	)
	(segment
		(start 235.356146 -44.856654)
		(end 235.45673 -44.75607)
		(width 0.1016)
		(layer "In2.Cu")
		(net "PCIE_REFCLK_S3_N")
	)
	(segment
		(start 55.827168 -200.575926)
		(end 66.81851 -192.879472)
		(width 0.1397)
		(layer "In2.Cu")
		(net "PCIE_REFCLK_S3_N")
	)
	(segment
		(start 96.842326 -183.00446)
		(end 97.176082 -181.11216)
		(width 0.1397)
		(layer "In2.Cu")
		(net "PCIE_REFCLK_S3_N")
	)
	(segment
		(start 195.137024 -77.133704)
		(end 197.024752 -66.433954)
		(width 0.1397)
		(layer "In2.Cu")
		(net "PCIE_REFCLK_S3_N")
	)
	(segment
		(start 72.46366 -191.884046)
		(end 74.803 -190.246)
		(width 0.1397)
		(layer "In2.Cu")
		(net "PCIE_REFCLK_S3_N")
	)
	(segment
		(start 202.796902 -54.44363)
		(end 205.778862 -52.35575)
		(width 0.1397)
		(layer "In2.Cu")
		(net "PCIE_REFCLK_S3_N")
	)
	(segment
		(start 79.310992 -190.22695)
		(end 81.312512 -189.874398)
		(width 0.1397)
		(layer "In2.Cu")
		(net "PCIE_REFCLK_S3_N")
	)
	(segment
		(start 208.415382 -48.60798)
		(end 212.202522 -45.95622)
		(width 0.1397)
		(layer "In2.Cu")
		(net "PCIE_REFCLK_S3_N")
	)
	(segment
		(start 235.493814 -44.666408)
		(end 235.493814 -36.313364)
		(width 0.1016)
		(layer "In2.Cu")
		(net "PCIE_REFCLK_S3_N")
	)
	(segment
		(start 197.303136 -56.829198)
		(end 200.09104 -55.018686)
		(width 0.1397)
		(layer "In2.Cu")
		(net "PCIE_REFCLK_S3_N")
	)
	(segment
		(start 236.304836 -35.873436)
		(end 236.464094 -35.714178)
		(width 0.1016)
		(layer "In2.Cu")
		(net "PCIE_REFCLK_S3_N")
	)
	(segment
		(start 238.100108 -33.702498)
		(end 238.100108 -33.50006)
		(width 0.1016)
		(layer "In2.Cu")
		(net "PCIE_REFCLK_S3_N")
	)
	(segment
		(start 235.59008 -36.079938)
		(end 235.670598 -35.99942)
		(width 0.1016)
		(layer "In2.Cu")
		(net "PCIE_REFCLK_S3_N")
	)
	(segment
		(start 237.494064 -34.741358)
		(end 237.494064 -34.227008)
		(width 0.1016)
		(layer "In2.Cu")
		(net "PCIE_REFCLK_S3_N")
	)
	(segment
		(start 97.176082 -181.11216)
		(end 124.327412 -142.335758)
		(width 0.1397)
		(layer "In2.Cu")
		(net "PCIE_REFCLK_S3_N")
	)
	(segment
		(start 124.327412 -142.335758)
		(end 173.666658 -107.787948)
		(width 0.1397)
		(layer "In2.Cu")
		(net "PCIE_REFCLK_S3_N")
	)
	(arc
		(start 236.815376 -34.94024)
		(mid 236.856527 -34.912807)
		(end 236.905038 -34.903156)
		(width 0.1016)
		(layer "In2.Cu")
		(net "PCIE_REFCLK_S3_N")
	)
	(arc
		(start 237.332266 -34.903156)
		(mid 237.380784 -34.893523)
		(end 237.421928 -34.866072)
		(width 0.1016)
		(layer "In2.Cu")
		(net "PCIE_REFCLK_S3_N")
	)
	(arc
		(start 235.45673 -44.75607)
		(mid 235.484163 -44.714919)
		(end 235.493814 -44.666408)
		(width 0.1016)
		(layer "In2.Cu")
		(net "PCIE_REFCLK_S3_N")
	)
	(arc
		(start 235.266484 -44.893738)
		(mid 235.315002 -44.884105)
		(end 235.356146 -44.856654)
		(width 0.1016)
		(layer "In2.Cu")
		(net "PCIE_REFCLK_S3_N")
	)
	(arc
		(start 237.92942 -33.901126)
		(mid 237.929674 -33.901126)
		(end 237.929928 -33.901126)
		(width 0.1016)
		(layer "In2.Cu")
		(net "PCIE_REFCLK_S3_N")
	)
	(arc
		(start 237.494064 -34.227008)
		(mid 237.518374 -34.103701)
		(end 237.58779 -33.998916)
		(width 0.1016)
		(layer "In2.Cu")
		(net "PCIE_REFCLK_S3_N")
	)
	(arc
		(start 50.14468 -208.712054)
		(mid 50.316477 -208.460729)
		(end 50.385218 -208.164176)
		(width 0.1397)
		(layer "In2.Cu")
		(net "PCIE_REFCLK_S3_N")
	)
	(arc
		(start 237.45698 -34.83102)
		(mid 237.484413 -34.789869)
		(end 237.494064 -34.741358)
		(width 0.1016)
		(layer "In2.Cu")
		(net "PCIE_REFCLK_S3_N")
	)
	(arc
		(start 50.385218 -208.164176)
		(mid 50.385785 -208.146781)
		(end 50.38598 -208.129378)
		(width 0.1397)
		(layer "In2.Cu")
		(net "PCIE_REFCLK_S3_N")
	)
	(arc
		(start 236.493812 -35.388042)
		(mid 236.516881 -35.271415)
		(end 236.582712 -35.172396)
		(width 0.1016)
		(layer "In2.Cu")
		(net "PCIE_REFCLK_S3_N")
	)
	(arc
		(start 236.232954 -35.903154)
		(mid 236.271849 -35.895435)
		(end 236.304836 -35.873436)
		(width 0.1016)
		(layer "In2.Cu")
		(net "PCIE_REFCLK_S3_N")
	)
	(arc
		(start 237.589314 -33.997646)
		(mid 237.693381 -33.928111)
		(end 237.816136 -33.903666)
		(width 0.1016)
		(layer "In2.Cu")
		(net "PCIE_REFCLK_S3_N")
	)
	(arc
		(start 235.670598 -35.99942)
		(mid 235.777738 -35.92805)
		(end 235.904024 -35.903154)
		(width 0.1016)
		(layer "In2.Cu")
		(net "PCIE_REFCLK_S3_N")
	)
	(arc
		(start 236.464094 -35.714178)
		(mid 236.486077 -35.681184)
		(end 236.493812 -35.642296)
		(width 0.1016)
		(layer "In2.Cu")
		(net "PCIE_REFCLK_S3_N")
	)
	(arc
		(start 238.04118 -33.844738)
		(mid 238.084786 -33.779478)
		(end 238.100108 -33.702498)
		(width 0.1016)
		(layer "In2.Cu")
		(net "PCIE_REFCLK_S3_N")
	)
	(arc
		(start 237.899194 -33.903666)
		(mid 237.914356 -33.902976)
		(end 237.92942 -33.901126)
		(width 0.1016)
		(layer "In2.Cu")
		(net "PCIE_REFCLK_S3_N")
	)
	(arc
		(start 50.38598 -206.41691)
		(mid 50.459451 -206.047544)
		(end 50.668682 -205.734412)
		(width 0.1397)
		(layer "In2.Cu")
		(net "PCIE_REFCLK_S3_N")
	)
	(arc
		(start 235.493814 -36.313364)
		(mid 235.518797 -36.187114)
		(end 235.59008 -36.079938)
		(width 0.1016)
		(layer "In2.Cu")
		(net "PCIE_REFCLK_S3_N")
	)
	(arc
		(start 237.929928 -33.901126)
		(mid 237.989895 -33.881891)
		(end 238.040926 -33.844992)
		(width 0.1016)
		(layer "In2.Cu")
		(net "PCIE_REFCLK_S3_N")
	)
	(segment
		(start 237.599982 -34.99993)
		(end 237.10011 -34.500058)
		(width 0.136652)
		(layer "F.Cu")
		(net "PCIE_REFCLK_S2_P")
	)
	(via
		(at 94.20225 -183.642)
		(size 0.508)
		(drill 0.254)
		(layers "F.Cu" "B.Cu")
		(net "PCIE_REFCLK_S2_P")
	)
	(via
		(at 237.10011 -34.500058)
		(size 0.4572)
		(drill 0.2032)
		(layers "F.Cu" "B.Cu")
		(net "PCIE_REFCLK_S2_P")
	)
	(segment
		(start 108.06049 -203.59624)
		(end 107.825286 -203.260452)
		(width 0.136652)
		(layer "B.Cu")
		(net "PCIE_REFCLK_S2_P")
	)
	(segment
		(start 110.65256 -224.62998)
		(end 110.65256 -220.666818)
		(width 0.136652)
		(layer "B.Cu")
		(net "PCIE_REFCLK_S2_P")
	)
	(segment
		(start 111.127032 -218.980004)
		(end 111.126778 -218.97975)
		(width 0.136652)
		(layer "B.Cu")
		(net "PCIE_REFCLK_S2_P")
	)
	(segment
		(start 93.9038 -185.244994)
		(end 93.9038 -184.474358)
		(width 0.136652)
		(layer "B.Cu")
		(net "PCIE_REFCLK_S2_P")
	)
	(segment
		(start 111.126778 -211.63153)
		(end 110.333282 -207.131158)
		(width 0.136652)
		(layer "B.Cu")
		(net "PCIE_REFCLK_S2_P")
	)
	(segment
		(start 108.019596 -203.826872)
		(end 108.06049 -203.59624)
		(width 0.136652)
		(layer "B.Cu")
		(net "PCIE_REFCLK_S2_P")
	)
	(segment
		(start 108.2548 -204.16266)
		(end 108.019596 -203.826872)
		(width 0.136652)
		(layer "B.Cu")
		(net "PCIE_REFCLK_S2_P")
	)
	(segment
		(start 94.463108 -188.416438)
		(end 93.9038 -185.244994)
		(width 0.136652)
		(layer "B.Cu")
		(net "PCIE_REFCLK_S2_P")
	)
	(segment
		(start 108.679742 -204.769466)
		(end 108.720636 -204.539088)
		(width 0.136652)
		(layer "B.Cu")
		(net "PCIE_REFCLK_S2_P")
	)
	(segment
		(start 107.35945 -202.884024)
		(end 107.40009 -202.653392)
		(width 0.136652)
		(layer "B.Cu")
		(net "PCIE_REFCLK_S2_P")
	)
	(segment
		(start 102.143052 -195.43395)
		(end 96.715834 -191.633602)
		(width 0.136652)
		(layer "B.Cu")
		(net "PCIE_REFCLK_S2_P")
	)
	(segment
		(start 110.689644 -220.577156)
		(end 111.089948 -220.176852)
		(width 0.136652)
		(layer "B.Cu")
		(net "PCIE_REFCLK_S2_P")
	)
	(segment
		(start 107.16514 -202.317604)
		(end 106.934508 -202.276964)
		(width 0.136652)
		(layer "B.Cu")
		(net "PCIE_REFCLK_S2_P")
	)
	(segment
		(start 107.594654 -203.219812)
		(end 107.35945 -202.884024)
		(width 0.136652)
		(layer "B.Cu")
		(net "PCIE_REFCLK_S2_P")
	)
	(segment
		(start 93.9038 -184.46877)
		(end 93.9038 -184.362598)
		(width 0.136652)
		(layer "B.Cu")
		(net "PCIE_REFCLK_S2_P")
	)
	(segment
		(start 106.934508 -202.276964)
		(end 102.143052 -195.43395)
		(width 0.136652)
		(layer "B.Cu")
		(net "PCIE_REFCLK_S2_P")
	)
	(segment
		(start 111.126778 -218.97975)
		(end 111.126778 -211.63153)
		(width 0.136652)
		(layer "B.Cu")
		(net "PCIE_REFCLK_S2_P")
	)
	(segment
		(start 108.720636 -204.539088)
		(end 108.485432 -204.2033)
		(width 0.136652)
		(layer "B.Cu")
		(net "PCIE_REFCLK_S2_P")
	)
	(segment
		(start 111.127032 -220.08719)
		(end 111.127032 -218.980004)
		(width 0.136652)
		(layer "B.Cu")
		(net "PCIE_REFCLK_S2_P")
	)
	(segment
		(start 108.485432 -204.2033)
		(end 108.2548 -204.16266)
		(width 0.136652)
		(layer "B.Cu")
		(net "PCIE_REFCLK_S2_P")
	)
	(segment
		(start 107.40009 -202.653392)
		(end 107.16514 -202.317604)
		(width 0.136652)
		(layer "B.Cu")
		(net "PCIE_REFCLK_S2_P")
	)
	(segment
		(start 107.825286 -203.260452)
		(end 107.594654 -203.219812)
		(width 0.136652)
		(layer "B.Cu")
		(net "PCIE_REFCLK_S2_P")
	)
	(segment
		(start 110.333282 -207.131158)
		(end 108.679742 -204.769466)
		(width 0.136652)
		(layer "B.Cu")
		(net "PCIE_REFCLK_S2_P")
	)
	(segment
		(start 110.899956 -225.92538)
		(end 110.899956 -225.227388)
		(width 0.136652)
		(layer "B.Cu")
		(net "PCIE_REFCLK_S2_P")
	)
	(segment
		(start 96.715834 -191.633602)
		(end 94.463108 -188.416438)
		(width 0.136652)
		(layer "B.Cu")
		(net "PCIE_REFCLK_S2_P")
	)
	(arc
		(start 111.089948 -220.176852)
		(mid 111.117381 -220.135701)
		(end 111.127032 -220.08719)
		(width 0.136652)
		(layer "B.Cu")
		(net "PCIE_REFCLK_S2_P")
	)
	(arc
		(start 93.9038 -184.362598)
		(mid 93.98137 -183.972625)
		(end 94.20225 -183.642)
		(width 0.136652)
		(layer "B.Cu")
		(net "PCIE_REFCLK_S2_P")
	)
	(arc
		(start 110.899956 -225.227388)
		(mid 110.855718 -225.004991)
		(end 110.729776 -224.816416)
		(width 0.136652)
		(layer "B.Cu")
		(net "PCIE_REFCLK_S2_P")
	)
	(arc
		(start 110.729776 -224.816416)
		(mid 110.672622 -224.730878)
		(end 110.65256 -224.62998)
		(width 0.136652)
		(layer "B.Cu")
		(net "PCIE_REFCLK_S2_P")
	)
	(arc
		(start 110.65256 -220.666818)
		(mid 110.662193 -220.6183)
		(end 110.689644 -220.577156)
		(width 0.136652)
		(layer "B.Cu")
		(net "PCIE_REFCLK_S2_P")
	)
	(arc
		(start 93.9038 -184.474358)
		(mid 93.903785 -184.471564)
		(end 93.9038 -184.46877)
		(width 0.136652)
		(layer "B.Cu")
		(net "PCIE_REFCLK_S2_P")
	)
	(segment
		(start 237.1344 -34.2392)
		(end 237.1344 -34.417254)
		(width 0.1016)
		(layer "In2.Cu")
		(net "PCIE_REFCLK_S2_P")
	)
	(segment
		(start 195.845684 -57.691782)
		(end 196.093842 -57.319418)
		(width 0.1397)
		(layer "In2.Cu")
		(net "PCIE_REFCLK_S2_P")
	)
	(segment
		(start 236.389926 -35.059874)
		(end 236.659928 -34.789872)
		(width 0.1016)
		(layer "In2.Cu")
		(net "PCIE_REFCLK_S2_P")
	)
	(segment
		(start 123.89739 -141.491208)
		(end 130.387598 -136.94664)
		(width 0.1397)
		(layer "In2.Cu")
		(net "PCIE_REFCLK_S2_P")
	)
	(segment
		(start 236.697012 -34.70021)
		(end 236.697012 -34.621978)
		(width 0.1016)
		(layer "In2.Cu")
		(net "PCIE_REFCLK_S2_P")
	)
	(segment
		(start 196.318124 -66.347848)
		(end 195.319142 -60.682632)
		(width 0.1397)
		(layer "In2.Cu")
		(net "PCIE_REFCLK_S2_P")
	)
	(segment
		(start 207.6958 -48.246538)
		(end 211.882228 -45.315124)
		(width 0.1397)
		(layer "In2.Cu")
		(net "PCIE_REFCLK_S2_P")
	)
	(segment
		(start 236.817662 -34.106866)
		(end 237.002066 -34.106866)
		(width 0.1016)
		(layer "In2.Cu")
		(net "PCIE_REFCLK_S2_P")
	)
	(segment
		(start 130.387598 -136.94664)
		(end 173.646338 -106.656886)
		(width 0.1397)
		(layer "In2.Cu")
		(net "PCIE_REFCLK_S2_P")
	)
	(segment
		(start 218.516962 -44.1452)
		(end 223.0882 -44.1452)
		(width 0.1397)
		(layer "In2.Cu")
		(net "PCIE_REFCLK_S2_P")
	)
	(segment
		(start 236.697266 -34.621724)
		(end 236.697266 -34.227008)
		(width 0.1016)
		(layer "In2.Cu")
		(net "PCIE_REFCLK_S2_P")
	)
	(segment
		(start 93.960696 -183.0324)
		(end 93.96095 -183.0324)
		(width 0.1397)
		(layer "In2.Cu")
		(net "PCIE_REFCLK_S2_P")
	)
	(segment
		(start 234.88142 -35.096958)
		(end 236.300264 -35.096958)
		(width 0.1016)
		(layer "In2.Cu")
		(net "PCIE_REFCLK_S2_P")
	)
	(segment
		(start 194.4497 -76.946252)
		(end 196.318124 -66.347848)
		(width 0.1397)
		(layer "In2.Cu")
		(net "PCIE_REFCLK_S2_P")
	)
	(segment
		(start 96.627188 -178.982624)
		(end 98.624898 -177.5841)
		(width 0.1397)
		(layer "In2.Cu")
		(net "PCIE_REFCLK_S2_P")
	)
	(segment
		(start 93.960696 -183.058816)
		(end 93.960696 -183.0324)
		(width 0.1397)
		(layer "In2.Cu")
		(net "PCIE_REFCLK_S2_P")
	)
	(segment
		(start 234.706414 -43.752008)
		(end 234.706414 -35.271964)
		(width 0.1016)
		(layer "In2.Cu")
		(net "PCIE_REFCLK_S2_P")
	)
	(segment
		(start 117.595904 -150.490936)
		(end 117.595904 -150.490682)
		(width 0.1397)
		(layer "In2.Cu")
		(net "PCIE_REFCLK_S2_P")
	)
	(segment
		(start 196.76237 -56.365648)
		(end 200.848976 -53.504084)
		(width 0.1397)
		(layer "In2.Cu")
		(net "PCIE_REFCLK_S2_P")
	)
	(segment
		(start 117.595904 -150.490682)
		(end 120.74652 -145.991072)
		(width 0.1397)
		(layer "In2.Cu")
		(net "PCIE_REFCLK_S2_P")
	)
	(segment
		(start 93.96095 -182.790084)
		(end 96.627188 -178.982624)
		(width 0.1397)
		(layer "In2.Cu")
		(net "PCIE_REFCLK_S2_P")
	)
	(segment
		(start 93.96095 -183.0324)
		(end 93.96095 -182.790084)
		(width 0.1397)
		(layer "In2.Cu")
		(net "PCIE_REFCLK_S2_P")
	)
	(segment
		(start 205.0542 -52.0192)
		(end 207.6958 -48.246538)
		(width 0.1397)
		(layer "In2.Cu")
		(net "PCIE_REFCLK_S2_P")
	)
	(segment
		(start 211.882228 -45.315124)
		(end 218.516962 -44.1452)
		(width 0.1397)
		(layer "In2.Cu")
		(net "PCIE_REFCLK_S2_P")
	)
	(segment
		(start 98.624898 -177.5841)
		(end 117.595904 -150.490936)
		(width 0.1397)
		(layer "In2.Cu")
		(net "PCIE_REFCLK_S2_P")
	)
	(segment
		(start 196.093842 -57.319418)
		(end 196.76237 -56.365648)
		(width 0.1397)
		(layer "In2.Cu")
		(net "PCIE_REFCLK_S2_P")
	)
	(segment
		(start 200.848976 -53.504084)
		(end 203.635102 -53.012848)
		(width 0.1397)
		(layer "In2.Cu")
		(net "PCIE_REFCLK_S2_P")
	)
	(segment
		(start 234.58551 -44.010072)
		(end 234.610148 -43.985434)
		(width 0.1016)
		(layer "In2.Cu")
		(net "PCIE_REFCLK_S2_P")
	)
	(segment
		(start 203.635102 -53.012848)
		(end 205.0542 -52.0192)
		(width 0.1397)
		(layer "In2.Cu")
		(net "PCIE_REFCLK_S2_P")
	)
	(segment
		(start 236.697012 -34.621978)
		(end 236.697266 -34.621724)
		(width 0.1016)
		(layer "In2.Cu")
		(net "PCIE_REFCLK_S2_P")
	)
	(segment
		(start 120.74652 -145.991072)
		(end 123.89739 -141.491208)
		(width 0.1397)
		(layer "In2.Cu")
		(net "PCIE_REFCLK_S2_P")
	)
	(segment
		(start 223.125792 -44.106338)
		(end 234.352084 -44.106338)
		(width 0.1016)
		(layer "In2.Cu")
		(net "PCIE_REFCLK_S2_P")
	)
	(segment
		(start 223.0882 -44.1452)
		(end 223.125792 -44.1452)
		(width 0.1016)
		(layer "In2.Cu")
		(net "PCIE_REFCLK_S2_P")
	)
	(segment
		(start 173.646338 -106.656886)
		(end 194.4497 -76.946252)
		(width 0.1397)
		(layer "In2.Cu")
		(net "PCIE_REFCLK_S2_P")
	)
	(segment
		(start 234.743498 -35.182302)
		(end 234.791758 -35.134042)
		(width 0.1016)
		(layer "In2.Cu")
		(net "PCIE_REFCLK_S2_P")
	)
	(segment
		(start 195.319142 -60.682632)
		(end 195.845684 -57.691782)
		(width 0.1397)
		(layer "In2.Cu")
		(net "PCIE_REFCLK_S2_P")
	)
	(segment
		(start 223.125792 -44.1452)
		(end 223.125792 -44.106338)
		(width 0.1016)
		(layer "In2.Cu")
		(net "PCIE_REFCLK_S2_P")
	)
	(arc
		(start 236.697266 -34.227008)
		(mid 236.706377 -34.181115)
		(end 236.732318 -34.142172)
		(width 0.1016)
		(layer "In2.Cu")
		(net "PCIE_REFCLK_S2_P")
	)
	(arc
		(start 234.706414 -35.271964)
		(mid 234.716047 -35.223446)
		(end 234.743498 -35.182302)
		(width 0.1016)
		(layer "In2.Cu")
		(net "PCIE_REFCLK_S2_P")
	)
	(arc
		(start 236.732318 -34.142172)
		(mid 236.771488 -34.116062)
		(end 236.817662 -34.106866)
		(width 0.1016)
		(layer "In2.Cu")
		(net "PCIE_REFCLK_S2_P")
	)
	(arc
		(start 234.791758 -35.134042)
		(mid 234.832909 -35.106609)
		(end 234.88142 -35.096958)
		(width 0.1016)
		(layer "In2.Cu")
		(net "PCIE_REFCLK_S2_P")
	)
	(arc
		(start 94.20225 -183.642)
		(mid 94.023467 -183.374433)
		(end 93.960696 -183.058816)
		(width 0.1397)
		(layer "In2.Cu")
		(net "PCIE_REFCLK_S2_P")
	)
	(arc
		(start 236.659928 -34.789872)
		(mid 236.687361 -34.748721)
		(end 236.697012 -34.70021)
		(width 0.1016)
		(layer "In2.Cu")
		(net "PCIE_REFCLK_S2_P")
	)
	(arc
		(start 237.1344 -34.417254)
		(mid 237.125487 -34.462064)
		(end 237.10011 -34.500058)
		(width 0.1016)
		(layer "In2.Cu")
		(net "PCIE_REFCLK_S2_P")
	)
	(arc
		(start 234.610148 -43.985434)
		(mid 234.681518 -43.878294)
		(end 234.706414 -43.752008)
		(width 0.1016)
		(layer "In2.Cu")
		(net "PCIE_REFCLK_S2_P")
	)
	(arc
		(start 234.352084 -44.106338)
		(mid 234.478334 -44.081355)
		(end 234.58551 -44.010072)
		(width 0.1016)
		(layer "In2.Cu")
		(net "PCIE_REFCLK_S2_P")
	)
	(arc
		(start 237.002066 -34.106866)
		(mid 237.09564 -34.145626)
		(end 237.1344 -34.2392)
		(width 0.1016)
		(layer "In2.Cu")
		(net "PCIE_REFCLK_S2_P")
	)
	(arc
		(start 236.300264 -35.096958)
		(mid 236.348782 -35.087325)
		(end 236.389926 -35.059874)
		(width 0.1016)
		(layer "In2.Cu")
		(net "PCIE_REFCLK_S2_P")
	)
	(segment
		(start 237.599982 -33.999932)
		(end 237.10011 -33.50006)
		(width 0.136652)
		(layer "F.Cu")
		(net "PCIE_REFCLK_S2_N")
	)
	(via
		(at 237.10011 -33.50006)
		(size 0.4572)
		(drill 0.2032)
		(layers "F.Cu" "B.Cu")
		(net "PCIE_REFCLK_S2_N")
	)
	(via
		(at 93.38945 -183.642)
		(size 0.508)
		(drill 0.254)
		(layers "F.Cu" "B.Cu")
		(net "PCIE_REFCLK_S2_N")
	)
	(segment
		(start 110.821978 -219.106242)
		(end 110.822232 -219.106496)
		(width 0.136652)
		(layer "B.Cu")
		(net "PCIE_REFCLK_S2_N")
	)
	(segment
		(start 110.822232 -219.106496)
		(end 110.822232 -219.956634)
		(width 0.136652)
		(layer "B.Cu")
		(net "PCIE_REFCLK_S2_N")
	)
	(segment
		(start 110.290864 -224.782126)
		(end 110.240064 -224.832926)
		(width 0.136652)
		(layer "B.Cu")
		(net "PCIE_REFCLK_S2_N")
	)
	(segment
		(start 110.821978 -211.6582)
		(end 110.821978 -219.106242)
		(width 0.136652)
		(layer "B.Cu")
		(net "PCIE_REFCLK_S2_N")
	)
	(segment
		(start 110.044738 -207.250538)
		(end 110.821978 -211.6582)
		(width 0.136652)
		(layer "B.Cu")
		(net "PCIE_REFCLK_S2_N")
	)
	(segment
		(start 110.34776 -220.666818)
		(end 110.34776 -223.8121)
		(width 0.136652)
		(layer "B.Cu")
		(net "PCIE_REFCLK_S2_N")
	)
	(segment
		(start 93.599 -184.147968)
		(end 93.599 -185.271664)
		(width 0.136652)
		(layer "B.Cu")
		(net "PCIE_REFCLK_S2_N")
	)
	(segment
		(start 110.7821 -220.053408)
		(end 110.473744 -220.36151)
		(width 0.136652)
		(layer "B.Cu")
		(net "PCIE_REFCLK_S2_N")
	)
	(segment
		(start 110.34776 -223.8121)
		(end 110.347506 -224.0534)
		(width 0.136652)
		(layer "B.Cu")
		(net "PCIE_REFCLK_S2_N")
	)
	(segment
		(start 110.34776 -224.053654)
		(end 110.34776 -224.644712)
		(width 0.136652)
		(layer "B.Cu")
		(net "PCIE_REFCLK_S2_N")
	)
	(segment
		(start 96.496886 -191.85255)
		(end 101.924104 -195.652898)
		(width 0.136652)
		(layer "B.Cu")
		(net "PCIE_REFCLK_S2_N")
	)
	(segment
		(start 110.347506 -224.0534)
		(end 110.34776 -224.053654)
		(width 0.136652)
		(layer "B.Cu")
		(net "PCIE_REFCLK_S2_N")
	)
	(segment
		(start 110.10011 -225.170746)
		(end 110.10011 -225.92538)
		(width 0.136652)
		(layer "B.Cu")
		(net "PCIE_REFCLK_S2_N")
	)
	(segment
		(start 94.174564 -188.535818)
		(end 96.496886 -191.85255)
		(width 0.136652)
		(layer "B.Cu")
		(net "PCIE_REFCLK_S2_N")
	)
	(segment
		(start 101.924104 -195.652898)
		(end 110.044738 -207.250538)
		(width 0.136652)
		(layer "B.Cu")
		(net "PCIE_REFCLK_S2_N")
	)
	(segment
		(start 93.599 -185.271664)
		(end 94.174564 -188.535818)
		(width 0.136652)
		(layer "B.Cu")
		(net "PCIE_REFCLK_S2_N")
	)
	(arc
		(start 110.34776 -224.644712)
		(mid 110.332969 -224.719071)
		(end 110.290864 -224.782126)
		(width 0.136652)
		(layer "B.Cu")
		(net "PCIE_REFCLK_S2_N")
	)
	(arc
		(start 110.473744 -220.36151)
		(mid 110.380421 -220.501645)
		(end 110.34776 -220.666818)
		(width 0.136652)
		(layer "B.Cu")
		(net "PCIE_REFCLK_S2_N")
	)
	(arc
		(start 93.38945 -183.642)
		(mid 93.544561 -183.87414)
		(end 93.599 -184.147968)
		(width 0.136652)
		(layer "B.Cu")
		(net "PCIE_REFCLK_S2_N")
	)
	(arc
		(start 110.822232 -219.956634)
		(mid 110.811796 -220.009011)
		(end 110.7821 -220.053408)
		(width 0.136652)
		(layer "B.Cu")
		(net "PCIE_REFCLK_S2_N")
	)
	(arc
		(start 110.240064 -224.832926)
		(mid 110.136501 -224.987919)
		(end 110.10011 -225.170746)
		(width 0.136652)
		(layer "B.Cu")
		(net "PCIE_REFCLK_S2_N")
	)
	(segment
		(start 195.98259 -66.347848)
		(end 194.137026 -76.816712)
		(width 0.1397)
		(layer "In2.Cu")
		(net "PCIE_REFCLK_S2_N")
	)
	(segment
		(start 207.425036 -48.057054)
		(end 207.42529 -48.057054)
		(width 0.1397)
		(layer "In2.Cu")
		(net "PCIE_REFCLK_S2_N")
	)
	(segment
		(start 96.389952 -178.745388)
		(end 93.63075 -182.685944)
		(width 0.1397)
		(layer "In2.Cu")
		(net "PCIE_REFCLK_S2_N")
	)
	(segment
		(start 200.719436 -53.19141)
		(end 196.525388 -56.128412)
		(width 0.1397)
		(layer "In2.Cu")
		(net "PCIE_REFCLK_S2_N")
	)
	(segment
		(start 203.505562 -52.700174)
		(end 200.719436 -53.19141)
		(width 0.1397)
		(layer "In2.Cu")
		(net "PCIE_REFCLK_S2_N")
	)
	(segment
		(start 236.899196 -33.903666)
		(end 236.816138 -33.903666)
		(width 0.1016)
		(layer "In2.Cu")
		(net "PCIE_REFCLK_S2_N")
	)
	(segment
		(start 237.041182 -33.844738)
		(end 237.040928 -33.844992)
		(width 0.1016)
		(layer "In2.Cu")
		(net "PCIE_REFCLK_S2_N")
	)
	(segment
		(start 207.42529 -48.057054)
		(end 204.816964 -51.781964)
		(width 0.1397)
		(layer "In2.Cu")
		(net "PCIE_REFCLK_S2_N")
	)
	(segment
		(start 194.983608 -60.682632)
		(end 195.98259 -66.347848)
		(width 0.1397)
		(layer "In2.Cu")
		(net "PCIE_REFCLK_S2_N")
	)
	(segment
		(start 111.024416 -159.300164)
		(end 98.387662 -177.34661)
		(width 0.1397)
		(layer "In2.Cu")
		(net "PCIE_REFCLK_S2_N")
	)
	(segment
		(start 123.660154 -141.253972)
		(end 111.024416 -159.300164)
		(width 0.1397)
		(layer "In2.Cu")
		(net "PCIE_REFCLK_S2_N")
	)
	(segment
		(start 236.494066 -34.227008)
		(end 236.493812 -34.227262)
		(width 0.1016)
		(layer "In2.Cu")
		(net "PCIE_REFCLK_S2_N")
	)
	(segment
		(start 234.46613 -43.84167)
		(end 234.441746 -43.866054)
		(width 0.1016)
		(layer "In2.Cu")
		(net "PCIE_REFCLK_S2_N")
	)
	(segment
		(start 173.409102 -106.41965)
		(end 123.660154 -141.253972)
		(width 0.1397)
		(layer "In2.Cu")
		(net "PCIE_REFCLK_S2_N")
	)
	(segment
		(start 194.137026 -76.816712)
		(end 173.409102 -106.41965)
		(width 0.1397)
		(layer "In2.Cu")
		(net "PCIE_REFCLK_S2_N")
	)
	(segment
		(start 223.0882 -43.815)
		(end 218.48699 -43.815)
		(width 0.1397)
		(layer "In2.Cu")
		(net "PCIE_REFCLK_S2_N")
	)
	(segment
		(start 218.48699 -43.815)
		(end 211.752688 -45.00245)
		(width 0.1397)
		(layer "In2.Cu")
		(net "PCIE_REFCLK_S2_N")
	)
	(segment
		(start 204.816964 -51.781964)
		(end 203.505562 -52.700174)
		(width 0.1397)
		(layer "In2.Cu")
		(net "PCIE_REFCLK_S2_N")
	)
	(segment
		(start 234.503214 -35.271964)
		(end 234.503214 -43.752008)
		(width 0.1016)
		(layer "In2.Cu")
		(net "PCIE_REFCLK_S2_N")
	)
	(segment
		(start 237.10011 -33.50006)
		(end 237.10011 -33.702498)
		(width 0.1016)
		(layer "In2.Cu")
		(net "PCIE_REFCLK_S2_N")
	)
	(segment
		(start 234.352084 -43.903138)
		(end 223.228916 -43.903138)
		(width 0.1016)
		(layer "In2.Cu")
		(net "PCIE_REFCLK_S2_N")
	)
	(segment
		(start 93.63075 -182.685944)
		(end 93.63075 -183.059324)
		(width 0.1397)
		(layer "In2.Cu")
		(net "PCIE_REFCLK_S2_N")
	)
	(segment
		(start 195.532248 -57.566306)
		(end 194.983608 -60.682632)
		(width 0.1397)
		(layer "In2.Cu")
		(net "PCIE_REFCLK_S2_N")
	)
	(segment
		(start 236.493812 -34.66846)
		(end 236.268514 -34.893758)
		(width 0.1016)
		(layer "In2.Cu")
		(net "PCIE_REFCLK_S2_N")
	)
	(segment
		(start 207.458564 -48.009302)
		(end 207.425036 -48.057054)
		(width 0.1397)
		(layer "In2.Cu")
		(net "PCIE_REFCLK_S2_N")
	)
	(segment
		(start 211.752688 -45.00245)
		(end 207.458564 -48.009302)
		(width 0.1397)
		(layer "In2.Cu")
		(net "PCIE_REFCLK_S2_N")
	)
	(segment
		(start 236.589062 -33.997646)
		(end 236.587792 -33.998916)
		(width 0.1016)
		(layer "In2.Cu")
		(net "PCIE_REFCLK_S2_N")
	)
	(segment
		(start 236.268514 -34.893758)
		(end 234.88142 -34.893758)
		(width 0.1016)
		(layer "In2.Cu")
		(net "PCIE_REFCLK_S2_N")
	)
	(segment
		(start 236.589316 -33.997646)
		(end 236.589062 -33.997646)
		(width 0.1016)
		(layer "In2.Cu")
		(net "PCIE_REFCLK_S2_N")
	)
	(segment
		(start 98.387662 -177.34661)
		(end 96.389952 -178.745388)
		(width 0.1397)
		(layer "In2.Cu")
		(net "PCIE_REFCLK_S2_N")
	)
	(segment
		(start 223.139254 -43.866054)
		(end 223.0882 -43.815)
		(width 0.1016)
		(layer "In2.Cu")
		(net "PCIE_REFCLK_S2_N")
	)
	(segment
		(start 234.647994 -34.990024)
		(end 234.59948 -35.038538)
		(width 0.1016)
		(layer "In2.Cu")
		(net "PCIE_REFCLK_S2_N")
	)
	(segment
		(start 195.821046 -57.132982)
		(end 195.532248 -57.566306)
		(width 0.1397)
		(layer "In2.Cu")
		(net "PCIE_REFCLK_S2_N")
	)
	(segment
		(start 236.493812 -34.227262)
		(end 236.493812 -34.66846)
		(width 0.1016)
		(layer "In2.Cu")
		(net "PCIE_REFCLK_S2_N")
	)
	(segment
		(start 196.525388 -56.128412)
		(end 195.821046 -57.132982)
		(width 0.1397)
		(layer "In2.Cu")
		(net "PCIE_REFCLK_S2_N")
	)
	(arc
		(start 234.88142 -34.893758)
		(mid 234.75517 -34.918741)
		(end 234.647994 -34.990024)
		(width 0.1016)
		(layer "In2.Cu")
		(net "PCIE_REFCLK_S2_N")
	)
	(arc
		(start 234.503214 -43.752008)
		(mid 234.493581 -43.800526)
		(end 234.46613 -43.84167)
		(width 0.1016)
		(layer "In2.Cu")
		(net "PCIE_REFCLK_S2_N")
	)
	(arc
		(start 234.441746 -43.866054)
		(mid 234.400595 -43.893487)
		(end 234.352084 -43.903138)
		(width 0.1016)
		(layer "In2.Cu")
		(net "PCIE_REFCLK_S2_N")
	)
	(arc
		(start 236.587792 -33.998916)
		(mid 236.518324 -34.103679)
		(end 236.494066 -34.227008)
		(width 0.1016)
		(layer "In2.Cu")
		(net "PCIE_REFCLK_S2_N")
	)
	(arc
		(start 236.816138 -33.903666)
		(mid 236.693372 -33.928086)
		(end 236.589316 -33.997646)
		(width 0.1016)
		(layer "In2.Cu")
		(net "PCIE_REFCLK_S2_N")
	)
	(arc
		(start 93.63075 -183.059324)
		(mid 93.568029 -183.374646)
		(end 93.38945 -183.642)
		(width 0.1397)
		(layer "In2.Cu")
		(net "PCIE_REFCLK_S2_N")
	)
	(arc
		(start 223.228916 -43.903138)
		(mid 223.180398 -43.893505)
		(end 223.139254 -43.866054)
		(width 0.1016)
		(layer "In2.Cu")
		(net "PCIE_REFCLK_S2_N")
	)
	(arc
		(start 237.040928 -33.844992)
		(mid 236.99299 -33.880281)
		(end 236.936788 -33.899856)
		(width 0.1016)
		(layer "In2.Cu")
		(net "PCIE_REFCLK_S2_N")
	)
	(arc
		(start 236.936788 -33.899856)
		(mid 236.918082 -33.902644)
		(end 236.899196 -33.903666)
		(width 0.1016)
		(layer "In2.Cu")
		(net "PCIE_REFCLK_S2_N")
	)
	(arc
		(start 237.10011 -33.702498)
		(mid 237.084797 -33.779482)
		(end 237.041182 -33.844738)
		(width 0.1016)
		(layer "In2.Cu")
		(net "PCIE_REFCLK_S2_N")
	)
	(arc
		(start 234.59948 -35.038538)
		(mid 234.52811 -35.145678)
		(end 234.503214 -35.271964)
		(width 0.1016)
		(layer "In2.Cu")
		(net "PCIE_REFCLK_S2_N")
	)
	(segment
		(start 110.34776 -221.8182)
		(end 110.34776 -211.011262)
		(width 0.136652)
		(layer "F.Cu")
		(net "PCIE_REFCLK_S1_P")
	)
	(segment
		(start 110.347506 -224.131378)
		(end 110.347506 -221.818454)
		(width 0.136652)
		(layer "F.Cu")
		(net "PCIE_REFCLK_S1_P")
	)
	(segment
		(start 110.099856 -225.5266)
		(end 110.099856 -224.828608)
		(width 0.136652)
		(layer "F.Cu")
		(net "PCIE_REFCLK_S1_P")
	)
	(segment
		(start 91.799156 -185.872628)
		(end 91.90863 -185.763154)
		(width 0.136652)
		(layer "F.Cu")
		(net "PCIE_REFCLK_S1_P")
	)
	(segment
		(start 109.888528 -209.554318)
		(end 103.919782 -201.030332)
		(width 0.136652)
		(layer "F.Cu")
		(net "PCIE_REFCLK_S1_P")
	)
	(segment
		(start 110.10011 -225.526854)
		(end 110.099856 -225.5266)
		(width 0.136652)
		(layer "F.Cu")
		(net "PCIE_REFCLK_S1_P")
	)
	(segment
		(start 110.347506 -221.818454)
		(end 110.34776 -221.8182)
		(width 0.136652)
		(layer "F.Cu")
		(net "PCIE_REFCLK_S1_P")
	)
	(segment
		(start 91.971114 -185.612278)
		(end 91.971114 -185.302652)
		(width 0.136652)
		(layer "F.Cu")
		(net "PCIE_REFCLK_S1_P")
	)
	(segment
		(start 91.669616 -186.696096)
		(end 91.669616 -186.185048)
		(width 0.136652)
		(layer "F.Cu")
		(net "PCIE_REFCLK_S1_P")
	)
	(segment
		(start 103.919782 -201.030332)
		(end 95.969074 -195.46316)
		(width 0.136652)
		(layer "F.Cu")
		(net "PCIE_REFCLK_S1_P")
	)
	(segment
		(start 110.099856 -224.828608)
		(end 110.10011 -224.828354)
		(width 0.136652)
		(layer "F.Cu")
		(net "PCIE_REFCLK_S1_P")
	)
	(segment
		(start 239.599978 -34.99993)
		(end 239.100106 -34.500058)
		(width 0.136652)
		(layer "F.Cu")
		(net "PCIE_REFCLK_S1_P")
	)
	(segment
		(start 110.10011 -225.54438)
		(end 110.10011 -225.526854)
		(width 0.136652)
		(layer "F.Cu")
		(net "PCIE_REFCLK_S1_P")
	)
	(segment
		(start 92.288868 -190.207392)
		(end 91.669616 -186.696096)
		(width 0.136652)
		(layer "F.Cu")
		(net "PCIE_REFCLK_S1_P")
	)
	(segment
		(start 95.969074 -195.46316)
		(end 92.288868 -190.207392)
		(width 0.136652)
		(layer "F.Cu")
		(net "PCIE_REFCLK_S1_P")
	)
	(via
		(at 91.971114 -185.302652)
		(size 0.508)
		(drill 0.254)
		(layers "F.Cu" "B.Cu")
		(net "PCIE_REFCLK_S1_P")
	)
	(via
		(at 239.100106 -34.500058)
		(size 0.4572)
		(drill 0.2032)
		(layers "F.Cu" "B.Cu")
		(net "PCIE_REFCLK_S1_P")
	)
	(arc
		(start 110.10011 -224.828354)
		(mid 110.143249 -224.561886)
		(end 110.268258 -224.32264)
		(width 0.136652)
		(layer "F.Cu")
		(net "PCIE_REFCLK_S1_P")
	)
	(arc
		(start 110.268258 -224.32264)
		(mid 110.326892 -224.234888)
		(end 110.347506 -224.131378)
		(width 0.136652)
		(layer "F.Cu")
		(net "PCIE_REFCLK_S1_P")
	)
	(arc
		(start 91.669616 -186.185048)
		(mid 91.703341 -186.015971)
		(end 91.799156 -185.872628)
		(width 0.136652)
		(layer "F.Cu")
		(net "PCIE_REFCLK_S1_P")
	)
	(arc
		(start 110.34776 -211.011262)
		(mid 110.230274 -210.247446)
		(end 109.888528 -209.554318)
		(width 0.136652)
		(layer "F.Cu")
		(net "PCIE_REFCLK_S1_P")
	)
	(arc
		(start 91.90863 -185.763154)
		(mid 91.954883 -185.693932)
		(end 91.971114 -185.612278)
		(width 0.136652)
		(layer "F.Cu")
		(net "PCIE_REFCLK_S1_P")
	)
	(segment
		(start 163.392612 -133.333998)
		(end 163.438586 -133.595872)
		(width 0.1397)
		(layer "In5.Cu")
		(net "PCIE_REFCLK_S1_P")
	)
	(segment
		(start 163.89477 -132.944616)
		(end 163.632896 -132.99059)
		(width 0.1397)
		(layer "In5.Cu")
		(net "PCIE_REFCLK_S1_P")
	)
	(segment
		(start 195.064634 -78.272386)
		(end 192.670938 -91.847162)
		(width 0.1397)
		(layer "In5.Cu")
		(net "PCIE_REFCLK_S1_P")
	)
	(segment
		(start 239.100106 -34.500058)
		(end 239.100106 -34.152332)
		(width 0.1016)
		(layer "In5.Cu")
		(net "PCIE_REFCLK_S1_P")
	)
	(segment
		(start 196.986144 -56.73471)
		(end 195.723256 -58.537094)
		(width 0.1397)
		(layer "In5.Cu")
		(net "PCIE_REFCLK_S1_P")
	)
	(segment
		(start 193.6877 -70.0786)
		(end 193.6877 -70.46468)
		(width 0.1397)
		(layer "In5.Cu")
		(net "PCIE_REFCLK_S1_P")
	)
	(segment
		(start 203.979272 -55.600854)
		(end 201.214228 -55.113174)
		(width 0.1397)
		(layer "In5.Cu")
		(net "PCIE_REFCLK_S1_P")
	)
	(segment
		(start 239.6998 -36.703)
		(end 239.6998 -36.7284)
		(width 0.1016)
		(layer "In5.Cu")
		(net "PCIE_REFCLK_S1_P")
	)
	(segment
		(start 92.199714 -185.302652)
		(end 91.971114 -185.302652)
		(width 0.1397)
		(layer "In5.Cu")
		(net "PCIE_REFCLK_S1_P")
	)
	(segment
		(start 222.6056 -44.9326)
		(end 220.321886 -44.9326)
		(width 0.1397)
		(layer "In5.Cu")
		(net "PCIE_REFCLK_S1_P")
	)
	(segment
		(start 239.662716 -47.281084)
		(end 239.533684 -47.410116)
		(width 0.1397)
		(layer "In5.Cu")
		(net "PCIE_REFCLK_S1_P")
	)
	(segment
		(start 225.112326 -47.09922)
		(end 223.28759 -45.274484)
		(width 0.1397)
		(layer "In5.Cu")
		(net "PCIE_REFCLK_S1_P")
	)
	(segment
		(start 163.438586 -133.595872)
		(end 157.919674 -141.477746)
		(width 0.1397)
		(layer "In5.Cu")
		(net "PCIE_REFCLK_S1_P")
	)
	(segment
		(start 216.30767 -45.638212)
		(end 210.210146 -49.680114)
		(width 0.1397)
		(layer "In5.Cu")
		(net "PCIE_REFCLK_S1_P")
	)
	(segment
		(start 223.197928 -45.2374)
		(end 222.9104 -45.2374)
		(width 0.1397)
		(layer "In5.Cu")
		(net "PCIE_REFCLK_S1_P")
	)
	(segment
		(start 195.723256 -58.537094)
		(end 193.6877 -70.0786)
		(width 0.1397)
		(layer "In5.Cu")
		(net "PCIE_REFCLK_S1_P")
	)
	(segment
		(start 95.5548 -184.5564)
		(end 93.304106 -184.5564)
		(width 0.1397)
		(layer "In5.Cu")
		(net "PCIE_REFCLK_S1_P")
	)
	(segment
		(start 239.444022 -47.4472)
		(end 225.952304 -47.4472)
		(width 0.1397)
		(layer "In5.Cu")
		(net "PCIE_REFCLK_S1_P")
	)
	(segment
		(start 219.74175 -45.512736)
		(end 216.30767 -45.638212)
		(width 0.1397)
		(layer "In5.Cu")
		(net "PCIE_REFCLK_S1_P")
	)
	(segment
		(start 206.895954 -54.413404)
		(end 205.61046 -55.313326)
		(width 0.1397)
		(layer "In5.Cu")
		(net "PCIE_REFCLK_S1_P")
	)
	(segment
		(start 92.84843 -184.744868)
		(end 92.354908 -185.23839)
		(width 0.1397)
		(layer "In5.Cu")
		(net "PCIE_REFCLK_S1_P")
	)
	(segment
		(start 239.73155 -36.67125)
		(end 239.6998 -36.703)
		(width 0.1016)
		(layer "In5.Cu")
		(net "PCIE_REFCLK_S1_P")
	)
	(segment
		(start 198.658734 -55.56377)
		(end 196.986144 -56.73471)
		(width 0.1397)
		(layer "In5.Cu")
		(net "PCIE_REFCLK_S1_P")
	)
	(segment
		(start 163.632896 -132.99059)
		(end 163.392612 -133.333998)
		(width 0.1397)
		(layer "In5.Cu")
		(net "PCIE_REFCLK_S1_P")
	)
	(segment
		(start 157.919674 -141.477746)
		(end 96.99371 -184.13857)
		(width 0.1397)
		(layer "In5.Cu")
		(net "PCIE_REFCLK_S1_P")
	)
	(segment
		(start 210.210146 -49.680114)
		(end 206.895954 -54.413404)
		(width 0.1397)
		(layer "In5.Cu")
		(net "PCIE_REFCLK_S1_P")
	)
	(segment
		(start 222.9104 -45.2374)
		(end 222.6056 -44.9326)
		(width 0.1397)
		(layer "In5.Cu")
		(net "PCIE_REFCLK_S1_P")
	)
	(segment
		(start 239.227106 -34.025332)
		(end 239.6363 -34.025332)
		(width 0.1016)
		(layer "In5.Cu")
		(net "PCIE_REFCLK_S1_P")
	)
	(segment
		(start 201.214228 -55.113174)
		(end 198.658734 -55.56377)
		(width 0.1397)
		(layer "In5.Cu")
		(net "PCIE_REFCLK_S1_P")
	)
	(segment
		(start 192.670684 -91.847416)
		(end 163.89477 -132.944616)
		(width 0.1397)
		(layer "In5.Cu")
		(net "PCIE_REFCLK_S1_P")
	)
	(segment
		(start 220.321886 -44.9326)
		(end 219.74175 -45.512736)
		(width 0.1397)
		(layer "In5.Cu")
		(net "PCIE_REFCLK_S1_P")
	)
	(segment
		(start 192.670938 -91.847162)
		(end 192.670684 -91.847416)
		(width 0.1397)
		(layer "In5.Cu")
		(net "PCIE_REFCLK_S1_P")
	)
	(segment
		(start 205.61046 -55.313326)
		(end 203.979272 -55.600854)
		(width 0.1397)
		(layer "In5.Cu")
		(net "PCIE_REFCLK_S1_P")
	)
	(segment
		(start 193.6877 -70.46468)
		(end 195.064634 -78.272386)
		(width 0.1397)
		(layer "In5.Cu")
		(net "PCIE_REFCLK_S1_P")
	)
	(segment
		(start 239.7633 -34.152332)
		(end 239.7633 -36.594542)
		(width 0.1016)
		(layer "In5.Cu")
		(net "PCIE_REFCLK_S1_P")
	)
	(segment
		(start 239.6998 -36.7284)
		(end 239.6998 -47.191422)
		(width 0.1397)
		(layer "In5.Cu")
		(net "PCIE_REFCLK_S1_P")
	)
	(arc
		(start 92.354908 -185.23839)
		(mid 92.283704 -185.285967)
		(end 92.199714 -185.302652)
		(width 0.1397)
		(layer "In5.Cu")
		(net "PCIE_REFCLK_S1_P")
	)
	(arc
		(start 96.99371 -184.13857)
		(mid 96.303973 -184.449828)
		(end 95.5548 -184.5564)
		(width 0.1397)
		(layer "In5.Cu")
		(net "PCIE_REFCLK_S1_P")
	)
	(arc
		(start 239.100106 -34.152332)
		(mid 239.137303 -34.062529)
		(end 239.227106 -34.025332)
		(width 0.1016)
		(layer "In5.Cu")
		(net "PCIE_REFCLK_S1_P")
	)
	(arc
		(start 225.952304 -47.4472)
		(mid 225.497692 -47.356772)
		(end 225.112326 -47.09922)
		(width 0.1397)
		(layer "In5.Cu")
		(net "PCIE_REFCLK_S1_P")
	)
	(arc
		(start 239.533684 -47.410116)
		(mid 239.492533 -47.437549)
		(end 239.444022 -47.4472)
		(width 0.1397)
		(layer "In5.Cu")
		(net "PCIE_REFCLK_S1_P")
	)
	(arc
		(start 239.6998 -47.191422)
		(mid 239.690167 -47.23994)
		(end 239.662716 -47.281084)
		(width 0.1397)
		(layer "In5.Cu")
		(net "PCIE_REFCLK_S1_P")
	)
	(arc
		(start 239.6363 -34.025332)
		(mid 239.726103 -34.062529)
		(end 239.7633 -34.152332)
		(width 0.1016)
		(layer "In5.Cu")
		(net "PCIE_REFCLK_S1_P")
	)
	(arc
		(start 239.7633 -36.594542)
		(mid 239.755044 -36.636047)
		(end 239.73155 -36.67125)
		(width 0.1016)
		(layer "In5.Cu")
		(net "PCIE_REFCLK_S1_P")
	)
	(arc
		(start 223.28759 -45.274484)
		(mid 223.246439 -45.247051)
		(end 223.197928 -45.2374)
		(width 0.1397)
		(layer "In5.Cu")
		(net "PCIE_REFCLK_S1_P")
	)
	(arc
		(start 93.304106 -184.5564)
		(mid 93.057535 -184.605335)
		(end 92.84843 -184.744868)
		(width 0.1397)
		(layer "In5.Cu")
		(net "PCIE_REFCLK_S1_P")
	)
	(segment
		(start 110.65256 -224.133664)
		(end 110.65256 -211.011008)
		(width 0.136652)
		(layer "F.Cu")
		(net "PCIE_REFCLK_S1_N")
	)
	(segment
		(start 92.014802 -186.088274)
		(end 92.124276 -185.9788)
		(width 0.136652)
		(layer "F.Cu")
		(net "PCIE_REFCLK_S1_N")
	)
	(segment
		(start 91.974416 -186.669172)
		(end 91.974416 -186.185302)
		(width 0.136652)
		(layer "F.Cu")
		(net "PCIE_REFCLK_S1_N")
	)
	(segment
		(start 239.599978 -33.999932)
		(end 239.100106 -33.50006)
		(width 0.136652)
		(layer "F.Cu")
		(net "PCIE_REFCLK_S1_N")
	)
	(segment
		(start 92.368878 -185.877454)
		(end 92.545916 -185.877454)
		(width 0.136652)
		(layer "F.Cu")
		(net "PCIE_REFCLK_S1_N")
	)
	(segment
		(start 96.188022 -195.244212)
		(end 92.577412 -190.088012)
		(width 0.136652)
		(layer "F.Cu")
		(net "PCIE_REFCLK_S1_N")
	)
	(segment
		(start 92.577412 -190.088012)
		(end 91.974416 -186.669172)
		(width 0.136652)
		(layer "F.Cu")
		(net "PCIE_REFCLK_S1_N")
	)
	(segment
		(start 110.13821 -209.379312)
		(end 104.13873 -200.811384)
		(width 0.136652)
		(layer "F.Cu")
		(net "PCIE_REFCLK_S1_N")
	)
	(segment
		(start 104.13873 -200.811384)
		(end 96.188022 -195.244212)
		(width 0.136652)
		(layer "F.Cu")
		(net "PCIE_REFCLK_S1_N")
	)
	(segment
		(start 110.899956 -225.54438)
		(end 110.899956 -224.828354)
		(width 0.136652)
		(layer "F.Cu")
		(net "PCIE_REFCLK_S1_N")
	)
	(via
		(at 239.100106 -33.50006)
		(size 0.4572)
		(drill 0.2032)
		(layers "F.Cu" "B.Cu")
		(net "PCIE_REFCLK_S1_N")
	)
	(via
		(at 92.545916 -185.877454)
		(size 0.508)
		(drill 0.254)
		(layers "F.Cu" "B.Cu")
		(net "PCIE_REFCLK_S1_N")
	)
	(arc
		(start 110.899956 -224.828354)
		(mid 110.856319 -224.560646)
		(end 110.73003 -224.320608)
		(width 0.136652)
		(layer "F.Cu")
		(net "PCIE_REFCLK_S1_N")
	)
	(arc
		(start 110.73003 -224.320608)
		(mid 110.67272 -224.234837)
		(end 110.65256 -224.133664)
		(width 0.136652)
		(layer "F.Cu")
		(net "PCIE_REFCLK_S1_N")
	)
	(arc
		(start 92.124276 -185.9788)
		(mid 92.2365 -185.903814)
		(end 92.368878 -185.877454)
		(width 0.136652)
		(layer "F.Cu")
		(net "PCIE_REFCLK_S1_N")
	)
	(arc
		(start 91.974416 -186.185302)
		(mid 91.984891 -186.13273)
		(end 92.014802 -186.088274)
		(width 0.136652)
		(layer "F.Cu")
		(net "PCIE_REFCLK_S1_N")
	)
	(arc
		(start 110.65256 -211.011008)
		(mid 110.520976 -210.155567)
		(end 110.13821 -209.379312)
		(width 0.136652)
		(layer "F.Cu")
		(net "PCIE_REFCLK_S1_N")
	)
	(segment
		(start 239.9665 -36.594542)
		(end 239.9665 -34.152332)
		(width 0.1016)
		(layer "In5.Cu")
		(net "PCIE_REFCLK_S1_N")
	)
	(segment
		(start 222.831406 -45.5676)
		(end 223.055688 -45.5676)
		(width 0.1397)
		(layer "In5.Cu")
		(net "PCIE_REFCLK_S1_N")
	)
	(segment
		(start 239.100106 -33.695132)
		(end 239.100106 -33.50006)
		(width 0.1016)
		(layer "In5.Cu")
		(net "PCIE_REFCLK_S1_N")
	)
	(segment
		(start 194.0179 -70.435724)
		(end 194.0179 -70.107556)
		(width 0.1397)
		(layer "In5.Cu")
		(net "PCIE_REFCLK_S1_N")
	)
	(segment
		(start 210.444842 -49.920906)
		(end 216.412572 -45.964856)
		(width 0.1397)
		(layer "In5.Cu")
		(net "PCIE_REFCLK_S1_N")
	)
	(segment
		(start 222.468694 -45.2628)
		(end 222.7326 -45.526706)
		(width 0.1397)
		(layer "In5.Cu")
		(net "PCIE_REFCLK_S1_N")
	)
	(segment
		(start 239.76711 -47.643796)
		(end 239.896396 -47.51451)
		(width 0.1397)
		(layer "In5.Cu")
		(net "PCIE_REFCLK_S1_N")
	)
	(segment
		(start 240.03 -36.703)
		(end 239.99825 -36.67125)
		(width 0.1016)
		(layer "In5.Cu")
		(net "PCIE_REFCLK_S1_N")
	)
	(segment
		(start 158.15691 -141.714982)
		(end 192.983612 -91.976702)
		(width 0.1397)
		(layer "In5.Cu")
		(net "PCIE_REFCLK_S1_N")
	)
	(segment
		(start 225.95205 -47.7774)
		(end 239.444022 -47.7774)
		(width 0.1397)
		(layer "In5.Cu")
		(net "PCIE_REFCLK_S1_N")
	)
	(segment
		(start 216.412572 -45.964856)
		(end 219.883482 -45.83811)
		(width 0.1397)
		(layer "In5.Cu")
		(net "PCIE_REFCLK_S1_N")
	)
	(segment
		(start 97.384616 -184.26811)
		(end 158.15691 -141.714982)
		(width 0.1397)
		(layer "In5.Cu")
		(net "PCIE_REFCLK_S1_N")
	)
	(segment
		(start 196.03593 -58.666634)
		(end 197.223126 -56.971946)
		(width 0.1397)
		(layer "In5.Cu")
		(net "PCIE_REFCLK_S1_N")
	)
	(segment
		(start 198.788274 -55.876444)
		(end 201.214228 -55.448708)
		(width 0.1397)
		(layer "In5.Cu")
		(net "PCIE_REFCLK_S1_N")
	)
	(segment
		(start 197.223126 -56.971946)
		(end 198.788274 -55.876444)
		(width 0.1397)
		(layer "In5.Cu")
		(net "PCIE_REFCLK_S1_N")
	)
	(segment
		(start 240.03 -36.7284)
		(end 240.03 -36.703)
		(width 0.1016)
		(layer "In5.Cu")
		(net "PCIE_REFCLK_S1_N")
	)
	(segment
		(start 207.13319 -54.65064)
		(end 210.444842 -49.920906)
		(width 0.1397)
		(layer "In5.Cu")
		(net "PCIE_REFCLK_S1_N")
	)
	(segment
		(start 203.979272 -55.936388)
		(end 205.74 -55.626)
		(width 0.1397)
		(layer "In5.Cu")
		(net "PCIE_REFCLK_S1_N")
	)
	(segment
		(start 194.0179 -70.107556)
		(end 196.03593 -58.666634)
		(width 0.1397)
		(layer "In5.Cu")
		(net "PCIE_REFCLK_S1_N")
	)
	(segment
		(start 220.458792 -45.2628)
		(end 222.468694 -45.2628)
		(width 0.1397)
		(layer "In5.Cu")
		(net "PCIE_REFCLK_S1_N")
	)
	(segment
		(start 92.545916 -185.877454)
		(end 92.545916 -185.575448)
		(width 0.1397)
		(layer "In5.Cu")
		(net "PCIE_REFCLK_S1_N")
	)
	(segment
		(start 205.74 -55.626)
		(end 207.13319 -54.65064)
		(width 0.1397)
		(layer "In5.Cu")
		(net "PCIE_REFCLK_S1_N")
	)
	(segment
		(start 239.6363 -33.822132)
		(end 239.227106 -33.822132)
		(width 0.1016)
		(layer "In5.Cu")
		(net "PCIE_REFCLK_S1_N")
	)
	(segment
		(start 201.214228 -55.448708)
		(end 203.979272 -55.936388)
		(width 0.1397)
		(layer "In5.Cu")
		(net "PCIE_REFCLK_S1_N")
	)
	(segment
		(start 195.400168 -78.272386)
		(end 194.0179 -70.435724)
		(width 0.1397)
		(layer "In5.Cu")
		(net "PCIE_REFCLK_S1_N")
	)
	(segment
		(start 219.883482 -45.83811)
		(end 220.458792 -45.2628)
		(width 0.1397)
		(layer "In5.Cu")
		(net "PCIE_REFCLK_S1_N")
	)
	(segment
		(start 223.154494 -45.608494)
		(end 224.8789 -47.3329)
		(width 0.1397)
		(layer "In5.Cu")
		(net "PCIE_REFCLK_S1_N")
	)
	(segment
		(start 92.588842 -185.471816)
		(end 93.08211 -184.978548)
		(width 0.1397)
		(layer "In5.Cu")
		(net "PCIE_REFCLK_S1_N")
	)
	(segment
		(start 240.03 -47.191422)
		(end 240.03 -36.7284)
		(width 0.1397)
		(layer "In5.Cu")
		(net "PCIE_REFCLK_S1_N")
	)
	(segment
		(start 93.304106 -184.8866)
		(end 95.5548 -184.8866)
		(width 0.1397)
		(layer "In5.Cu")
		(net "PCIE_REFCLK_S1_N")
	)
	(segment
		(start 192.983612 -91.976702)
		(end 195.400168 -78.272386)
		(width 0.1397)
		(layer "In5.Cu")
		(net "PCIE_REFCLK_S1_N")
	)
	(arc
		(start 93.08211 -184.978548)
		(mid 93.183963 -184.910492)
		(end 93.304106 -184.8866)
		(width 0.1397)
		(layer "In5.Cu")
		(net "PCIE_REFCLK_S1_N")
	)
	(arc
		(start 95.5548 -184.8866)
		(mid 96.520558 -184.727796)
		(end 97.384616 -184.26811)
		(width 0.1397)
		(layer "In5.Cu")
		(net "PCIE_REFCLK_S1_N")
	)
	(arc
		(start 92.545916 -185.575448)
		(mid 92.557072 -185.519363)
		(end 92.588842 -185.471816)
		(width 0.1397)
		(layer "In5.Cu")
		(net "PCIE_REFCLK_S1_N")
	)
	(arc
		(start 239.9665 -34.152332)
		(mid 239.869787 -33.918845)
		(end 239.6363 -33.822132)
		(width 0.1016)
		(layer "In5.Cu")
		(net "PCIE_REFCLK_S1_N")
	)
	(arc
		(start 222.7326 -45.526706)
		(mid 222.777933 -45.556996)
		(end 222.831406 -45.5676)
		(width 0.1397)
		(layer "In5.Cu")
		(net "PCIE_REFCLK_S1_N")
	)
	(arc
		(start 224.8789 -47.3329)
		(mid 225.371279 -47.661864)
		(end 225.95205 -47.7774)
		(width 0.1397)
		(layer "In5.Cu")
		(net "PCIE_REFCLK_S1_N")
	)
	(arc
		(start 239.99825 -36.67125)
		(mid 239.974734 -36.636056)
		(end 239.9665 -36.594542)
		(width 0.1016)
		(layer "In5.Cu")
		(net "PCIE_REFCLK_S1_N")
	)
	(arc
		(start 239.896396 -47.51451)
		(mid 239.995282 -47.366233)
		(end 240.03 -47.191422)
		(width 0.1397)
		(layer "In5.Cu")
		(net "PCIE_REFCLK_S1_N")
	)
	(arc
		(start 239.227106 -33.822132)
		(mid 239.137303 -33.784935)
		(end 239.100106 -33.695132)
		(width 0.1016)
		(layer "In5.Cu")
		(net "PCIE_REFCLK_S1_N")
	)
	(arc
		(start 239.444022 -47.7774)
		(mid 239.618833 -47.742681)
		(end 239.76711 -47.643796)
		(width 0.1397)
		(layer "In5.Cu")
		(net "PCIE_REFCLK_S1_N")
	)
	(arc
		(start 223.055688 -45.5676)
		(mid 223.109149 -45.578234)
		(end 223.154494 -45.608494)
		(width 0.1397)
		(layer "In5.Cu")
		(net "PCIE_REFCLK_S1_N")
	)
	(segment
		(start 236.599984 -37.999924)
		(end 236.100112 -37.500052)
		(width 0.136652)
		(layer "F.Cu")
		(net "PCIE_REFCLK_H3_P")
	)
	(via
		(at 236.100112 -37.500052)
		(size 0.4572)
		(drill 0.2032)
		(layers "F.Cu" "B.Cu")
		(net "PCIE_REFCLK_H3_P")
	)
	(via
		(at 184.558686 -11.696954)
		(size 0.508)
		(drill 0.254)
		(layers "F.Cu" "B.Cu")
		(net "PCIE_REFCLK_H3_P")
	)
	(segment
		(start 184.304686 -11.950954)
		(end 184.168034 -11.950954)
		(width 0.136652)
		(layer "B.Cu")
		(net "PCIE_REFCLK_H3_P")
	)
	(segment
		(start 183.846216 -12.08405)
		(end 183.236108 -12.694158)
		(width 0.136652)
		(layer "B.Cu")
		(net "PCIE_REFCLK_H3_P")
	)
	(segment
		(start 235.6104 -37.01034)
		(end 236.100112 -37.500052)
		(width 0.136652)
		(layer "B.Cu")
		(net "PCIE_REFCLK_H3_P")
	)
	(segment
		(start 183.068722 -12.763246)
		(end 182.912004 -12.763246)
		(width 0.136652)
		(layer "B.Cu")
		(net "PCIE_REFCLK_H3_P")
	)
	(segment
		(start 182.740046 -12.691872)
		(end 182.51932 -12.4714)
		(width 0.136652)
		(layer "B.Cu")
		(net "PCIE_REFCLK_H3_P")
	)
	(segment
		(start 184.558686 -11.696954)
		(end 184.304686 -11.950954)
		(width 0.136652)
		(layer "B.Cu")
		(net "PCIE_REFCLK_H3_P")
	)
	(segment
		(start 235.6104 -36.8046)
		(end 235.6104 -37.01034)
		(width 0.136652)
		(layer "B.Cu")
		(net "PCIE_REFCLK_H3_P")
	)
	(arc
		(start 182.912004 -12.763246)
		(mid 182.818939 -12.744641)
		(end 182.740046 -12.691872)
		(width 0.136652)
		(layer "B.Cu")
		(net "PCIE_REFCLK_H3_P")
	)
	(arc
		(start 184.168034 -11.950954)
		(mid 183.993878 -11.985484)
		(end 183.846216 -12.08405)
		(width 0.136652)
		(layer "B.Cu")
		(net "PCIE_REFCLK_H3_P")
	)
	(arc
		(start 183.236108 -12.694158)
		(mid 183.159281 -12.745336)
		(end 183.068722 -12.763246)
		(width 0.136652)
		(layer "B.Cu")
		(net "PCIE_REFCLK_H3_P")
	)
	(segment
		(start 237.139734 -22.890734)
		(end 238.161068 -23.912068)
		(width 0.1397)
		(layer "In2.Cu")
		(net "PCIE_REFCLK_H3_P")
	)
	(segment
		(start 198.491348 -16.1544)
		(end 232.273856 -16.1544)
		(width 0.1397)
		(layer "In2.Cu")
		(net "PCIE_REFCLK_H3_P")
	)
	(segment
		(start 190.426848 -12.235688)
		(end 192.936876 -14.745716)
		(width 0.1397)
		(layer "In2.Cu")
		(net "PCIE_REFCLK_H3_P")
	)
	(segment
		(start 238.706406 -28.984194)
		(end 238.706406 -35.738308)
		(width 0.1016)
		(layer "In2.Cu")
		(net "PCIE_REFCLK_H3_P")
	)
	(segment
		(start 238.7854 -28.9052)
		(end 238.706406 -28.984194)
		(width 0.1016)
		(layer "In2.Cu")
		(net "PCIE_REFCLK_H3_P")
	)
	(segment
		(start 236.100112 -37.412168)
		(end 236.100112 -37.500052)
		(width 0.1016)
		(layer "In2.Cu")
		(net "PCIE_REFCLK_H3_P")
	)
	(segment
		(start 184.799986 -11.938254)
		(end 189.708028 -11.938254)
		(width 0.1397)
		(layer "In2.Cu")
		(net "PCIE_REFCLK_H3_P")
	)
	(segment
		(start 232.784904 -16.365982)
		(end 236.471714 -20.0533)
		(width 0.1397)
		(layer "In2.Cu")
		(net "PCIE_REFCLK_H3_P")
	)
	(segment
		(start 238.347758 -36.096956)
		(end 236.946186 -36.096956)
		(width 0.1016)
		(layer "In2.Cu")
		(net "PCIE_REFCLK_H3_P")
	)
	(segment
		(start 184.558686 -11.696954)
		(end 184.799986 -11.938254)
		(width 0.1397)
		(layer "In2.Cu")
		(net "PCIE_REFCLK_H3_P")
	)
	(segment
		(start 236.471714 -20.0533)
		(end 236.471968 -20.0533)
		(width 0.1397)
		(layer "In2.Cu")
		(net "PCIE_REFCLK_H3_P")
	)
	(segment
		(start 238.4806 -24.683466)
		(end 238.4806 -24.953722)
		(width 0.1397)
		(layer "In2.Cu")
		(net "PCIE_REFCLK_H3_P")
	)
	(segment
		(start 197.0151 -15.252446)
		(end 197.510908 -15.748254)
		(width 0.1397)
		(layer "In2.Cu")
		(net "PCIE_REFCLK_H3_P")
	)
	(segment
		(start 238.706406 -35.738308)
		(end 238.347758 -36.096956)
		(width 0.1016)
		(layer "In2.Cu")
		(net "PCIE_REFCLK_H3_P")
	)
	(segment
		(start 238.7854 -25.68956)
		(end 238.7854 -28.9052)
		(width 0.1397)
		(layer "In2.Cu")
		(net "PCIE_REFCLK_H3_P")
	)
	(segment
		(start 193.271648 -14.8844)
		(end 196.1261 -14.8844)
		(width 0.1397)
		(layer "In2.Cu")
		(net "PCIE_REFCLK_H3_P")
	)
	(segment
		(start 236.946186 -36.096956)
		(end 236.695996 -36.347146)
		(width 0.1016)
		(layer "In2.Cu")
		(net "PCIE_REFCLK_H3_P")
	)
	(segment
		(start 236.695996 -36.347146)
		(end 236.695996 -36.762944)
		(width 0.1016)
		(layer "In2.Cu")
		(net "PCIE_REFCLK_H3_P")
	)
	(segment
		(start 236.855 -20.978114)
		(end 236.855 -22.203156)
		(width 0.1397)
		(layer "In2.Cu")
		(net "PCIE_REFCLK_H3_P")
	)
	(arc
		(start 236.357414 -37.101526)
		(mid 236.282056 -37.111755)
		(end 236.212126 -37.141658)
		(width 0.1016)
		(layer "In2.Cu")
		(net "PCIE_REFCLK_H3_P")
	)
	(arc
		(start 236.855 -22.203156)
		(mid 236.928998 -22.575258)
		(end 237.139734 -22.890734)
		(width 0.1397)
		(layer "In2.Cu")
		(net "PCIE_REFCLK_H3_P")
	)
	(arc
		(start 197.510908 -15.748254)
		(mid 197.960737 -16.04885)
		(end 198.491348 -16.1544)
		(width 0.1397)
		(layer "In2.Cu")
		(net "PCIE_REFCLK_H3_P")
	)
	(arc
		(start 238.4806 -24.953722)
		(mid 238.511299 -25.107967)
		(end 238.59871 -25.23871)
		(width 0.1397)
		(layer "In2.Cu")
		(net "PCIE_REFCLK_H3_P")
	)
	(arc
		(start 238.161068 -23.912068)
		(mid 238.39755 -24.265988)
		(end 238.4806 -24.683466)
		(width 0.1397)
		(layer "In2.Cu")
		(net "PCIE_REFCLK_H3_P")
	)
	(arc
		(start 236.695996 -36.762944)
		(mid 236.596828 -37.002358)
		(end 236.357414 -37.101526)
		(width 0.1016)
		(layer "In2.Cu")
		(net "PCIE_REFCLK_H3_P")
	)
	(arc
		(start 236.471968 -20.0533)
		(mid 236.755428 -20.477623)
		(end 236.855 -20.978114)
		(width 0.1397)
		(layer "In2.Cu")
		(net "PCIE_REFCLK_H3_P")
	)
	(arc
		(start 192.936876 -14.745716)
		(mid 193.090471 -14.848345)
		(end 193.271648 -14.8844)
		(width 0.1397)
		(layer "In2.Cu")
		(net "PCIE_REFCLK_H3_P")
	)
	(arc
		(start 196.1261 -14.8844)
		(mid 196.60719 -14.980019)
		(end 197.0151 -15.252446)
		(width 0.1397)
		(layer "In2.Cu")
		(net "PCIE_REFCLK_H3_P")
	)
	(arc
		(start 238.59871 -25.23871)
		(mid 238.73687 -25.445576)
		(end 238.7854 -25.68956)
		(width 0.1397)
		(layer "In2.Cu")
		(net "PCIE_REFCLK_H3_P")
	)
	(arc
		(start 189.708028 -11.938254)
		(mid 190.097 -12.015514)
		(end 190.426848 -12.235688)
		(width 0.1397)
		(layer "In2.Cu")
		(net "PCIE_REFCLK_H3_P")
	)
	(arc
		(start 236.212126 -37.141658)
		(mid 236.129198 -37.265769)
		(end 236.100112 -37.412168)
		(width 0.1016)
		(layer "In2.Cu")
		(net "PCIE_REFCLK_H3_P")
	)
	(arc
		(start 232.273856 -16.1544)
		(mid 232.550423 -16.209377)
		(end 232.784904 -16.365982)
		(width 0.1397)
		(layer "In2.Cu")
		(net "PCIE_REFCLK_H3_P")
	)
	(segment
		(start 236.599984 -36.999926)
		(end 236.100112 -36.500054)
		(width 0.136652)
		(layer "F.Cu")
		(net "PCIE_REFCLK_H3_N")
	)
	(via
		(at 236.100112 -36.500054)
		(size 0.4572)
		(drill 0.2032)
		(layers "F.Cu" "B.Cu")
		(net "PCIE_REFCLK_H3_N")
	)
	(via
		(at 184.558686 -12.509754)
		(size 0.508)
		(drill 0.254)
		(layers "F.Cu" "B.Cu")
		(net "PCIE_REFCLK_H3_N")
	)
	(segment
		(start 184.168034 -12.255754)
		(end 184.304686 -12.255754)
		(width 0.136652)
		(layer "B.Cu")
		(net "PCIE_REFCLK_H3_N")
	)
	(segment
		(start 235.845858 -36.2458)
		(end 236.100112 -36.500054)
		(width 0.136652)
		(layer "B.Cu")
		(net "PCIE_REFCLK_H3_N")
	)
	(segment
		(start 183.975756 -12.385802)
		(end 184.061862 -12.299696)
		(width 0.136652)
		(layer "B.Cu")
		(net "PCIE_REFCLK_H3_N")
	)
	(segment
		(start 183.975756 -12.386056)
		(end 183.975756 -12.385802)
		(width 0.136652)
		(layer "B.Cu")
		(net "PCIE_REFCLK_H3_N")
	)
	(segment
		(start 235.6104 -36.2458)
		(end 235.845858 -36.2458)
		(width 0.136652)
		(layer "B.Cu")
		(net "PCIE_REFCLK_H3_N")
	)
	(segment
		(start 183.451754 -12.909804)
		(end 183.744108 -12.617704)
		(width 0.136652)
		(layer "B.Cu")
		(net "PCIE_REFCLK_H3_N")
	)
	(segment
		(start 182.51932 -13.5128)
		(end 182.889652 -13.142722)
		(width 0.136652)
		(layer "B.Cu")
		(net "PCIE_REFCLK_H3_N")
	)
	(segment
		(start 184.304686 -12.255754)
		(end 184.558686 -12.509754)
		(width 0.136652)
		(layer "B.Cu")
		(net "PCIE_REFCLK_H3_N")
	)
	(segment
		(start 183.744108 -12.617704)
		(end 183.975756 -12.386056)
		(width 0.136652)
		(layer "B.Cu")
		(net "PCIE_REFCLK_H3_N")
	)
	(arc
		(start 182.889652 -13.142722)
		(mid 182.971912 -13.087665)
		(end 183.068976 -13.0683)
		(width 0.136652)
		(layer "B.Cu")
		(net "PCIE_REFCLK_H3_N")
	)
	(arc
		(start 183.068976 -13.0683)
		(mid 183.276127 -13.027113)
		(end 183.451754 -12.909804)
		(width 0.136652)
		(layer "B.Cu")
		(net "PCIE_REFCLK_H3_N")
	)
	(arc
		(start 184.061862 -12.299696)
		(mid 184.110574 -12.267148)
		(end 184.168034 -12.255754)
		(width 0.136652)
		(layer "B.Cu")
		(net "PCIE_REFCLK_H3_N")
	)
	(segment
		(start 236.357414 -36.898326)
		(end 236.201712 -36.898326)
		(width 0.1016)
		(layer "In2.Cu")
		(net "PCIE_REFCLK_H3_N")
	)
	(segment
		(start 188.381386 -12.268454)
		(end 189.708282 -12.268454)
		(width 0.1397)
		(layer "In2.Cu")
		(net "PCIE_REFCLK_H3_N")
	)
	(segment
		(start 230.482902 -16.6624)
		(end 230.660702 -16.4846)
		(width 0.1397)
		(layer "In2.Cu")
		(net "PCIE_REFCLK_H3_N")
	)
	(segment
		(start 231.257602 -16.6624)
		(end 231.676702 -16.6624)
		(width 0.1397)
		(layer "In2.Cu")
		(net "PCIE_REFCLK_H3_N")
	)
	(segment
		(start 185.815986 -12.446254)
		(end 185.993786 -12.268454)
		(width 0.1397)
		(layer "In2.Cu")
		(net "PCIE_REFCLK_H3_N")
	)
	(segment
		(start 231.676702 -16.6624)
		(end 231.854502 -16.4846)
		(width 0.1397)
		(layer "In2.Cu")
		(net "PCIE_REFCLK_H3_N")
	)
	(segment
		(start 229.886002 -16.4846)
		(end 230.063802 -16.6624)
		(width 0.1397)
		(layer "In2.Cu")
		(net "PCIE_REFCLK_H3_N")
	)
	(segment
		(start 228.870002 -16.6624)
		(end 229.289102 -16.6624)
		(width 0.1397)
		(layer "In2.Cu")
		(net "PCIE_REFCLK_H3_N")
	)
	(segment
		(start 187.009786 -12.446254)
		(end 187.187586 -12.268454)
		(width 0.1397)
		(layer "In2.Cu")
		(net "PCIE_REFCLK_H3_N")
	)
	(segment
		(start 238.4552 -25.68956)
		(end 238.4552 -28.9052)
		(width 0.1397)
		(layer "In2.Cu")
		(net "PCIE_REFCLK_H3_N")
	)
	(segment
		(start 190.193168 -12.469368)
		(end 192.703196 -14.979396)
		(width 0.1397)
		(layer "In2.Cu")
		(net "PCIE_REFCLK_H3_N")
	)
	(segment
		(start 228.095302 -16.6624)
		(end 228.273102 -16.4846)
		(width 0.1397)
		(layer "In2.Cu")
		(net "PCIE_REFCLK_H3_N")
	)
	(segment
		(start 236.861858 -35.893756)
		(end 236.492796 -36.262818)
		(width 0.1016)
		(layer "In2.Cu")
		(net "PCIE_REFCLK_H3_N")
	)
	(segment
		(start 231.079802 -16.4846)
		(end 231.257602 -16.6624)
		(width 0.1397)
		(layer "In2.Cu")
		(net "PCIE_REFCLK_H3_N")
	)
	(segment
		(start 184.558686 -12.509754)
		(end 184.799986 -12.268454)
		(width 0.1397)
		(layer "In2.Cu")
		(net "PCIE_REFCLK_H3_N")
	)
	(segment
		(start 227.498402 -16.4846)
		(end 227.676202 -16.6624)
		(width 0.1397)
		(layer "In2.Cu")
		(net "PCIE_REFCLK_H3_N")
	)
	(segment
		(start 227.676202 -16.6624)
		(end 228.095302 -16.6624)
		(width 0.1397)
		(layer "In2.Cu")
		(net "PCIE_REFCLK_H3_N")
	)
	(segment
		(start 229.466902 -16.4846)
		(end 229.886002 -16.4846)
		(width 0.1397)
		(layer "In2.Cu")
		(net "PCIE_REFCLK_H3_N")
	)
	(segment
		(start 236.492796 -36.262818)
		(end 236.492796 -36.762944)
		(width 0.1016)
		(layer "In2.Cu")
		(net "PCIE_REFCLK_H3_N")
	)
	(segment
		(start 238.26343 -35.893756)
		(end 236.861858 -35.893756)
		(width 0.1016)
		(layer "In2.Cu")
		(net "PCIE_REFCLK_H3_N")
	)
	(segment
		(start 229.289102 -16.6624)
		(end 229.466902 -16.4846)
		(width 0.1397)
		(layer "In2.Cu")
		(net "PCIE_REFCLK_H3_N")
	)
	(segment
		(start 193.271648 -15.2146)
		(end 196.126354 -15.2146)
		(width 0.1397)
		(layer "In2.Cu")
		(net "PCIE_REFCLK_H3_N")
	)
	(segment
		(start 184.799986 -12.268454)
		(end 185.219086 -12.268454)
		(width 0.1397)
		(layer "In2.Cu")
		(net "PCIE_REFCLK_H3_N")
	)
	(segment
		(start 238.4552 -29.042106)
		(end 238.503206 -29.090112)
		(width 0.1016)
		(layer "In2.Cu")
		(net "PCIE_REFCLK_H3_N")
	)
	(segment
		(start 185.993786 -12.268454)
		(end 186.412886 -12.268454)
		(width 0.1397)
		(layer "In2.Cu")
		(net "PCIE_REFCLK_H3_N")
	)
	(segment
		(start 230.063802 -16.6624)
		(end 230.482902 -16.6624)
		(width 0.1397)
		(layer "In2.Cu")
		(net "PCIE_REFCLK_H3_N")
	)
	(segment
		(start 238.503206 -29.090112)
		(end 238.503206 -35.65398)
		(width 0.1016)
		(layer "In2.Cu")
		(net "PCIE_REFCLK_H3_N")
	)
	(segment
		(start 238.1504 -24.683466)
		(end 238.1504 -24.953722)
		(width 0.1397)
		(layer "In2.Cu")
		(net "PCIE_REFCLK_H3_N")
	)
	(segment
		(start 186.412886 -12.268454)
		(end 186.590686 -12.446254)
		(width 0.1397)
		(layer "In2.Cu")
		(net "PCIE_REFCLK_H3_N")
	)
	(segment
		(start 188.203586 -12.446254)
		(end 188.381386 -12.268454)
		(width 0.1397)
		(layer "In2.Cu")
		(net "PCIE_REFCLK_H3_N")
	)
	(segment
		(start 230.660702 -16.4846)
		(end 231.079802 -16.4846)
		(width 0.1397)
		(layer "In2.Cu")
		(net "PCIE_REFCLK_H3_N")
	)
	(segment
		(start 187.606686 -12.268454)
		(end 187.784486 -12.446254)
		(width 0.1397)
		(layer "In2.Cu")
		(net "PCIE_REFCLK_H3_N")
	)
	(segment
		(start 185.219086 -12.268454)
		(end 185.396886 -12.446254)
		(width 0.1397)
		(layer "In2.Cu")
		(net "PCIE_REFCLK_H3_N")
	)
	(segment
		(start 238.503206 -35.65398)
		(end 238.26343 -35.893756)
		(width 0.1016)
		(layer "In2.Cu")
		(net "PCIE_REFCLK_H3_N")
	)
	(segment
		(start 196.78142 -15.486126)
		(end 197.277228 -15.981934)
		(width 0.1397)
		(layer "In2.Cu")
		(net "PCIE_REFCLK_H3_N")
	)
	(segment
		(start 198.491094 -16.4846)
		(end 227.498402 -16.4846)
		(width 0.1397)
		(layer "In2.Cu")
		(net "PCIE_REFCLK_H3_N")
	)
	(segment
		(start 185.396886 -12.446254)
		(end 185.815986 -12.446254)
		(width 0.1397)
		(layer "In2.Cu")
		(net "PCIE_REFCLK_H3_N")
	)
	(segment
		(start 228.273102 -16.4846)
		(end 228.692202 -16.4846)
		(width 0.1397)
		(layer "In2.Cu")
		(net "PCIE_REFCLK_H3_N")
	)
	(segment
		(start 236.906054 -23.124414)
		(end 237.927388 -24.145748)
		(width 0.1397)
		(layer "In2.Cu")
		(net "PCIE_REFCLK_H3_N")
	)
	(segment
		(start 187.187586 -12.268454)
		(end 187.606686 -12.268454)
		(width 0.1397)
		(layer "In2.Cu")
		(net "PCIE_REFCLK_H3_N")
	)
	(segment
		(start 231.854502 -16.4846)
		(end 232.273602 -16.4846)
		(width 0.1397)
		(layer "In2.Cu")
		(net "PCIE_REFCLK_H3_N")
	)
	(segment
		(start 238.4552 -28.9052)
		(end 238.4552 -29.042106)
		(width 0.1016)
		(layer "In2.Cu")
		(net "PCIE_REFCLK_H3_N")
	)
	(segment
		(start 187.784486 -12.446254)
		(end 188.203586 -12.446254)
		(width 0.1397)
		(layer "In2.Cu")
		(net "PCIE_REFCLK_H3_N")
	)
	(segment
		(start 186.590686 -12.446254)
		(end 187.009786 -12.446254)
		(width 0.1397)
		(layer "In2.Cu")
		(net "PCIE_REFCLK_H3_N")
	)
	(segment
		(start 236.100112 -36.796726)
		(end 236.100112 -36.500054)
		(width 0.1016)
		(layer "In2.Cu")
		(net "PCIE_REFCLK_H3_N")
	)
	(segment
		(start 228.692202 -16.4846)
		(end 228.870002 -16.6624)
		(width 0.1397)
		(layer "In2.Cu")
		(net "PCIE_REFCLK_H3_N")
	)
	(segment
		(start 236.5248 -20.978114)
		(end 236.5248 -22.203156)
		(width 0.1397)
		(layer "In2.Cu")
		(net "PCIE_REFCLK_H3_N")
	)
	(segment
		(start 232.551224 -16.599662)
		(end 236.238288 -20.28698)
		(width 0.1397)
		(layer "In2.Cu")
		(net "PCIE_REFCLK_H3_N")
	)
	(arc
		(start 238.1504 -24.953722)
		(mid 238.206136 -25.234397)
		(end 238.36503 -25.47239)
		(width 0.1397)
		(layer "In2.Cu")
		(net "PCIE_REFCLK_H3_N")
	)
	(arc
		(start 189.708282 -12.268454)
		(mid 189.970701 -12.32071)
		(end 190.193168 -12.469368)
		(width 0.1397)
		(layer "In2.Cu")
		(net "PCIE_REFCLK_H3_N")
	)
	(arc
		(start 236.492796 -36.762944)
		(mid 236.453144 -36.858674)
		(end 236.357414 -36.898326)
		(width 0.1016)
		(layer "In2.Cu")
		(net "PCIE_REFCLK_H3_N")
	)
	(arc
		(start 192.703196 -14.979396)
		(mid 192.964019 -15.153579)
		(end 193.271648 -15.2146)
		(width 0.1397)
		(layer "In2.Cu")
		(net "PCIE_REFCLK_H3_N")
	)
	(arc
		(start 196.126354 -15.2146)
		(mid 196.480892 -15.285216)
		(end 196.78142 -15.486126)
		(width 0.1397)
		(layer "In2.Cu")
		(net "PCIE_REFCLK_H3_N")
	)
	(arc
		(start 237.927388 -24.145748)
		(mid 238.092369 -24.392426)
		(end 238.1504 -24.683466)
		(width 0.1397)
		(layer "In2.Cu")
		(net "PCIE_REFCLK_H3_N")
	)
	(arc
		(start 236.238288 -20.28698)
		(mid 236.450247 -20.60406)
		(end 236.5248 -20.978114)
		(width 0.1397)
		(layer "In2.Cu")
		(net "PCIE_REFCLK_H3_N")
	)
	(arc
		(start 232.273602 -16.4846)
		(mid 232.423876 -16.514491)
		(end 232.551224 -16.599662)
		(width 0.1397)
		(layer "In2.Cu")
		(net "PCIE_REFCLK_H3_N")
	)
	(arc
		(start 238.36503 -25.47239)
		(mid 238.431689 -25.572013)
		(end 238.4552 -25.68956)
		(width 0.1397)
		(layer "In2.Cu")
		(net "PCIE_REFCLK_H3_N")
	)
	(arc
		(start 236.5248 -22.203156)
		(mid 236.62385 -22.701674)
		(end 236.906054 -23.124414)
		(width 0.1397)
		(layer "In2.Cu")
		(net "PCIE_REFCLK_H3_N")
	)
	(arc
		(start 197.277228 -15.981934)
		(mid 197.834183 -16.353953)
		(end 198.491094 -16.4846)
		(width 0.1397)
		(layer "In2.Cu")
		(net "PCIE_REFCLK_H3_N")
	)
	(arc
		(start 236.201712 -36.898326)
		(mid 236.12987 -36.868568)
		(end 236.100112 -36.796726)
		(width 0.1016)
		(layer "In2.Cu")
		(net "PCIE_REFCLK_H3_N")
	)
	(segment
		(start 238.59998 -37.999924)
		(end 238.100108 -37.500052)
		(width 0.136652)
		(layer "F.Cu")
		(net "PCIE_REFCLK_H2_P")
	)
	(via
		(at 238.100108 -37.500052)
		(size 0.4572)
		(drill 0.2032)
		(layers "F.Cu" "B.Cu")
		(net "PCIE_REFCLK_H2_P")
	)
	(via
		(at 184.44337 -8.40613)
		(size 0.508)
		(drill 0.254)
		(layers "F.Cu" "B.Cu")
		(net "PCIE_REFCLK_H2_P")
	)
	(segment
		(start 183.914796 -7.293356)
		(end 183.82996 -7.20852)
		(width 0.136652)
		(layer "B.Cu")
		(net "PCIE_REFCLK_H2_P")
	)
	(segment
		(start 238.33836 -37.2618)
		(end 238.100108 -37.500052)
		(width 0.136652)
		(layer "B.Cu")
		(net "PCIE_REFCLK_H2_P")
	)
	(segment
		(start 184.18937 -8.15213)
		(end 184.18937 -7.957058)
		(width 0.136652)
		(layer "B.Cu")
		(net "PCIE_REFCLK_H2_P")
	)
	(segment
		(start 184.44337 -8.40613)
		(end 184.18937 -8.15213)
		(width 0.136652)
		(layer "B.Cu")
		(net "PCIE_REFCLK_H2_P")
	)
	(segment
		(start 238.6076 -37.2618)
		(end 238.33836 -37.2618)
		(width 0.136652)
		(layer "B.Cu")
		(net "PCIE_REFCLK_H2_P")
	)
	(segment
		(start 184.18937 -7.957058)
		(end 184.189624 -7.957058)
		(width 0.136652)
		(layer "B.Cu")
		(net "PCIE_REFCLK_H2_P")
	)
	(arc
		(start 183.82996 -7.20852)
		(mid 183.551371 -7.0003)
		(end 183.225186 -6.87959)
		(width 0.136652)
		(layer "B.Cu")
		(net "PCIE_REFCLK_H2_P")
	)
	(arc
		(start 183.225186 -6.87959)
		(mid 182.846521 -6.769799)
		(end 182.58536 -6.47446)
		(width 0.136652)
		(layer "B.Cu")
		(net "PCIE_REFCLK_H2_P")
	)
	(arc
		(start 184.189624 -7.957058)
		(mid 184.118251 -7.597859)
		(end 183.914796 -7.293356)
		(width 0.136652)
		(layer "B.Cu")
		(net "PCIE_REFCLK_H2_P")
	)
	(segment
		(start 184.690512 -9.4742)
		(end 188.979556 -9.4742)
		(width 0.1397)
		(layer "In2.Cu")
		(net "PCIE_REFCLK_H2_P")
	)
	(segment
		(start 197.379336 -13.914882)
		(end 198.145908 -14.681454)
		(width 0.1397)
		(layer "In2.Cu")
		(net "PCIE_REFCLK_H2_P")
	)
	(segment
		(start 193.70548 -13.5128)
		(end 196.40804 -13.5128)
		(width 0.1397)
		(layer "In2.Cu")
		(net "PCIE_REFCLK_H2_P")
	)
	(segment
		(start 239.8522 -36.711128)
		(end 239.461548 -37.10178)
		(width 0.1016)
		(layer "In2.Cu")
		(net "PCIE_REFCLK_H2_P")
	)
	(segment
		(start 239.709198 -24.458422)
		(end 239.709198 -25.554686)
		(width 0.1397)
		(layer "In2.Cu")
		(net "PCIE_REFCLK_H2_P")
	)
	(segment
		(start 239.9792 -36.304728)
		(end 239.9792 -36.3728)
		(width 0.1016)
		(layer "In2.Cu")
		(net "PCIE_REFCLK_H2_P")
	)
	(segment
		(start 239.9792 -36.3728)
		(end 239.8522 -36.4998)
		(width 0.1016)
		(layer "In2.Cu")
		(net "PCIE_REFCLK_H2_P")
	)
	(segment
		(start 239.8522 -36.4998)
		(end 239.8522 -36.711128)
		(width 0.1016)
		(layer "In2.Cu")
		(net "PCIE_REFCLK_H2_P")
	)
	(segment
		(start 238.9886 -21.63318)
		(end 238.9886 -23.044658)
		(width 0.1397)
		(layer "In2.Cu")
		(net "PCIE_REFCLK_H2_P")
	)
	(segment
		(start 239.9792 -26.077418)
		(end 239.9792 -36.304728)
		(width 0.1397)
		(layer "In2.Cu")
		(net "PCIE_REFCLK_H2_P")
	)
	(segment
		(start 184.20207 -8.64743)
		(end 184.20207 -8.985758)
		(width 0.1397)
		(layer "In2.Cu")
		(net "PCIE_REFCLK_H2_P")
	)
	(segment
		(start 238.100108 -37.294058)
		(end 238.100108 -37.500052)
		(width 0.1016)
		(layer "In2.Cu")
		(net "PCIE_REFCLK_H2_P")
	)
	(segment
		(start 198.512938 -14.8336)
		(end 232.001568 -14.8336)
		(width 0.1397)
		(layer "In2.Cu")
		(net "PCIE_REFCLK_H2_P")
	)
	(segment
		(start 239.461548 -37.10178)
		(end 238.450374 -37.10178)
		(width 0.1016)
		(layer "In2.Cu")
		(net "PCIE_REFCLK_H2_P")
	)
	(segment
		(start 184.44337 -8.40613)
		(end 184.20207 -8.64743)
		(width 0.1397)
		(layer "In2.Cu")
		(net "PCIE_REFCLK_H2_P")
	)
	(segment
		(start 189.667134 -9.75868)
		(end 193.22034 -13.311886)
		(width 0.1397)
		(layer "In2.Cu")
		(net "PCIE_REFCLK_H2_P")
	)
	(segment
		(start 184.243218 -9.084818)
		(end 184.591452 -9.433052)
		(width 0.1397)
		(layer "In2.Cu")
		(net "PCIE_REFCLK_H2_P")
	)
	(segment
		(start 239.750346 -25.653746)
		(end 239.841532 -25.744932)
		(width 0.1397)
		(layer "In2.Cu")
		(net "PCIE_REFCLK_H2_P")
	)
	(segment
		(start 239.209072 -23.576788)
		(end 239.43945 -23.807166)
		(width 0.1397)
		(layer "In2.Cu")
		(net "PCIE_REFCLK_H2_P")
	)
	(segment
		(start 233.17581 -15.319756)
		(end 238.634778 -20.778978)
		(width 0.1397)
		(layer "In2.Cu")
		(net "PCIE_REFCLK_H2_P")
	)
	(arc
		(start 184.20207 -8.985758)
		(mid 184.212826 -9.03936)
		(end 184.243218 -9.084818)
		(width 0.1397)
		(layer "In2.Cu")
		(net "PCIE_REFCLK_H2_P")
	)
	(arc
		(start 232.001568 -14.8336)
		(mid 232.637029 -14.959907)
		(end 233.17581 -15.319756)
		(width 0.1397)
		(layer "In2.Cu")
		(net "PCIE_REFCLK_H2_P")
	)
	(arc
		(start 238.634778 -20.778978)
		(mid 238.896645 -21.170889)
		(end 238.9886 -21.63318)
		(width 0.1397)
		(layer "In2.Cu")
		(net "PCIE_REFCLK_H2_P")
	)
	(arc
		(start 238.450374 -37.10178)
		(mid 238.250575 -37.153001)
		(end 238.100108 -37.294058)
		(width 0.1016)
		(layer "In2.Cu")
		(net "PCIE_REFCLK_H2_P")
	)
	(arc
		(start 193.22034 -13.311886)
		(mid 193.442938 -13.460558)
		(end 193.70548 -13.5128)
		(width 0.1397)
		(layer "In2.Cu")
		(net "PCIE_REFCLK_H2_P")
	)
	(arc
		(start 239.841532 -25.744932)
		(mid 239.943406 -25.897492)
		(end 239.9792 -26.077418)
		(width 0.1397)
		(layer "In2.Cu")
		(net "PCIE_REFCLK_H2_P")
	)
	(arc
		(start 239.43945 -23.807166)
		(mid 239.639101 -24.105965)
		(end 239.709198 -24.458422)
		(width 0.1397)
		(layer "In2.Cu")
		(net "PCIE_REFCLK_H2_P")
	)
	(arc
		(start 184.591452 -9.433052)
		(mid 184.636886 -9.463503)
		(end 184.690512 -9.4742)
		(width 0.1397)
		(layer "In2.Cu")
		(net "PCIE_REFCLK_H2_P")
	)
	(arc
		(start 198.145908 -14.681454)
		(mid 198.314288 -14.794055)
		(end 198.512938 -14.8336)
		(width 0.1397)
		(layer "In2.Cu")
		(net "PCIE_REFCLK_H2_P")
	)
	(arc
		(start 188.979556 -9.4742)
		(mid 189.351614 -9.548096)
		(end 189.667134 -9.75868)
		(width 0.1397)
		(layer "In2.Cu")
		(net "PCIE_REFCLK_H2_P")
	)
	(arc
		(start 239.709198 -25.554686)
		(mid 239.719954 -25.608288)
		(end 239.750346 -25.653746)
		(width 0.1397)
		(layer "In2.Cu")
		(net "PCIE_REFCLK_H2_P")
	)
	(arc
		(start 196.40804 -13.5128)
		(mid 196.933663 -13.617259)
		(end 197.379336 -13.914882)
		(width 0.1397)
		(layer "In2.Cu")
		(net "PCIE_REFCLK_H2_P")
	)
	(arc
		(start 238.9886 -23.044658)
		(mid 239.045903 -23.332652)
		(end 239.209072 -23.576788)
		(width 0.1397)
		(layer "In2.Cu")
		(net "PCIE_REFCLK_H2_P")
	)
	(segment
		(start 238.59998 -36.999926)
		(end 238.100108 -36.500054)
		(width 0.136652)
		(layer "F.Cu")
		(net "PCIE_REFCLK_H2_N")
	)
	(via
		(at 183.63057 -8.40613)
		(size 0.508)
		(drill 0.254)
		(layers "F.Cu" "B.Cu")
		(net "PCIE_REFCLK_H2_N")
	)
	(via
		(at 238.100108 -36.500054)
		(size 0.4572)
		(drill 0.2032)
		(layers "F.Cu" "B.Cu")
		(net "PCIE_REFCLK_H2_N")
	)
	(segment
		(start 183.69915 -7.509002)
		(end 183.614314 -7.424166)
		(width 0.136652)
		(layer "B.Cu")
		(net "PCIE_REFCLK_H2_N")
	)
	(segment
		(start 183.88457 -8.15213)
		(end 183.88457 -7.957058)
		(width 0.136652)
		(layer "B.Cu")
		(net "PCIE_REFCLK_H2_N")
	)
	(segment
		(start 238.6076 -36.703)
		(end 238.303054 -36.703)
		(width 0.136652)
		(layer "B.Cu")
		(net "PCIE_REFCLK_H2_N")
	)
	(segment
		(start 183.63057 -8.40613)
		(end 183.88457 -8.15213)
		(width 0.136652)
		(layer "B.Cu")
		(net "PCIE_REFCLK_H2_N")
	)
	(segment
		(start 238.303054 -36.703)
		(end 238.100108 -36.500054)
		(width 0.136652)
		(layer "B.Cu")
		(net "PCIE_REFCLK_H2_N")
	)
	(arc
		(start 183.88457 -7.957058)
		(mid 183.836417 -7.714598)
		(end 183.69915 -7.509002)
		(width 0.136652)
		(layer "B.Cu")
		(net "PCIE_REFCLK_H2_N")
	)
	(arc
		(start 183.614314 -7.424166)
		(mid 183.405819 -7.268244)
		(end 183.161686 -7.177786)
		(width 0.136652)
		(layer "B.Cu")
		(net "PCIE_REFCLK_H2_N")
	)
	(arc
		(start 183.161686 -7.177786)
		(mid 182.818156 -7.276898)
		(end 182.58028 -7.5438)
		(width 0.136652)
		(layer "B.Cu")
		(net "PCIE_REFCLK_H2_N")
	)
	(segment
		(start 230.211122 -15.3416)
		(end 230.388922 -15.1638)
		(width 0.1397)
		(layer "In2.Cu")
		(net "PCIE_REFCLK_H2_N")
	)
	(segment
		(start 227.404422 -15.3416)
		(end 227.823522 -15.3416)
		(width 0.1397)
		(layer "In2.Cu")
		(net "PCIE_REFCLK_H2_N")
	)
	(segment
		(start 183.87187 -8.64743)
		(end 183.87187 -8.986012)
		(width 0.1397)
		(layer "In2.Cu")
		(net "PCIE_REFCLK_H2_N")
	)
	(segment
		(start 186.243468 -9.9822)
		(end 186.662568 -9.9822)
		(width 0.1397)
		(layer "In2.Cu")
		(net "PCIE_REFCLK_H2_N")
	)
	(segment
		(start 227.823522 -15.3416)
		(end 228.001322 -15.1638)
		(width 0.1397)
		(layer "In2.Cu")
		(net "PCIE_REFCLK_H2_N")
	)
	(segment
		(start 239.649 -36.313364)
		(end 239.649 -36.6268)
		(width 0.1016)
		(layer "In2.Cu")
		(net "PCIE_REFCLK_H2_N")
	)
	(segment
		(start 184.009792 -9.318498)
		(end 184.357772 -9.666478)
		(width 0.1397)
		(layer "In2.Cu")
		(net "PCIE_REFCLK_H2_N")
	)
	(segment
		(start 228.001322 -15.1638)
		(end 228.420422 -15.1638)
		(width 0.1397)
		(layer "In2.Cu")
		(net "PCIE_REFCLK_H2_N")
	)
	(segment
		(start 232.94213 -15.553436)
		(end 238.401098 -21.012658)
		(width 0.1397)
		(layer "In2.Cu")
		(net "PCIE_REFCLK_H2_N")
	)
	(segment
		(start 230.388922 -15.1638)
		(end 230.808022 -15.1638)
		(width 0.1397)
		(layer "In2.Cu")
		(net "PCIE_REFCLK_H2_N")
	)
	(segment
		(start 231.404922 -15.3416)
		(end 231.582722 -15.1638)
		(width 0.1397)
		(layer "In2.Cu")
		(net "PCIE_REFCLK_H2_N")
	)
	(segment
		(start 239.37722 -36.89858)
		(end 238.389668 -36.89858)
		(width 0.1016)
		(layer "In2.Cu")
		(net "PCIE_REFCLK_H2_N")
	)
	(segment
		(start 230.985822 -15.3416)
		(end 231.404922 -15.3416)
		(width 0.1397)
		(layer "In2.Cu")
		(net "PCIE_REFCLK_H2_N")
	)
	(segment
		(start 186.662568 -9.9822)
		(end 186.840368 -9.8044)
		(width 0.1397)
		(layer "In2.Cu")
		(net "PCIE_REFCLK_H2_N")
	)
	(segment
		(start 238.100108 -36.614608)
		(end 238.100108 -36.500054)
		(width 0.1016)
		(layer "In2.Cu")
		(net "PCIE_REFCLK_H2_N")
	)
	(segment
		(start 189.433454 -9.99236)
		(end 192.98666 -13.545566)
		(width 0.1397)
		(layer "In2.Cu")
		(net "PCIE_REFCLK_H2_N")
	)
	(segment
		(start 239.378998 -24.458422)
		(end 239.378998 -25.55494)
		(width 0.1397)
		(layer "In2.Cu")
		(net "PCIE_REFCLK_H2_N")
	)
	(segment
		(start 239.51692 -25.887426)
		(end 239.607852 -25.978612)
		(width 0.1397)
		(layer "In2.Cu")
		(net "PCIE_REFCLK_H2_N")
	)
	(segment
		(start 187.856368 -9.9822)
		(end 188.034168 -9.8044)
		(width 0.1397)
		(layer "In2.Cu")
		(net "PCIE_REFCLK_H2_N")
	)
	(segment
		(start 230.808022 -15.1638)
		(end 230.985822 -15.3416)
		(width 0.1397)
		(layer "In2.Cu")
		(net "PCIE_REFCLK_H2_N")
	)
	(segment
		(start 239.649 -36.6268)
		(end 239.37722 -36.89858)
		(width 0.1016)
		(layer "In2.Cu")
		(net "PCIE_REFCLK_H2_N")
	)
	(segment
		(start 197.145656 -14.148562)
		(end 197.912228 -14.915134)
		(width 0.1397)
		(layer "In2.Cu")
		(net "PCIE_REFCLK_H2_N")
	)
	(segment
		(start 229.792022 -15.3416)
		(end 230.211122 -15.3416)
		(width 0.1397)
		(layer "In2.Cu")
		(net "PCIE_REFCLK_H2_N")
	)
	(segment
		(start 239.649 -26.077418)
		(end 239.649 -36.313364)
		(width 0.1397)
		(layer "In2.Cu")
		(net "PCIE_REFCLK_H2_N")
	)
	(segment
		(start 229.614222 -15.1638)
		(end 229.792022 -15.3416)
		(width 0.1397)
		(layer "In2.Cu")
		(net "PCIE_REFCLK_H2_N")
	)
	(segment
		(start 198.512684 -15.1638)
		(end 227.226622 -15.1638)
		(width 0.1397)
		(layer "In2.Cu")
		(net "PCIE_REFCLK_H2_N")
	)
	(segment
		(start 231.582722 -15.1638)
		(end 232.001822 -15.1638)
		(width 0.1397)
		(layer "In2.Cu")
		(net "PCIE_REFCLK_H2_N")
	)
	(segment
		(start 188.034168 -9.8044)
		(end 188.97981 -9.8044)
		(width 0.1397)
		(layer "In2.Cu")
		(net "PCIE_REFCLK_H2_N")
	)
	(segment
		(start 229.017322 -15.3416)
		(end 229.195122 -15.1638)
		(width 0.1397)
		(layer "In2.Cu")
		(net "PCIE_REFCLK_H2_N")
	)
	(segment
		(start 229.195122 -15.1638)
		(end 229.614222 -15.1638)
		(width 0.1397)
		(layer "In2.Cu")
		(net "PCIE_REFCLK_H2_N")
	)
	(segment
		(start 228.420422 -15.1638)
		(end 228.598222 -15.3416)
		(width 0.1397)
		(layer "In2.Cu")
		(net "PCIE_REFCLK_H2_N")
	)
	(segment
		(start 184.690258 -9.8044)
		(end 186.065668 -9.8044)
		(width 0.1397)
		(layer "In2.Cu")
		(net "PCIE_REFCLK_H2_N")
	)
	(segment
		(start 187.437268 -9.9822)
		(end 187.856368 -9.9822)
		(width 0.1397)
		(layer "In2.Cu")
		(net "PCIE_REFCLK_H2_N")
	)
	(segment
		(start 183.63057 -8.40613)
		(end 183.87187 -8.64743)
		(width 0.1397)
		(layer "In2.Cu")
		(net "PCIE_REFCLK_H2_N")
	)
	(segment
		(start 186.065668 -9.8044)
		(end 186.243468 -9.9822)
		(width 0.1397)
		(layer "In2.Cu")
		(net "PCIE_REFCLK_H2_N")
	)
	(segment
		(start 187.259468 -9.8044)
		(end 187.437268 -9.9822)
		(width 0.1397)
		(layer "In2.Cu")
		(net "PCIE_REFCLK_H2_N")
	)
	(segment
		(start 193.70548 -13.843)
		(end 196.408294 -13.843)
		(width 0.1397)
		(layer "In2.Cu")
		(net "PCIE_REFCLK_H2_N")
	)
	(segment
		(start 238.975392 -23.810468)
		(end 239.20577 -24.040846)
		(width 0.1397)
		(layer "In2.Cu")
		(net "PCIE_REFCLK_H2_N")
	)
	(segment
		(start 227.226622 -15.1638)
		(end 227.404422 -15.3416)
		(width 0.1397)
		(layer "In2.Cu")
		(net "PCIE_REFCLK_H2_N")
	)
	(segment
		(start 228.598222 -15.3416)
		(end 229.017322 -15.3416)
		(width 0.1397)
		(layer "In2.Cu")
		(net "PCIE_REFCLK_H2_N")
	)
	(segment
		(start 238.184944 -36.813744)
		(end 238.181134 -36.809934)
		(width 0.1016)
		(layer "In2.Cu")
		(net "PCIE_REFCLK_H2_N")
	)
	(segment
		(start 238.6584 -21.63318)
		(end 238.6584 -23.044658)
		(width 0.1397)
		(layer "In2.Cu")
		(net "PCIE_REFCLK_H2_N")
	)
	(segment
		(start 186.840368 -9.8044)
		(end 187.259468 -9.8044)
		(width 0.1397)
		(layer "In2.Cu")
		(net "PCIE_REFCLK_H2_N")
	)
	(arc
		(start 192.98666 -13.545566)
		(mid 193.316487 -13.765793)
		(end 193.70548 -13.843)
		(width 0.1397)
		(layer "In2.Cu")
		(net "PCIE_REFCLK_H2_N")
	)
	(arc
		(start 184.357772 -9.666478)
		(mid 184.510303 -9.768489)
		(end 184.690258 -9.8044)
		(width 0.1397)
		(layer "In2.Cu")
		(net "PCIE_REFCLK_H2_N")
	)
	(arc
		(start 238.181134 -36.809934)
		(mid 238.121171 -36.720333)
		(end 238.100108 -36.614608)
		(width 0.1016)
		(layer "In2.Cu")
		(net "PCIE_REFCLK_H2_N")
	)
	(arc
		(start 239.20577 -24.040846)
		(mid 239.333866 -24.232416)
		(end 239.378998 -24.458422)
		(width 0.1397)
		(layer "In2.Cu")
		(net "PCIE_REFCLK_H2_N")
	)
	(arc
		(start 188.97981 -9.8044)
		(mid 189.225316 -9.853292)
		(end 189.433454 -9.99236)
		(width 0.1397)
		(layer "In2.Cu")
		(net "PCIE_REFCLK_H2_N")
	)
	(arc
		(start 239.378998 -25.55494)
		(mid 239.414889 -25.734904)
		(end 239.51692 -25.887426)
		(width 0.1397)
		(layer "In2.Cu")
		(net "PCIE_REFCLK_H2_N")
	)
	(arc
		(start 238.401098 -21.012658)
		(mid 238.591464 -21.297327)
		(end 238.6584 -21.63318)
		(width 0.1397)
		(layer "In2.Cu")
		(net "PCIE_REFCLK_H2_N")
	)
	(arc
		(start 238.6584 -23.044658)
		(mid 238.74074 -23.459082)
		(end 238.975392 -23.810468)
		(width 0.1397)
		(layer "In2.Cu")
		(net "PCIE_REFCLK_H2_N")
	)
	(arc
		(start 196.408294 -13.843)
		(mid 196.807364 -13.922456)
		(end 197.145656 -14.148562)
		(width 0.1397)
		(layer "In2.Cu")
		(net "PCIE_REFCLK_H2_N")
	)
	(arc
		(start 197.912228 -14.915134)
		(mid 198.187734 -15.099158)
		(end 198.512684 -15.1638)
		(width 0.1397)
		(layer "In2.Cu")
		(net "PCIE_REFCLK_H2_N")
	)
	(arc
		(start 238.389668 -36.89858)
		(mid 238.278858 -36.876539)
		(end 238.184944 -36.813744)
		(width 0.1016)
		(layer "In2.Cu")
		(net "PCIE_REFCLK_H2_N")
	)
	(arc
		(start 232.001822 -15.1638)
		(mid 232.510716 -15.265119)
		(end 232.94213 -15.553436)
		(width 0.1397)
		(layer "In2.Cu")
		(net "PCIE_REFCLK_H2_N")
	)
	(arc
		(start 239.607852 -25.978612)
		(mid 239.638225 -26.02393)
		(end 239.649 -26.077418)
		(width 0.1397)
		(layer "In2.Cu")
		(net "PCIE_REFCLK_H2_N")
	)
	(arc
		(start 183.87187 -8.986012)
		(mid 183.907761 -9.165976)
		(end 184.009792 -9.318498)
		(width 0.1397)
		(layer "In2.Cu")
		(net "PCIE_REFCLK_H2_N")
	)
	(segment
		(start 237.599982 -37.999924)
		(end 237.10011 -37.500052)
		(width 0.136652)
		(layer "F.Cu")
		(net "PCIE_REFCLK_H1_P")
	)
	(via
		(at 237.10011 -37.500052)
		(size 0.4572)
		(drill 0.2032)
		(layers "F.Cu" "B.Cu")
		(net "PCIE_REFCLK_H1_P")
	)
	(via
		(at 269.5448 -6.118352)
		(size 0.508)
		(drill 0.254)
		(layers "F.Cu" "B.Cu")
		(net "PCIE_REFCLK_H1_P")
	)
	(segment
		(start 236.601 -37.2872)
		(end 236.887258 -37.2872)
		(width 0.136652)
		(layer "B.Cu")
		(net "PCIE_REFCLK_H1_P")
	)
	(segment
		(start 236.887258 -37.2872)
		(end 237.10011 -37.500052)
		(width 0.136652)
		(layer "B.Cu")
		(net "PCIE_REFCLK_H1_P")
	)
	(segment
		(start 270.214852 -5.864352)
		(end 270.5735 -6.223)
		(width 0.136652)
		(layer "B.Cu")
		(net "PCIE_REFCLK_H1_P")
	)
	(segment
		(start 269.7988 -5.864352)
		(end 270.214852 -5.864352)
		(width 0.136652)
		(layer "B.Cu")
		(net "PCIE_REFCLK_H1_P")
	)
	(segment
		(start 269.5448 -6.118352)
		(end 269.7988 -5.864352)
		(width 0.136652)
		(layer "B.Cu")
		(net "PCIE_REFCLK_H1_P")
	)
	(segment
		(start 243.235988 -20.50923)
		(end 242.894104 -20.7518)
		(width 0.1397)
		(layer "In2.Cu")
		(net "PCIE_REFCLK_H1_P")
	)
	(segment
		(start 242.304316 -20.951952)
		(end 241.66195 -21.594318)
		(width 0.1397)
		(layer "In2.Cu")
		(net "PCIE_REFCLK_H1_P")
	)
	(segment
		(start 240.623598 -36.821364)
		(end 239.43691 -38.008052)
		(width 0.1016)
		(layer "In2.Cu")
		(net "PCIE_REFCLK_H1_P")
	)
	(segment
		(start 242.6462 -20.709636)
		(end 242.304316 -20.951952)
		(width 0.1397)
		(layer "In2.Cu")
		(net "PCIE_REFCLK_H1_P")
	)
	(segment
		(start 267.590778 -6.222238)
		(end 267.590524 -6.222492)
		(width 0.1397)
		(layer "In2.Cu")
		(net "PCIE_REFCLK_H1_P")
	)
	(segment
		(start 240.687098 -36.161218)
		(end 240.623598 -36.224718)
		(width 0.1016)
		(layer "In2.Cu")
		(net "PCIE_REFCLK_H1_P")
	)
	(segment
		(start 246.815864 -17.752568)
		(end 244.251988 -19.5707)
		(width 0.1397)
		(layer "In2.Cu")
		(net "PCIE_REFCLK_H1_P")
	)
	(segment
		(start 241.66195 -22.555708)
		(end 240.687098 -24.136858)
		(width 0.1397)
		(layer "In2.Cu")
		(net "PCIE_REFCLK_H1_P")
	)
	(segment
		(start 244.251988 -19.5707)
		(end 244.209824 -19.818604)
		(width 0.1397)
		(layer "In2.Cu")
		(net "PCIE_REFCLK_H1_P")
	)
	(segment
		(start 269.5448 -6.118352)
		(end 269.3035 -5.877052)
		(width 0.1397)
		(layer "In2.Cu")
		(net "PCIE_REFCLK_H1_P")
	)
	(segment
		(start 237.27791 -37.1094)
		(end 237.260892 -37.112448)
		(width 0.1016)
		(layer "In2.Cu")
		(net "PCIE_REFCLK_H1_P")
	)
	(segment
		(start 242.894104 -20.7518)
		(end 242.6462 -20.709636)
		(width 0.1397)
		(layer "In2.Cu")
		(net "PCIE_REFCLK_H1_P")
	)
	(segment
		(start 269.3035 -5.877052)
		(end 267.877798 -5.877052)
		(width 0.1397)
		(layer "In2.Cu")
		(net "PCIE_REFCLK_H1_P")
	)
	(segment
		(start 267.877798 -5.877052)
		(end 267.590778 -6.222238)
		(width 0.1397)
		(layer "In2.Cu")
		(net "PCIE_REFCLK_H1_P")
	)
	(segment
		(start 237.10011 -37.304726)
		(end 237.10011 -37.500052)
		(width 0.1016)
		(layer "In2.Cu")
		(net "PCIE_REFCLK_H1_P")
	)
	(segment
		(start 240.687098 -24.136858)
		(end 240.687098 -36.135818)
		(width 0.1397)
		(layer "In2.Cu")
		(net "PCIE_REFCLK_H1_P")
	)
	(segment
		(start 243.278152 -20.261326)
		(end 243.235988 -20.50923)
		(width 0.1397)
		(layer "In2.Cu")
		(net "PCIE_REFCLK_H1_P")
	)
	(segment
		(start 267.590524 -6.222492)
		(end 266.092432 -9.274048)
		(width 0.1397)
		(layer "In2.Cu")
		(net "PCIE_REFCLK_H1_P")
	)
	(segment
		(start 266.092432 -9.274048)
		(end 262.40867 -11.853418)
		(width 0.1397)
		(layer "In2.Cu")
		(net "PCIE_REFCLK_H1_P")
	)
	(segment
		(start 262.40867 -11.853418)
		(end 251.47016 -13.781786)
		(width 0.1397)
		(layer "In2.Cu")
		(net "PCIE_REFCLK_H1_P")
	)
	(segment
		(start 247.693688 -17.130014)
		(end 246.815864 -17.752568)
		(width 0.1397)
		(layer "In2.Cu")
		(net "PCIE_REFCLK_H1_P")
	)
	(segment
		(start 251.04344 -13.857224)
		(end 250.787154 -14.036548)
		(width 0.1397)
		(layer "In2.Cu")
		(net "PCIE_REFCLK_H1_P")
	)
	(segment
		(start 241.66195 -21.594318)
		(end 241.66195 -22.555708)
		(width 0.1397)
		(layer "In2.Cu")
		(net "PCIE_REFCLK_H1_P")
	)
	(segment
		(start 237.301532 -37.1094)
		(end 237.27791 -37.1094)
		(width 0.1016)
		(layer "In2.Cu")
		(net "PCIE_REFCLK_H1_P")
	)
	(segment
		(start 240.687098 -36.135818)
		(end 240.687098 -36.161218)
		(width 0.1016)
		(layer "In2.Cu")
		(net "PCIE_REFCLK_H1_P")
	)
	(segment
		(start 239.221264 -38.096952)
		(end 238.041942 -38.096952)
		(width 0.1016)
		(layer "In2.Cu")
		(net "PCIE_REFCLK_H1_P")
	)
	(segment
		(start 237.503208 -37.558218)
		(end 237.503208 -37.311076)
		(width 0.1016)
		(layer "In2.Cu")
		(net "PCIE_REFCLK_H1_P")
	)
	(segment
		(start 240.623598 -36.224718)
		(end 240.623598 -36.821364)
		(width 0.1016)
		(layer "In2.Cu")
		(net "PCIE_REFCLK_H1_P")
	)
	(segment
		(start 251.47016 -13.781786)
		(end 251.04344 -13.857224)
		(width 0.1397)
		(layer "In2.Cu")
		(net "PCIE_REFCLK_H1_P")
	)
	(segment
		(start 237.7186 -37.963094)
		(end 237.637066 -37.88156)
		(width 0.1016)
		(layer "In2.Cu")
		(net "PCIE_REFCLK_H1_P")
	)
	(segment
		(start 250.787154 -14.036548)
		(end 247.693688 -17.130014)
		(width 0.1397)
		(layer "In2.Cu")
		(net "PCIE_REFCLK_H1_P")
	)
	(segment
		(start 243.86794 -20.061174)
		(end 243.620036 -20.01901)
		(width 0.1397)
		(layer "In2.Cu")
		(net "PCIE_REFCLK_H1_P")
	)
	(segment
		(start 244.209824 -19.818604)
		(end 243.86794 -20.061174)
		(width 0.1397)
		(layer "In2.Cu")
		(net "PCIE_REFCLK_H1_P")
	)
	(segment
		(start 243.620036 -20.01901)
		(end 243.278152 -20.261326)
		(width 0.1397)
		(layer "In2.Cu")
		(net "PCIE_REFCLK_H1_P")
	)
	(arc
		(start 237.260892 -37.112448)
		(mid 237.145582 -37.179395)
		(end 237.10011 -37.304726)
		(width 0.1016)
		(layer "In2.Cu")
		(net "PCIE_REFCLK_H1_P")
	)
	(arc
		(start 237.637066 -37.88156)
		(mid 237.538024 -37.733194)
		(end 237.503208 -37.558218)
		(width 0.1016)
		(layer "In2.Cu")
		(net "PCIE_REFCLK_H1_P")
	)
	(arc
		(start 239.43691 -38.008052)
		(mid 239.337927 -38.073971)
		(end 239.221264 -38.096952)
		(width 0.1016)
		(layer "In2.Cu")
		(net "PCIE_REFCLK_H1_P")
	)
	(arc
		(start 238.041942 -38.096952)
		(mid 237.866925 -38.062233)
		(end 237.7186 -37.963094)
		(width 0.1016)
		(layer "In2.Cu")
		(net "PCIE_REFCLK_H1_P")
	)
	(arc
		(start 237.503208 -37.311076)
		(mid 237.444138 -37.16847)
		(end 237.301532 -37.1094)
		(width 0.1016)
		(layer "In2.Cu")
		(net "PCIE_REFCLK_H1_P")
	)
	(segment
		(start 237.599982 -36.999926)
		(end 237.10011 -36.500054)
		(width 0.136652)
		(layer "F.Cu")
		(net "PCIE_REFCLK_H1_N")
	)
	(via
		(at 269.5448 -5.305552)
		(size 0.508)
		(drill 0.254)
		(layers "F.Cu" "B.Cu")
		(net "PCIE_REFCLK_H1_N")
	)
	(via
		(at 237.10011 -36.500054)
		(size 0.4572)
		(drill 0.2032)
		(layers "F.Cu" "B.Cu")
		(net "PCIE_REFCLK_H1_N")
	)
	(segment
		(start 236.871764 -36.7284)
		(end 237.10011 -36.500054)
		(width 0.136652)
		(layer "B.Cu")
		(net "PCIE_REFCLK_H1_N")
	)
	(segment
		(start 269.7988 -5.559552)
		(end 270.220948 -5.559552)
		(width 0.136652)
		(layer "B.Cu")
		(net "PCIE_REFCLK_H1_N")
	)
	(segment
		(start 269.5448 -5.305552)
		(end 269.7988 -5.559552)
		(width 0.136652)
		(layer "B.Cu")
		(net "PCIE_REFCLK_H1_N")
	)
	(segment
		(start 236.601 -36.7284)
		(end 236.871764 -36.7284)
		(width 0.136652)
		(layer "B.Cu")
		(net "PCIE_REFCLK_H1_N")
	)
	(segment
		(start 270.220948 -5.559552)
		(end 270.5735 -5.207)
		(width 0.136652)
		(layer "B.Cu")
		(net "PCIE_REFCLK_H1_N")
	)
	(segment
		(start 240.356898 -24.043132)
		(end 240.356898 -36.135818)
		(width 0.1397)
		(layer "In2.Cu")
		(net "PCIE_REFCLK_H1_N")
	)
	(segment
		(start 240.420398 -36.224718)
		(end 240.420398 -36.736782)
		(width 0.1016)
		(layer "In2.Cu")
		(net "PCIE_REFCLK_H1_N")
	)
	(segment
		(start 250.574048 -13.782548)
		(end 247.47982 -16.876776)
		(width 0.1397)
		(layer "In2.Cu")
		(net "PCIE_REFCLK_H1_N")
	)
	(segment
		(start 241.33175 -21.457412)
		(end 241.33175 -22.461982)
		(width 0.1397)
		(layer "In2.Cu")
		(net "PCIE_REFCLK_H1_N")
	)
	(segment
		(start 240.356898 -36.161218)
		(end 240.420398 -36.224718)
		(width 0.1016)
		(layer "In2.Cu")
		(net "PCIE_REFCLK_H1_N")
	)
	(segment
		(start 250.9139 -13.54455)
		(end 250.574048 -13.782548)
		(width 0.1397)
		(layer "In2.Cu")
		(net "PCIE_REFCLK_H1_N")
	)
	(segment
		(start 269.5448 -5.305552)
		(end 269.3035 -5.546852)
		(width 0.1397)
		(layer "In2.Cu")
		(net "PCIE_REFCLK_H1_N")
	)
	(segment
		(start 240.420398 -36.736782)
		(end 239.293146 -37.864034)
		(width 0.1016)
		(layer "In2.Cu")
		(net "PCIE_REFCLK_H1_N")
	)
	(segment
		(start 245.770146 -18.089118)
		(end 242.090448 -20.69846)
		(width 0.1397)
		(layer "In2.Cu")
		(net "PCIE_REFCLK_H1_N")
	)
	(segment
		(start 237.862364 -37.81933)
		(end 237.78083 -37.737796)
		(width 0.1016)
		(layer "In2.Cu")
		(net "PCIE_REFCLK_H1_N")
	)
	(segment
		(start 239.221264 -37.893752)
		(end 238.041942 -37.893752)
		(width 0.1016)
		(layer "In2.Cu")
		(net "PCIE_REFCLK_H1_N")
	)
	(segment
		(start 237.10011 -36.78174)
		(end 237.10011 -36.500054)
		(width 0.1016)
		(layer "In2.Cu")
		(net "PCIE_REFCLK_H1_N")
	)
	(segment
		(start 269.3035 -5.546852)
		(end 267.722858 -5.546852)
		(width 0.1397)
		(layer "In2.Cu")
		(net "PCIE_REFCLK_H1_N")
	)
	(segment
		(start 247.47982 -16.876776)
		(end 245.770146 -18.089118)
		(width 0.1397)
		(layer "In2.Cu")
		(net "PCIE_REFCLK_H1_N")
	)
	(segment
		(start 240.356898 -36.135818)
		(end 240.356898 -36.161218)
		(width 0.1016)
		(layer "In2.Cu")
		(net "PCIE_REFCLK_H1_N")
	)
	(segment
		(start 267.311378 -6.041644)
		(end 265.833352 -9.052306)
		(width 0.1397)
		(layer "In2.Cu")
		(net "PCIE_REFCLK_H1_N")
	)
	(segment
		(start 262.27913 -11.540744)
		(end 251.41301 -13.456666)
		(width 0.1397)
		(layer "In2.Cu")
		(net "PCIE_REFCLK_H1_N")
	)
	(segment
		(start 264.056622 -10.296398)
		(end 262.27913 -11.540744)
		(width 0.1397)
		(layer "In2.Cu")
		(net "PCIE_REFCLK_H1_N")
	)
	(segment
		(start 265.833352 -9.052306)
		(end 264.056622 -10.296398)
		(width 0.1397)
		(layer "In2.Cu")
		(net "PCIE_REFCLK_H1_N")
	)
	(segment
		(start 237.301532 -36.9062)
		(end 237.22457 -36.9062)
		(width 0.1016)
		(layer "In2.Cu")
		(net "PCIE_REFCLK_H1_N")
	)
	(segment
		(start 237.706408 -37.558218)
		(end 237.706408 -37.311076)
		(width 0.1016)
		(layer "In2.Cu")
		(net "PCIE_REFCLK_H1_N")
	)
	(segment
		(start 251.41301 -13.456666)
		(end 250.9139 -13.54455)
		(width 0.1397)
		(layer "In2.Cu")
		(net "PCIE_REFCLK_H1_N")
	)
	(segment
		(start 242.090448 -20.69846)
		(end 241.33175 -21.457412)
		(width 0.1397)
		(layer "In2.Cu")
		(net "PCIE_REFCLK_H1_N")
	)
	(segment
		(start 241.33175 -22.461982)
		(end 240.356898 -24.043132)
		(width 0.1397)
		(layer "In2.Cu")
		(net "PCIE_REFCLK_H1_N")
	)
	(segment
		(start 267.722858 -5.546852)
		(end 267.311378 -6.041644)
		(width 0.1397)
		(layer "In2.Cu")
		(net "PCIE_REFCLK_H1_N")
	)
	(arc
		(start 237.22457 -36.9062)
		(mid 237.136563 -36.869747)
		(end 237.10011 -36.78174)
		(width 0.1016)
		(layer "In2.Cu")
		(net "PCIE_REFCLK_H1_N")
	)
	(arc
		(start 237.78083 -37.737796)
		(mid 237.725724 -37.655419)
		(end 237.706408 -37.558218)
		(width 0.1016)
		(layer "In2.Cu")
		(net "PCIE_REFCLK_H1_N")
	)
	(arc
		(start 238.041942 -37.893752)
		(mid 237.944755 -37.874402)
		(end 237.862364 -37.81933)
		(width 0.1016)
		(layer "In2.Cu")
		(net "PCIE_REFCLK_H1_N")
	)
	(arc
		(start 237.706408 -37.311076)
		(mid 237.587823 -37.024785)
		(end 237.301532 -36.9062)
		(width 0.1016)
		(layer "In2.Cu")
		(net "PCIE_REFCLK_H1_N")
	)
	(arc
		(start 239.293146 -37.864034)
		(mid 239.260152 -37.886017)
		(end 239.221264 -37.893752)
		(width 0.1016)
		(layer "In2.Cu")
		(net "PCIE_REFCLK_H1_N")
	)
	(segment
		(start 240.599976 -37.999924)
		(end 241.099848 -37.500052)
		(width 0.136652)
		(layer "F.Cu")
		(net "PCIE_REFCLK_H0_P")
	)
	(via
		(at 241.099848 -37.500052)
		(size 0.4572)
		(drill 0.2032)
		(layers "F.Cu" "B.Cu")
		(net "PCIE_REFCLK_H0_P")
	)
	(via
		(at 270.6878 -9.166352)
		(size 0.508)
		(drill 0.254)
		(layers "F.Cu" "B.Cu")
		(net "PCIE_REFCLK_H0_P")
	)
	(segment
		(start 241.2619 -37.338)
		(end 241.099848 -37.500052)
		(width 0.136652)
		(layer "B.Cu")
		(net "PCIE_REFCLK_H0_P")
	)
	(segment
		(start 270.9418 -8.912352)
		(end 271.357852 -8.912352)
		(width 0.136652)
		(layer "B.Cu")
		(net "PCIE_REFCLK_H0_P")
	)
	(segment
		(start 241.6048 -37.338)
		(end 241.2619 -37.338)
		(width 0.136652)
		(layer "B.Cu")
		(net "PCIE_REFCLK_H0_P")
	)
	(segment
		(start 270.6878 -9.166352)
		(end 270.9418 -8.912352)
		(width 0.136652)
		(layer "B.Cu")
		(net "PCIE_REFCLK_H0_P")
	)
	(segment
		(start 271.357852 -8.912352)
		(end 271.7165 -9.271)
		(width 0.136652)
		(layer "B.Cu")
		(net "PCIE_REFCLK_H0_P")
	)
	(segment
		(start 257.891026 -14.681962)
		(end 257.768344 -14.660372)
		(width 0.1397)
		(layer "In2.Cu")
		(net "PCIE_REFCLK_H0_P")
	)
	(segment
		(start 268.869922 -9.318498)
		(end 268.869922 -10.592054)
		(width 0.1397)
		(layer "In2.Cu")
		(net "PCIE_REFCLK_H0_P")
	)
	(segment
		(start 268.773402 -10.688828)
		(end 268.407134 -11.055096)
		(width 0.1397)
		(layer "In2.Cu")
		(net "PCIE_REFCLK_H0_P")
	)
	(segment
		(start 265.448034 -11.856212)
		(end 263.452102 -13.852144)
		(width 0.1397)
		(layer "In2.Cu")
		(net "PCIE_REFCLK_H0_P")
	)
	(segment
		(start 267.627608 -11.45032)
		(end 267.222986 -11.559794)
		(width 0.1397)
		(layer "In2.Cu")
		(net "PCIE_REFCLK_H0_P")
	)
	(segment
		(start 251.163328 -15.095982)
		(end 242.1255 -24.13381)
		(width 0.1397)
		(layer "In2.Cu")
		(net "PCIE_REFCLK_H0_P")
	)
	(segment
		(start 242.1255 -28.490672)
		(end 241.769646 -28.846526)
		(width 0.1397)
		(layer "In2.Cu")
		(net "PCIE_REFCLK_H0_P")
	)
	(segment
		(start 267.222986 -11.559794)
		(end 267.0048 -11.434826)
		(width 0.1397)
		(layer "In2.Cu")
		(net "PCIE_REFCLK_H0_P")
	)
	(segment
		(start 268.869922 -10.592054)
		(end 268.773148 -10.688828)
		(width 0.1397)
		(layer "In2.Cu")
		(net "PCIE_REFCLK_H0_P")
	)
	(segment
		(start 270.441166 -8.919718)
		(end 269.268702 -8.919718)
		(width 0.1397)
		(layer "In2.Cu")
		(net "PCIE_REFCLK_H0_P")
	)
	(segment
		(start 263.452102 -13.852144)
		(end 258.318 -14.7574)
		(width 0.1397)
		(layer "In2.Cu")
		(net "PCIE_REFCLK_H0_P")
	)
	(segment
		(start 241.706146 -29.075126)
		(end 241.706146 -36.730178)
		(width 0.1016)
		(layer "In2.Cu")
		(net "PCIE_REFCLK_H0_P")
	)
	(segment
		(start 241.099848 -37.246052)
		(end 241.099848 -37.500052)
		(width 0.1016)
		(layer "In2.Cu")
		(net "PCIE_REFCLK_H0_P")
	)
	(segment
		(start 267.0048 -11.434826)
		(end 266.600432 -11.5443)
		(width 0.1397)
		(layer "In2.Cu")
		(net "PCIE_REFCLK_H0_P")
	)
	(segment
		(start 270.6878 -9.166352)
		(end 270.441166 -8.919718)
		(width 0.1397)
		(layer "In2.Cu")
		(net "PCIE_REFCLK_H0_P")
	)
	(segment
		(start 257.768344 -14.660372)
		(end 256.963418 -14.518386)
		(width 0.1397)
		(layer "In2.Cu")
		(net "PCIE_REFCLK_H0_P")
	)
	(segment
		(start 268.773148 -10.688828)
		(end 268.773402 -10.688828)
		(width 0.1397)
		(layer "In2.Cu")
		(net "PCIE_REFCLK_H0_P")
	)
	(segment
		(start 241.769646 -28.986226)
		(end 241.769646 -29.011626)
		(width 0.1016)
		(layer "In2.Cu")
		(net "PCIE_REFCLK_H0_P")
	)
	(segment
		(start 267.752576 -11.232134)
		(end 267.627608 -11.45032)
		(width 0.1397)
		(layer "In2.Cu")
		(net "PCIE_REFCLK_H0_P")
	)
	(segment
		(start 269.268702 -8.919718)
		(end 268.869922 -9.318498)
		(width 0.1397)
		(layer "In2.Cu")
		(net "PCIE_REFCLK_H0_P")
	)
	(segment
		(start 255.701038 -14.295628)
		(end 251.163328 -15.095982)
		(width 0.1397)
		(layer "In2.Cu")
		(net "PCIE_REFCLK_H0_P")
	)
	(segment
		(start 241.769646 -29.011626)
		(end 241.706146 -29.075126)
		(width 0.1016)
		(layer "In2.Cu")
		(net "PCIE_REFCLK_H0_P")
	)
	(segment
		(start 241.769646 -28.846526)
		(end 241.769646 -28.986226)
		(width 0.1397)
		(layer "In2.Cu")
		(net "PCIE_REFCLK_H0_P")
	)
	(segment
		(start 268.407134 -11.055096)
		(end 267.752576 -11.232134)
		(width 0.1397)
		(layer "In2.Cu")
		(net "PCIE_REFCLK_H0_P")
	)
	(segment
		(start 266.600432 -11.5443)
		(end 266.47521 -11.762232)
		(width 0.1397)
		(layer "In2.Cu")
		(net "PCIE_REFCLK_H0_P")
	)
	(segment
		(start 256.963418 -14.518386)
		(end 255.701038 -14.295628)
		(width 0.1397)
		(layer "In2.Cu")
		(net "PCIE_REFCLK_H0_P")
	)
	(segment
		(start 258.318 -14.7574)
		(end 257.891026 -14.681962)
		(width 0.1397)
		(layer "In2.Cu")
		(net "PCIE_REFCLK_H0_P")
	)
	(segment
		(start 266.47521 -11.762232)
		(end 266.070588 -11.87196)
		(width 0.1397)
		(layer "In2.Cu")
		(net "PCIE_REFCLK_H0_P")
	)
	(segment
		(start 241.301524 -37.1348)
		(end 241.2111 -37.1348)
		(width 0.1016)
		(layer "In2.Cu")
		(net "PCIE_REFCLK_H0_P")
	)
	(segment
		(start 242.1255 -24.13381)
		(end 242.1255 -28.490672)
		(width 0.1397)
		(layer "In2.Cu")
		(net "PCIE_REFCLK_H0_P")
	)
	(segment
		(start 266.070588 -11.87196)
		(end 265.852656 -11.746738)
		(width 0.1397)
		(layer "In2.Cu")
		(net "PCIE_REFCLK_H0_P")
	)
	(segment
		(start 265.852656 -11.746738)
		(end 265.448034 -11.856212)
		(width 0.1397)
		(layer "In2.Cu")
		(net "PCIE_REFCLK_H0_P")
	)
	(arc
		(start 241.2111 -37.1348)
		(mid 241.132433 -37.167385)
		(end 241.099848 -37.246052)
		(width 0.1016)
		(layer "In2.Cu")
		(net "PCIE_REFCLK_H0_P")
	)
	(arc
		(start 241.587528 -37.016436)
		(mid 241.456294 -37.104061)
		(end 241.301524 -37.1348)
		(width 0.1016)
		(layer "In2.Cu")
		(net "PCIE_REFCLK_H0_P")
	)
	(arc
		(start 241.706146 -36.730178)
		(mid 241.675327 -36.885117)
		(end 241.587528 -37.016436)
		(width 0.1016)
		(layer "In2.Cu")
		(net "PCIE_REFCLK_H0_P")
	)
	(segment
		(start 240.599976 -36.999926)
		(end 241.099848 -36.500054)
		(width 0.136652)
		(layer "F.Cu")
		(net "PCIE_REFCLK_H0_N")
	)
	(via
		(at 241.099848 -36.500054)
		(size 0.4572)
		(drill 0.2032)
		(layers "F.Cu" "B.Cu")
		(net "PCIE_REFCLK_H0_N")
	)
	(via
		(at 270.6878 -8.353552)
		(size 0.508)
		(drill 0.254)
		(layers "F.Cu" "B.Cu")
		(net "PCIE_REFCLK_H0_N")
	)
	(segment
		(start 270.9418 -8.607552)
		(end 271.363948 -8.607552)
		(width 0.136652)
		(layer "B.Cu")
		(net "PCIE_REFCLK_H0_N")
	)
	(segment
		(start 241.378994 -36.7792)
		(end 241.099848 -36.500054)
		(width 0.136652)
		(layer "B.Cu")
		(net "PCIE_REFCLK_H0_N")
	)
	(segment
		(start 271.363948 -8.607552)
		(end 271.7165 -8.255)
		(width 0.136652)
		(layer "B.Cu")
		(net "PCIE_REFCLK_H0_N")
	)
	(segment
		(start 270.6878 -8.353552)
		(end 270.9418 -8.607552)
		(width 0.136652)
		(layer "B.Cu")
		(net "PCIE_REFCLK_H0_N")
	)
	(segment
		(start 241.6048 -36.7792)
		(end 241.378994 -36.7792)
		(width 0.136652)
		(layer "B.Cu")
		(net "PCIE_REFCLK_H0_N")
	)
	(segment
		(start 241.439446 -28.70962)
		(end 241.439446 -28.986226)
		(width 0.1397)
		(layer "In2.Cu")
		(net "PCIE_REFCLK_H0_N")
	)
	(segment
		(start 241.099848 -36.7157)
		(end 241.099848 -36.500054)
		(width 0.1016)
		(layer "In2.Cu")
		(net "PCIE_REFCLK_H0_N")
	)
	(segment
		(start 265.276584 -11.560302)
		(end 263.292082 -13.544804)
		(width 0.1397)
		(layer "In2.Cu")
		(net "PCIE_REFCLK_H0_N")
	)
	(segment
		(start 241.502946 -29.075126)
		(end 241.502946 -36.729924)
		(width 0.1016)
		(layer "In2.Cu")
		(net "PCIE_REFCLK_H0_N")
	)
	(segment
		(start 241.439446 -28.986226)
		(end 241.439446 -29.011626)
		(width 0.1016)
		(layer "In2.Cu")
		(net "PCIE_REFCLK_H0_N")
	)
	(segment
		(start 241.7953 -28.353766)
		(end 241.439446 -28.70962)
		(width 0.1397)
		(layer "In2.Cu")
		(net "PCIE_REFCLK_H0_N")
	)
	(segment
		(start 270.451834 -8.589518)
		(end 269.131796 -8.589518)
		(width 0.1397)
		(layer "In2.Cu")
		(net "PCIE_REFCLK_H0_N")
	)
	(segment
		(start 270.6878 -8.353552)
		(end 270.451834 -8.589518)
		(width 0.1397)
		(layer "In2.Cu")
		(net "PCIE_REFCLK_H0_N")
	)
	(segment
		(start 241.7953 -23.996904)
		(end 241.7953 -28.353766)
		(width 0.1397)
		(layer "In2.Cu")
		(net "PCIE_REFCLK_H0_N")
	)
	(segment
		(start 268.235684 -10.759186)
		(end 265.276584 -11.560302)
		(width 0.1397)
		(layer "In2.Cu")
		(net "PCIE_REFCLK_H0_N")
	)
	(segment
		(start 268.539722 -9.181592)
		(end 268.539722 -10.455148)
		(width 0.1397)
		(layer "In2.Cu")
		(net "PCIE_REFCLK_H0_N")
	)
	(segment
		(start 257.825748 -14.334998)
		(end 257.020822 -14.193012)
		(width 0.1397)
		(layer "In2.Cu")
		(net "PCIE_REFCLK_H0_N")
	)
	(segment
		(start 258.318 -14.421866)
		(end 257.825748 -14.334998)
		(width 0.1397)
		(layer "In2.Cu")
		(net "PCIE_REFCLK_H0_N")
	)
	(segment
		(start 251.003308 -14.788642)
		(end 241.7953 -23.996904)
		(width 0.1397)
		(layer "In2.Cu")
		(net "PCIE_REFCLK_H0_N")
	)
	(segment
		(start 257.020822 -14.193012)
		(end 255.701038 -13.960094)
		(width 0.1397)
		(layer "In2.Cu")
		(net "PCIE_REFCLK_H0_N")
	)
	(segment
		(start 268.539722 -10.455148)
		(end 268.235684 -10.759186)
		(width 0.1397)
		(layer "In2.Cu")
		(net "PCIE_REFCLK_H0_N")
	)
	(segment
		(start 241.439446 -29.011626)
		(end 241.502946 -29.075126)
		(width 0.1016)
		(layer "In2.Cu")
		(net "PCIE_REFCLK_H0_N")
	)
	(segment
		(start 263.292082 -13.544804)
		(end 258.318 -14.421866)
		(width 0.1397)
		(layer "In2.Cu")
		(net "PCIE_REFCLK_H0_N")
	)
	(segment
		(start 255.701038 -13.960094)
		(end 251.003308 -14.788642)
		(width 0.1397)
		(layer "In2.Cu")
		(net "PCIE_REFCLK_H0_N")
	)
	(segment
		(start 269.131796 -8.589518)
		(end 268.539722 -9.181592)
		(width 0.1397)
		(layer "In2.Cu")
		(net "PCIE_REFCLK_H0_N")
	)
	(arc
		(start 241.301016 -36.9316)
		(mid 241.157915 -36.863258)
		(end 241.099848 -36.7157)
		(width 0.1016)
		(layer "In2.Cu")
		(net "PCIE_REFCLK_H0_N")
	)
	(arc
		(start 241.444018 -36.872418)
		(mid 241.378394 -36.916203)
		(end 241.301016 -36.9316)
		(width 0.1016)
		(layer "In2.Cu")
		(net "PCIE_REFCLK_H0_N")
	)
	(arc
		(start 241.502946 -36.729924)
		(mid 241.487629 -36.807019)
		(end 241.444018 -36.872418)
		(width 0.1016)
		(layer "In2.Cu")
		(net "PCIE_REFCLK_H0_N")
	)
	(segment
		(start 161.118042 -87.518494)
		(end 161.118042 -87.039958)
		(width 0.136652)
		(layer "F.Cu")
		(net "PCIE_REFCLK_D_P_R")
	)
	(segment
		(start 161.031936 -88.088978)
		(end 161.031936 -87.726266)
		(width 0.136652)
		(layer "F.Cu")
		(net "PCIE_REFCLK_D_P_R")
	)
	(segment
		(start 161.118042 -87.039958)
		(end 161.798 -86.36)
		(width 0.136652)
		(layer "F.Cu")
		(net "PCIE_REFCLK_D_P_R")
	)
	(segment
		(start 161.753804 -85.89645)
		(end 161.544 -85.6869)
		(width 0.136652)
		(layer "F.Cu")
		(net "PCIE_REFCLK_D_P_R")
	)
	(segment
		(start 161.798 -86.36)
		(end 161.809684 -86.348062)
		(width 0.136652)
		(layer "F.Cu")
		(net "PCIE_REFCLK_D_P_R")
	)
	(arc
		(start 161.8996 -86.1314)
		(mid 161.840276 -86.005501)
		(end 161.753804 -85.89645)
		(width 0.136652)
		(layer "F.Cu")
		(net "PCIE_REFCLK_D_P_R")
	)
	(arc
		(start 161.809684 -86.348062)
		(mid 161.876187 -86.248672)
		(end 161.8996 -86.1314)
		(width 0.136652)
		(layer "F.Cu")
		(net "PCIE_REFCLK_D_P_R")
	)
	(arc
		(start 161.031936 -87.726266)
		(mid 161.043165 -87.669903)
		(end 161.075116 -87.622126)
		(width 0.136652)
		(layer "F.Cu")
		(net "PCIE_REFCLK_D_P_R")
	)
	(arc
		(start 161.075116 -87.622126)
		(mid 161.106886 -87.574579)
		(end 161.118042 -87.518494)
		(width 0.136652)
		(layer "F.Cu")
		(net "PCIE_REFCLK_D_P_R")
	)
	(segment
		(start 239.599978 -37.999924)
		(end 239.100106 -37.500052)
		(width 0.136652)
		(layer "F.Cu")
		(net "PCIE_REFCLK_D_P")
	)
	(segment
		(start 161.8996 -83.528408)
		(end 162.9664 -82.461608)
		(width 0.136652)
		(layer "F.Cu")
		(net "PCIE_REFCLK_D_P")
	)
	(segment
		(start 161.8996 -84.1756)
		(end 161.8996 -83.528408)
		(width 0.136652)
		(layer "F.Cu")
		(net "PCIE_REFCLK_D_P")
	)
	(segment
		(start 162.83178 -81.792826)
		(end 162.6997 -81.661)
		(width 0.136652)
		(layer "F.Cu")
		(net "PCIE_REFCLK_D_P")
	)
	(segment
		(start 162.9664 -82.461608)
		(end 162.9664 -82.117946)
		(width 0.136652)
		(layer "F.Cu")
		(net "PCIE_REFCLK_D_P")
	)
	(segment
		(start 161.544 -84.7979)
		(end 161.711132 -84.631022)
		(width 0.136652)
		(layer "F.Cu")
		(net "PCIE_REFCLK_D_P")
	)
	(via
		(at 162.6997 -81.661)
		(size 0.508)
		(drill 0.254)
		(layers "F.Cu" "B.Cu")
		(net "PCIE_REFCLK_D_P")
	)
	(via
		(at 239.100106 -37.500052)
		(size 0.4572)
		(drill 0.2032)
		(layers "F.Cu" "B.Cu")
		(net "PCIE_REFCLK_D_P")
	)
	(arc
		(start 162.9664 -82.117946)
		(mid 162.931419 -81.941997)
		(end 162.83178 -81.792826)
		(width 0.136652)
		(layer "F.Cu")
		(net "PCIE_REFCLK_D_P")
	)
	(arc
		(start 161.711132 -84.631022)
		(mid 161.850665 -84.422058)
		(end 161.8996 -84.1756)
		(width 0.136652)
		(layer "F.Cu")
		(net "PCIE_REFCLK_D_P")
	)
	(segment
		(start 239.6236 -37.3126)
		(end 239.287558 -37.3126)
		(width 0.136652)
		(layer "B.Cu")
		(net "PCIE_REFCLK_D_P")
	)
	(segment
		(start 239.287558 -37.3126)
		(end 239.100106 -37.500052)
		(width 0.136652)
		(layer "B.Cu")
		(net "PCIE_REFCLK_D_P")
	)
	(segment
		(start 216.777824 -44.87799)
		(end 217.024458 -44.8691)
		(width 0.1397)
		(layer "In5.Cu")
		(net "PCIE_REFCLK_D_P")
	)
	(segment
		(start 203.581 -54.691534)
		(end 203.638404 -54.681628)
		(width 0.1397)
		(layer "In5.Cu")
		(net "PCIE_REFCLK_D_P")
	)
	(segment
		(start 219.960952 -44.6532)
		(end 222.963994 -44.6532)
		(width 0.1397)
		(layer "In5.Cu")
		(net "PCIE_REFCLK_D_P")
	)
	(segment
		(start 238.697008 -44.6913)
		(end 238.697008 -37.355272)
		(width 0.1016)
		(layer "In5.Cu")
		(net "PCIE_REFCLK_D_P")
	)
	(segment
		(start 223.433132 -44.8691)
		(end 223.733868 -45.169836)
		(width 0.1397)
		(layer "In5.Cu")
		(net "PCIE_REFCLK_D_P")
	)
	(segment
		(start 162.941 -82.243676)
		(end 162.941 -82.333084)
		(width 0.1397)
		(layer "In5.Cu")
		(net "PCIE_REFCLK_D_P")
	)
	(segment
		(start 205.264004 -54.394608)
		(end 206.063596 -53.834792)
		(width 0.1397)
		(layer "In5.Cu")
		(net "PCIE_REFCLK_D_P")
	)
	(segment
		(start 209.32394 -49.177956)
		(end 215.0237 -45.187362)
		(width 0.1397)
		(layer "In5.Cu")
		(net "PCIE_REFCLK_D_P")
	)
	(segment
		(start 190.559436 -80.247236)
		(end 191.979804 -78.218538)
		(width 0.1397)
		(layer "In5.Cu")
		(net "PCIE_REFCLK_D_P")
	)
	(segment
		(start 224.274888 -45.169836)
		(end 224.338388 -45.106336)
		(width 0.1016)
		(layer "In5.Cu")
		(net "PCIE_REFCLK_D_P")
	)
	(segment
		(start 200.620884 -54.169564)
		(end 203.581 -54.691534)
		(width 0.1397)
		(layer "In5.Cu")
		(net "PCIE_REFCLK_D_P")
	)
	(segment
		(start 194.7926 -57.7088)
		(end 195.965572 -56.034178)
		(width 0.1397)
		(layer "In5.Cu")
		(net "PCIE_REFCLK_D_P")
	)
	(segment
		(start 163.818316 -83.2104)
		(end 164.659564 -83.2104)
		(width 0.1397)
		(layer "In5.Cu")
		(net "PCIE_REFCLK_D_P")
	)
	(segment
		(start 224.249488 -45.169836)
		(end 224.274888 -45.169836)
		(width 0.1016)
		(layer "In5.Cu")
		(net "PCIE_REFCLK_D_P")
	)
	(segment
		(start 192.764156 -73.769982)
		(end 192.362582 -71.491348)
		(width 0.1397)
		(layer "In5.Cu")
		(net "PCIE_REFCLK_D_P")
	)
	(segment
		(start 215.0237 -45.187362)
		(end 216.777824 -44.87799)
		(width 0.1397)
		(layer "In5.Cu")
		(net "PCIE_REFCLK_D_P")
	)
	(segment
		(start 195.965572 -56.034178)
		(end 197.958202 -54.63921)
		(width 0.1397)
		(layer "In5.Cu")
		(net "PCIE_REFCLK_D_P")
	)
	(segment
		(start 197.958202 -54.63921)
		(end 200.620884 -54.169564)
		(width 0.1397)
		(layer "In5.Cu")
		(net "PCIE_REFCLK_D_P")
	)
	(segment
		(start 204.415136 -54.544214)
		(end 205.264004 -54.394608)
		(width 0.1397)
		(layer "In5.Cu")
		(net "PCIE_REFCLK_D_P")
	)
	(segment
		(start 238.408464 -45.106336)
		(end 238.4679 -45.0469)
		(width 0.1016)
		(layer "In5.Cu")
		(net "PCIE_REFCLK_D_P")
	)
	(segment
		(start 164.683694 -83.208368)
		(end 169.13098 -82.424524)
		(width 0.1397)
		(layer "In5.Cu")
		(net "PCIE_REFCLK_D_P")
	)
	(segment
		(start 239.100106 -37.203126)
		(end 239.100106 -37.500052)
		(width 0.1016)
		(layer "In5.Cu")
		(net "PCIE_REFCLK_D_P")
	)
	(segment
		(start 223.179894 -44.8691)
		(end 223.433132 -44.8691)
		(width 0.1397)
		(layer "In5.Cu")
		(net "PCIE_REFCLK_D_P")
	)
	(segment
		(start 178.158394 -84.007706)
		(end 187.555632 -82.35061)
		(width 0.1397)
		(layer "In5.Cu")
		(net "PCIE_REFCLK_D_P")
	)
	(segment
		(start 203.638404 -54.681628)
		(end 203.638404 -54.681374)
		(width 0.1397)
		(layer "In5.Cu")
		(net "PCIE_REFCLK_D_P")
	)
	(segment
		(start 238.4679 -45.0469)
		(end 238.608108 -44.906946)
		(width 0.1016)
		(layer "In5.Cu")
		(net "PCIE_REFCLK_D_P")
	)
	(segment
		(start 238.773462 -37.170868)
		(end 238.80445 -37.140134)
		(width 0.1016)
		(layer "In5.Cu")
		(net "PCIE_REFCLK_D_P")
	)
	(segment
		(start 219.745052 -44.8691)
		(end 219.960952 -44.6532)
		(width 0.1397)
		(layer "In5.Cu")
		(net "PCIE_REFCLK_D_P")
	)
	(segment
		(start 238.896906 -37.101526)
		(end 238.998506 -37.101526)
		(width 0.1016)
		(layer "In5.Cu")
		(net "PCIE_REFCLK_D_P")
	)
	(segment
		(start 206.063596 -53.834792)
		(end 209.32394 -49.177956)
		(width 0.1397)
		(layer "In5.Cu")
		(net "PCIE_REFCLK_D_P")
	)
	(segment
		(start 222.963994 -44.6532)
		(end 223.179894 -44.8691)
		(width 0.1397)
		(layer "In5.Cu")
		(net "PCIE_REFCLK_D_P")
	)
	(segment
		(start 217.024458 -44.8691)
		(end 219.745052 -44.8691)
		(width 0.1397)
		(layer "In5.Cu")
		(net "PCIE_REFCLK_D_P")
	)
	(segment
		(start 224.338388 -45.106336)
		(end 238.408464 -45.106336)
		(width 0.1016)
		(layer "In5.Cu")
		(net "PCIE_REFCLK_D_P")
	)
	(segment
		(start 223.733868 -45.169836)
		(end 224.249488 -45.169836)
		(width 0.1397)
		(layer "In5.Cu")
		(net "PCIE_REFCLK_D_P")
	)
	(segment
		(start 171.406058 -82.817208)
		(end 178.158394 -84.007706)
		(width 0.1397)
		(layer "In5.Cu")
		(net "PCIE_REFCLK_D_P")
	)
	(segment
		(start 191.979804 -78.218538)
		(end 192.764156 -73.769982)
		(width 0.1397)
		(layer "In5.Cu")
		(net "PCIE_REFCLK_D_P")
	)
	(segment
		(start 192.362582 -71.491348)
		(end 194.7926 -57.7088)
		(width 0.1397)
		(layer "In5.Cu")
		(net "PCIE_REFCLK_D_P")
	)
	(segment
		(start 169.17924 -82.424524)
		(end 171.406058 -82.817208)
		(width 0.1397)
		(layer "In5.Cu")
		(net "PCIE_REFCLK_D_P")
	)
	(segment
		(start 187.555632 -82.35061)
		(end 190.559436 -80.247236)
		(width 0.1397)
		(layer "In5.Cu")
		(net "PCIE_REFCLK_D_P")
	)
	(segment
		(start 203.638404 -54.681374)
		(end 204.415136 -54.544214)
		(width 0.1397)
		(layer "In5.Cu")
		(net "PCIE_REFCLK_D_P")
	)
	(segment
		(start 238.80445 -37.140134)
		(end 238.804704 -37.13988)
		(width 0.1016)
		(layer "In5.Cu")
		(net "PCIE_REFCLK_D_P")
	)
	(arc
		(start 238.998506 -37.101526)
		(mid 239.070348 -37.131284)
		(end 239.100106 -37.203126)
		(width 0.1016)
		(layer "In5.Cu")
		(net "PCIE_REFCLK_D_P")
	)
	(arc
		(start 238.608108 -44.906946)
		(mid 238.674027 -44.807963)
		(end 238.697008 -44.6913)
		(width 0.1016)
		(layer "In5.Cu")
		(net "PCIE_REFCLK_D_P")
	)
	(arc
		(start 238.804704 -37.13988)
		(mid 238.846992 -37.111531)
		(end 238.896906 -37.101526)
		(width 0.1016)
		(layer "In5.Cu")
		(net "PCIE_REFCLK_D_P")
	)
	(arc
		(start 169.13098 -82.424524)
		(mid 169.15511 -82.422425)
		(end 169.17924 -82.424524)
		(width 0.1397)
		(layer "In5.Cu")
		(net "PCIE_REFCLK_D_P")
	)
	(arc
		(start 238.697008 -37.355272)
		(mid 238.716948 -37.2555)
		(end 238.773462 -37.170868)
		(width 0.1016)
		(layer "In5.Cu")
		(net "PCIE_REFCLK_D_P")
	)
	(arc
		(start 162.6997 -81.661)
		(mid 162.878273 -81.928348)
		(end 162.941 -82.243676)
		(width 0.1397)
		(layer "In5.Cu")
		(net "PCIE_REFCLK_D_P")
	)
	(arc
		(start 162.941 -82.333084)
		(mid 163.007699 -82.668872)
		(end 163.197794 -82.953606)
		(width 0.1397)
		(layer "In5.Cu")
		(net "PCIE_REFCLK_D_P")
	)
	(arc
		(start 164.659564 -83.2104)
		(mid 164.671674 -83.209918)
		(end 164.683694 -83.208368)
		(width 0.1397)
		(layer "In5.Cu")
		(net "PCIE_REFCLK_D_P")
	)
	(arc
		(start 163.197794 -82.953606)
		(mid 163.482507 -83.143752)
		(end 163.818316 -83.2104)
		(width 0.1397)
		(layer "In5.Cu")
		(net "PCIE_REFCLK_D_P")
	)
	(segment
		(start 162.267138 -85.979508)
		(end 162.56 -85.6869)
		(width 0.136652)
		(layer "F.Cu")
		(net "PCIE_REFCLK_D_N_R")
	)
	(segment
		(start 161.532062 -88.088978)
		(end 161.532062 -87.771478)
		(width 0.136652)
		(layer "F.Cu")
		(net "PCIE_REFCLK_D_N_R")
	)
	(segment
		(start 161.422842 -87.16645)
		(end 162.024568 -86.564724)
		(width 0.136652)
		(layer "F.Cu")
		(net "PCIE_REFCLK_D_N_R")
	)
	(segment
		(start 161.422842 -87.511636)
		(end 161.422842 -87.16645)
		(width 0.136652)
		(layer "F.Cu")
		(net "PCIE_REFCLK_D_N_R")
	)
	(arc
		(start 161.532062 -87.771478)
		(mid 161.51787 -87.700132)
		(end 161.477452 -87.639652)
		(width 0.136652)
		(layer "F.Cu")
		(net "PCIE_REFCLK_D_N_R")
	)
	(arc
		(start 162.204146 -86.131146)
		(mid 162.220552 -86.04905)
		(end 162.267138 -85.979508)
		(width 0.136652)
		(layer "F.Cu")
		(net "PCIE_REFCLK_D_N_R")
	)
	(arc
		(start 162.024568 -86.564724)
		(mid 162.157487 -86.365797)
		(end 162.204146 -86.131146)
		(width 0.136652)
		(layer "F.Cu")
		(net "PCIE_REFCLK_D_N_R")
	)
	(arc
		(start 161.477452 -87.639652)
		(mid 161.437777 -87.580926)
		(end 161.422842 -87.511636)
		(width 0.136652)
		(layer "F.Cu")
		(net "PCIE_REFCLK_D_N_R")
	)
	(segment
		(start 163.423854 -81.749646)
		(end 163.5125 -81.661)
		(width 0.136652)
		(layer "F.Cu")
		(net "PCIE_REFCLK_D_N")
	)
	(segment
		(start 162.2044 -84.1756)
		(end 162.2044 -83.6549)
		(width 0.136652)
		(layer "F.Cu")
		(net "PCIE_REFCLK_D_N")
	)
	(segment
		(start 239.599978 -36.999926)
		(end 239.100106 -36.500054)
		(width 0.136652)
		(layer "F.Cu")
		(net "PCIE_REFCLK_D_N")
	)
	(segment
		(start 162.2044 -83.6549)
		(end 163.2712 -82.5881)
		(width 0.136652)
		(layer "F.Cu")
		(net "PCIE_REFCLK_D_N")
	)
	(segment
		(start 163.2712 -82.5881)
		(end 163.2712 -82.1182)
		(width 0.136652)
		(layer "F.Cu")
		(net "PCIE_REFCLK_D_N")
	)
	(segment
		(start 162.56 -84.7979)
		(end 162.392868 -84.631022)
		(width 0.136652)
		(layer "F.Cu")
		(net "PCIE_REFCLK_D_N")
	)
	(via
		(at 239.100106 -36.500054)
		(size 0.4572)
		(drill 0.2032)
		(layers "F.Cu" "B.Cu")
		(net "PCIE_REFCLK_D_N")
	)
	(via
		(at 163.5125 -81.661)
		(size 0.508)
		(drill 0.254)
		(layers "F.Cu" "B.Cu")
		(net "PCIE_REFCLK_D_N")
	)
	(arc
		(start 162.392868 -84.631022)
		(mid 162.253335 -84.422058)
		(end 162.2044 -84.1756)
		(width 0.136652)
		(layer "F.Cu")
		(net "PCIE_REFCLK_D_N")
	)
	(arc
		(start 163.2712 -82.1182)
		(mid 163.310875 -81.918742)
		(end 163.423854 -81.749646)
		(width 0.136652)
		(layer "F.Cu")
		(net "PCIE_REFCLK_D_N")
	)
	(segment
		(start 239.6236 -36.7538)
		(end 239.353852 -36.7538)
		(width 0.136652)
		(layer "B.Cu")
		(net "PCIE_REFCLK_D_N")
	)
	(segment
		(start 239.353852 -36.7538)
		(end 239.100106 -36.500054)
		(width 0.136652)
		(layer "B.Cu")
		(net "PCIE_REFCLK_D_N")
	)
	(segment
		(start 191.66713 -78.088998)
		(end 192.428622 -73.769982)
		(width 0.1397)
		(layer "In5.Cu")
		(net "PCIE_REFCLK_D_N")
	)
	(segment
		(start 204.357732 -54.21884)
		(end 204.357986 -54.21884)
		(width 0.1397)
		(layer "In5.Cu")
		(net "PCIE_REFCLK_D_N")
	)
	(segment
		(start 239.226344 -36.500054)
		(end 239.100106 -36.500054)
		(width 0.1016)
		(layer "In5.Cu")
		(net "PCIE_REFCLK_D_N")
	)
	(segment
		(start 217.018362 -44.5389)
		(end 219.608146 -44.5389)
		(width 0.1397)
		(layer "In5.Cu")
		(net "PCIE_REFCLK_D_N")
	)
	(segment
		(start 192.428622 -73.769982)
		(end 192.027048 -71.491348)
		(width 0.1397)
		(layer "In5.Cu")
		(net "PCIE_REFCLK_D_N")
	)
	(segment
		(start 173.713902 -82.888582)
		(end 178.158394 -83.672172)
		(width 0.1397)
		(layer "In5.Cu")
		(net "PCIE_REFCLK_D_N")
	)
	(segment
		(start 224.249488 -44.839636)
		(end 224.274888 -44.839636)
		(width 0.1016)
		(layer "In5.Cu")
		(net "PCIE_REFCLK_D_N")
	)
	(segment
		(start 204.357986 -54.21884)
		(end 205.134718 -54.081934)
		(width 0.1397)
		(layer "In5.Cu")
		(net "PCIE_REFCLK_D_N")
	)
	(segment
		(start 187.426092 -82.037936)
		(end 190.3222 -80.01)
		(width 0.1397)
		(layer "In5.Cu")
		(net "PCIE_REFCLK_D_N")
	)
	(segment
		(start 219.824046 -44.323)
		(end 223.1009 -44.323)
		(width 0.1397)
		(layer "In5.Cu")
		(net "PCIE_REFCLK_D_N")
	)
	(segment
		(start 223.570038 -44.5389)
		(end 223.870774 -44.839636)
		(width 0.1397)
		(layer "In5.Cu")
		(net "PCIE_REFCLK_D_N")
	)
	(segment
		(start 192.027048 -71.491348)
		(end 194.479926 -57.57926)
		(width 0.1397)
		(layer "In5.Cu")
		(net "PCIE_REFCLK_D_N")
	)
	(segment
		(start 205.134718 -54.081934)
		(end 205.82636 -53.597556)
		(width 0.1397)
		(layer "In5.Cu")
		(net "PCIE_REFCLK_D_N")
	)
	(segment
		(start 190.3222 -80.01)
		(end 191.66713 -78.088998)
		(width 0.1397)
		(layer "In5.Cu")
		(net "PCIE_REFCLK_D_N")
	)
	(segment
		(start 214.89416 -44.874688)
		(end 216.743026 -44.548806)
		(width 0.1397)
		(layer "In5.Cu")
		(net "PCIE_REFCLK_D_N")
	)
	(segment
		(start 216.743026 -44.548806)
		(end 217.018362 -44.5389)
		(width 0.1397)
		(layer "In5.Cu")
		(net "PCIE_REFCLK_D_N")
	)
	(segment
		(start 224.338388 -44.903136)
		(end 238.324136 -44.903136)
		(width 0.1016)
		(layer "In5.Cu")
		(net "PCIE_REFCLK_D_N")
	)
	(segment
		(start 223.1009 -44.323)
		(end 223.3168 -44.5389)
		(width 0.1397)
		(layer "In5.Cu")
		(net "PCIE_REFCLK_D_N")
	)
	(segment
		(start 219.608146 -44.5389)
		(end 219.824046 -44.323)
		(width 0.1397)
		(layer "In5.Cu")
		(net "PCIE_REFCLK_D_N")
	)
	(segment
		(start 238.629952 -37.02685)
		(end 238.661194 -36.995862)
		(width 0.1016)
		(layer "In5.Cu")
		(net "PCIE_REFCLK_D_N")
	)
	(segment
		(start 209.086704 -48.94072)
		(end 214.89416 -44.874688)
		(width 0.1397)
		(layer "In5.Cu")
		(net "PCIE_REFCLK_D_N")
	)
	(segment
		(start 195.72859 -55.796942)
		(end 197.828662 -54.326536)
		(width 0.1397)
		(layer "In5.Cu")
		(net "PCIE_REFCLK_D_N")
	)
	(segment
		(start 223.870774 -44.839636)
		(end 224.249488 -44.839636)
		(width 0.1397)
		(layer "In5.Cu")
		(net "PCIE_REFCLK_D_N")
	)
	(segment
		(start 178.158394 -83.672172)
		(end 187.426092 -82.037936)
		(width 0.1397)
		(layer "In5.Cu")
		(net "PCIE_REFCLK_D_N")
	)
	(segment
		(start 223.3168 -44.5389)
		(end 223.570038 -44.5389)
		(width 0.1397)
		(layer "In5.Cu")
		(net "PCIE_REFCLK_D_N")
	)
	(segment
		(start 203.581 -54.356)
		(end 204.357732 -54.21884)
		(width 0.1397)
		(layer "In5.Cu")
		(net "PCIE_REFCLK_D_N")
	)
	(segment
		(start 163.2712 -82.243676)
		(end 163.2712 -82.333084)
		(width 0.1397)
		(layer "In5.Cu")
		(net "PCIE_REFCLK_D_N")
	)
	(segment
		(start 224.274888 -44.839636)
		(end 224.338388 -44.903136)
		(width 0.1016)
		(layer "In5.Cu")
		(net "PCIE_REFCLK_D_N")
	)
	(segment
		(start 238.493808 -44.6913)
		(end 238.493808 -37.355272)
		(width 0.1016)
		(layer "In5.Cu")
		(net "PCIE_REFCLK_D_N")
	)
	(segment
		(start 197.828662 -54.326536)
		(end 200.620884 -53.83403)
		(width 0.1397)
		(layer "In5.Cu")
		(net "PCIE_REFCLK_D_N")
	)
	(segment
		(start 238.629698 -37.027104)
		(end 238.629952 -37.02685)
		(width 0.1016)
		(layer "In5.Cu")
		(net "PCIE_REFCLK_D_N")
	)
	(segment
		(start 164.6428 -82.8802)
		(end 169.15511 -82.084672)
		(width 0.1397)
		(layer "In5.Cu")
		(net "PCIE_REFCLK_D_N")
	)
	(segment
		(start 200.620884 -53.83403)
		(end 203.581 -54.356)
		(width 0.1397)
		(layer "In5.Cu")
		(net "PCIE_REFCLK_D_N")
	)
	(segment
		(start 238.896652 -36.898326)
		(end 239.226344 -36.898326)
		(width 0.1016)
		(layer "In5.Cu")
		(net "PCIE_REFCLK_D_N")
	)
	(segment
		(start 169.15511 -82.084672)
		(end 173.713902 -82.888582)
		(width 0.1397)
		(layer "In5.Cu")
		(net "PCIE_REFCLK_D_N")
	)
	(segment
		(start 194.479926 -57.57926)
		(end 195.72859 -55.796942)
		(width 0.1397)
		(layer "In5.Cu")
		(net "PCIE_REFCLK_D_N")
	)
	(segment
		(start 205.82636 -53.597556)
		(end 209.086704 -48.94072)
		(width 0.1397)
		(layer "In5.Cu")
		(net "PCIE_REFCLK_D_N")
	)
	(segment
		(start 163.818316 -82.8802)
		(end 164.6428 -82.8802)
		(width 0.1397)
		(layer "In5.Cu")
		(net "PCIE_REFCLK_D_N")
	)
	(segment
		(start 238.324136 -44.903136)
		(end 238.46409 -44.763182)
		(width 0.1016)
		(layer "In5.Cu")
		(net "PCIE_REFCLK_D_N")
	)
	(arc
		(start 238.661194 -36.995862)
		(mid 238.769251 -36.923757)
		(end 238.896652 -36.898326)
		(width 0.1016)
		(layer "In5.Cu")
		(net "PCIE_REFCLK_D_N")
	)
	(arc
		(start 238.46409 -44.763182)
		(mid 238.486073 -44.730188)
		(end 238.493808 -44.6913)
		(width 0.1016)
		(layer "In5.Cu")
		(net "PCIE_REFCLK_D_N")
	)
	(arc
		(start 163.5125 -81.661)
		(mid 163.333927 -81.928348)
		(end 163.2712 -82.243676)
		(width 0.1397)
		(layer "In5.Cu")
		(net "PCIE_REFCLK_D_N")
	)
	(arc
		(start 163.2712 -82.333084)
		(mid 163.312862 -82.542442)
		(end 163.431474 -82.719926)
		(width 0.1397)
		(layer "In5.Cu")
		(net "PCIE_REFCLK_D_N")
	)
	(arc
		(start 238.493808 -37.355272)
		(mid 238.529117 -37.17767)
		(end 238.629698 -37.027104)
		(width 0.1016)
		(layer "In5.Cu")
		(net "PCIE_REFCLK_D_N")
	)
	(arc
		(start 163.431474 -82.719926)
		(mid 163.608944 -82.838571)
		(end 163.818316 -82.8802)
		(width 0.1397)
		(layer "In5.Cu")
		(net "PCIE_REFCLK_D_N")
	)
	(arc
		(start 239.226344 -36.898326)
		(mid 239.42548 -36.69919)
		(end 239.226344 -36.500054)
		(width 0.1016)
		(layer "In5.Cu")
		(net "PCIE_REFCLK_D_N")
	)
	(segment
		(start 261.300214 -225.54438)
		(end 261.300214 -162.113214)
		(width 0.12065)
		(layer "F.Cu")
		(net "PCIE_MATED#_B")
	)
	(segment
		(start 20.84705 -173.52645)
		(end 21.1709 -173.2026)
		(width 0.12065)
		(layer "F.Cu")
		(net "PCIE_MATED#_B")
	)
	(segment
		(start 22.2123 -173.2026)
		(end 21.1709 -173.2026)
		(width 0.12065)
		(layer "F.Cu")
		(net "PCIE_MATED#_B")
	)
	(segment
		(start 12.8016 -169.2656)
		(end 18.2626 -174.7266)
		(width 0.12065)
		(layer "F.Cu")
		(net "PCIE_MATED#_B")
	)
	(segment
		(start 261.300214 -162.113214)
		(end 254.381 -155.194)
		(width 0.12065)
		(layer "F.Cu")
		(net "PCIE_MATED#_B")
	)
	(segment
		(start 20.84705 -174.7266)
		(end 20.84705 -173.52645)
		(width 0.12065)
		(layer "F.Cu")
		(net "PCIE_MATED#_B")
	)
	(segment
		(start 243.205 -155.194)
		(end 242.189 -154.178)
		(width 0.12065)
		(layer "F.Cu")
		(net "PCIE_MATED#_B")
	)
	(segment
		(start 12.1412 -169.2656)
		(end 12.8016 -169.2656)
		(width 0.12065)
		(layer "F.Cu")
		(net "PCIE_MATED#_B")
	)
	(segment
		(start 18.2626 -174.7266)
		(end 20.84705 -174.7266)
		(width 0.12065)
		(layer "F.Cu")
		(net "PCIE_MATED#_B")
	)
	(segment
		(start 254.381 -155.194)
		(end 243.205 -155.194)
		(width 0.12065)
		(layer "F.Cu")
		(net "PCIE_MATED#_B")
	)
	(via
		(at 12.1412 -169.2656)
		(size 0.508)
		(drill 0.254)
		(layers "F.Cu" "B.Cu")
		(net "PCIE_MATED#_B")
	)
	(via
		(at 242.189 -154.178)
		(size 0.508)
		(drill 0.254)
		(layers "F.Cu" "B.Cu")
		(net "PCIE_MATED#_B")
	)
	(via
		(at 222.314008 -158.431992)
		(size 0.7112)
		(drill 0.3556)
		(layers "F.Cu" "B.Cu")
		(net "PCIE_MATED#_B")
	)
	(segment
		(start 53.135022 -169.06875)
		(end 53.135276 -169.069004)
		(width 0.12065)
		(layer "B.Cu")
		(net "PCIE_MATED#_B")
	)
	(segment
		(start 53.125624 -169.06875)
		(end 53.135022 -169.06875)
		(width 0.12065)
		(layer "B.Cu")
		(net "PCIE_MATED#_B")
	)
	(segment
		(start 226.568 -154.178)
		(end 222.314008 -158.431992)
		(width 0.12065)
		(layer "B.Cu")
		(net "PCIE_MATED#_B")
	)
	(segment
		(start 15.877032 -169.728896)
		(end 15.877286 -169.72915)
		(width 0.12065)
		(layer "B.Cu")
		(net "PCIE_MATED#_B")
	)
	(segment
		(start 12.1412 -169.2656)
		(end 12.74826 -169.87266)
		(width 0.12065)
		(layer "B.Cu")
		(net "PCIE_MATED#_B")
	)
	(segment
		(start 14.676374 -169.72915)
		(end 14.676628 -169.728896)
		(width 0.12065)
		(layer "B.Cu")
		(net "PCIE_MATED#_B")
	)
	(segment
		(start 34.76117 -169.72915)
		(end 35.932872 -168.557448)
		(width 0.12065)
		(layer "B.Cu")
		(net "PCIE_MATED#_B")
	)
	(segment
		(start 14.0843 -169.87266)
		(end 14.22781 -169.72915)
		(width 0.12065)
		(layer "B.Cu")
		(net "PCIE_MATED#_B")
	)
	(segment
		(start 15.877286 -169.72915)
		(end 34.76117 -169.72915)
		(width 0.12065)
		(layer "B.Cu")
		(net "PCIE_MATED#_B")
	)
	(segment
		(start 53.434996 -169.069004)
		(end 53.43525 -169.06875)
		(width 0.12065)
		(layer "B.Cu")
		(net "PCIE_MATED#_B")
	)
	(segment
		(start 12.74826 -169.87266)
		(end 14.0843 -169.87266)
		(width 0.12065)
		(layer "B.Cu")
		(net "PCIE_MATED#_B")
	)
	(segment
		(start 53.43525 -169.06875)
		(end 211.67725 -169.06875)
		(width 0.12065)
		(layer "B.Cu")
		(net "PCIE_MATED#_B")
	)
	(segment
		(start 14.676628 -169.728896)
		(end 15.877032 -169.728896)
		(width 0.12065)
		(layer "B.Cu")
		(net "PCIE_MATED#_B")
	)
	(segment
		(start 53.135276 -169.069004)
		(end 53.434996 -169.069004)
		(width 0.12065)
		(layer "B.Cu")
		(net "PCIE_MATED#_B")
	)
	(segment
		(start 242.189 -154.178)
		(end 226.568 -154.178)
		(width 0.12065)
		(layer "B.Cu")
		(net "PCIE_MATED#_B")
	)
	(segment
		(start 52.614322 -168.557448)
		(end 53.125624 -169.06875)
		(width 0.12065)
		(layer "B.Cu")
		(net "PCIE_MATED#_B")
	)
	(segment
		(start 14.22781 -169.72915)
		(end 14.676374 -169.72915)
		(width 0.12065)
		(layer "B.Cu")
		(net "PCIE_MATED#_B")
	)
	(segment
		(start 35.932872 -168.557448)
		(end 52.614322 -168.557448)
		(width 0.12065)
		(layer "B.Cu")
		(net "PCIE_MATED#_B")
	)
	(segment
		(start 211.67725 -169.06875)
		(end 222.314008 -158.431992)
		(width 0.12065)
		(layer "B.Cu")
		(net "PCIE_MATED#_B")
	)
	(segment
		(start 81.28 -182.4228)
		(end 81.28 -182.9562)
		(width 0.12065)
		(layer "F.Cu")
		(net "PCIE_MATED#_A")
	)
	(segment
		(start 27.178 -176.9618)
		(end 25.71115 -175.49495)
		(width 0.12065)
		(layer "F.Cu")
		(net "PCIE_MATED#_A")
	)
	(segment
		(start 25.0063 -173.2026)
		(end 26.0223 -173.2026)
		(width 0.12065)
		(layer "F.Cu")
		(net "PCIE_MATED#_A")
	)
	(segment
		(start 27.178 -182.3212)
		(end 27.178 -176.9618)
		(width 0.12065)
		(layer "F.Cu")
		(net "PCIE_MATED#_A")
	)
	(segment
		(start 74.168 -219.883736)
		(end 74.168 -209.931)
		(width 0.12065)
		(layer "F.Cu")
		(net "PCIE_MATED#_A")
	)
	(segment
		(start 72.499982 -225.54438)
		(end 72.499982 -224.287842)
		(width 0.12065)
		(layer "F.Cu")
		(net "PCIE_MATED#_A")
	)
	(segment
		(start 25.71115 -175.49495)
		(end 24.87295 -175.49495)
		(width 0.12065)
		(layer "F.Cu")
		(net "PCIE_MATED#_A")
	)
	(segment
		(start 74.168 -209.931)
		(end 75.405488 -208.693512)
		(width 0.12065)
		(layer "F.Cu")
		(net "PCIE_MATED#_A")
	)
	(segment
		(start 72.07123 -223.85909)
		(end 72.07123 -221.980506)
		(width 0.12065)
		(layer "F.Cu")
		(net "PCIE_MATED#_A")
	)
	(segment
		(start 72.499982 -224.287842)
		(end 72.07123 -223.85909)
		(width 0.12065)
		(layer "F.Cu")
		(net "PCIE_MATED#_A")
	)
	(segment
		(start 72.07123 -221.980506)
		(end 74.168 -219.883736)
		(width 0.12065)
		(layer "F.Cu")
		(net "PCIE_MATED#_A")
	)
	(segment
		(start 84.286852 -185.963052)
		(end 84.286852 -199.812148)
		(width 0.12065)
		(layer "F.Cu")
		(net "PCIE_MATED#_A")
	)
	(segment
		(start 84.286852 -199.812148)
		(end 75.405488 -208.693512)
		(width 0.12065)
		(layer "F.Cu")
		(net "PCIE_MATED#_A")
	)
	(segment
		(start 24.87295 -175.49495)
		(end 24.40305 -175.02505)
		(width 0.12065)
		(layer "F.Cu")
		(net "PCIE_MATED#_A")
	)
	(segment
		(start 24.40305 -175.02505)
		(end 24.40305 -174.7266)
		(width 0.12065)
		(layer "F.Cu")
		(net "PCIE_MATED#_A")
	)
	(segment
		(start 25.0063 -174.12335)
		(end 24.40305 -174.7266)
		(width 0.12065)
		(layer "F.Cu")
		(net "PCIE_MATED#_A")
	)
	(segment
		(start 81.28 -182.9562)
		(end 84.286852 -185.963052)
		(width 0.12065)
		(layer "F.Cu")
		(net "PCIE_MATED#_A")
	)
	(segment
		(start 25.0063 -173.2026)
		(end 25.0063 -174.12335)
		(width 0.12065)
		(layer "F.Cu")
		(net "PCIE_MATED#_A")
	)
	(via
		(at 81.28 -182.4228)
		(size 0.508)
		(drill 0.254)
		(layers "F.Cu" "B.Cu")
		(net "PCIE_MATED#_A")
	)
	(via
		(at 75.405488 -208.693512)
		(size 0.7112)
		(drill 0.3556)
		(layers "F.Cu" "B.Cu")
		(net "PCIE_MATED#_A")
	)
	(via
		(at 27.178 -182.3212)
		(size 0.508)
		(drill 0.254)
		(layers "F.Cu" "B.Cu")
		(net "PCIE_MATED#_A")
	)
	(segment
		(start 56.2991 -170.6118)
		(end 79.4004 -170.6118)
		(width 0.127)
		(layer "In2.Cu")
		(net "PCIE_MATED#_A")
	)
	(segment
		(start 27.178 -182.3212)
		(end 36.1315 -173.3677)
		(width 0.127)
		(layer "In2.Cu")
		(net "PCIE_MATED#_A")
	)
	(segment
		(start 53.5432 -173.3677)
		(end 56.2991 -170.6118)
		(width 0.127)
		(layer "In2.Cu")
		(net "PCIE_MATED#_A")
	)
	(segment
		(start 81.28 -172.4914)
		(end 81.28 -182.4228)
		(width 0.127)
		(layer "In2.Cu")
		(net "PCIE_MATED#_A")
	)
	(segment
		(start 79.4004 -170.6118)
		(end 81.28 -172.4914)
		(width 0.127)
		(layer "In2.Cu")
		(net "PCIE_MATED#_A")
	)
	(segment
		(start 36.1315 -173.3677)
		(end 53.5432 -173.3677)
		(width 0.127)
		(layer "In2.Cu")
		(net "PCIE_MATED#_A")
	)
	(segment
		(start 160.532064 -88.088978)
		(end 160.532064 -87.3252)
		(width 0.12065)
		(layer "F.Cu")
		(net "PCIE_CLKGEN2_OE0_R")
	)
	(segment
		(start 160.532064 -87.3252)
		(end 160.7185 -87.138764)
		(width 0.12065)
		(layer "F.Cu")
		(net "PCIE_CLKGEN2_OE0_R")
	)
	(segment
		(start 160.7185 -86.622382)
		(end 160.7185 -85.8774)
		(width 0.12065)
		(layer "F.Cu")
		(net "PCIE_CLKGEN2_OE0_R")
	)
	(segment
		(start 160.7185 -85.8774)
		(end 160.528 -85.6869)
		(width 0.12065)
		(layer "F.Cu")
		(net "PCIE_CLKGEN2_OE0_R")
	)
	(segment
		(start 160.7185 -87.138764)
		(end 160.7185 -86.622382)
		(width 0.12065)
		(layer "F.Cu")
		(net "PCIE_CLKGEN2_OE0_R")
	)
	(via
		(at 160.7185 -86.622382)
		(size 0.7112)
		(drill 0.3556)
		(layers "F.Cu" "B.Cu")
		(net "PCIE_CLKGEN2_OE0_R")
	)
	(segment
		(start 160.528 -84.7979)
		(end 160.528 -83.5914)
		(width 0.12065)
		(layer "F.Cu")
		(net "PCIE_CLKGEN2_OE0")
	)
	(segment
		(start 160.528 -83.5914)
		(end 160.528 -82.3849)
		(width 0.12065)
		(layer "F.Cu")
		(net "PCIE_CLKGEN2_OE0")
	)
	(via
		(at 36.6522 -59.7916)
		(size 0.7112)
		(drill 0.3556)
		(layers "F.Cu" "B.Cu")
		(net "P5V_USB_BP1_F")
	)
	(segment
		(start 34.099754 -38.999922)
		(end 34.099754 -40.04183)
		(width 0.508)
		(layer "F.Cu")
		(net "P5V_USB")
	)
	(segment
		(start 37.58311 -42.25925)
		(end 37.94252 -42.61866)
		(width 0.508)
		(layer "F.Cu")
		(net "P5V_USB")
	)
	(segment
		(start 35.23869 -42.25925)
		(end 37.58311 -42.25925)
		(width 0.508)
		(layer "F.Cu")
		(net "P5V_USB")
	)
	(segment
		(start 34.099754 -38.999922)
		(end 35.141662 -38.999922)
		(width 0.508)
		(layer "F.Cu")
		(net "P5V_USB")
	)
	(segment
		(start 33.057846 -38.999922)
		(end 34.099754 -38.999922)
		(width 0.508)
		(layer "F.Cu")
		(net "P5V_USB")
	)
	(segment
		(start 37.94252 -42.61866)
		(end 37.94252 -43.314874)
		(width 0.508)
		(layer "F.Cu")
		(net "P5V_USB")
	)
	(segment
		(start 34.099754 -37.958014)
		(end 34.099754 -38.999922)
		(width 0.508)
		(layer "F.Cu")
		(net "P5V_USB")
	)
	(via
		(at 32.51581 -55.829962)
		(size 0.7112)
		(drill 0.3556)
		(layers "F.Cu" "B.Cu")
		(net "P5V_USB")
	)
	(segment
		(start 35.577526 -74.693526)
		(end 35.577526 -72.690482)
		(width 0.508)
		(layer "F.Cu")
		(net "P5V_STBY_LX")
	)
	(segment
		(start 36.9062 -76.7588)
		(end 36.9062 -77.8256)
		(width 0.508)
		(layer "F.Cu")
		(net "P5V_STBY_LX")
	)
	(segment
		(start 36.9062 -76.7588)
		(end 36.9062 -76.0222)
		(width 0.508)
		(layer "F.Cu")
		(net "P5V_STBY_LX")
	)
	(segment
		(start 36.9062 -76.0222)
		(end 35.577526 -74.693526)
		(width 0.508)
		(layer "F.Cu")
		(net "P5V_STBY_LX")
	)
	(via
		(at 36.9062 -76.7588)
		(size 0.7112)
		(drill 0.3556)
		(layers "F.Cu" "B.Cu")
		(net "P5V_STBY_LX")
	)
	(segment
		(start 37.719508 -76.504292)
		(end 37.719508 -77.864462)
		(width 0.3048)
		(layer "F.Cu")
		(net "P5V_STBY_LR")
	)
	(segment
		(start 37.8968 -76.327)
		(end 37.719508 -76.504292)
		(width 0.3048)
		(layer "F.Cu")
		(net "P5V_STBY_LR")
	)
	(segment
		(start 37.719 -78.503272)
		(end 37.404802 -78.81747)
		(width 0.3048)
		(layer "F.Cu")
		(net "P5V_STBY_LR")
	)
	(segment
		(start 37.404802 -78.81747)
		(end 36.437316 -78.81747)
		(width 0.3048)
		(layer "F.Cu")
		(net "P5V_STBY_LR")
	)
	(segment
		(start 37.719 -77.86497)
		(end 37.719 -78.503272)
		(width 0.3048)
		(layer "F.Cu")
		(net "P5V_STBY_LR")
	)
	(segment
		(start 32.24022 -80.191356)
		(end 31.41472 -80.191356)
		(width 0.3048)
		(layer "F.Cu")
		(net "P5V_STBY_LR")
	)
	(segment
		(start 40.554148 -69.195442)
		(end 40.554148 -69.984874)
		(width 0.3048)
		(layer "F.Cu")
		(net "P5V_STBY_LR")
	)
	(segment
		(start 36.437316 -78.81747)
		(end 35.430714 -79.824072)
		(width 0.3048)
		(layer "F.Cu")
		(net "P5V_STBY_LR")
	)
	(segment
		(start 35.430714 -79.824072)
		(end 35.080956 -79.824072)
		(width 0.3048)
		(layer "F.Cu")
		(net "P5V_STBY_LR")
	)
	(segment
		(start 35.080956 -79.824072)
		(end 34.609278 -80.29575)
		(width 0.3048)
		(layer "F.Cu")
		(net "P5V_STBY_LR")
	)
	(segment
		(start 32.55772 -79.873856)
		(end 34.187384 -79.873856)
		(width 0.3048)
		(layer "F.Cu")
		(net "P5V_STBY_LR")
	)
	(segment
		(start 39.538148 -69.195442)
		(end 39.538148 -69.98462)
		(width 0.3048)
		(layer "F.Cu")
		(net "P5V_STBY_LR")
	)
	(segment
		(start 32.55772 -79.873856)
		(end 32.24022 -80.191356)
		(width 0.3048)
		(layer "F.Cu")
		(net "P5V_STBY_LR")
	)
	(segment
		(start 37.719508 -77.864462)
		(end 37.719 -77.86497)
		(width 0.3048)
		(layer "F.Cu")
		(net "P5V_STBY_LR")
	)
	(segment
		(start 34.187384 -79.873856)
		(end 34.609278 -80.29575)
		(width 0.3048)
		(layer "F.Cu")
		(net "P5V_STBY_LR")
	)
	(via
		(at 34.609278 -80.29575)
		(size 0.7112)
		(drill 0.3556)
		(layers "F.Cu" "B.Cu")
		(net "P5V_STBY_LR")
	)
	(segment
		(start 32.62122 -79.048356)
		(end 32.55772 -78.984856)
		(width 0.254)
		(layer "F.Cu")
		(net "P5V_STBY_FB")
	)
	(segment
		(start 33.63722 -79.048356)
		(end 32.62122 -79.048356)
		(width 0.254)
		(layer "F.Cu")
		(net "P5V_STBY_FB")
	)
	(segment
		(start 30.8229 -75.7174)
		(end 30.8229 -78.075536)
		(width 0.254)
		(layer "F.Cu")
		(net "P5V_STBY_FB")
	)
	(segment
		(start 32.55772 -78.984856)
		(end 32.24022 -78.667356)
		(width 0.254)
		(layer "F.Cu")
		(net "P5V_STBY_FB")
	)
	(segment
		(start 32.24022 -78.667356)
		(end 31.41472 -78.667356)
		(width 0.254)
		(layer "F.Cu")
		(net "P5V_STBY_FB")
	)
	(segment
		(start 30.8229 -78.075536)
		(end 31.41472 -78.667356)
		(width 0.254)
		(layer "F.Cu")
		(net "P5V_STBY_FB")
	)
	(segment
		(start 30.8229 -72.0725)
		(end 30.8229 -73.025)
		(width 0.12065)
		(layer "F.Cu")
		(net "P5V_STBY_EN")
	)
	(segment
		(start 30.6578 -71.9074)
		(end 30.8229 -72.0725)
		(width 0.12065)
		(layer "F.Cu")
		(net "P5V_STBY_EN")
	)
	(segment
		(start 30.6578 -71.7296)
		(end 30.6578 -71.9074)
		(width 0.12065)
		(layer "F.Cu")
		(net "P5V_STBY_EN")
	)
	(via
		(at 29.694124 -71.943976)
		(size 0.7112)
		(drill 0.3556)
		(layers "F.Cu" "B.Cu")
		(net "P5V_STBY_EN")
	)
	(via
		(at 30.6578 -71.7296)
		(size 0.508)
		(drill 0.254)
		(layers "F.Cu" "B.Cu")
		(net "P5V_STBY_EN")
	)
	(segment
		(start 29.0449 -73.1774)
		(end 28.956 -73.0885)
		(width 0.12065)
		(layer "B.Cu")
		(net "P5V_STBY_EN")
	)
	(segment
		(start 29.2608 -72.3773)
		(end 29.2608 -72.9615)
		(width 0.12065)
		(layer "B.Cu")
		(net "P5V_STBY_EN")
	)
	(segment
		(start 28.956 -73.0885)
		(end 27.94 -73.0885)
		(width 0.12065)
		(layer "B.Cu")
		(net "P5V_STBY_EN")
	)
	(segment
		(start 30.6578 -71.7296)
		(end 29.9085 -71.7296)
		(width 0.12065)
		(layer "B.Cu")
		(net "P5V_STBY_EN")
	)
	(segment
		(start 29.2608 -72.9615)
		(end 29.0449 -73.1774)
		(width 0.12065)
		(layer "B.Cu")
		(net "P5V_STBY_EN")
	)
	(segment
		(start 29.9085 -71.7296)
		(end 29.694124 -71.943976)
		(width 0.12065)
		(layer "B.Cu")
		(net "P5V_STBY_EN")
	)
	(segment
		(start 27.94 -73.0885)
		(end 26.797 -73.0885)
		(width 0.12065)
		(layer "B.Cu")
		(net "P5V_STBY_EN")
	)
	(segment
		(start 29.694124 -71.943976)
		(end 29.2608 -72.3773)
		(width 0.12065)
		(layer "B.Cu")
		(net "P5V_STBY_EN")
	)
	(segment
		(start 34.2392 -77.8256)
		(end 34.2392 -77.0128)
		(width 0.254)
		(layer "F.Cu")
		(net "P5V_STBY_BS_RC")
	)
	(segment
		(start 35.3822 -76.9874)
		(end 35.3822 -77.8256)
		(width 0.254)
		(layer "F.Cu")
		(net "P5V_STBY_BS_RC")
	)
	(segment
		(start 34.2392 -77.0128)
		(end 34.4678 -76.7842)
		(width 0.254)
		(layer "F.Cu")
		(net "P5V_STBY_BS_RC")
	)
	(segment
		(start 34.8488 -76.7842)
		(end 35.179 -76.7842)
		(width 0.254)
		(layer "F.Cu")
		(net "P5V_STBY_BS_RC")
	)
	(segment
		(start 35.179 -76.7842)
		(end 35.3822 -76.9874)
		(width 0.254)
		(layer "F.Cu")
		(net "P5V_STBY_BS_RC")
	)
	(segment
		(start 34.4678 -76.7842)
		(end 34.8488 -76.7842)
		(width 0.254)
		(layer "F.Cu")
		(net "P5V_STBY_BS_RC")
	)
	(via
		(at 34.8488 -76.7842)
		(size 0.7112)
		(drill 0.3556)
		(layers "F.Cu" "B.Cu")
		(net "P5V_STBY_BS_RC")
	)
	(segment
		(start 32.7279 -76.3905)
		(end 31.5722 -77.5462)
		(width 0.254)
		(layer "F.Cu")
		(net "P5V_STBY_BS")
	)
	(segment
		(start 32.7152 -77.8256)
		(end 31.8516 -77.8256)
		(width 0.254)
		(layer "F.Cu")
		(net "P5V_STBY_BS")
	)
	(segment
		(start 32.7279 -75.7174)
		(end 32.7279 -76.3905)
		(width 0.254)
		(layer "F.Cu")
		(net "P5V_STBY_BS")
	)
	(segment
		(start 31.8516 -77.8256)
		(end 31.5722 -77.5462)
		(width 0.254)
		(layer "F.Cu")
		(net "P5V_STBY_BS")
	)
	(via
		(at 31.5722 -77.5462)
		(size 0.7112)
		(drill 0.3556)
		(layers "F.Cu" "B.Cu")
		(net "P5V_STBY_BS")
	)
	(segment
		(start 114.063272 -15.819628)
		(end 114.063272 -15.82039)
		(width 0.508)
		(layer "F.Cu")
		(net "P5V_STBY")
	)
	(segment
		(start 126.429008 2.196592)
		(end 119.450866 -4.78155)
		(width 0.508)
		(layer "F.Cu")
		(net "P5V_STBY")
	)
	(segment
		(start 185.048652 3.006852)
		(end 184.238392 2.196592)
		(width 0.508)
		(layer "F.Cu")
		(net "P5V_STBY")
	)
	(segment
		(start 134.51332 -97.61982)
		(end 141.866874 -97.61982)
		(width 0.508)
		(layer "F.Cu")
		(net "P5V_STBY")
	)
	(segment
		(start 119.450866 -10.432034)
		(end 114.063272 -15.819628)
		(width 0.508)
		(layer "F.Cu")
		(net "P5V_STBY")
	)
	(segment
		(start 5.261102 -106.254804)
		(end 5.261102 -106.649012)
		(width 0.508)
		(layer "F.Cu")
		(net "P5V_STBY")
	)
	(segment
		(start 114.02314 -21.26488)
		(end 106.12882 -29.1592)
		(width 0.508)
		(layer "F.Cu")
		(net "P5V_STBY")
	)
	(segment
		(start 23.76424 -99.683316)
		(end 22.073616 -97.992692)
		(width 0.508)
		(layer "F.Cu")
		(net "P5V_STBY")
	)
	(segment
		(start 184.238392 2.196592)
		(end 126.429008 2.196592)
		(width 0.508)
		(layer "F.Cu")
		(net "P5V_STBY")
	)
	(segment
		(start 5.5245 -106.91241)
		(end 5.5245 -107.696)
		(width 0.508)
		(layer "F.Cu")
		(net "P5V_STBY")
	)
	(segment
		(start 137.69848 -54.62397)
		(end 138.566906 -54.62397)
		(width 0.508)
		(layer "F.Cu")
		(net "P5V_STBY")
	)
	(segment
		(start 117.877844 -86.487)
		(end 119.881904 -88.49106)
		(width 0.508)
		(layer "F.Cu")
		(net "P5V_STBY")
	)
	(segment
		(start 46.8249 -69.804788)
		(end 46.7106 -69.690488)
		(width 0.508)
		(layer "F.Cu")
		(net "P5V_STBY")
	)
	(segment
		(start 16.071088 -102.717092)
		(end 20.795488 -97.992692)
		(width 0.508)
		(layer "F.Cu")
		(net "P5V_STBY")
	)
	(segment
		(start 190.79591 3.006852)
		(end 185.048652 3.006852)
		(width 0.508)
		(layer "F.Cu")
		(net "P5V_STBY")
	)
	(segment
		(start 210.7692 1.651)
		(end 202.722988 1.651)
		(width 0.508)
		(layer "F.Cu")
		(net "P5V_STBY")
	)
	(segment
		(start 212.9282 -0.508)
		(end 210.7692 1.651)
		(width 0.508)
		(layer "F.Cu")
		(net "P5V_STBY")
	)
	(segment
		(start 125.38456 -88.49106)
		(end 134.51332 -97.61982)
		(width 0.508)
		(layer "F.Cu")
		(net "P5V_STBY")
	)
	(segment
		(start 72.5297 -166.1033)
		(end 72.5297 -163.5506)
		(width 0.508)
		(layer "F.Cu")
		(net "P5V_STBY")
	)
	(segment
		(start 71.501 -33.9725)
		(end 72.4535 -33.9725)
		(width 0.508)
		(layer "F.Cu")
		(net "P5V_STBY")
	)
	(segment
		(start 5.261102 -104.162098)
		(end 6.706108 -102.717092)
		(width 0.508)
		(layer "F.Cu")
		(net "P5V_STBY")
	)
	(segment
		(start 114.02314 -15.860522)
		(end 114.02314 -21.26488)
		(width 0.508)
		(layer "F.Cu")
		(net "P5V_STBY")
	)
	(segment
		(start 41.3766 -61.22416)
		(end 41.3766 -62.04712)
		(width 0.508)
		(layer "F.Cu")
		(net "P5V_STBY")
	)
	(segment
		(start 82.314288 -33.9725)
		(end 72.4535 -33.9725)
		(width 0.508)
		(layer "F.Cu")
		(net "P5V_STBY")
	)
	(segment
		(start 30.166818 -82.414618)
		(end 29.8958 -82.1436)
		(width 0.508)
		(layer "F.Cu")
		(net "P5V_STBY")
	)
	(segment
		(start 46.8249 -73.525888)
		(end 46.8249 -69.804788)
		(width 0.508)
		(layer "F.Cu")
		(net "P5V_STBY")
	)
	(segment
		(start 24.186642 -99.683316)
		(end 23.76424 -99.683316)
		(width 0.508)
		(layer "F.Cu")
		(net "P5V_STBY")
	)
	(segment
		(start 39.538148 -68.585842)
		(end 39.538148 -67.675252)
		(width 0.3048)
		(layer "F.Cu")
		(net "P5V_STBY")
	)
	(segment
		(start 228.732588 -3.356864)
		(end 229.174548 -3.356864)
		(width 0.508)
		(layer "F.Cu")
		(net "P5V_STBY")
	)
	(segment
		(start 24.186642 -101.35616)
		(end 24.167592 -101.37521)
		(width 0.381)
		(layer "F.Cu")
		(net "P5V_STBY")
	)
	(segment
		(start 201.9808 2.3622)
		(end 191.440562 2.3622)
		(width 0.508)
		(layer "F.Cu")
		(net "P5V_STBY")
	)
	(segment
		(start 106.12882 -29.1592)
		(end 87.127588 -29.1592)
		(width 0.508)
		(layer "F.Cu")
		(net "P5V_STBY")
	)
	(segment
		(start 32.814006 -82.406744)
		(end 30.166818 -82.414618)
		(width 0.508)
		(layer "F.Cu")
		(net "P5V_STBY")
	)
	(segment
		(start 229.92842 -3.122676)
		(end 231.550464 -1.500632)
		(width 0.508)
		(layer "F.Cu")
		(net "P5V_STBY")
	)
	(segment
		(start 24.186642 -99.683316)
		(end 24.186642 -101.35616)
		(width 0.381)
		(layer "F.Cu")
		(net "P5V_STBY")
	)
	(segment
		(start 201.9046 0.832612)
		(end 202.707494 1.635506)
		(width 0.508)
		(layer "F.Cu")
		(net "P5V_STBY")
	)
	(segment
		(start 79.5528 -76.1746)
		(end 81.8896 -78.5114)
		(width 0.508)
		(layer "F.Cu")
		(net "P5V_STBY")
	)
	(segment
		(start 229.408736 -3.122676)
		(end 229.92842 -3.122676)
		(width 0.508)
		(layer "F.Cu")
		(net "P5V_STBY")
	)
	(segment
		(start 6.706108 -102.717092)
		(end 16.071088 -102.717092)
		(width 0.508)
		(layer "F.Cu")
		(net "P5V_STBY")
	)
	(segment
		(start 40.554148 -68.585842)
		(end 40.554148 -67.7164)
		(width 0.3048)
		(layer "F.Cu")
		(net "P5V_STBY")
	)
	(segment
		(start 41.3766 -62.04712)
		(end 41.37914 -62.04966)
		(width 0.508)
		(layer "F.Cu")
		(net "P5V_STBY")
	)
	(segment
		(start 119.881904 -88.49106)
		(end 125.38456 -88.49106)
		(width 0.508)
		(layer "F.Cu")
		(net "P5V_STBY")
	)
	(segment
		(start 5.261102 -106.649012)
		(end 5.5245 -106.91241)
		(width 0.508)
		(layer "F.Cu")
		(net "P5V_STBY")
	)
	(segment
		(start 81.8896 -78.5114)
		(end 84.2772 -78.5114)
		(width 0.508)
		(layer "F.Cu")
		(net "P5V_STBY")
	)
	(segment
		(start 202.722988 1.651)
		(end 202.707494 1.635506)
		(width 0.508)
		(layer "F.Cu")
		(net "P5V_STBY")
	)
	(segment
		(start 191.440562 2.3622)
		(end 190.79591 3.006852)
		(width 0.508)
		(layer "F.Cu")
		(net "P5V_STBY")
	)
	(segment
		(start 135.291068 -54.532276)
		(end 135.062468 -54.760876)
		(width 0.508)
		(layer "F.Cu")
		(net "P5V_STBY")
	)
	(segment
		(start 229.174548 -3.356864)
		(end 229.408736 -3.122676)
		(width 0.508)
		(layer "F.Cu")
		(net "P5V_STBY")
	)
	(segment
		(start 137.69848 -54.62397)
		(end 137.606786 -54.532276)
		(width 0.508)
		(layer "F.Cu")
		(net "P5V_STBY")
	)
	(segment
		(start 20.795488 -97.992692)
		(end 22.073616 -97.992692)
		(width 0.508)
		(layer "F.Cu")
		(net "P5V_STBY")
	)
	(segment
		(start 114.063272 -15.82039)
		(end 114.02314 -15.860522)
		(width 0.508)
		(layer "F.Cu")
		(net "P5V_STBY")
	)
	(segment
		(start 201.9046 -0.2794)
		(end 201.9046 0.832612)
		(width 0.508)
		(layer "F.Cu")
		(net "P5V_STBY")
	)
	(segment
		(start 87.127588 -29.1592)
		(end 82.314288 -33.9725)
		(width 0.508)
		(layer "F.Cu")
		(net "P5V_STBY")
	)
	(segment
		(start 228.6508 -3.275076)
		(end 228.6508 -2.4384)
		(width 0.508)
		(layer "F.Cu")
		(net "P5V_STBY")
	)
	(segment
		(start 119.450866 -4.78155)
		(end 119.450866 -10.432034)
		(width 0.508)
		(layer "F.Cu")
		(net "P5V_STBY")
	)
	(segment
		(start 72.009 -166.624)
		(end 72.5297 -166.1033)
		(width 0.508)
		(layer "F.Cu")
		(net "P5V_STBY")
	)
	(segment
		(start 138.566906 -54.62397)
		(end 138.809476 -54.86654)
		(width 0.508)
		(layer "F.Cu")
		(net "P5V_STBY")
	)
	(segment
		(start 228.732588 -3.356864)
		(end 228.6508 -3.275076)
		(width 0.508)
		(layer "F.Cu")
		(net "P5V_STBY")
	)
	(segment
		(start 202.707494 1.635506)
		(end 201.9808 2.3622)
		(width 0.508)
		(layer "F.Cu")
		(net "P5V_STBY")
	)
	(segment
		(start 59.944 -166.624)
		(end 72.009 -166.624)
		(width 0.508)
		(layer "F.Cu")
		(net "P5V_STBY")
	)
	(segment
		(start 137.606786 -54.532276)
		(end 135.291068 -54.532276)
		(width 0.508)
		(layer "F.Cu")
		(net "P5V_STBY")
	)
	(via
		(at 117.877844 -86.487)
		(size 0.508)
		(drill 0.254)
		(layers "F.Cu" "B.Cu")
		(net "P5V_STBY")
	)
	(via
		(at 39.538148 -67.675252)
		(size 0.508)
		(drill 0.254)
		(layers "F.Cu" "B.Cu")
		(net "P5V_STBY")
	)
	(via
		(at 117.877844 -73.053956)
		(size 0.508)
		(drill 0.254)
		(layers "F.Cu" "B.Cu")
		(net "P5V_STBY")
	)
	(via
		(at 40.554148 -67.7164)
		(size 0.508)
		(drill 0.254)
		(layers "F.Cu" "B.Cu")
		(net "P5V_STBY")
	)
	(via
		(at 5.261102 -106.254804)
		(size 0.508)
		(drill 0.254)
		(layers "F.Cu" "B.Cu")
		(net "P5V_STBY")
	)
	(via
		(at 202.707494 1.635506)
		(size 0.508)
		(drill 0.254)
		(layers "F.Cu" "B.Cu")
		(net "P5V_STBY")
	)
	(via
		(at 72.4535 -33.9725)
		(size 0.508)
		(drill 0.254)
		(layers "F.Cu" "B.Cu")
		(net "P5V_STBY")
	)
	(via
		(at 71.8058 -76.2254)
		(size 0.508)
		(drill 0.254)
		(layers "F.Cu" "B.Cu")
		(net "P5V_STBY")
	)
	(via
		(at 29.8958 -82.1436)
		(size 0.508)
		(drill 0.254)
		(layers "F.Cu" "B.Cu")
		(net "P5V_STBY")
	)
	(via
		(at 138.809476 -54.86654)
		(size 0.508)
		(drill 0.254)
		(layers "F.Cu" "B.Cu")
		(net "P5V_STBY")
	)
	(via
		(at 84.2772 -78.5114)
		(size 0.508)
		(drill 0.254)
		(layers "F.Cu" "B.Cu")
		(net "P5V_STBY")
	)
	(via
		(at 5.261102 -104.162098)
		(size 0.508)
		(drill 0.254)
		(layers "F.Cu" "B.Cu")
		(net "P5V_STBY")
	)
	(via
		(at 59.944 -166.624)
		(size 0.508)
		(drill 0.254)
		(layers "F.Cu" "B.Cu")
		(net "P5V_STBY")
	)
	(via
		(at 79.5528 -76.1746)
		(size 0.508)
		(drill 0.254)
		(layers "F.Cu" "B.Cu")
		(net "P5V_STBY")
	)
	(via
		(at 228.6508 -2.4384)
		(size 0.508)
		(drill 0.254)
		(layers "F.Cu" "B.Cu")
		(net "P5V_STBY")
	)
	(via
		(at 41.37914 -62.04966)
		(size 0.508)
		(drill 0.254)
		(layers "F.Cu" "B.Cu")
		(net "P5V_STBY")
	)
	(via
		(at 66.8782 -133.6802)
		(size 0.508)
		(drill 0.254)
		(layers "F.Cu" "B.Cu")
		(net "P5V_STBY")
	)
	(via
		(at 22.073616 -97.992692)
		(size 0.508)
		(drill 0.254)
		(layers "F.Cu" "B.Cu")
		(net "P5V_STBY")
	)
	(segment
		(start 202.8444 1.4986)
		(end 202.707494 1.635506)
		(width 0.508)
		(layer "B.Cu")
		(net "P5V_STBY")
	)
	(segment
		(start 58.166 -134.4295)
		(end 58.6105 -134.4295)
		(width 0.508)
		(layer "B.Cu")
		(net "P5V_STBY")
	)
	(segment
		(start 117.877844 -86.487)
		(end 117.877844 -73.053956)
		(width 0.508)
		(layer "B.Cu")
		(net "P5V_STBY")
	)
	(segment
		(start 63.810896 -134.563104)
		(end 64.6938 -133.6802)
		(width 0.508)
		(layer "B.Cu")
		(net "P5V_STBY")
	)
	(segment
		(start 224.8408 1.4986)
		(end 202.8444 1.4986)
		(width 0.508)
		(layer "B.Cu")
		(net "P5V_STBY")
	)
	(segment
		(start 228.6508 -2.4384)
		(end 228.6508 -2.3114)
		(width 0.508)
		(layer "B.Cu")
		(net "P5V_STBY")
	)
	(segment
		(start 58.744104 -134.563104)
		(end 63.810896 -134.563104)
		(width 0.508)
		(layer "B.Cu")
		(net "P5V_STBY")
	)
	(segment
		(start 58.6105 -134.4295)
		(end 58.744104 -134.563104)
		(width 0.508)
		(layer "B.Cu")
		(net "P5V_STBY")
	)
	(segment
		(start 228.6508 -2.3114)
		(end 224.8408 1.4986)
		(width 0.508)
		(layer "B.Cu")
		(net "P5V_STBY")
	)
	(segment
		(start 64.6938 -133.6802)
		(end 66.8782 -133.6802)
		(width 0.508)
		(layer "B.Cu")
		(net "P5V_STBY")
	)
	(segment
		(start 49.846992 -50.539396)
		(end 49.846992 -47.638208)
		(width 0.508)
		(layer "In2.Cu")
		(net "P5V_STBY")
	)
	(segment
		(start 45.643292 -69.690488)
		(end 46.7106 -69.690488)
		(width 0.508)
		(layer "In2.Cu")
		(net "P5V_STBY")
	)
	(segment
		(start 56.1721 -35.634422)
		(end 59.065922 -32.7406)
		(width 0.508)
		(layer "In2.Cu")
		(net "P5V_STBY")
	)
	(segment
		(start 56.1721 -41.3131)
		(end 56.1721 -35.634422)
		(width 0.508)
		(layer "In2.Cu")
		(net "P5V_STBY")
	)
	(segment
		(start 46.7106 -68.62318)
		(end 46.7106 -69.690488)
		(width 0.508)
		(layer "In2.Cu")
		(net "P5V_STBY")
	)
	(segment
		(start 71.2216 -32.7406)
		(end 72.4535 -33.9725)
		(width 0.508)
		(layer "In2.Cu")
		(net "P5V_STBY")
	)
	(segment
		(start 49.846992 -47.638208)
		(end 56.1721 -41.3131)
		(width 0.508)
		(layer "In2.Cu")
		(net "P5V_STBY")
	)
	(segment
		(start 46.7106 -69.690488)
		(end 46.7106 -70.757796)
		(width 0.508)
		(layer "In2.Cu")
		(net "P5V_STBY")
	)
	(segment
		(start 41.37914 -59.007248)
		(end 49.846992 -50.539396)
		(width 0.508)
		(layer "In2.Cu")
		(net "P5V_STBY")
	)
	(segment
		(start 41.37914 -62.04966)
		(end 41.37914 -59.007248)
		(width 0.508)
		(layer "In2.Cu")
		(net "P5V_STBY")
	)
	(segment
		(start 59.065922 -32.7406)
		(end 71.2216 -32.7406)
		(width 0.508)
		(layer "In2.Cu")
		(net "P5V_STBY")
	)
	(segment
		(start 62.844426 -135.6614)
		(end 62.844426 -146.113754)
		(width 0.508)
		(layer "In5.Cu")
		(net "P5V_STBY")
	)
	(segment
		(start 132.5118 -67.927982)
		(end 132.5118 -61.081158)
		(width 0.508)
		(layer "In5.Cu")
		(net "P5V_STBY")
	)
	(segment
		(start 22.073616 -91.209114)
		(end 22.073616 -97.992692)
		(width 0.508)
		(layer "In5.Cu")
		(net "P5V_STBY")
	)
	(segment
		(start 129.83337 -70.606412)
		(end 132.5118 -67.927982)
		(width 0.508)
		(layer "In5.Cu")
		(net "P5V_STBY")
	)
	(segment
		(start 29.8958 -82.1436)
		(end 27.7876 -84.2518)
		(width 0.508)
		(layer "In5.Cu")
		(net "P5V_STBY")
	)
	(segment
		(start 27.7876 -84.2518)
		(end 27.7876 -85.49513)
		(width 0.508)
		(layer "In5.Cu")
		(net "P5V_STBY")
	)
	(segment
		(start 67.345306 -133.213094)
		(end 67.345306 -133.184392)
		(width 0.508)
		(layer "In5.Cu")
		(net "P5V_STBY")
	)
	(segment
		(start 117.877844 -73.053956)
		(end 118.738142 -72.193658)
		(width 0.508)
		(layer "In5.Cu")
		(net "P5V_STBY")
	)
	(segment
		(start 137.574528 -55.083964)
		(end 138.592052 -55.083964)
		(width 0.508)
		(layer "In5.Cu")
		(net "P5V_STBY")
	)
	(segment
		(start 41.177718 -76.068428)
		(end 41.180004 -76.068428)
		(width 0.508)
		(layer "In5.Cu")
		(net "P5V_STBY")
	)
	(segment
		(start 70.3199 -79.8957)
		(end 71.8058 -78.4098)
		(width 0.508)
		(layer "In5.Cu")
		(net "P5V_STBY")
	)
	(segment
		(start 59.74588 -149.2123)
		(end 59.74588 -166.42588)
		(width 0.508)
		(layer "In5.Cu")
		(net "P5V_STBY")
	)
	(segment
		(start 39.538148 -68.443348)
		(end 39.538148 -67.675252)
		(width 0.508)
		(layer "In5.Cu")
		(net "P5V_STBY")
	)
	(segment
		(start 39.538148 -67.675252)
		(end 39.579296 -67.7164)
		(width 0.508)
		(layer "In5.Cu")
		(net "P5V_STBY")
	)
	(segment
		(start 69.4182 -117.602)
		(end 70.3199 -116.7003)
		(width 0.508)
		(layer "In5.Cu")
		(net "P5V_STBY")
	)
	(segment
		(start 41.65346 -76.068428)
		(end 42.869358 -76.068428)
		(width 0.508)
		(layer "In5.Cu")
		(net "P5V_STBY")
	)
	(segment
		(start 39.579296 -67.7164)
		(end 40.554148 -67.7164)
		(width 0.508)
		(layer "In5.Cu")
		(net "P5V_STBY")
	)
	(segment
		(start 29.8958 -82.1436)
		(end 31.1023 -80.9371)
		(width 0.508)
		(layer "In5.Cu")
		(net "P5V_STBY")
	)
	(segment
		(start 40.554148 -67.7164)
		(end 41.37914 -66.891408)
		(width 0.508)
		(layer "In5.Cu")
		(net "P5V_STBY")
	)
	(segment
		(start 68.909946 -130.960876)
		(end 68.909946 -129.624836)
		(width 0.508)
		(layer "In5.Cu")
		(net "P5V_STBY")
	)
	(segment
		(start 132.5118 -61.081158)
		(end 134.048754 -59.544204)
		(width 0.508)
		(layer "In5.Cu")
		(net "P5V_STBY")
	)
	(segment
		(start 134.048754 -59.544204)
		(end 134.048754 -57.988708)
		(width 0.508)
		(layer "In5.Cu")
		(net "P5V_STBY")
	)
	(segment
		(start 68.9102 -129.624582)
		(end 68.9102 -128.61036)
		(width 0.508)
		(layer "In5.Cu")
		(net "P5V_STBY")
	)
	(segment
		(start 65.9638 -134.5946)
		(end 63.911226 -134.5946)
		(width 0.508)
		(layer "In5.Cu")
		(net "P5V_STBY")
	)
	(segment
		(start 69.262244 -128.258316)
		(end 69.262244 -125.448568)
		(width 0.508)
		(layer "In5.Cu")
		(net "P5V_STBY")
	)
	(segment
		(start 41.180004 -76.068428)
		(end 41.180258 -76.068174)
		(width 0.508)
		(layer "In5.Cu")
		(net "P5V_STBY")
	)
	(segment
		(start 66.8782 -133.6802)
		(end 65.9638 -134.5946)
		(width 0.508)
		(layer "In5.Cu")
		(net "P5V_STBY")
	)
	(segment
		(start 122.874024 -72.193658)
		(end 124.46127 -70.606412)
		(width 0.508)
		(layer "In5.Cu")
		(net "P5V_STBY")
	)
	(segment
		(start 41.37914 -66.891408)
		(end 41.37914 -62.04966)
		(width 0.508)
		(layer "In5.Cu")
		(net "P5V_STBY")
	)
	(segment
		(start 62.844426 -146.113754)
		(end 59.74588 -149.2123)
		(width 0.508)
		(layer "In5.Cu")
		(net "P5V_STBY")
	)
	(segment
		(start 67.345306 -133.184392)
		(end 68.9102 -131.619498)
		(width 0.508)
		(layer "In5.Cu")
		(net "P5V_STBY")
	)
	(segment
		(start 70.3199 -116.7003)
		(end 70.3199 -79.8957)
		(width 0.508)
		(layer "In5.Cu")
		(net "P5V_STBY")
	)
	(segment
		(start 86.36 -80.5942)
		(end 90.8558 -80.5942)
		(width 0.508)
		(layer "In5.Cu")
		(net "P5V_STBY")
	)
	(segment
		(start 68.9102 -128.61036)
		(end 69.262244 -128.258316)
		(width 0.508)
		(layer "In5.Cu")
		(net "P5V_STBY")
	)
	(segment
		(start 134.048754 -57.988708)
		(end 136.109202 -55.92826)
		(width 0.508)
		(layer "In5.Cu")
		(net "P5V_STBY")
	)
	(segment
		(start 136.109202 -55.92826)
		(end 136.730232 -55.92826)
		(width 0.508)
		(layer "In5.Cu")
		(net "P5V_STBY")
	)
	(segment
		(start 69.262244 -125.448568)
		(end 70.358 -124.352812)
		(width 0.508)
		(layer "In5.Cu")
		(net "P5V_STBY")
	)
	(segment
		(start 41.653206 -76.068174)
		(end 41.65346 -76.068428)
		(width 0.508)
		(layer "In5.Cu")
		(net "P5V_STBY")
	)
	(segment
		(start 59.74588 -166.42588)
		(end 59.944 -166.624)
		(width 0.508)
		(layer "In5.Cu")
		(net "P5V_STBY")
	)
	(segment
		(start 136.730232 -55.92826)
		(end 137.574528 -55.083964)
		(width 0.508)
		(layer "In5.Cu")
		(net "P5V_STBY")
	)
	(segment
		(start 68.9102 -131.619498)
		(end 68.9102 -130.96113)
		(width 0.508)
		(layer "In5.Cu")
		(net "P5V_STBY")
	)
	(segment
		(start 68.9102 -130.96113)
		(end 68.909946 -130.960876)
		(width 0.508)
		(layer "In5.Cu")
		(net "P5V_STBY")
	)
	(segment
		(start 124.46127 -70.606412)
		(end 129.83337 -70.606412)
		(width 0.508)
		(layer "In5.Cu")
		(net "P5V_STBY")
	)
	(segment
		(start 90.8558 -80.5942)
		(end 96.7486 -86.487)
		(width 0.508)
		(layer "In5.Cu")
		(net "P5V_STBY")
	)
	(segment
		(start 42.869358 -76.068428)
		(end 43.2562 -75.681586)
		(width 0.508)
		(layer "In5.Cu")
		(net "P5V_STBY")
	)
	(segment
		(start 5.261102 -104.162098)
		(end 5.261102 -106.254804)
		(width 0.508)
		(layer "In5.Cu")
		(net "P5V_STBY")
	)
	(segment
		(start 68.909946 -129.624836)
		(end 68.9102 -129.624582)
		(width 0.508)
		(layer "In5.Cu")
		(net "P5V_STBY")
	)
	(segment
		(start 70.358 -119.907812)
		(end 69.4182 -118.968012)
		(width 0.508)
		(layer "In5.Cu")
		(net "P5V_STBY")
	)
	(segment
		(start 27.7876 -85.49513)
		(end 22.073616 -91.209114)
		(width 0.508)
		(layer "In5.Cu")
		(net "P5V_STBY")
	)
	(segment
		(start 66.8782 -133.6802)
		(end 67.345306 -133.213094)
		(width 0.508)
		(layer "In5.Cu")
		(net "P5V_STBY")
	)
	(segment
		(start 138.592052 -55.083964)
		(end 138.809476 -54.86654)
		(width 0.508)
		(layer "In5.Cu")
		(net "P5V_STBY")
	)
	(segment
		(start 43.2562 -72.1614)
		(end 39.538148 -68.443348)
		(width 0.508)
		(layer "In5.Cu")
		(net "P5V_STBY")
	)
	(segment
		(start 36.309046 -80.9371)
		(end 41.177718 -76.068428)
		(width 0.508)
		(layer "In5.Cu")
		(net "P5V_STBY")
	)
	(segment
		(start 31.1023 -80.9371)
		(end 36.309046 -80.9371)
		(width 0.508)
		(layer "In5.Cu")
		(net "P5V_STBY")
	)
	(segment
		(start 69.4182 -118.968012)
		(end 69.4182 -117.602)
		(width 0.508)
		(layer "In5.Cu")
		(net "P5V_STBY")
	)
	(segment
		(start 71.8058 -78.4098)
		(end 71.8058 -76.2254)
		(width 0.508)
		(layer "In5.Cu")
		(net "P5V_STBY")
	)
	(segment
		(start 96.7486 -86.487)
		(end 117.877844 -86.487)
		(width 0.508)
		(layer "In5.Cu")
		(net "P5V_STBY")
	)
	(segment
		(start 118.738142 -72.193658)
		(end 122.874024 -72.193658)
		(width 0.508)
		(layer "In5.Cu")
		(net "P5V_STBY")
	)
	(segment
		(start 84.2772 -78.5114)
		(end 86.36 -80.5942)
		(width 0.508)
		(layer "In5.Cu")
		(net "P5V_STBY")
	)
	(segment
		(start 63.911226 -134.5946)
		(end 62.844426 -135.6614)
		(width 0.508)
		(layer "In5.Cu")
		(net "P5V_STBY")
	)
	(segment
		(start 43.2562 -75.681586)
		(end 43.2562 -72.1614)
		(width 0.508)
		(layer "In5.Cu")
		(net "P5V_STBY")
	)
	(segment
		(start 41.180258 -76.068174)
		(end 41.653206 -76.068174)
		(width 0.508)
		(layer "In5.Cu")
		(net "P5V_STBY")
	)
	(segment
		(start 70.358 -124.352812)
		(end 70.358 -119.907812)
		(width 0.508)
		(layer "In5.Cu")
		(net "P5V_STBY")
	)
	(segment
		(start 59.37758 -38.061138)
		(end 59.37758 -38.838886)
		(width 0.254)
		(layer "F.Cu")
		(net "P3V3_STBY_VREG")
	)
	(segment
		(start 60.8584 -38.0111)
		(end 60.955174 -38.107874)
		(width 0.254)
		(layer "F.Cu")
		(net "P3V3_STBY_VREG")
	)
	(segment
		(start 59.81827 -37.620448)
		(end 59.37758 -38.061138)
		(width 0.254)
		(layer "F.Cu")
		(net "P3V3_STBY_VREG")
	)
	(segment
		(start 60.208922 -38.0111)
		(end 59.81827 -37.620448)
		(width 0.254)
		(layer "F.Cu")
		(net "P3V3_STBY_VREG")
	)
	(segment
		(start 60.8584 -38.0111)
		(end 60.208922 -38.0111)
		(width 0.254)
		(layer "F.Cu")
		(net "P3V3_STBY_VREG")
	)
	(segment
		(start 60.955174 -38.107874)
		(end 63.463678 -38.107874)
		(width 0.254)
		(layer "F.Cu")
		(net "P3V3_STBY_VREG")
	)
	(via
		(at 59.37758 -38.838886)
		(size 0.7112)
		(drill 0.3556)
		(layers "F.Cu" "B.Cu")
		(net "P3V3_STBY_VREG")
	)
	(via
		(at 60.833 -40.767)
		(size 0.7112)
		(drill 0.3556)
		(layers "F.Cu" "B.Cu")
		(net "P3V3_STBY_VIN")
	)
	(via
		(at 61.722 -47.244)
		(size 0.7112)
		(drill 0.4064)
		(layers "F.Cu" "B.Cu")
		(net "P3V3_STBY_VIN")
	)
	(via
		(at 61.722 -44.831)
		(size 0.7112)
		(drill 0.4064)
		(layers "F.Cu" "B.Cu")
		(net "P3V3_STBY_VIN")
	)
	(via
		(at 61.722 -45.974)
		(size 0.7112)
		(drill 0.4064)
		(layers "F.Cu" "B.Cu")
		(net "P3V3_STBY_VIN")
	)
	(via
		(at 61.849 -39.878)
		(size 0.7112)
		(drill 0.4064)
		(layers "F.Cu" "B.Cu")
		(net "P3V3_STBY_VIN")
	)
	(via
		(at 61.849 -41.148)
		(size 0.7112)
		(drill 0.4064)
		(layers "F.Cu" "B.Cu")
		(net "P3V3_STBY_VIN")
	)
	(via
		(at 61.849 -42.291)
		(size 0.7112)
		(drill 0.4064)
		(layers "F.Cu" "B.Cu")
		(net "P3V3_STBY_VIN")
	)
	(segment
		(start 72.644 -31.33852)
		(end 72.24268 -30.9372)
		(width 0.254)
		(layer "F.Cu")
		(net "P3V3_STBY_VFB_R")
	)
	(segment
		(start 72.24268 -30.9372)
		(end 71.4883 -30.9372)
		(width 0.254)
		(layer "F.Cu")
		(net "P3V3_STBY_VFB_R")
	)
	(segment
		(start 72.644 -32.004)
		(end 72.644 -31.33852)
		(width 0.254)
		(layer "F.Cu")
		(net "P3V3_STBY_VFB_R")
	)
	(segment
		(start 71.4883 -30.9372)
		(end 71.4375 -30.988)
		(width 0.254)
		(layer "F.Cu")
		(net "P3V3_STBY_VFB_R")
	)
	(segment
		(start 71.4375 -32.004)
		(end 71.4375 -30.988)
		(width 0.254)
		(layer "F.Cu")
		(net "P3V3_STBY_VFB_R")
	)
	(segment
		(start 68.362322 -36.107878)
		(end 68.362322 -34.515044)
		(width 0.254)
		(layer "F.Cu")
		(net "P3V3_STBY_VFB")
	)
	(segment
		(start 70.5485 -32.004)
		(end 70.5485 -33.02)
		(width 0.254)
		(layer "F.Cu")
		(net "P3V3_STBY_VFB")
	)
	(segment
		(start 70.5485 -30.988)
		(end 70.5485 -32.004)
		(width 0.254)
		(layer "F.Cu")
		(net "P3V3_STBY_VFB")
	)
	(segment
		(start 69.857366 -33.02)
		(end 70.5485 -33.02)
		(width 0.254)
		(layer "F.Cu")
		(net "P3V3_STBY_VFB")
	)
	(segment
		(start 68.362322 -34.515044)
		(end 69.857366 -33.02)
		(width 0.254)
		(layer "F.Cu")
		(net "P3V3_STBY_VFB")
	)
	(segment
		(start 69.4055 -32.004)
		(end 70.5485 -32.004)
		(width 0.254)
		(layer "F.Cu")
		(net "P3V3_STBY_VFB")
	)
	(segment
		(start 61.992002 -37.608002)
		(end 61.849 -37.465)
		(width 0.3048)
		(layer "F.Cu")
		(net "P3V3_STBY_VDD")
	)
	(segment
		(start 63.463678 -37.608002)
		(end 61.992002 -37.608002)
		(width 0.3048)
		(layer "F.Cu")
		(net "P3V3_STBY_VDD")
	)
	(via
		(at 60.071 -37.465)
		(size 0.7112)
		(drill 0.3556)
		(layers "F.Cu" "B.Cu")
		(net "P3V3_STBY_VDD")
	)
	(via
		(at 61.849 -37.465)
		(size 0.508)
		(drill 0.254)
		(layers "F.Cu" "B.Cu")
		(net "P3V3_STBY_VDD")
	)
	(segment
		(start 58.7502 -37.465)
		(end 60.071 -37.465)
		(width 0.508)
		(layer "B.Cu")
		(net "P3V3_STBY_VDD")
	)
	(segment
		(start 58.039 -38.1762)
		(end 58.7502 -37.465)
		(width 0.508)
		(layer "B.Cu")
		(net "P3V3_STBY_VDD")
	)
	(segment
		(start 60.071 -37.465)
		(end 61.849 -37.465)
		(width 0.508)
		(layer "B.Cu")
		(net "P3V3_STBY_VDD")
	)
	(segment
		(start 58.039 -38.1762)
		(end 58.039 -39.624)
		(width 0.508)
		(layer "B.Cu")
		(net "P3V3_STBY_VDD")
	)
	(segment
		(start 71.755 -36.3982)
		(end 71.7042 -36.449)
		(width 0.254)
		(layer "B.Cu")
		(net "P3V3_STBY_VBST_RC")
	)
	(segment
		(start 71.7042 -36.449)
		(end 71.7042 -37.2618)
		(width 0.254)
		(layer "B.Cu")
		(net "P3V3_STBY_VBST_RC")
	)
	(segment
		(start 71.7042 -37.2618)
		(end 71.1454 -37.8206)
		(width 0.254)
		(layer "B.Cu")
		(net "P3V3_STBY_VBST_RC")
	)
	(segment
		(start 69.723 -37.465)
		(end 69.85 -37.465)
		(width 0.254)
		(layer "F.Cu")
		(net "P3V3_STBY_VBST")
	)
	(segment
		(start 69.579998 -37.608002)
		(end 69.723 -37.465)
		(width 0.254)
		(layer "F.Cu")
		(net "P3V3_STBY_VBST")
	)
	(segment
		(start 68.362322 -37.608002)
		(end 69.579998 -37.608002)
		(width 0.254)
		(layer "F.Cu")
		(net "P3V3_STBY_VBST")
	)
	(via
		(at 69.85 -37.465)
		(size 0.508)
		(drill 0.254)
		(layers "F.Cu" "B.Cu")
		(net "P3V3_STBY_VBST")
	)
	(segment
		(start 70.231 -37.084)
		(end 69.85 -37.465)
		(width 0.254)
		(layer "B.Cu")
		(net "P3V3_STBY_VBST")
	)
	(segment
		(start 70.231 -36.3982)
		(end 70.231 -37.084)
		(width 0.254)
		(layer "B.Cu")
		(net "P3V3_STBY_VBST")
	)
	(segment
		(start 61.722 -35.507422)
		(end 62.822582 -36.608004)
		(width 0.254)
		(layer "F.Cu")
		(net "P3V3_STBY_TRIP")
	)
	(segment
		(start 62.822582 -36.608004)
		(end 63.463678 -36.608004)
		(width 0.254)
		(layer "F.Cu")
		(net "P3V3_STBY_TRIP")
	)
	(segment
		(start 61.629036 -34.22904)
		(end 61.722 -34.322004)
		(width 0.254)
		(layer "F.Cu")
		(net "P3V3_STBY_TRIP")
	)
	(segment
		(start 61.722 -34.322004)
		(end 61.722 -35.306)
		(width 0.254)
		(layer "F.Cu")
		(net "P3V3_STBY_TRIP")
	)
	(segment
		(start 61.722 -35.306)
		(end 61.722 -35.507422)
		(width 0.254)
		(layer "F.Cu")
		(net "P3V3_STBY_TRIP")
	)
	(via
		(at 61.629036 -34.22904)
		(size 0.7112)
		(drill 0.3556)
		(layers "F.Cu" "B.Cu")
		(net "P3V3_STBY_TRIP")
	)
	(via
		(at 61.722 -35.306)
		(size 0.508)
		(drill 0.254)
		(layers "F.Cu" "B.Cu")
		(net "P3V3_STBY_TRIP")
	)
	(segment
		(start 61.341 -34.4805)
		(end 61.341 -34.925)
		(width 0.254)
		(layer "B.Cu")
		(net "P3V3_STBY_TRIP")
	)
	(segment
		(start 61.341 -34.925)
		(end 61.722 -35.306)
		(width 0.254)
		(layer "B.Cu")
		(net "P3V3_STBY_TRIP")
	)
	(segment
		(start 69.9262 -41.125902)
		(end 70.1548 -40.897302)
		(width 0.254)
		(layer "B.Cu")
		(net "P3V3_STBY_SNB")
	)
	(segment
		(start 70.1548 -40.897302)
		(end 70.1548 -40.6146)
		(width 0.254)
		(layer "B.Cu")
		(net "P3V3_STBY_SNB")
	)
	(segment
		(start 69.9262 -42.164)
		(end 69.9262 -41.125902)
		(width 0.254)
		(layer "B.Cu")
		(net "P3V3_STBY_SNB")
	)
	(segment
		(start 70.5866 -37.9349)
		(end 70.413626 -38.107874)
		(width 0.254)
		(layer "F.Cu")
		(net "P3V3_STBY_ROVP")
	)
	(segment
		(start 71.1327 -37.9349)
		(end 70.5866 -37.9349)
		(width 0.254)
		(layer "F.Cu")
		(net "P3V3_STBY_ROVP")
	)
	(segment
		(start 72.46366 -37.9349)
		(end 71.1327 -37.9349)
		(width 0.254)
		(layer "F.Cu")
		(net "P3V3_STBY_ROVP")
	)
	(segment
		(start 70.413626 -38.107874)
		(end 68.362322 -38.107874)
		(width 0.254)
		(layer "F.Cu")
		(net "P3V3_STBY_ROVP")
	)
	(via
		(at 71.1327 -37.9349)
		(size 0.7112)
		(drill 0.3556)
		(layers "F.Cu" "B.Cu")
		(net "P3V3_STBY_ROVP")
	)
	(segment
		(start 62.611 -35.306)
		(end 62.611 -33.820862)
		(width 0.254)
		(layer "F.Cu")
		(net "P3V3_STBY_RF")
	)
	(segment
		(start 58.74258 -36.444428)
		(end 59.0296 -36.731448)
		(width 0.254)
		(layer "F.Cu")
		(net "P3V3_STBY_RF")
	)
	(segment
		(start 62.611 -35.433)
		(end 63.285878 -36.107878)
		(width 0.254)
		(layer "F.Cu")
		(net "P3V3_STBY_RF")
	)
	(segment
		(start 62.611 -33.820862)
		(end 62.14237 -33.352232)
		(width 0.254)
		(layer "F.Cu")
		(net "P3V3_STBY_RF")
	)
	(segment
		(start 58.74258 -34.61004)
		(end 58.74258 -35.78352)
		(width 0.254)
		(layer "F.Cu")
		(net "P3V3_STBY_RF")
	)
	(segment
		(start 60.000388 -33.352232)
		(end 58.74258 -34.61004)
		(width 0.254)
		(layer "F.Cu")
		(net "P3V3_STBY_RF")
	)
	(segment
		(start 62.14237 -33.352232)
		(end 60.000388 -33.352232)
		(width 0.254)
		(layer "F.Cu")
		(net "P3V3_STBY_RF")
	)
	(segment
		(start 63.285878 -36.107878)
		(end 63.463678 -36.107878)
		(width 0.254)
		(layer "F.Cu")
		(net "P3V3_STBY_RF")
	)
	(segment
		(start 58.74258 -35.78352)
		(end 58.74258 -36.444428)
		(width 0.254)
		(layer "F.Cu")
		(net "P3V3_STBY_RF")
	)
	(segment
		(start 59.0296 -36.731448)
		(end 59.81827 -36.731448)
		(width 0.254)
		(layer "F.Cu")
		(net "P3V3_STBY_RF")
	)
	(segment
		(start 62.611 -35.306)
		(end 62.611 -35.433)
		(width 0.254)
		(layer "F.Cu")
		(net "P3V3_STBY_RF")
	)
	(via
		(at 58.74258 -35.78352)
		(size 0.7112)
		(drill 0.3556)
		(layers "F.Cu" "B.Cu")
		(net "P3V3_STBY_RF")
	)
	(via
		(at 62.611 -35.306)
		(size 0.508)
		(drill 0.254)
		(layers "F.Cu" "B.Cu")
		(net "P3V3_STBY_RF")
	)
	(segment
		(start 62.357 -34.4805)
		(end 62.357 -35.052)
		(width 0.254)
		(layer "B.Cu")
		(net "P3V3_STBY_RF")
	)
	(segment
		(start 62.357 -35.052)
		(end 62.611 -35.306)
		(width 0.254)
		(layer "B.Cu")
		(net "P3V3_STBY_RF")
	)
	(segment
		(start 59.944 -35.433)
		(end 59.309 -34.798)
		(width 0.12065)
		(layer "F.Cu")
		(net "P3V3_STBY_PG")
	)
	(segment
		(start 131.40817 -49.97577)
		(end 128.509268 -49.97577)
		(width 0.12065)
		(layer "F.Cu")
		(net "P3V3_STBY_PG")
	)
	(segment
		(start 114.971068 -55.014876)
		(end 113.331244 -53.375052)
		(width 0.12065)
		(layer "F.Cu")
		(net "P3V3_STBY_PG")
	)
	(segment
		(start 98.536506 -53.375052)
		(end 94.5388 -49.377346)
		(width 0.12065)
		(layer "F.Cu")
		(net "P3V3_STBY_PG")
	)
	(segment
		(start 127.562864 -51.4477)
		(end 127.117094 -51.89347)
		(width 0.12065)
		(layer "F.Cu")
		(net "P3V3_STBY_PG")
	)
	(segment
		(start 71.0819 -36.4236)
		(end 70.5485 -36.957)
		(width 0.12065)
		(layer "F.Cu")
		(net "P3V3_STBY_PG")
	)
	(segment
		(start 140.878814 -72.97674)
		(end 140.878814 -53.870352)
		(width 0.12065)
		(layer "F.Cu")
		(net "P3V3_STBY_PG")
	)
	(segment
		(start 113.331244 -53.375052)
		(end 98.536506 -53.375052)
		(width 0.12065)
		(layer "F.Cu")
		(net "P3V3_STBY_PG")
	)
	(segment
		(start 133.153658 -51.721258)
		(end 131.40817 -49.97577)
		(width 0.12065)
		(layer "F.Cu")
		(net "P3V3_STBY_PG")
	)
	(segment
		(start 72.328532 -35.372548)
		(end 72.24776 -35.45332)
		(width 0.12065)
		(layer "F.Cu")
		(net "P3V3_STBY_PG")
	)
	(segment
		(start 60.0075 -35.433)
		(end 59.944 -35.433)
		(width 0.12065)
		(layer "F.Cu")
		(net "P3V3_STBY_PG")
	)
	(segment
		(start 138.445748 -87.512652)
		(end 138.445748 -77.851762)
		(width 0.12065)
		(layer "F.Cu")
		(net "P3V3_STBY_PG")
	)
	(segment
		(start 128.509268 -49.97577)
		(end 127.562864 -50.922174)
		(width 0.12065)
		(layer "F.Cu")
		(net "P3V3_STBY_PG")
	)
	(segment
		(start 55.67045 -33.12795)
		(end 55.9562 -32.8422)
		(width 0.12065)
		(layer "F.Cu")
		(net "P3V3_STBY_PG")
	)
	(segment
		(start 141.303248 -74.994262)
		(end 141.303248 -73.401174)
		(width 0.12065)
		(layer "F.Cu")
		(net "P3V3_STBY_PG")
	)
	(segment
		(start 137.5156 -93.61932)
		(end 137.5156 -88.4428)
		(width 0.12065)
		(layer "F.Cu")
		(net "P3V3_STBY_PG")
	)
	(segment
		(start 141.303248 -73.401174)
		(end 140.878814 -72.97674)
		(width 0.12065)
		(layer "F.Cu")
		(net "P3V3_STBY_PG")
	)
	(segment
		(start 72.24776 -35.45332)
		(end 71.27748 -36.4236)
		(width 0.12065)
		(layer "F.Cu")
		(net "P3V3_STBY_PG")
	)
	(segment
		(start 123.468638 -55.014876)
		(end 114.971068 -55.014876)
		(width 0.12065)
		(layer "F.Cu")
		(net "P3V3_STBY_PG")
	)
	(segment
		(start 88.028526 -35.372548)
		(end 72.328532 -35.372548)
		(width 0.12065)
		(layer "F.Cu")
		(net "P3V3_STBY_PG")
	)
	(segment
		(start 69.5833 -36.998148)
		(end 70.507352 -36.998148)
		(width 0.12065)
		(layer "F.Cu")
		(net "P3V3_STBY_PG")
	)
	(segment
		(start 127.562864 -50.922174)
		(end 127.562864 -51.4477)
		(width 0.12065)
		(layer "F.Cu")
		(net "P3V3_STBY_PG")
	)
	(segment
		(start 54.256178 -33.12795)
		(end 55.67045 -33.12795)
		(width 0.12065)
		(layer "F.Cu")
		(net "P3V3_STBY_PG")
	)
	(segment
		(start 70.507352 -36.998148)
		(end 70.5485 -36.957)
		(width 0.12065)
		(layer "F.Cu")
		(net "P3V3_STBY_PG")
	)
	(segment
		(start 94.5388 -41.882822)
		(end 88.028526 -35.372548)
		(width 0.12065)
		(layer "F.Cu")
		(net "P3V3_STBY_PG")
	)
	(segment
		(start 68.362322 -37.107876)
		(end 69.473572 -37.107876)
		(width 0.12065)
		(layer "F.Cu")
		(net "P3V3_STBY_PG")
	)
	(segment
		(start 138.72972 -51.721258)
		(end 133.153658 -51.721258)
		(width 0.12065)
		(layer "F.Cu")
		(net "P3V3_STBY_PG")
	)
	(segment
		(start 140.878814 -53.870352)
		(end 138.72972 -51.721258)
		(width 0.12065)
		(layer "F.Cu")
		(net "P3V3_STBY_PG")
	)
	(segment
		(start 127.117094 -51.89347)
		(end 126.590044 -51.89347)
		(width 0.12065)
		(layer "F.Cu")
		(net "P3V3_STBY_PG")
	)
	(segment
		(start 94.5388 -49.377346)
		(end 94.5388 -41.882822)
		(width 0.12065)
		(layer "F.Cu")
		(net "P3V3_STBY_PG")
	)
	(segment
		(start 71.27748 -36.4236)
		(end 71.0819 -36.4236)
		(width 0.12065)
		(layer "F.Cu")
		(net "P3V3_STBY_PG")
	)
	(segment
		(start 126.590044 -51.89347)
		(end 123.468638 -55.014876)
		(width 0.12065)
		(layer "F.Cu")
		(net "P3V3_STBY_PG")
	)
	(segment
		(start 137.5156 -88.4428)
		(end 138.445748 -87.512652)
		(width 0.12065)
		(layer "F.Cu")
		(net "P3V3_STBY_PG")
	)
	(segment
		(start 137.5156 -93.61932)
		(end 139.326874 -93.61932)
		(width 0.12065)
		(layer "F.Cu")
		(net "P3V3_STBY_PG")
	)
	(segment
		(start 69.473572 -37.107876)
		(end 69.5833 -36.998148)
		(width 0.12065)
		(layer "F.Cu")
		(net "P3V3_STBY_PG")
	)
	(segment
		(start 138.445748 -77.851762)
		(end 141.303248 -74.994262)
		(width 0.12065)
		(layer "F.Cu")
		(net "P3V3_STBY_PG")
	)
	(via
		(at 59.309 -34.798)
		(size 0.508)
		(drill 0.254)
		(layers "F.Cu" "B.Cu")
		(net "P3V3_STBY_PG")
	)
	(via
		(at 55.9562 -32.8422)
		(size 0.508)
		(drill 0.254)
		(layers "F.Cu" "B.Cu")
		(net "P3V3_STBY_PG")
	)
	(via
		(at 137.5156 -93.61932)
		(size 0.7112)
		(drill 0.3556)
		(layers "F.Cu" "B.Cu")
		(net "P3V3_STBY_PG")
	)
	(via
		(at 72.24776 -35.45332)
		(size 0.508)
		(drill 0.254)
		(layers "F.Cu" "B.Cu")
		(net "P3V3_STBY_PG")
	)
	(segment
		(start 72.02424 -35.2298)
		(end 71.607172 -35.2298)
		(width 0.127)
		(layer "In2.Cu")
		(net "P3V3_STBY_PG")
	)
	(segment
		(start 72.24776 -35.45332)
		(end 72.02424 -35.2298)
		(width 0.127)
		(layer "In2.Cu")
		(net "P3V3_STBY_PG")
	)
	(segment
		(start 70.984872 -34.6075)
		(end 59.4995 -34.6075)
		(width 0.127)
		(layer "In2.Cu")
		(net "P3V3_STBY_PG")
	)
	(segment
		(start 71.607172 -35.2298)
		(end 70.984872 -34.6075)
		(width 0.127)
		(layer "In2.Cu")
		(net "P3V3_STBY_PG")
	)
	(segment
		(start 59.4995 -34.6075)
		(end 59.309 -34.798)
		(width 0.127)
		(layer "In2.Cu")
		(net "P3V3_STBY_PG")
	)
	(segment
		(start 59.309 -34.798)
		(end 57.84342 -33.33242)
		(width 0.127)
		(layer "In5.Cu")
		(net "P3V3_STBY_PG")
	)
	(segment
		(start 57.3151 -33.1724)
		(end 56.2864 -33.1724)
		(width 0.127)
		(layer "In5.Cu")
		(net "P3V3_STBY_PG")
	)
	(segment
		(start 57.84342 -33.33242)
		(end 57.47512 -33.33242)
		(width 0.127)
		(layer "In5.Cu")
		(net "P3V3_STBY_PG")
	)
	(segment
		(start 57.47512 -33.33242)
		(end 57.3151 -33.1724)
		(width 0.127)
		(layer "In5.Cu")
		(net "P3V3_STBY_PG")
	)
	(segment
		(start 56.2864 -33.1724)
		(end 55.9562 -32.8422)
		(width 0.127)
		(layer "In5.Cu")
		(net "P3V3_STBY_PG")
	)
	(segment
		(start 63.463678 -37.107876)
		(end 62.568074 -37.107876)
		(width 0.254)
		(layer "F.Cu")
		(net "P3V3_STBY_MODE")
	)
	(segment
		(start 61.878972 -36.418774)
		(end 61.188346 -35.728148)
		(width 0.254)
		(layer "F.Cu")
		(net "P3V3_STBY_MODE")
	)
	(segment
		(start 61.188346 -35.724846)
		(end 60.8965 -35.433)
		(width 0.254)
		(layer "F.Cu")
		(net "P3V3_STBY_MODE")
	)
	(segment
		(start 61.188346 -35.728148)
		(end 61.188346 -35.724846)
		(width 0.254)
		(layer "F.Cu")
		(net "P3V3_STBY_MODE")
	)
	(segment
		(start 62.568074 -37.107876)
		(end 61.878972 -36.418774)
		(width 0.254)
		(layer "F.Cu")
		(net "P3V3_STBY_MODE")
	)
	(via
		(at 61.878972 -36.418774)
		(size 0.508)
		(drill 0.254)
		(layers "F.Cu" "B.Cu")
		(net "P3V3_STBY_MODE")
	)
	(via
		(at 60.148978 -35.641788)
		(size 0.7112)
		(drill 0.3556)
		(layers "F.Cu" "B.Cu")
		(net "P3V3_STBY_MODE")
	)
	(segment
		(start 60.19419 -35.687)
		(end 60.148978 -35.641788)
		(width 0.254)
		(layer "B.Cu")
		(net "P3V3_STBY_MODE")
	)
	(segment
		(start 61.147198 -35.687)
		(end 60.19419 -35.687)
		(width 0.254)
		(layer "B.Cu")
		(net "P3V3_STBY_MODE")
	)
	(segment
		(start 60.148978 -34.656522)
		(end 60.325 -34.4805)
		(width 0.254)
		(layer "B.Cu")
		(net "P3V3_STBY_MODE")
	)
	(segment
		(start 61.878972 -36.418774)
		(end 61.147198 -35.687)
		(width 0.254)
		(layer "B.Cu")
		(net "P3V3_STBY_MODE")
	)
	(segment
		(start 60.148978 -35.641788)
		(end 60.148978 -34.656522)
		(width 0.254)
		(layer "B.Cu")
		(net "P3V3_STBY_MODE")
	)
	(segment
		(start 71.4375 -33.02)
		(end 72.517 -33.02)
		(width 0.254)
		(layer "F.Cu")
		(net "P3V3_STBY_LL_R")
	)
	(via
		(at 72.517 -33.02)
		(size 0.508)
		(drill 0.254)
		(layers "F.Cu" "B.Cu")
		(net "P3V3_STBY_LL_R")
	)
	(segment
		(start 74.9935 -35.4965)
		(end 72.517 -33.02)
		(width 0.254)
		(layer "B.Cu")
		(net "P3V3_STBY_LL_R")
	)
	(segment
		(start 74.803 -37.0205)
		(end 73.787 -37.0205)
		(width 0.254)
		(layer "B.Cu")
		(net "P3V3_STBY_LL_R")
	)
	(segment
		(start 74.9935 -36.83)
		(end 74.9935 -35.4965)
		(width 0.254)
		(layer "B.Cu")
		(net "P3V3_STBY_LL_R")
	)
	(segment
		(start 74.803 -37.0205)
		(end 74.9935 -36.83)
		(width 0.254)
		(layer "B.Cu")
		(net "P3V3_STBY_LL_R")
	)
	(segment
		(start 73.8886 -42.291)
		(end 74.1426 -42.037)
		(width 0.254)
		(layer "F.Cu")
		(net "P3V3_STBY_LL")
	)
	(segment
		(start 73.914 -38.862)
		(end 73.787 -38.735)
		(width 0.254)
		(layer "F.Cu")
		(net "P3V3_STBY_LL")
	)
	(segment
		(start 74.1426 -42.037)
		(end 74.1426 -39.0652)
		(width 0.254)
		(layer "F.Cu")
		(net "P3V3_STBY_LL")
	)
	(segment
		(start 71.388478 -42.291)
		(end 73.8886 -42.291)
		(width 0.254)
		(layer "F.Cu")
		(net "P3V3_STBY_LL")
	)
	(segment
		(start 71.363078 -42.291)
		(end 71.388478 -42.291)
		(width 0.254)
		(layer "F.Cu")
		(net "P3V3_STBY_LL")
	)
	(segment
		(start 73.9394 -38.862)
		(end 73.914 -38.862)
		(width 0.254)
		(layer "F.Cu")
		(net "P3V3_STBY_LL")
	)
	(segment
		(start 74.1426 -39.0652)
		(end 73.9394 -38.862)
		(width 0.254)
		(layer "F.Cu")
		(net "P3V3_STBY_LL")
	)
	(via
		(at 73.787 -38.735)
		(size 0.508)
		(drill 0.254)
		(layers "F.Cu" "B.Cu")
		(net "P3V3_STBY_LL")
	)
	(via
		(at 71.12 -39.0906)
		(size 0.508)
		(drill 0.254)
		(layers "F.Cu" "B.Cu")
		(net "P3V3_STBY_LL")
	)
	(via
		(at 72.6694 -39.0906)
		(size 0.508)
		(drill 0.254)
		(layers "F.Cu" "B.Cu")
		(net "P3V3_STBY_LL")
	)
	(segment
		(start 73.787 -37.9095)
		(end 73.787 -38.735)
		(width 0.254)
		(layer "B.Cu")
		(net "P3V3_STBY_LL")
	)
	(segment
		(start 72.6694 -37.8206)
		(end 72.6694 -39.0906)
		(width 0.254)
		(layer "B.Cu")
		(net "P3V3_STBY_LL")
	)
	(segment
		(start 70.1548 -39.0906)
		(end 71.12 -39.0906)
		(width 0.254)
		(layer "B.Cu")
		(net "P3V3_STBY_LL")
	)
	(segment
		(start 70.485 -35.53841)
		(end 70.842886 -35.896296)
		(width 0.12065)
		(layer "F.Cu")
		(net "P3V3_STBY_EN")
	)
	(segment
		(start 71.501 -35.56)
		(end 71.501 -34.8615)
		(width 0.12065)
		(layer "F.Cu")
		(net "P3V3_STBY_EN")
	)
	(segment
		(start 70.842886 -35.896296)
		(end 71.164704 -35.896296)
		(width 0.12065)
		(layer "F.Cu")
		(net "P3V3_STBY_EN")
	)
	(segment
		(start 68.928996 -36.608004)
		(end 68.362322 -36.608004)
		(width 0.12065)
		(layer "F.Cu")
		(net "P3V3_STBY_EN")
	)
	(segment
		(start 69.3166 -36.2204)
		(end 68.928996 -36.608004)
		(width 0.12065)
		(layer "F.Cu")
		(net "P3V3_STBY_EN")
	)
	(segment
		(start 70.485 -34.8615)
		(end 69.786754 -34.8615)
		(width 0.12065)
		(layer "F.Cu")
		(net "P3V3_STBY_EN")
	)
	(segment
		(start 69.786754 -34.8615)
		(end 69.3166 -35.331654)
		(width 0.12065)
		(layer "F.Cu")
		(net "P3V3_STBY_EN")
	)
	(segment
		(start 69.3166 -35.331654)
		(end 69.3166 -36.2204)
		(width 0.12065)
		(layer "F.Cu")
		(net "P3V3_STBY_EN")
	)
	(segment
		(start 70.485 -34.8615)
		(end 70.485 -35.53841)
		(width 0.12065)
		(layer "F.Cu")
		(net "P3V3_STBY_EN")
	)
	(segment
		(start 71.164704 -35.896296)
		(end 71.501 -35.56)
		(width 0.12065)
		(layer "F.Cu")
		(net "P3V3_STBY_EN")
	)
	(via
		(at 70.842886 -35.896296)
		(size 0.7112)
		(drill 0.3556)
		(layers "F.Cu" "B.Cu")
		(net "P3V3_STBY_EN")
	)
	(segment
		(start 50.2539 -110.210854)
		(end 50.2539 -111.1123)
		(width 0.508)
		(layer "F.Cu")
		(net "P3V3_STBY")
	)
	(segment
		(start 67.31 -77.216)
		(end 66.802 -76.708)
		(width 0.508)
		(layer "F.Cu")
		(net "P3V3_STBY")
	)
	(segment
		(start 329.819 -86.0425)
		(end 328.803 -86.0425)
		(width 0.508)
		(layer "F.Cu")
		(net "P3V3_STBY")
	)
	(segment
		(start 69.3039 -124.112782)
		(end 69.3039 -123.3932)
		(width 0.508)
		(layer "F.Cu")
		(net "P3V3_STBY")
	)
	(segment
		(start 24.642064 -65.294764)
		(end 24.642064 -66.59499)
		(width 0.508)
		(layer "F.Cu")
		(net "P3V3_STBY")
	)
	(segment
		(start 187.6679 -28.96108)
		(end 188.31814 -28.96108)
		(width 0.508)
		(layer "F.Cu")
		(net "P3V3_STBY")
	)
	(segment
		(start 72.30364 -36.5252)
		(end 72.644 -36.5252)
		(width 0.508)
		(layer "F.Cu")
		(net "P3V3_STBY")
	)
	(segment
		(start 263.416034 -6.837934)
		(end 264.17778 -6.837934)
		(width 0.508)
		(layer "F.Cu")
		(net "P3V3_STBY")
	)
	(segment
		(start 332.634336 -100.097336)
		(end 332.757272 -100.097336)
		(width 0.508)
		(layer "F.Cu")
		(net "P3V3_STBY")
	)
	(segment
		(start 50.8762 -48.768)
		(end 50.2666 -48.1584)
		(width 0.508)
		(layer "F.Cu")
		(net "P3V3_STBY")
	)
	(segment
		(start 25.419304 -110.28172)
		(end 26.206704 -110.28172)
		(width 0.508)
		(layer "F.Cu")
		(net "P3V3_STBY")
	)
	(segment
		(start 217.564716 -200.914)
		(end 218.186 -200.914)
		(width 0.508)
		(layer "F.Cu")
		(net "P3V3_STBY")
	)
	(segment
		(start 54.1655 -144.907)
		(end 54.1655 -140.843)
		(width 0.508)
		(layer "F.Cu")
		(net "P3V3_STBY")
	)
	(segment
		(start 235.51388 -5.97916)
		(end 235.382308 -6.110732)
		(width 0.508)
		(layer "F.Cu")
		(net "P3V3_STBY")
	)
	(segment
		(start 84.8868 -76.0984)
		(end 85.27288 -76.0984)
		(width 0.508)
		(layer "F.Cu")
		(net "P3V3_STBY")
	)
	(segment
		(start 193.84264 -33.909)
		(end 192.6844 -32.75076)
		(width 0.508)
		(layer "F.Cu")
		(net "P3V3_STBY")
	)
	(segment
		(start 68.3006 -192.11036)
		(end 68.121022 -191.930782)
		(width 0.508)
		(layer "F.Cu")
		(net "P3V3_STBY")
	)
	(segment
		(start 22.16912 -69.94652)
		(end 22.7076 -70.485)
		(width 0.508)
		(layer "F.Cu")
		(net "P3V3_STBY")
	)
	(segment
		(start 70.5612 -52.959)
		(end 70.5739 -52.9717)
		(width 0.508)
		(layer "F.Cu")
		(net "P3V3_STBY")
	)
	(segment
		(start 236.8169 -19.9644)
		(end 237.617 -19.9644)
		(width 0.508)
		(layer "F.Cu")
		(net "P3V3_STBY")
	)
	(segment
		(start 20.420076 -128.143254)
		(end 20.420076 -128.227074)
		(width 0.508)
		(layer "F.Cu")
		(net "P3V3_STBY")
	)
	(segment
		(start 27.232102 -76.502768)
		(end 27.197558 -76.502768)
		(width 0.508)
		(layer "F.Cu")
		(net "P3V3_STBY")
	)
	(segment
		(start 117.962172 -95.2373)
		(end 118.086632 -95.11284)
		(width 0.381)
		(layer "F.Cu")
		(net "P3V3_STBY")
	)
	(segment
		(start 68.058284 -191.99352)
		(end 68.121022 -191.930782)
		(width 0.508)
		(layer "F.Cu")
		(net "P3V3_STBY")
	)
	(segment
		(start 25.58542 -77.93228)
		(end 25.6159 -77.9018)
		(width 0.508)
		(layer "F.Cu")
		(net "P3V3_STBY")
	)
	(segment
		(start 71.7042 -127.7493)
		(end 71.533258 -127.7493)
		(width 0.4064)
		(layer "F.Cu")
		(net "P3V3_STBY")
	)
	(segment
		(start 19.31797 -90.05443)
		(end 20.5232 -88.8492)
		(width 0.508)
		(layer "F.Cu")
		(net "P3V3_STBY")
	)
	(segment
		(start 67.8942 -74.4855)
		(end 68.1355 -74.4855)
		(width 0.508)
		(layer "F.Cu")
		(net "P3V3_STBY")
	)
	(segment
		(start 184.284112 -14.32052)
		(end 184.12206 -14.32052)
		(width 0.508)
		(layer "F.Cu")
		(net "P3V3_STBY")
	)
	(segment
		(start 39.0398 -186.9821)
		(end 38.1508 -186.9821)
		(width 0.381)
		(layer "F.Cu")
		(net "P3V3_STBY")
	)
	(segment
		(start 89.2048 -45.974)
		(end 89.337388 -45.974)
		(width 0.3048)
		(layer "F.Cu")
		(net "P3V3_STBY")
	)
	(segment
		(start 71.755 -124.9045)
		(end 71.964804 -124.9045)
		(width 0.508)
		(layer "F.Cu")
		(net "P3V3_STBY")
	)
	(segment
		(start 126.5936 -50.4063)
		(end 126.5936 -49.4284)
		(width 0.508)
		(layer "F.Cu")
		(net "P3V3_STBY")
	)
	(segment
		(start 71.05142 -127.267462)
		(end 71.05142 -126.878842)
		(width 0.4064)
		(layer "F.Cu")
		(net "P3V3_STBY")
	)
	(segment
		(start 184.04078 -14.23924)
		(end 184.12206 -14.32052)
		(width 0.508)
		(layer "F.Cu")
		(net "P3V3_STBY")
	)
	(segment
		(start 208.026 -23.5204)
		(end 208.026 -24.6634)
		(width 0.508)
		(layer "F.Cu")
		(net "P3V3_STBY")
	)
	(segment
		(start 351.063052 -46.768766)
		(end 351.063052 -46.717458)
		(width 0.508)
		(layer "F.Cu")
		(net "P3V3_STBY")
	)
	(segment
		(start 73.9267 -118.760748)
		(end 73.917048 -118.7704)
		(width 0.381)
		(layer "F.Cu")
		(net "P3V3_STBY")
	)
	(segment
		(start 71.0311 -119.6467)
		(end 70.0786 -118.6942)
		(width 0.508)
		(layer "F.Cu")
		(net "P3V3_STBY")
	)
	(segment
		(start 235.382308 -6.110732)
		(end 234.503468 -6.110732)
		(width 0.508)
		(layer "F.Cu")
		(net "P3V3_STBY")
	)
	(segment
		(start 23.330662 -76.416662)
		(end 23.7998 -76.8858)
		(width 0.3048)
		(layer "F.Cu")
		(net "P3V3_STBY")
	)
	(segment
		(start 54.1655 -138.811)
		(end 54.1655 -137.795)
		(width 0.508)
		(layer "F.Cu")
		(net "P3V3_STBY")
	)
	(segment
		(start 258.854702 -4.419092)
		(end 258.608576 -4.665218)
		(width 0.508)
		(layer "F.Cu")
		(net "P3V3_STBY")
	)
	(segment
		(start 22.08276 -163.01974)
		(end 22.0345 -163.068)
		(width 0.4064)
		(layer "F.Cu")
		(net "P3V3_STBY")
	)
	(segment
		(start 22.08276 -161.3535)
		(end 22.08276 -163.01974)
		(width 0.4064)
		(layer "F.Cu")
		(net "P3V3_STBY")
	)
	(segment
		(start 37.704522 -126.084838)
		(end 37.304726 -125.685042)
		(width 0.3556)
		(layer "F.Cu")
		(net "P3V3_STBY")
	)
	(segment
		(start 193.2813 -27.7622)
		(end 193.2813 -28.6512)
		(width 0.508)
		(layer "F.Cu")
		(net "P3V3_STBY")
	)
	(segment
		(start 218.8845 -9.144)
		(end 218.059 -9.144)
		(width 0.508)
		(layer "F.Cu")
		(net "P3V3_STBY")
	)
	(segment
		(start 24.7142 -77.9018)
		(end 25.6159 -77.9018)
		(width 0.508)
		(layer "F.Cu")
		(net "P3V3_STBY")
	)
	(segment
		(start 48.7172 -48.1584)
		(end 47.858172 -48.1584)
		(width 0.508)
		(layer "F.Cu")
		(net "P3V3_STBY")
	)
	(segment
		(start 266.940284 -15.51686)
		(end 266.92225 -15.51686)
		(width 0.508)
		(layer "F.Cu")
		(net "P3V3_STBY")
	)
	(segment
		(start 6.97738 -83.11642)
		(end 6.97738 -83.897978)
		(width 0.508)
		(layer "F.Cu")
		(net "P3V3_STBY")
	)
	(segment
		(start 50.1777 -63.754)
		(end 50.1523 -63.7794)
		(width 0.508)
		(layer "F.Cu")
		(net "P3V3_STBY")
	)
	(segment
		(start 84.539836 -74.135996)
		(end 84.539836 -72.00646)
		(width 0.508)
		(layer "F.Cu")
		(net "P3V3_STBY")
	)
	(segment
		(start 56.73471 -31.3817)
		(end 56.279796 -30.926786)
		(width 0.508)
		(layer "F.Cu")
		(net "P3V3_STBY")
	)
	(segment
		(start 183.505602 -1.057656)
		(end 183.505602 -0.60452)
		(width 0.508)
		(layer "F.Cu")
		(net "P3V3_STBY")
	)
	(segment
		(start 54.049676 -65.0494)
		(end 54.557676 -64.5414)
		(width 0.508)
		(layer "F.Cu")
		(net "P3V3_STBY")
	)
	(segment
		(start 46.863 -150.876)
		(end 46.863 -151.988266)
		(width 0.508)
		(layer "F.Cu")
		(net "P3V3_STBY")
	)
	(segment
		(start 257.112262 -8.713978)
		(end 257.112262 -9.573514)
		(width 0.3556)
		(layer "F.Cu")
		(net "P3V3_STBY")
	)
	(segment
		(start 10.125964 -98.789236)
		(end 9.9822 -98.933)
		(width 0.508)
		(layer "F.Cu")
		(net "P3V3_STBY")
	)
	(segment
		(start 240.665 -17.145)
		(end 239.014 -17.145)
		(width 0.508)
		(layer "F.Cu")
		(net "P3V3_STBY")
	)
	(segment
		(start 117.20576 -27.1272)
		(end 117.20576 -27.94)
		(width 0.3556)
		(layer "F.Cu")
		(net "P3V3_STBY")
	)
	(segment
		(start 71.533258 -127.7493)
		(end 71.05142 -127.267462)
		(width 0.4064)
		(layer "F.Cu")
		(net "P3V3_STBY")
	)
	(segment
		(start 257.670554 -10.131806)
		(end 257.670554 -10.555224)
		(width 0.508)
		(layer "F.Cu")
		(net "P3V3_STBY")
	)
	(segment
		(start 264.121646 -9.071864)
		(end 265.028172 -9.071864)
		(width 0.508)
		(layer "F.Cu")
		(net "P3V3_STBY")
	)
	(segment
		(start 67.794124 -195.236592)
		(end 68.058284 -194.972432)
		(width 0.508)
		(layer "F.Cu")
		(net "P3V3_STBY")
	)
	(segment
		(start 20.420076 -129.243074)
		(end 20.275804 -129.387346)
		(width 0.508)
		(layer "F.Cu")
		(net "P3V3_STBY")
	)
	(segment
		(start 52.1335 -65.0494)
		(end 54.049676 -65.0494)
		(width 0.508)
		(layer "F.Cu")
		(net "P3V3_STBY")
	)
	(segment
		(start 27.271472 -99.817428)
		(end 27.5336 -99.5553)
		(width 0.3556)
		(layer "F.Cu")
		(net "P3V3_STBY")
	)
	(segment
		(start 68.9102 -75.2602)
		(end 69.2023 -75.2602)
		(width 0.508)
		(layer "F.Cu")
		(net "P3V3_STBY")
	)
	(segment
		(start 32.522414 -136.099804)
		(end 32.510984 -136.088374)
		(width 0.254)
		(layer "F.Cu")
		(net "P3V3_STBY")
	)
	(segment
		(start 218.321636 -11.184636)
		(end 218.186 -11.049)
		(width 0.508)
		(layer "F.Cu")
		(net "P3V3_STBY")
	)
	(segment
		(start 69.3166 -76.6572)
		(end 68.7578 -77.216)
		(width 0.508)
		(layer "F.Cu")
		(net "P3V3_STBY")
	)
	(segment
		(start 230.9114 -95.631)
		(end 231.8512 -94.6912)
		(width 0.508)
		(layer "F.Cu")
		(net "P3V3_STBY")
	)
	(segment
		(start 69.30644 -124.243338)
		(end 69.30644 -124.115322)
		(width 0.508)
		(layer "F.Cu")
		(net "P3V3_STBY")
	)
	(segment
		(start 20.5232 -88.8492)
		(end 23.540974 -88.8492)
		(width 0.508)
		(layer "F.Cu")
		(net "P3V3_STBY")
	)
	(segment
		(start 29.52369 -113.73739)
		(end 29.52369 -112.94491)
		(width 0.508)
		(layer "F.Cu")
		(net "P3V3_STBY")
	)
	(segment
		(start 69.3039 -118.6942)
		(end 70.0786 -118.6942)
		(width 0.508)
		(layer "F.Cu")
		(net "P3V3_STBY")
	)
	(segment
		(start 29.911294 -93.740224)
		(end 30.127194 -93.524324)
		(width 0.508)
		(layer "F.Cu")
		(net "P3V3_STBY")
	)
	(segment
		(start 331.216 -4.1275)
		(end 331.216 -4.944364)
		(width 0.508)
		(layer "F.Cu")
		(net "P3V3_STBY")
	)
	(segment
		(start 56.107838 -112.225582)
		(end 56.126126 -112.207294)
		(width 0.508)
		(layer "F.Cu")
		(net "P3V3_STBY")
	)
	(segment
		(start 42.299636 -113.837212)
		(end 42.299636 -114.508534)
		(width 0.508)
		(layer "F.Cu")
		(net "P3V3_STBY")
	)
	(segment
		(start 62.0268 -58.5089)
		(end 62.0522 -58.4835)
		(width 0.508)
		(layer "F.Cu")
		(net "P3V3_STBY")
	)
	(segment
		(start 27.1526 -186.8297)
		(end 27.1526 -187.6044)
		(width 0.508)
		(layer "F.Cu")
		(net "P3V3_STBY")
	)
	(segment
		(start 6.647688 -78.961488)
		(end 6.096 -78.4098)
		(width 0.508)
		(layer "F.Cu")
		(net "P3V3_STBY")
	)
	(segment
		(start 350.904556 -46.875954)
		(end 350.05264 -46.875954)
		(width 0.508)
		(layer "F.Cu")
		(net "P3V3_STBY")
	)
	(segment
		(start 31.5341 -180.5432)
		(end 31.5341 -179.5907)
		(width 0.508)
		(layer "F.Cu")
		(net "P3V3_STBY")
	)
	(segment
		(start 31.09087 -93.524324)
		(end 31.15183 -93.463364)
		(width 0.508)
		(layer "F.Cu")
		(net "P3V3_STBY")
	)
	(segment
		(start 33.704784 -127.685292)
		(end 34.10458 -128.085088)
		(width 0.3556)
		(layer "F.Cu")
		(net "P3V3_STBY")
	)
	(segment
		(start 18.8595 -130.8227)
		(end 18.8595 -130.683)
		(width 0.508)
		(layer "F.Cu")
		(net "P3V3_STBY")
	)
	(segment
		(start 326.39 -100.1395)
		(end 326.517 -100.0125)
		(width 0.508)
		(layer "F.Cu")
		(net "P3V3_STBY")
	)
	(segment
		(start 19.7358 -127.635)
		(end 19.911822 -127.635)
		(width 0.508)
		(layer "F.Cu")
		(net "P3V3_STBY")
	)
	(segment
		(start 16.133826 -128.35128)
		(end 16.133826 -127.56388)
		(width 0.508)
		(layer "F.Cu")
		(net "P3V3_STBY")
	)
	(segment
		(start 17.1704 -82.4484)
		(end 17.0434 -82.3214)
		(width 0.3048)
		(layer "F.Cu")
		(net "P3V3_STBY")
	)
	(segment
		(start 123.838208 -205.612492)
		(end 123.2662 -206.1845)
		(width 0.3556)
		(layer "F.Cu")
		(net "P3V3_STBY")
	)
	(segment
		(start 24.30018 -88.089994)
		(end 24.30018 -87.442294)
		(width 0.508)
		(layer "F.Cu")
		(net "P3V3_STBY")
	)
	(segment
		(start 87.716614 -83.29041)
		(end 89.28481 -83.29041)
		(width 0.254)
		(layer "F.Cu")
		(net "P3V3_STBY")
	)
	(segment
		(start 22.497542 -127.99949)
		(end 22.868636 -128.317498)
		(width 0.508)
		(layer "F.Cu")
		(net "P3V3_STBY")
	)
	(segment
		(start 47.350172 -48.6664)
		(end 47.350172 -49.861724)
		(width 0.508)
		(layer "F.Cu")
		(net "P3V3_STBY")
	)
	(segment
		(start 49.8475 -199.39)
		(end 49.022 -199.39)
		(width 0.508)
		(layer "F.Cu")
		(net "P3V3_STBY")
	)
	(segment
		(start 25.019 -152.8445)
		(end 25.7175 -152.8445)
		(width 0.508)
		(layer "F.Cu")
		(net "P3V3_STBY")
	)
	(segment
		(start 57.0484 -31.3817)
		(end 56.73471 -31.3817)
		(width 0.508)
		(layer "F.Cu")
		(net "P3V3_STBY")
	)
	(segment
		(start 53.2003 -50.7619)
		(end 54.557676 -52.119276)
		(width 0.508)
		(layer "F.Cu")
		(net "P3V3_STBY")
	)
	(segment
		(start 27.635454 -164.004244)
		(end 27.698954 -164.067744)
		(width 0.508)
		(layer "F.Cu")
		(net "P3V3_STBY")
	)
	(segment
		(start 55.6006 -122.729244)
		(end 55.502556 -122.6312)
		(width 0.508)
		(layer "F.Cu")
		(net "P3V3_STBY")
	)
	(segment
		(start 240.7666 -17.2466)
		(end 240.665 -17.145)
		(width 0.508)
		(layer "F.Cu")
		(net "P3V3_STBY")
	)
	(segment
		(start 89.2048 -44.0944)
		(end 89.299288 -44.0944)
		(width 0.3048)
		(layer "F.Cu")
		(net "P3V3_STBY")
	)
	(segment
		(start 46.9138 -186.0931)
		(end 46.9138 -185.2676)
		(width 0.508)
		(layer "F.Cu")
		(net "P3V3_STBY")
	)
	(segment
		(start 19.2024 -131.1656)
		(end 18.8595 -130.8227)
		(width 0.508)
		(layer "F.Cu")
		(net "P3V3_STBY")
	)
	(segment
		(start 22.7076 -70.9422)
		(end 22.407118 -71.242682)
		(width 0.3048)
		(layer "F.Cu")
		(net "P3V3_STBY")
	)
	(segment
		(start 20.3962 -65.8241)
		(end 20.3962 -65.5574)
		(width 0.508)
		(layer "F.Cu")
		(net "P3V3_STBY")
	)
	(segment
		(start 15.0495 -127.697992)
		(end 15.0495 -127.508)
		(width 0.508)
		(layer "F.Cu")
		(net "P3V3_STBY")
	)
	(segment
		(start 10.9347 -100.1014)
		(end 11.0109 -100.1776)
		(width 0.508)
		(layer "F.Cu")
		(net "P3V3_STBY")
	)
	(segment
		(start 27.635454 -162.162744)
		(end 27.635454 -164.004244)
		(width 0.508)
		(layer "F.Cu")
		(net "P3V3_STBY")
	)
	(segment
		(start 70.440296 -192.532)
		(end 68.72224 -192.532)
		(width 0.3048)
		(layer "F.Cu")
		(net "P3V3_STBY")
	)
	(segment
		(start 42.504868 -130.885184)
		(end 42.904664 -131.28498)
		(width 0.3556)
		(layer "F.Cu")
		(net "P3V3_STBY")
	)
	(segment
		(start 5.4102 -109.093)
		(end 6.35 -109.093)
		(width 0.508)
		(layer "F.Cu")
		(net "P3V3_STBY")
	)
	(segment
		(start 226.822 -83.439)
		(end 229.235 -83.439)
		(width 0.3048)
		(layer "F.Cu")
		(net "P3V3_STBY")
	)
	(segment
		(start 122.73788 -6.78688)
		(end 122.7455 -6.7945)
		(width 0.508)
		(layer "F.Cu")
		(net "P3V3_STBY")
	)
	(segment
		(start 204.331824 -25.527)
		(end 204.4954 -25.690576)
		(width 0.3048)
		(layer "F.Cu")
		(net "P3V3_STBY")
	)
	(segment
		(start 47.244 -180.9115)
		(end 47.5234 -180.6321)
		(width 0.381)
		(layer "F.Cu")
		(net "P3V3_STBY")
	)
	(segment
		(start 47.41545 -115.19027)
		(end 47.7901 -115.56492)
		(width 0.508)
		(layer "F.Cu")
		(net "P3V3_STBY")
	)
	(segment
		(start 16.9799 -83.1469)
		(end 16.1417 -83.9851)
		(width 0.508)
		(layer "F.Cu")
		(net "P3V3_STBY")
	)
	(segment
		(start 27.197558 -76.502768)
		(end 26.763726 -76.9366)
		(width 0.508)
		(layer "F.Cu")
		(net "P3V3_STBY")
	)
	(segment
		(start 22.7076 -131.699)
		(end 22.6568 -131.7498)
		(width 0.508)
		(layer "F.Cu")
		(net "P3V3_STBY")
	)
	(segment
		(start 229.108 -11.43)
		(end 229.8065 -11.43)
		(width 0.508)
		(layer "F.Cu")
		(net "P3V3_STBY")
	)
	(segment
		(start 267.4239 -17.16913)
		(end 267.87094 -17.61617)
		(width 0.508)
		(layer "F.Cu")
		(net "P3V3_STBY")
	)
	(segment
		(start 233.5276 -7.0866)
		(end 233.5276 -8.4582)
		(width 0.508)
		(layer "F.Cu")
		(net "P3V3_STBY")
	)
	(segment
		(start 143.136874 -97.55632)
		(end 142.233142 -98.460052)
		(width 0.508)
		(layer "F.Cu")
		(net "P3V3_STBY")
	)
	(segment
		(start 85.27288 -76.0984)
		(end 85.70214 -75.66914)
		(width 0.508)
		(layer "F.Cu")
		(net "P3V3_STBY")
	)
	(segment
		(start 37.771832 -200.57364)
		(end 39.0779 -200.57364)
		(width 0.381)
		(layer "F.Cu")
		(net "P3V3_STBY")
	)
	(segment
		(start 20.32 -103.3653)
		(end 20.32 -104.000808)
		(width 0.508)
		(layer "F.Cu")
		(net "P3V3_STBY")
	)
	(segment
		(start 22.352 -155.0289)
		(end 22.352 -155.8544)
		(width 0.508)
		(layer "F.Cu")
		(net "P3V3_STBY")
	)
	(segment
		(start 32.3596 -103.7209)
		(end 32.3596 -104.2162)
		(width 0.508)
		(layer "F.Cu")
		(net "P3V3_STBY")
	)
	(segment
		(start 36.877498 -103.386636)
		(end 36.877498 -103.931974)
		(width 0.508)
		(layer "F.Cu")
		(net "P3V3_STBY")
	)
	(segment
		(start 22.6822 -134.2136)
		(end 22.6568 -134.239)
		(width 0.508)
		(layer "F.Cu")
		(net "P3V3_STBY")
	)
	(segment
		(start 257.112262 -9.573514)
		(end 257.670554 -10.131806)
		(width 0.3556)
		(layer "F.Cu")
		(net "P3V3_STBY")
	)
	(segment
		(start 261.506462 -3.321304)
		(end 261.506462 -3.551174)
		(width 0.508)
		(layer "F.Cu")
		(net "P3V3_STBY")
	)
	(segment
		(start 66.929 -195.453)
		(end 67.145408 -195.236592)
		(width 0.508)
		(layer "F.Cu")
		(net "P3V3_STBY")
	)
	(segment
		(start 268.000988 -3.2258)
		(end 267.62202 -2.846832)
		(width 0.508)
		(layer "F.Cu")
		(net "P3V3_STBY")
	)
	(segment
		(start 6.9342 -56.6928)
		(end 6.9342 -58.166)
		(width 0.508)
		(layer "F.Cu")
		(net "P3V3_STBY")
	)
	(segment
		(start 320.675 -86.0425)
		(end 320.675 -84.963)
		(width 0.508)
		(layer "F.Cu")
		(net "P3V3_STBY")
	)
	(segment
		(start 117.5258 -95.5167)
		(end 117.8052 -95.2373)
		(width 0.381)
		(layer "F.Cu")
		(net "P3V3_STBY")
	)
	(segment
		(start 50.165 -145.740628)
		(end 51.181 -145.740628)
		(width 0.508)
		(layer "F.Cu")
		(net "P3V3_STBY")
	)
	(segment
		(start 194.945 -36.2712)
		(end 197.3453 -36.2712)
		(width 0.508)
		(layer "F.Cu")
		(net "P3V3_STBY")
	)
	(segment
		(start 228.133656 -0.6985)
		(end 228.541326 -1.10617)
		(width 0.508)
		(layer "F.Cu")
		(net "P3V3_STBY")
	)
	(segment
		(start 55.118 -180.0225)
		(end 55.118 -179.197)
		(width 0.508)
		(layer "F.Cu")
		(net "P3V3_STBY")
	)
	(segment
		(start 147.53082 -101.6254)
		(end 161.5821 -101.6254)
		(width 0.508)
		(layer "F.Cu")
		(net "P3V3_STBY")
	)
	(segment
		(start 67.188588 -129.96926)
		(end 67.363848 -129.794)
		(width 0.4064)
		(layer "F.Cu")
		(net "P3V3_STBY")
	)
	(segment
		(start 191.1477 -13.6652)
		(end 190.0682 -13.6652)
		(width 0.508)
		(layer "F.Cu")
		(net "P3V3_STBY")
	)
	(segment
		(start 6.477 -108.966)
		(end 6.35 -109.093)
		(width 0.508)
		(layer "F.Cu")
		(net "P3V3_STBY")
	)
	(segment
		(start 218.8845 -7.112)
		(end 218.059 -7.112)
		(width 0.508)
		(layer "F.Cu")
		(net "P3V3_STBY")
	)
	(segment
		(start 66.929 -196.052948)
		(end 66.929 -195.453)
		(width 0.508)
		(layer "F.Cu")
		(net "P3V3_STBY")
	)
	(segment
		(start 45.085 -200.0885)
		(end 45.085 -199.263)
		(width 0.508)
		(layer "F.Cu")
		(net "P3V3_STBY")
	)
	(segment
		(start 62.2046 -111.5695)
		(end 62.2046 -110.3249)
		(width 0.508)
		(layer "F.Cu")
		(net "P3V3_STBY")
	)
	(segment
		(start 36.322 -200.9775)
		(end 35.3695 -200.9775)
		(width 0.508)
		(layer "F.Cu")
		(net "P3V3_STBY")
	)
	(segment
		(start 182.3085 -16.256)
		(end 184.3024 -16.256)
		(width 0.508)
		(layer "F.Cu")
		(net "P3V3_STBY")
	)
	(segment
		(start 23.2664 -87.4141)
		(end 24.271986 -87.4141)
		(width 0.508)
		(layer "F.Cu")
		(net "P3V3_STBY")
	)
	(segment
		(start 122.023124 -208.444592)
		(end 122.023124 -207.427576)
		(width 0.508)
		(layer "F.Cu")
		(net "P3V3_STBY")
	)
	(segment
		(start 73.28154 -117.04574)
		(end 73.9267 -117.6909)
		(width 0.508)
		(layer "F.Cu")
		(net "P3V3_STBY")
	)
	(segment
		(start 54.1655 -138.811)
		(end 54.1655 -139.827)
		(width 0.508)
		(layer "F.Cu")
		(net "P3V3_STBY")
	)
	(segment
		(start 182.675784 -0.60452)
		(end 183.505602 -0.60452)
		(width 0.508)
		(layer "F.Cu")
		(net "P3V3_STBY")
	)
	(segment
		(start 215.623648 -7.4676)
		(end 215.623648 -6.854952)
		(width 0.2032)
		(layer "F.Cu")
		(net "P3V3_STBY")
	)
	(segment
		(start 47.421292 -146.63928)
		(end 47.12208 -146.63928)
		(width 0.508)
		(layer "F.Cu")
		(net "P3V3_STBY")
	)
	(segment
		(start 47.12208 -146.63928)
		(end 47.117 -146.6342)
		(width 0.508)
		(layer "F.Cu")
		(net "P3V3_STBY")
	)
	(segment
		(start 33.704784 -131.684776)
		(end 33.704784 -131.684522)
		(width 0.3556)
		(layer "F.Cu")
		(net "P3V3_STBY")
	)
	(segment
		(start 229.997 -84.1375)
		(end 231.5845 -84.1375)
		(width 0.508)
		(layer "F.Cu")
		(net "P3V3_STBY")
	)
	(segment
		(start 54.1909 -125.5776)
		(end 55.6514 -125.5776)
		(width 0.381)
		(layer "F.Cu")
		(net "P3V3_STBY")
	)
	(segment
		(start 122.023124 -208.444592)
		(end 121.210324 -208.444592)
		(width 0.508)
		(layer "F.Cu")
		(net "P3V3_STBY")
	)
	(segment
		(start 239.014 -17.145)
		(end 238.5314 -17.6276)
		(width 0.508)
		(layer "F.Cu")
		(net "P3V3_STBY")
	)
	(segment
		(start 40.904922 -134.884922)
		(end 40.904414 -134.884922)
		(width 0.3556)
		(layer "F.Cu")
		(net "P3V3_STBY")
	)
	(segment
		(start 224.8662 -14.5161)
		(end 225.4631 -13.9192)
		(width 0.508)
		(layer "F.Cu")
		(net "P3V3_STBY")
	)
	(segment
		(start 217.9574 -5.4356)
		(end 217.8812 -5.4356)
		(width 0.508)
		(layer "F.Cu")
		(net "P3V3_STBY")
	)
	(segment
		(start 117.20576 -27.94)
		(end 116.698268 -28.447492)
		(width 0.3556)
		(layer "F.Cu")
		(net "P3V3_STBY")
	)
	(segment
		(start 120.67032 -31.1785)
		(end 120.64746 -31.15564)
		(width 0.508)
		(layer "F.Cu")
		(net "P3V3_STBY")
	)
	(segment
		(start 322.1736 -84.5566)
		(end 322.707 -85.09)
		(width 0.508)
		(layer "F.Cu")
		(net "P3V3_STBY")
	)
	(segment
		(start 217.996008 -5.396992)
		(end 217.996008 -4.5085)
		(width 0.508)
		(layer "F.Cu")
		(net "P3V3_STBY")
	)
	(segment
		(start 12.55522 -74.91476)
		(end 13.057124 -75.416664)
		(width 0.3048)
		(layer "F.Cu")
		(net "P3V3_STBY")
	)
	(segment
		(start 73.9267 -117.6909)
		(end 73.9267 -118.11)
		(width 0.508)
		(layer "F.Cu")
		(net "P3V3_STBY")
	)
	(segment
		(start 323.723 -86.0425)
		(end 322.707 -86.0425)
		(width 0.508)
		(layer "F.Cu")
		(net "P3V3_STBY")
	)
	(segment
		(start 15.9512 -84.8614)
		(end 15.8496 -84.963)
		(width 0.508)
		(layer "F.Cu")
		(net "P3V3_STBY")
	)
	(segment
		(start 116.604034 -30.172914)
		(end 115.551204 -30.172914)
		(width 0.508)
		(layer "F.Cu")
		(net "P3V3_STBY")
	)
	(segment
		(start 327.787 -86.0425)
		(end 326.771 -86.0425)
		(width 0.508)
		(layer "F.Cu")
		(net "P3V3_STBY")
	)
	(segment
		(start 20.420076 -129.243074)
		(end 20.420076 -128.227074)
		(width 0.508)
		(layer "F.Cu")
		(net "P3V3_STBY")
	)
	(segment
		(start 333.4766 -69.723)
		(end 333.2988 -69.9008)
		(width 0.254)
		(layer "F.Cu")
		(net "P3V3_STBY")
	)
	(segment
		(start 49.8475 -185.293)
		(end 49.022 -185.293)
		(width 0.508)
		(layer "F.Cu")
		(net "P3V3_STBY")
	)
	(segment
		(start 23.4315 -136.779)
		(end 23.4315 -135.763)
		(width 0.508)
		(layer "F.Cu")
		(net "P3V3_STBY")
	)
	(segment
		(start 54.64937 -140.843)
		(end 55.007002 -141.200632)
		(width 0.508)
		(layer "F.Cu")
		(net "P3V3_STBY")
	)
	(segment
		(start 9.9822 -99.187)
		(end 9.9441 -99.2251)
		(width 0.508)
		(layer "F.Cu")
		(net "P3V3_STBY")
	)
	(segment
		(start 36.877498 -103.931974)
		(end 36.957254 -104.01173)
		(width 0.508)
		(layer "F.Cu")
		(net "P3V3_STBY")
	)
	(segment
		(start 89.2048 -41.275)
		(end 89.362026 -41.275)
		(width 0.3048)
		(layer "F.Cu")
		(net "P3V3_STBY")
	)
	(segment
		(start 330.581 -100.0125)
		(end 329.565 -100.0125)
		(width 0.508)
		(layer "F.Cu")
		(net "P3V3_STBY")
	)
	(segment
		(start 197.3453 -36.2712)
		(end 198.3994 -35.2171)
		(width 0.508)
		(layer "F.Cu")
		(net "P3V3_STBY")
	)
	(segment
		(start 54.9021 -138.811)
		(end 54.1655 -138.811)
		(width 0.508)
		(layer "F.Cu")
		(net "P3V3_STBY")
	)
	(segment
		(start 272.237962 -5.30733)
		(end 272.492216 -5.053076)
		(width 0.508)
		(layer "F.Cu")
		(net "P3V3_STBY")
	)
	(segment
		(start 25.654 -78.932278)
		(end 25.58542 -78.863698)
		(width 0.508)
		(layer "F.Cu")
		(net "P3V3_STBY")
	)
	(segment
		(start 27.1526 -184.0357)
		(end 27.1526 -183.2102)
		(width 0.508)
		(layer "F.Cu")
		(net "P3V3_STBY")
	)
	(segment
		(start 89.2048 -45.0342)
		(end 89.31148 -45.0342)
		(width 0.3048)
		(layer "F.Cu")
		(net "P3V3_STBY")
	)
	(segment
		(start 44.904914 -134.084822)
		(end 45.30471 -133.685026)
		(width 0.3556)
		(layer "F.Cu")
		(net "P3V3_STBY")
	)
	(segment
		(start 47.244 -182.9435)
		(end 46.4185 -182.9435)
		(width 0.508)
		(layer "F.Cu")
		(net "P3V3_STBY")
	)
	(segment
		(start 182.448708 -0.831596)
		(end 182.675784 -0.60452)
		(width 0.508)
		(layer "F.Cu")
		(net "P3V3_STBY")
	)
	(segment
		(start 232.029 -88.646)
		(end 231.648 -89.027)
		(width 0.508)
		(layer "F.Cu")
		(net "P3V3_STBY")
	)
	(segment
		(start 76.689966 -90.16746)
		(end 76.689966 -89.1794)
		(width 0.508)
		(layer "F.Cu")
		(net "P3V3_STBY")
	)
	(segment
		(start 48.641 -147.858988)
		(end 47.421292 -146.63928)
		(width 0.508)
		(layer "F.Cu")
		(net "P3V3_STBY")
	)
	(segment
		(start 126.5936 -49.4284)
		(end 126.492 -49.3268)
		(width 0.508)
		(layer "F.Cu")
		(net "P3V3_STBY")
	)
	(segment
		(start 45.488606 -114.489738)
		(end 44.681648 -114.489738)
		(width 0.508)
		(layer "F.Cu")
		(net "P3V3_STBY")
	)
	(segment
		(start 17.0434 -81.231994)
		(end 16.911066 -81.09966)
		(width 0.3048)
		(layer "F.Cu")
		(net "P3V3_STBY")
	)
	(segment
		(start 9.3345 -118.364)
		(end 9.3345 -117.5766)
		(width 0.508)
		(layer "F.Cu")
		(net "P3V3_STBY")
	)
	(segment
		(start 39.8145 -205.359)
		(end 38.989 -205.359)
		(width 0.508)
		(layer "F.Cu")
		(net "P3V3_STBY")
	)
	(segment
		(start 321.0814 -84.5566)
		(end 322.1736 -84.5566)
		(width 0.508)
		(layer "F.Cu")
		(net "P3V3_STBY")
	)
	(segment
		(start 40.504618 -125.685042)
		(end 40.104822 -126.084838)
		(width 0.3556)
		(layer "F.Cu")
		(net "P3V3_STBY")
	)
	(segment
		(start 31.156402 -93.458792)
		(end 31.156402 -92.552012)
		(width 0.508)
		(layer "F.Cu")
		(net "P3V3_STBY")
	)
	(segment
		(start 187.66282 -27.79014)
		(end 188.20384 -27.79014)
		(width 0.508)
		(layer "F.Cu")
		(net "P3V3_STBY")
	)
	(segment
		(start 56.279796 -30.926786)
		(end 56.279796 -29.21381)
		(width 0.508)
		(layer "F.Cu")
		(net "P3V3_STBY")
	)
	(segment
		(start 218.969082 -11.184636)
		(end 218.321636 -11.184636)
		(width 0.508)
		(layer "F.Cu")
		(net "P3V3_STBY")
	)
	(segment
		(start 200.0885 -18.8468)
		(end 200.0631 -18.8214)
		(width 0.508)
		(layer "F.Cu")
		(net "P3V3_STBY")
	)
	(segment
		(start 22.584918 -76.416662)
		(end 23.330662 -76.416662)
		(width 0.3048)
		(layer "F.Cu")
		(net "P3V3_STBY")
	)
	(segment
		(start 64.957452 -145.856452)
		(end 64.957452 -146.72691)
		(width 0.508)
		(layer "F.Cu")
		(net "P3V3_STBY")
	)
	(segment
		(start 89.2048 -43.1546)
		(end 89.32291 -43.1546)
		(width 0.3048)
		(layer "F.Cu")
		(net "P3V3_STBY")
	)
	(segment
		(start 34.10458 -131.284726)
		(end 33.704784 -130.88493)
		(width 0.3556)
		(layer "F.Cu")
		(net "P3V3_STBY")
	)
	(segment
		(start 44.4373 -191.3636)
		(end 45.212 -191.3636)
		(width 0.508)
		(layer "F.Cu")
		(net "P3V3_STBY")
	)
	(segment
		(start 23.7998 -76.8858)
		(end 23.7998 -76.9874)
		(width 0.3048)
		(layer "F.Cu")
		(net "P3V3_STBY")
	)
	(segment
		(start 17.0434 -82.3214)
		(end 17.0434 -81.231994)
		(width 0.3048)
		(layer "F.Cu")
		(net "P3V3_STBY")
	)
	(segment
		(start 13.057124 -75.416664)
		(end 13.737082 -75.416664)
		(width 0.3048)
		(layer "F.Cu")
		(net "P3V3_STBY")
	)
	(segment
		(start 42.904664 -128.085088)
		(end 42.504868 -128.484884)
		(width 0.3556)
		(layer "F.Cu")
		(net "P3V3_STBY")
	)
	(segment
		(start 195.8213 -18.796)
		(end 196.8119 -18.796)
		(width 0.508)
		(layer "F.Cu")
		(net "P3V3_STBY")
	)
	(segment
		(start 195.8213 -18.796)
		(end 195.8213 -16.5735)
		(width 0.508)
		(layer "F.Cu")
		(net "P3V3_STBY")
	)
	(segment
		(start 55.502556 -122.6312)
		(end 55.1942 -122.6312)
		(width 0.508)
		(layer "F.Cu")
		(net "P3V3_STBY")
	)
	(segment
		(start 15.3543 -122.9868)
		(end 15.0495 -122.682)
		(width 0.508)
		(layer "F.Cu")
		(net "P3V3_STBY")
	)
	(segment
		(start 9.9822 -98.933)
		(end 9.9822 -98.947478)
		(width 0.508)
		(layer "F.Cu")
		(net "P3V3_STBY")
	)
	(segment
		(start 121.594626 -81.096866)
		(end 121.596912 -81.099152)
		(width 0.508)
		(layer "F.Cu")
		(net "P3V3_STBY")
	)
	(segment
		(start 121.596912 -81.160112)
		(end 122.055128 -81.618328)
		(width 0.508)
		(layer "F.Cu")
		(net "P3V3_STBY")
	)
	(segment
		(start 75.46086 -79.0829)
		(end 74.66076 -78.2828)
		(width 0.508)
		(layer "F.Cu")
		(net "P3V3_STBY")
	)
	(segment
		(start 19.812 -64.9732)
		(end 19.691858 -64.9732)
		(width 0.508)
		(layer "F.Cu")
		(net "P3V3_STBY")
	)
	(segment
		(start 328.549 -100.0125)
		(end 327.533 -100.0125)
		(width 0.508)
		(layer "F.Cu")
		(net "P3V3_STBY")
	)
	(segment
		(start 37.211 -203.0095)
		(end 36.3855 -203.0095)
		(width 0.508)
		(layer "F.Cu")
		(net "P3V3_STBY")
	)
	(segment
		(start 115.7732 -27.0383)
		(end 115.7732 -27.9908)
		(width 0.508)
		(layer "F.Cu")
		(net "P3V3_STBY")
	)
	(segment
		(start 51.6255 -146.373088)
		(end 51.6255 -147.447)
		(width 0.508)
		(layer "F.Cu")
		(net "P3V3_STBY")
	)
	(segment
		(start 192.4558 -19.2786)
		(end 191.9478 -19.7866)
		(width 0.508)
		(layer "F.Cu")
		(net "P3V3_STBY")
	)
	(segment
		(start 262.014462 -2.813304)
		(end 261.506462 -3.321304)
		(width 0.508)
		(layer "F.Cu")
		(net "P3V3_STBY")
	)
	(segment
		(start 324.485 -101.9175)
		(end 325.6915 -101.9175)
		(width 0.508)
		(layer "F.Cu")
		(net "P3V3_STBY")
	)
	(segment
		(start 178.0286 -101.6254)
		(end 184.023 -95.631)
		(width 0.508)
		(layer "F.Cu")
		(net "P3V3_STBY")
	)
	(segment
		(start 71.05142 -126.878842)
		(end 70.867778 -126.6952)
		(width 0.4064)
		(layer "F.Cu")
		(net "P3V3_STBY")
	)
	(segment
		(start 41.6433 -191.3636)
		(end 40.8178 -191.3636)
		(width 0.508)
		(layer "F.Cu")
		(net "P3V3_STBY")
	)
	(segment
		(start 29.4005 -98.7044)
		(end 29.4005 -97.622106)
		(width 0.508)
		(layer "F.Cu")
		(net "P3V3_STBY")
	)
	(segment
		(start 47.680372 -180.6321)
		(end 47.804832 -180.50764)
		(width 0.381)
		(layer "F.Cu")
		(net "P3V3_STBY")
	)
	(segment
		(start 24.71674 -152.54224)
		(end 25.019 -152.8445)
		(width 0.3048)
		(layer "F.Cu")
		(net "P3V3_STBY")
	)
	(segment
		(start 188.6458 -5.0673)
		(end 188.5569 -5.1562)
		(width 0.508)
		(layer "F.Cu")
		(net "P3V3_STBY")
	)
	(segment
		(start 25.8445 -150.495)
		(end 25.843992 -150.494492)
		(width 0.508)
		(layer "F.Cu")
		(net "P3V3_STBY")
	)
	(segment
		(start 345.217496 -43.52798)
		(end 344.44178 -43.52798)
		(width 0.508)
		(layer "F.Cu")
		(net "P3V3_STBY")
	)
	(segment
		(start 54.1655 -136.779)
		(end 54.1655 -137.795)
		(width 0.508)
		(layer "F.Cu")
		(net "P3V3_STBY")
	)
	(segment
		(start 121.6152 -31.1785)
		(end 120.67032 -31.1785)
		(width 0.508)
		(layer "F.Cu")
		(net "P3V3_STBY")
	)
	(segment
		(start 328.835512 -183.3118)
		(end 330.638912 -181.5084)
		(width 0.508)
		(layer "F.Cu")
		(net "P3V3_STBY")
	)
	(segment
		(start 66.2813 -112.5982)
		(end 67.3354 -112.5982)
		(width 0.508)
		(layer "F.Cu")
		(net "P3V3_STBY")
	)
	(segment
		(start 15.823692 -122.9868)
		(end 15.3543 -122.9868)
		(width 0.508)
		(layer "F.Cu")
		(net "P3V3_STBY")
	)
	(segment
		(start 25.7175 -70.1802)
		(end 26.8351 -70.1802)
		(width 0.508)
		(layer "F.Cu")
		(net "P3V3_STBY")
	)
	(segment
		(start 38.5064 -103.1875)
		(end 37.78123 -103.1875)
		(width 0.508)
		(layer "F.Cu")
		(net "P3V3_STBY")
	)
	(segment
		(start 269.9004 -3.2258)
		(end 268.000988 -3.2258)
		(width 0.508)
		(layer "F.Cu")
		(net "P3V3_STBY")
	)
	(segment
		(start 47.244 -197.0405)
		(end 46.4185 -197.0405)
		(width 0.508)
		(layer "F.Cu")
		(net "P3V3_STBY")
	)
	(segment
		(start 52.1208 -50.7619)
		(end 53.2003 -50.7619)
		(width 0.508)
		(layer "F.Cu")
		(net "P3V3_STBY")
	)
	(segment
		(start 188.54166 -17.22628)
		(end 187.54852 -16.23314)
		(width 0.508)
		(layer "F.Cu")
		(net "P3V3_STBY")
	)
	(segment
		(start 272.95094 -4.923028)
		(end 272.622264 -4.923028)
		(width 0.508)
		(layer "F.Cu")
		(net "P3V3_STBY")
	)
	(segment
		(start 55.6514 -125.5776)
		(end 55.8292 -125.3998)
		(width 0.381)
		(layer "F.Cu")
		(net "P3V3_STBY")
	)
	(segment
		(start 231.648 -90.551)
		(end 231.14 -91.059)
		(width 0.508)
		(layer "F.Cu")
		(net "P3V3_STBY")
	)
	(segment
		(start 23.3045 -152.54224)
		(end 24.71674 -152.54224)
		(width 0.3048)
		(layer "F.Cu")
		(net "P3V3_STBY")
	)
	(segment
		(start 54.1655 -122.936)
		(end 54.1655 -122.428)
		(width 0.508)
		(layer "F.Cu")
		(net "P3V3_STBY")
	)
	(segment
		(start 120.1293 -99.8982)
		(end 119.3038 -99.8982)
		(width 0.508)
		(layer "F.Cu")
		(net "P3V3_STBY")
	)
	(segment
		(start 324.739 -86.0425)
		(end 325.755 -86.0425)
		(width 0.508)
		(layer "F.Cu")
		(net "P3V3_STBY")
	)
	(segment
		(start 69.2023 -75.2602)
		(end 69.3166 -75.3745)
		(width 0.508)
		(layer "F.Cu")
		(net "P3V3_STBY")
	)
	(segment
		(start 82.509868 -75.2856)
		(end 82.636868 -75.1586)
		(width 0.508)
		(layer "F.Cu")
		(net "P3V3_STBY")
	)
	(segment
		(start 26.4795 -75.9206)
		(end 26.67 -75.7301)
		(width 0.508)
		(layer "F.Cu")
		(net "P3V3_STBY")
	)
	(segment
		(start 205.8035 -19.6215)
		(end 205.486 -19.304)
		(width 0.508)
		(layer "F.Cu")
		(net "P3V3_STBY")
	)
	(segment
		(start 33.704784 -127.684784)
		(end 33.704784 -127.685292)
		(width 0.3556)
		(layer "F.Cu")
		(net "P3V3_STBY")
	)
	(segment
		(start 47.244 -195.0085)
		(end 47.5234 -194.7291)
		(width 0.381)
		(layer "F.Cu")
		(net "P3V3_STBY")
	)
	(segment
		(start 204.9526 -27.0002)
		(end 204.8129 -27.0002)
		(width 0.508)
		(layer "F.Cu")
		(net "P3V3_STBY")
	)
	(segment
		(start 26.8351 -70.1802)
		(end 27.051 -70.3961)
		(width 0.508)
		(layer "F.Cu")
		(net "P3V3_STBY")
	)
	(segment
		(start 69.8246 -78.2828)
		(end 68.7578 -77.216)
		(width 0.508)
		(layer "F.Cu")
		(net "P3V3_STBY")
	)
	(segment
		(start 54.1655 -124.46)
		(end 54.1655 -123.444)
		(width 0.508)
		(layer "F.Cu")
		(net "P3V3_STBY")
	)
	(segment
		(start 205.74 -27.7876)
		(end 204.9526 -27.0002)
		(width 0.508)
		(layer "F.Cu")
		(net "P3V3_STBY")
	)
	(segment
		(start 61.7728 -129.032)
		(end 61.44768 -129.35712)
		(width 0.508)
		(layer "F.Cu")
		(net "P3V3_STBY")
	)
	(segment
		(start 23.114 -133.731)
		(end 22.6822 -134.1628)
		(width 0.508)
		(layer "F.Cu")
		(net "P3V3_STBY")
	)
	(segment
		(start 52.6415 -185.293)
		(end 53.4162 -185.293)
		(width 0.508)
		(layer "F.Cu")
		(net "P3V3_STBY")
	)
	(segment
		(start 33.704784 -131.684522)
		(end 34.10458 -131.284726)
		(width 0.3556)
		(layer "F.Cu")
		(net "P3V3_STBY")
	)
	(segment
		(start 228.727254 -12.37107)
		(end 229.661466 -12.37107)
		(width 0.508)
		(layer "F.Cu")
		(net "P3V3_STBY")
	)
	(segment
		(start 191.9478 -20.3581)
		(end 192.4939 -20.9042)
		(width 0.508)
		(layer "F.Cu")
		(net "P3V3_STBY")
	)
	(segment
		(start 31.5341 -181.4322)
		(end 31.5341 -180.5432)
		(width 0.381)
		(layer "F.Cu")
		(net "P3V3_STBY")
	)
	(segment
		(start 112.263174 -47.086774)
		(end 110.0836 -44.9072)
		(width 0.508)
		(layer "F.Cu")
		(net "P3V3_STBY")
	)
	(segment
		(start 215.223598 -6.670802)
		(end 215.773 -6.1214)
		(width 0.2032)
		(layer "F.Cu")
		(net "P3V3_STBY")
	)
	(segment
		(start 200.8632 -35.179)
		(end 200.4822 -35.56)
		(width 0.508)
		(layer "F.Cu")
		(net "P3V3_STBY")
	)
	(segment
		(start 194.4243 -33.909)
		(end 193.84264 -33.909)
		(width 0.508)
		(layer "F.Cu")
		(net "P3V3_STBY")
	)
	(segment
		(start 231.648 -89.027)
		(end 231.648 -90.551)
		(width 0.508)
		(layer "F.Cu")
		(net "P3V3_STBY")
	)
	(segment
		(start 79.383128 -73.867772)
		(end 79.383128 -74.5617)
		(width 0.508)
		(layer "F.Cu")
		(net "P3V3_STBY")
	)
	(segment
		(start 39.476172 -186.7027)
		(end 39.600632 -186.57824)
		(width 0.381)
		(layer "F.Cu")
		(net "P3V3_STBY")
	)
	(segment
		(start 31.15183 -93.463364)
		(end 31.156402 -93.458792)
		(width 0.508)
		(layer "F.Cu")
		(net "P3V3_STBY")
	)
	(segment
		(start 70.5739 -52.9717)
		(end 71.3994 -52.9717)
		(width 0.508)
		(layer "F.Cu")
		(net "P3V3_STBY")
	)
	(segment
		(start 119.863108 -47.086774)
		(end 112.263174 -47.086774)
		(width 0.508)
		(layer "F.Cu")
		(net "P3V3_STBY")
	)
	(segment
		(start 22.944836 -128.317498)
		(end 23.151338 -128.524)
		(width 0.508)
		(layer "F.Cu")
		(net "P3V3_STBY")
	)
	(segment
		(start 23.4315 -131.699)
		(end 22.7076 -131.699)
		(width 0.508)
		(layer "F.Cu")
		(net "P3V3_STBY")
	)
	(segment
		(start 125.3998 -94.6277)
		(end 125.3998 -93.8022)
		(width 0.508)
		(layer "F.Cu")
		(net "P3V3_STBY")
	)
	(segment
		(start 142.67688 -35.559492)
		(end 142.67688 -34.774886)
		(width 0.508)
		(layer "F.Cu")
		(net "P3V3_STBY")
	)
	(segment
		(start 188.20384 -27.79014)
		(end 188.84646 -28.43276)
		(width 0.508)
		(layer "F.Cu")
		(net "P3V3_STBY")
	)
	(segment
		(start 20.32 -104.000808)
		(end 20.133818 -104.18699)
		(width 0.508)
		(layer "F.Cu")
		(net "P3V3_STBY")
	)
	(segment
		(start 54.1655 -135.763)
		(end 54.1655 -136.779)
		(width 0.508)
		(layer "F.Cu")
		(net "P3V3_STBY")
	)
	(segment
		(start 121.596912 -81.099152)
		(end 121.596912 -81.160112)
		(width 0.508)
		(layer "F.Cu")
		(net "P3V3_STBY")
	)
	(segment
		(start 47.680372 -194.7291)
		(end 47.804832 -194.60464)
		(width 0.381)
		(layer "F.Cu")
		(net "P3V3_STBY")
	)
	(segment
		(start 47.6885 -150.0505)
		(end 46.863 -150.876)
		(width 0.508)
		(layer "F.Cu")
		(net "P3V3_STBY")
	)
	(segment
		(start 70.567804 -192.404492)
		(end 70.440296 -192.532)
		(width 0.3048)
		(layer "F.Cu")
		(net "P3V3_STBY")
	)
	(segment
		(start 20.413726 -130.10896)
		(end 20.413726 -129.887472)
		(width 0.508)
		(layer "F.Cu")
		(net "P3V3_STBY")
	)
	(segment
		(start 122.73534 -3.34772)
		(end 122.73788 -6.78688)
		(width 0.508)
		(layer "F.Cu")
		(net "P3V3_STBY")
	)
	(segment
		(start 25.58542 -78.863698)
		(end 25.58542 -77.93228)
		(width 0.508)
		(layer "F.Cu")
		(net "P3V3_STBY")
	)
	(segment
		(start 231.521 -88.9)
		(end 229.5525 -88.9)
		(width 0.508)
		(layer "F.Cu")
		(net "P3V3_STBY")
	)
	(segment
		(start 84.2899 -57.2262)
		(end 85.1281 -56.388)
		(width 0.508)
		(layer "F.Cu")
		(net "P3V3_STBY")
	)
	(segment
		(start 192.4939 -26.1366)
		(end 191.4398 -26.1366)
		(width 0.508)
		(layer "F.Cu")
		(net "P3V3_STBY")
	)
	(segment
		(start 17.1704 -83.1469)
		(end 16.9799 -83.1469)
		(width 0.508)
		(layer "F.Cu")
		(net "P3V3_STBY")
	)
	(segment
		(start 26.67 -75.7301)
		(end 27.559 -75.7301)
		(width 0.508)
		(layer "F.Cu")
		(net "P3V3_STBY")
	)
	(segment
		(start 267.4239 -16.000476)
		(end 266.940284 -15.51686)
		(width 0.508)
		(layer "F.Cu")
		(net "P3V3_STBY")
	)
	(segment
		(start 61.244226 -129.413)
		(end 60.6552 -129.413)
		(width 0.508)
		(layer "F.Cu")
		(net "P3V3_STBY")
	)
	(segment
		(start 14.036294 -128.877314)
		(end 14.036294 -128.711198)
		(width 0.508)
		(layer "F.Cu")
		(net "P3V3_STBY")
	)
	(segment
		(start 188.7855 -7.27456)
		(end 188.7855 -5.3848)
		(width 0.508)
		(layer "F.Cu")
		(net "P3V3_STBY")
	)
	(segment
		(start 322.453 -100.0125)
		(end 322.453 -100.838)
		(width 0.508)
		(layer "F.Cu")
		(net "P3V3_STBY")
	)
	(segment
		(start 225.4631 -13.9192)
		(end 225.4631 -13.081)
		(width 0.508)
		(layer "F.Cu")
		(net "P3V3_STBY")
	)
	(segment
		(start 67.622674 -74.213974)
		(end 67.8942 -74.4855)
		(width 0.381)
		(layer "F.Cu")
		(net "P3V3_STBY")
	)
	(segment
		(start 7.1247 -82.9691)
		(end 6.97738 -83.11642)
		(width 0.508)
		(layer "F.Cu")
		(net "P3V3_STBY")
	)
	(segment
		(start 116.698268 -30.07868)
		(end 116.698268 -29.020516)
		(width 0.3556)
		(layer "F.Cu")
		(net "P3V3_STBY")
	)
	(segment
		(start 257.112262 -4.441952)
		(end 257.112262 -3.481578)
		(width 0.3556)
		(layer "F.Cu")
		(net "P3V3_STBY")
	)
	(segment
		(start 67.363848 -129.794)
		(end 68.326 -129.794)
		(width 0.4064)
		(layer "F.Cu")
		(net "P3V3_STBY")
	)
	(segment
		(start 116.698268 -28.447492)
		(end 116.698268 -29.020516)
		(width 0.3556)
		(layer "F.Cu")
		(net "P3V3_STBY")
	)
	(segment
		(start 330.835 -86.0425)
		(end 329.819 -86.0425)
		(width 0.508)
		(layer "F.Cu")
		(net "P3V3_STBY")
	)
	(segment
		(start 128.996694 -34.075116)
		(end 128.996694 -33.201864)
		(width 0.508)
		(layer "F.Cu")
		(net "P3V3_STBY")
	)
	(segment
		(start 215.773 -6.1214)
		(end 216.9922 -6.1214)
		(width 0.2032)
		(layer "F.Cu")
		(net "P3V3_STBY")
	)
	(segment
		(start 42.904664 -131.28498)
		(end 42.504868 -131.684776)
		(width 0.3556)
		(layer "F.Cu")
		(net "P3V3_STBY")
	)
	(segment
		(start 23.540974 -88.8492)
		(end 24.30018 -88.089994)
		(width 0.508)
		(layer "F.Cu")
		(net "P3V3_STBY")
	)
	(segment
		(start 203.470256 -25.527)
		(end 204.331824 -25.527)
		(width 0.3048)
		(layer "F.Cu")
		(net "P3V3_STBY")
	)
	(segment
		(start 17.3736 -136.311894)
		(end 17.3736 -137.2616)
		(width 0.508)
		(layer "F.Cu")
		(net "P3V3_STBY")
	)
	(segment
		(start 40.904414 -134.884922)
		(end 40.504618 -134.485126)
		(width 0.3556)
		(layer "F.Cu")
		(net "P3V3_STBY")
	)
	(segment
		(start 15.9512 -83.9851)
		(end 15.9512 -84.8614)
		(width 0.508)
		(layer "F.Cu")
		(net "P3V3_STBY")
	)
	(segment
		(start 188.6458 -3.8227)
		(end 188.6458 -5.0673)
		(width 0.508)
		(layer "F.Cu")
		(net "P3V3_STBY")
	)
	(segment
		(start 37.211 -200.9775)
		(end 36.322 -200.9775)
		(width 0.381)
		(layer "F.Cu")
		(net "P3V3_STBY")
	)
	(segment
		(start 17.18818 -135.085074)
		(end 17.18818 -136.126474)
		(width 0.508)
		(layer "F.Cu")
		(net "P3V3_STBY")
	)
	(segment
		(start 218.649804 -200.450196)
		(end 218.649804 -199.770492)
		(width 0.3556)
		(layer "F.Cu")
		(net "P3V3_STBY")
	)
	(segment
		(start 23.7998 -76.9874)
		(end 24.7142 -77.9018)
		(width 0.508)
		(layer "F.Cu")
		(net "P3V3_STBY")
	)
	(segment
		(start 54.1655 -123.444)
		(end 54.1655 -122.936)
		(width 0.508)
		(layer "F.Cu")
		(net "P3V3_STBY")
	)
	(segment
		(start 56.279796 -29.21381)
		(end 56.829706 -28.6639)
		(width 0.508)
		(layer "F.Cu")
		(net "P3V3_STBY")
	)
	(segment
		(start 15.0495 -122.3391)
		(end 15.0495 -122.682)
		(width 0.508)
		(layer "F.Cu")
		(net "P3V3_STBY")
	)
	(segment
		(start 206.289402 -28.337002)
		(end 205.74 -27.7876)
		(width 0.508)
		(layer "F.Cu")
		(net "P3V3_STBY")
	)
	(segment
		(start 229.5525 -88.9)
		(end 229.5525 -87.7824)
		(width 0.508)
		(layer "F.Cu")
		(net "P3V3_STBY")
	)
	(segment
		(start 184.78246 -15.77594)
		(end 184.78246 -14.818868)
		(width 0.508)
		(layer "F.Cu")
		(net "P3V3_STBY")
	)
	(segment
		(start 56.829706 -28.6639)
		(end 57.1246 -28.6639)
		(width 0.508)
		(layer "F.Cu")
		(net "P3V3_STBY")
	)
	(segment
		(start 325.6915 -101.9175)
		(end 326.39 -101.219)
		(width 0.508)
		(layer "F.Cu")
		(net "P3V3_STBY")
	)
	(segment
		(start 161.5821 -101.6254)
		(end 178.0286 -101.6254)
		(width 0.508)
		(layer "F.Cu")
		(net "P3V3_STBY")
	)
	(segment
		(start 39.0398 -186.9821)
		(end 39.3192 -186.7027)
		(width 0.381)
		(layer "F.Cu")
		(net "P3V3_STBY")
	)
	(segment
		(start 47.7901 -115.56492)
		(end 47.7901 -116.44757)
		(width 0.508)
		(layer "F.Cu")
		(net "P3V3_STBY")
	)
	(segment
		(start 56.7055 -119.126)
		(end 56.7055 -118.11)
		(width 0.508)
		(layer "F.Cu")
		(net "P3V3_STBY")
	)
	(segment
		(start 55.118 -194.1195)
		(end 55.118 -193.294)
		(width 0.508)
		(layer "F.Cu")
		(net "P3V3_STBY")
	)
	(segment
		(start 144.365472 -98.460052)
		(end 147.53082 -101.6254)
		(width 0.508)
		(layer "F.Cu")
		(net "P3V3_STBY")
	)
	(segment
		(start 55.602124 -122.729244)
		(end 55.6006 -122.729244)
		(width 0.508)
		(layer "F.Cu")
		(net "P3V3_STBY")
	)
	(segment
		(start 188.31814 -28.96108)
		(end 188.84646 -28.43276)
		(width 0.508)
		(layer "F.Cu")
		(net "P3V3_STBY")
	)
	(segment
		(start 258.8006 -3.793998)
		(end 258.854702 -3.8481)
		(width 0.508)
		(layer "F.Cu")
		(net "P3V3_STBY")
	)
	(segment
		(start 128.996694 -33.201864)
		(end 128.953768 -33.158938)
		(width 0.508)
		(layer "F.Cu")
		(net "P3V3_STBY")
	)
	(segment
		(start 327.533 -100.0125)
		(end 326.517 -100.0125)
		(width 0.508)
		(layer "F.Cu")
		(net "P3V3_STBY")
	)
	(segment
		(start 23.4315 -132.715)
		(end 23.4315 -131.699)
		(width 0.508)
		(layer "F.Cu")
		(net "P3V3_STBY")
	)
	(segment
		(start 192.6844 -32.75076)
		(end 192.6844 -31.3817)
		(width 0.508)
		(layer "F.Cu")
		(net "P3V3_STBY")
	)
	(segment
		(start 29.4005 -97.622106)
		(end 29.451554 -97.571052)
		(width 0.508)
		(layer "F.Cu")
		(net "P3V3_STBY")
	)
	(segment
		(start 227.711 -2.413)
		(end 227.711 -3.3655)
		(width 0.508)
		(layer "F.Cu")
		(net "P3V3_STBY")
	)
	(segment
		(start 269.857982 -12.403328)
		(end 269.857982 -10.399268)
		(width 0.508)
		(layer "F.Cu")
		(net "P3V3_STBY")
	)
	(segment
		(start 29.383736 -112.804956)
		(end 29.52369 -112.94491)
		(width 0.508)
		(layer "F.Cu")
		(net "P3V3_STBY")
	)
	(segment
		(start 19.2024 -131.7244)
		(end 19.2024 -131.1656)
		(width 0.508)
		(layer "F.Cu")
		(net "P3V3_STBY")
	)
	(segment
		(start 154.914854 -33.866074)
		(end 154.454606 -33.405826)
		(width 0.508)
		(layer "F.Cu")
		(net "P3V3_STBY")
	)
	(segment
		(start 61.0616 -58.5089)
		(end 62.0268 -58.5089)
		(width 0.508)
		(layer "F.Cu")
		(net "P3V3_STBY")
	)
	(segment
		(start 20.5105 -148.844)
		(end 19.6215 -148.844)
		(width 0.508)
		(layer "F.Cu")
		(net "P3V3_STBY")
	)
	(segment
		(start 322.707 -85.09)
		(end 322.707 -85.217)
		(width 0.508)
		(layer "F.Cu")
		(net "P3V3_STBY")
	)
	(segment
		(start 257.670554 -10.555224)
		(end 258.548632 -10.555224)
		(width 0.508)
		(layer "F.Cu")
		(net "P3V3_STBY")
	)
	(segment
		(start 22.4536 -134.4422)
		(end 22.6568 -134.239)
		(width 0.508)
		(layer "F.Cu")
		(net "P3V3_STBY")
	)
	(segment
		(start 126.182628 -33.159192)
		(end 126.182628 -34.11601)
		(width 0.508)
		(layer "F.Cu")
		(net "P3V3_STBY")
	)
	(segment
		(start 46.863 -146.8882)
		(end 46.863 -150.876)
		(width 0.508)
		(layer "F.Cu")
		(net "P3V3_STBY")
	)
	(segment
		(start 23.4315 -135.763)
		(end 23.4315 -134.747)
		(width 0.508)
		(layer "F.Cu")
		(net "P3V3_STBY")
	)
	(segment
		(start 67.622674 -72.023986)
		(end 67.622674 -74.213974)
		(width 0.381)
		(layer "F.Cu")
		(net "P3V3_STBY")
	)
	(segment
		(start 50.2666 -48.1584)
		(end 48.7172 -48.1584)
		(width 0.508)
		(layer "F.Cu")
		(net "P3V3_STBY")
	)
	(segment
		(start 226.48164 -83.77936)
		(end 226.822 -83.439)
		(width 0.3048)
		(layer "F.Cu")
		(net "P3V3_STBY")
	)
	(segment
		(start 14.7574 -84.1121)
		(end 14.7574 -84.9884)
		(width 0.508)
		(layer "F.Cu")
		(net "P3V3_STBY")
	)
	(segment
		(start 20.420076 -129.881122)
		(end 20.420076 -129.243074)
		(width 0.508)
		(layer "F.Cu")
		(net "P3V3_STBY")
	)
	(segment
		(start 50.251614 -110.208568)
		(end 50.2539 -110.210854)
		(width 0.508)
		(layer "F.Cu")
		(net "P3V3_STBY")
	)
	(segment
		(start 32.904938 -136.484868)
		(end 32.522414 -136.102344)
		(width 0.254)
		(layer "F.Cu")
		(net "P3V3_STBY")
	)
	(segment
		(start 52.3113 -112.6871)
		(end 52.1208 -112.4966)
		(width 0.508)
		(layer "F.Cu")
		(net "P3V3_STBY")
	)
	(segment
		(start 37.704776 -126.084838)
		(end 37.704522 -126.084838)
		(width 0.3556)
		(layer "F.Cu")
		(net "P3V3_STBY")
	)
	(segment
		(start 179.590954 -3.092196)
		(end 179.78501 -3.092196)
		(width 0.508)
		(layer "F.Cu")
		(net "P3V3_STBY")
	)
	(segment
		(start 71.87184 -36.957)
		(end 72.30364 -36.5252)
		(width 0.508)
		(layer "F.Cu")
		(net "P3V3_STBY")
	)
	(segment
		(start 75.7936 -122.8217)
		(end 75.7682 -122.8471)
		(width 0.381)
		(layer "F.Cu")
		(net "P3V3_STBY")
	)
	(segment
		(start 68.7578 -77.216)
		(end 67.31 -77.216)
		(width 0.508)
		(layer "F.Cu")
		(net "P3V3_STBY")
	)
	(segment
		(start 9.9822 -98.947478)
		(end 9.9822 -99.187)
		(width 0.508)
		(layer "F.Cu")
		(net "P3V3_STBY")
	)
	(segment
		(start 332.5495 -100.0125)
		(end 332.634336 -100.097336)
		(width 0.508)
		(layer "F.Cu")
		(net "P3V3_STBY")
	)
	(segment
		(start 15.10538 -127.56388)
		(end 16.133826 -127.56388)
		(width 0.508)
		(layer "F.Cu")
		(net "P3V3_STBY")
	)
	(segment
		(start 75.6539 -57.2262)
		(end 84.2899 -57.2262)
		(width 0.508)
		(layer "F.Cu")
		(net "P3V3_STBY")
	)
	(segment
		(start 231.648 -89.027)
		(end 231.521 -88.9)
		(width 0.508)
		(layer "F.Cu")
		(net "P3V3_STBY")
	)
	(segment
		(start 350.046036 -44.058586)
		(end 350.950784 -44.058586)
		(width 0.508)
		(layer "F.Cu")
		(net "P3V3_STBY")
	)
	(segment
		(start 22.7076 -70.485)
		(end 22.7076 -70.9422)
		(width 0.508)
		(layer "F.Cu")
		(net "P3V3_STBY")
	)
	(segment
		(start 9.0678 -124.079)
		(end 9.4615 -123.6853)
		(width 0.508)
		(layer "F.Cu")
		(net "P3V3_STBY")
	)
	(segment
		(start 7.136892 -78.961488)
		(end 6.647688 -78.961488)
		(width 0.508)
		(layer "F.Cu")
		(net "P3V3_STBY")
	)
	(segment
		(start 215.876124 -202.602592)
		(end 217.564716 -200.914)
		(width 0.508)
		(layer "F.Cu")
		(net "P3V3_STBY")
	)
	(segment
		(start 78.953106 -86.487254)
		(end 78.953106 -87.462106)
		(width 0.508)
		(layer "F.Cu")
		(net "P3V3_STBY")
	)
	(segment
		(start 69.30644 -124.115322)
		(end 69.3039 -124.112782)
		(width 0.508)
		(layer "F.Cu")
		(net "P3V3_STBY")
	)
	(segment
		(start 7.1247 -81.5848)
		(end 6.268212 -81.5848)
		(width 0.508)
		(layer "F.Cu")
		(net "P3V3_STBY")
	)
	(segment
		(start 54.983126 -45.59935)
		(end 53.462936 -45.59935)
		(width 0.508)
		(layer "F.Cu")
		(net "P3V3_STBY")
	)
	(segment
		(start 27.488896 -41.754298)
		(end 27.488896 -42.780966)
		(width 0.508)
		(layer "F.Cu")
		(net "P3V3_STBY")
	)
	(segment
		(start 76.581 -122.8217)
		(end 75.7936 -122.8217)
		(width 0.381)
		(layer "F.Cu")
		(net "P3V3_STBY")
	)
	(segment
		(start 331.609192 -181.601618)
		(end 330.73213 -181.601618)
		(width 0.3048)
		(layer "F.Cu")
		(net "P3V3_STBY")
	)
	(segment
		(start 37.4904 -200.6981)
		(end 37.647372 -200.6981)
		(width 0.381)
		(layer "F.Cu")
		(net "P3V3_STBY")
	)
	(segment
		(start 59.9694 -130.0988)
		(end 59.9694 -131.3434)
		(width 0.508)
		(layer "F.Cu")
		(net "P3V3_STBY")
	)
	(segment
		(start 227.33 -11.684)
		(end 228.854 -11.684)
		(width 0.508)
		(layer "F.Cu")
		(net "P3V3_STBY")
	)
	(segment
		(start 22.6822 -134.1628)
		(end 22.6822 -134.2136)
		(width 0.508)
		(layer "F.Cu")
		(net "P3V3_STBY")
	)
	(segment
		(start 23.4315 -133.731)
		(end 23.114 -133.731)
		(width 0.508)
		(layer "F.Cu")
		(net "P3V3_STBY")
	)
	(segment
		(start 42.504868 -130.88493)
		(end 42.504868 -130.885184)
		(width 0.3556)
		(layer "F.Cu")
		(net "P3V3_STBY")
	)
	(segment
		(start 54.9402 -138.7729)
		(end 54.9021 -138.811)
		(width 0.508)
		(layer "F.Cu")
		(net "P3V3_STBY")
	)
	(segment
		(start 23.4315 -134.747)
		(end 23.4315 -133.731)
		(width 0.508)
		(layer "F.Cu")
		(net "P3V3_STBY")
	)
	(segment
		(start 46.355 -180.9115)
		(end 45.4025 -180.9115)
		(width 0.508)
		(layer "F.Cu")
		(net "P3V3_STBY")
	)
	(segment
		(start 68.058284 -194.972432)
		(end 68.058284 -191.99352)
		(width 0.508)
		(layer "F.Cu")
		(net "P3V3_STBY")
	)
	(segment
		(start 66.925952 -146.85391)
		(end 65.084452 -146.85391)
		(width 0.508)
		(layer "F.Cu")
		(net "P3V3_STBY")
	)
	(segment
		(start 63.03264 -87.15756)
		(end 63.0809 -87.1093)
		(width 0.508)
		(layer "F.Cu")
		(net "P3V3_STBY")
	)
	(segment
		(start 16.911066 -81.09966)
		(end 16.911066 -80.090518)
		(width 0.3048)
		(layer "F.Cu")
		(net "P3V3_STBY")
	)
	(segment
		(start 74.66076 -78.2828)
		(end 69.8246 -78.2828)
		(width 0.508)
		(layer "F.Cu")
		(net "P3V3_STBY")
	)
	(segment
		(start 194.4243 -33.909)
		(end 194.4243 -35.7505)
		(width 0.508)
		(layer "F.Cu")
		(net "P3V3_STBY")
	)
	(segment
		(start 75.623166 -90.14206)
		(end 74.099166 -90.14206)
		(width 0.508)
		(layer "F.Cu")
		(net "P3V3_STBY")
	)
	(segment
		(start 204.8129 -26.1112)
		(end 204.8129 -27.0002)
		(width 0.508)
		(layer "F.Cu")
		(net "P3V3_STBY")
	)
	(segment
		(start 75.7682 -122.8471)
		(end 75.214988 -122.8471)
		(width 0.381)
		(layer "F.Cu")
		(net "P3V3_STBY")
	)
	(segment
		(start 191.4525 -16.256)
		(end 190.70066 -16.256)
		(width 0.508)
		(layer "F.Cu")
		(net "P3V3_STBY")
	)
	(segment
		(start 328.803 -86.0425)
		(end 327.787 -86.0425)
		(width 0.508)
		(layer "F.Cu")
		(net "P3V3_STBY")
	)
	(segment
		(start 184.04078 -13.28674)
		(end 184.04078 -14.23924)
		(width 0.508)
		(layer "F.Cu")
		(net "P3V3_STBY")
	)
	(segment
		(start 31.8135 -181.868572)
		(end 31.93796 -181.993032)
		(width 0.381)
		(layer "F.Cu")
		(net "P3V3_STBY")
	)
	(segment
		(start 30.127194 -93.524324)
		(end 31.09087 -93.524324)
		(width 0.508)
		(layer "F.Cu")
		(net "P3V3_STBY")
	)
	(segment
		(start 19.514566 -148.950934)
		(end 19.6215 -148.844)
		(width 0.4064)
		(layer "F.Cu")
		(net "P3V3_STBY")
	)
	(segment
		(start 81.6102 -76.581)
		(end 81.448148 -76.418948)
		(width 0.508)
		(layer "F.Cu")
		(net "P3V3_STBY")
	)
	(segment
		(start 200.4822 -35.56)
		(end 198.7423 -35.56)
		(width 0.508)
		(layer "F.Cu")
		(net "P3V3_STBY")
	)
	(segment
		(start 57.85358 -31.3817)
		(end 57.913778 -31.441898)
		(width 0.508)
		(layer "F.Cu")
		(net "P3V3_STBY")
	)
	(segment
		(start 22.868636 -128.317498)
		(end 22.944836 -128.317498)
		(width 0.508)
		(layer "F.Cu")
		(net "P3V3_STBY")
	)
	(segment
		(start 48.641 -150.0505)
		(end 47.6885 -150.0505)
		(width 0.508)
		(layer "F.Cu")
		(net "P3V3_STBY")
	)
	(segment
		(start 334.0735 -69.723)
		(end 333.4766 -69.723)
		(width 0.254)
		(layer "F.Cu")
		(net "P3V3_STBY")
	)
	(segment
		(start 19.642074 -129.387346)
		(end 19.36242 -129.667)
		(width 0.508)
		(layer "F.Cu")
		(net "P3V3_STBY")
	)
	(segment
		(start 149.9362 -51.2064)
		(end 149.9362 -42.550588)
		(width 0.508)
		(layer "F.Cu")
		(net "P3V3_STBY")
	)
	(segment
		(start 181.19725 -5.647436)
		(end 181.19725 -6.210808)
		(width 0.508)
		(layer "F.Cu")
		(net "P3V3_STBY")
	)
	(segment
		(start 28.548584 -92.377514)
		(end 29.911294 -93.740224)
		(width 0.508)
		(layer "F.Cu")
		(net "P3V3_STBY")
	)
	(segment
		(start 156.898594 -33.866074)
		(end 155.882086 -33.866074)
		(width 0.508)
		(layer "F.Cu")
		(net "P3V3_STBY")
	)
	(segment
		(start 31.93796 -181.993032)
		(end 31.93796 -183.2991)
		(width 0.381)
		(layer "F.Cu")
		(net "P3V3_STBY")
	)
	(segment
		(start 198.7423 -35.56)
		(end 198.3994 -35.2171)
		(width 0.508)
		(layer "F.Cu")
		(net "P3V3_STBY")
	)
	(segment
		(start 183.900572 -1.452626)
		(end 183.505602 -1.057656)
		(width 0.508)
		(layer "F.Cu")
		(net "P3V3_STBY")
	)
	(segment
		(start 21.7805 -163.068)
		(end 22.0345 -163.068)
		(width 0.508)
		(layer "F.Cu")
		(net "P3V3_STBY")
	)
	(segment
		(start 20.275804 -129.387346)
		(end 19.642074 -129.387346)
		(width 0.508)
		(layer "F.Cu")
		(net "P3V3_STBY")
	)
	(segment
		(start 71.4375 -36.957)
		(end 71.87184 -36.957)
		(width 0.508)
		(layer "F.Cu")
		(net "P3V3_STBY")
	)
	(segment
		(start 26.4795 -76.9366)
		(end 26.4795 -75.9206)
		(width 0.508)
		(layer "F.Cu")
		(net "P3V3_STBY")
	)
	(segment
		(start 331.216 -22.0345)
		(end 331.216 -22.987)
		(width 0.508)
		(layer "F.Cu")
		(net "P3V3_STBY")
	)
	(segment
		(start 258.8006 -3.606292)
		(end 258.8006 -3.793998)
		(width 0.508)
		(layer "F.Cu")
		(net "P3V3_STBY")
	)
	(segment
		(start 34.10458 -128.085088)
		(end 33.704784 -128.484884)
		(width 0.3556)
		(layer "F.Cu")
		(net "P3V3_STBY")
	)
	(segment
		(start 66.802 -76.708)
		(end 66.802 -75.3999)
		(width 0.508)
		(layer "F.Cu")
		(net "P3V3_STBY")
	)
	(segment
		(start 190.70066 -16.256)
		(end 190.53302 -16.08836)
		(width 0.508)
		(layer "F.Cu")
		(net "P3V3_STBY")
	)
	(segment
		(start 217.996008 -4.5085)
		(end 218.885008 -4.5085)
		(width 0.508)
		(layer "F.Cu")
		(net "P3V3_STBY")
	)
	(segment
		(start 264.114788 -9.078722)
		(end 264.121646 -9.071864)
		(width 0.508)
		(layer "F.Cu")
		(net "P3V3_STBY")
	)
	(segment
		(start 28.4099 -99.5553)
		(end 28.4353 -99.5807)
		(width 0.508)
		(layer "F.Cu")
		(net "P3V3_STBY")
	)
	(segment
		(start 25.8445 -151.2824)
		(end 25.8445 -150.495)
		(width 0.508)
		(layer "F.Cu")
		(net "P3V3_STBY")
	)
	(segment
		(start 331.211682 -4.948682)
		(end 331.211682 -5.609082)
		(width 0.508)
		(layer "F.Cu")
		(net "P3V3_STBY")
	)
	(segment
		(start 23.151338 -128.524)
		(end 23.4315 -128.524)
		(width 0.508)
		(layer "F.Cu")
		(net "P3V3_STBY")
	)
	(segment
		(start 52.1208 -50.7619)
		(end 52.328572 -50.969672)
		(width 0.508)
		(layer "F.Cu")
		(net "P3V3_STBY")
	)
	(segment
		(start 56.816752 -146.281648)
		(end 56.4642 -146.6342)
		(width 0.508)
		(layer "F.Cu")
		(net "P3V3_STBY")
	)
	(segment
		(start 63.2333 -112.5982)
		(end 62.57925 -111.94415)
		(width 0.508)
		(layer "F.Cu")
		(net "P3V3_STBY")
	)
	(segment
		(start 26.318718 -85.41131)
		(end 26.937208 -85.41131)
		(width 0.508)
		(layer "F.Cu")
		(net "P3V3_STBY")
	)
	(segment
		(start 248.0818 -4.9784)
		(end 248.339102 -4.721098)
		(width 0.508)
		(layer "F.Cu")
		(net "P3V3_STBY")
	)
	(segment
		(start 62.57925 -111.94415)
		(end 62.2046 -111.5695)
		(width 0.508)
		(layer "F.Cu")
		(net "P3V3_STBY")
	)
	(segment
		(start 188.54166 -17.4117)
		(end 188.54166 -17.22628)
		(width 0.508)
		(layer "F.Cu")
		(net "P3V3_STBY")
	)
	(segment
		(start 216.9922 -6.1214)
		(end 217.0938 -6.223)
		(width 0.2032)
		(layer "F.Cu")
		(net "P3V3_STBY")
	)
	(segment
		(start 72.445626 -127.7493)
		(end 72.686926 -127.508)
		(width 0.4064)
		(layer "F.Cu")
		(net "P3V3_STBY")
	)
	(segment
		(start 61.300106 -129.35712)
		(end 61.244226 -129.413)
		(width 0.508)
		(layer "F.Cu")
		(net "P3V3_STBY")
	)
	(segment
		(start 328.835512 -184.433718)
		(end 328.835512 -183.3118)
		(width 0.508)
		(layer "F.Cu")
		(net "P3V3_STBY")
	)
	(segment
		(start 229.9335 -84.1375)
		(end 229.997 -84.1375)
		(width 0.3048)
		(layer "F.Cu")
		(net "P3V3_STBY")
	)
	(segment
		(start 66.80962 -129.590292)
		(end 66.003678 -129.590292)
		(width 0.4064)
		(layer "F.Cu")
		(net "P3V3_STBY")
	)
	(segment
		(start 215.623648 -6.854952)
		(end 216.0016 -6.477)
		(width 0.2032)
		(layer "F.Cu")
		(net "P3V3_STBY")
	)
	(segment
		(start 20.3962 -65.5574)
		(end 19.812 -64.9732)
		(width 0.508)
		(layer "F.Cu")
		(net "P3V3_STBY")
	)
	(segment
		(start 81.610708 -75.2856)
		(end 82.509868 -75.2856)
		(width 0.508)
		(layer "F.Cu")
		(net "P3V3_STBY")
	)
	(segment
		(start 205.8035 -23.0124)
		(end 207.518 -23.0124)
		(width 0.508)
		(layer "F.Cu")
		(net "P3V3_STBY")
	)
	(segment
		(start 207.518 -23.0124)
		(end 208.026 -23.5204)
		(width 0.508)
		(layer "F.Cu")
		(net "P3V3_STBY")
	)
	(segment
		(start 118.364 -16.6243)
		(end 118.364 -15.8242)
		(width 0.508)
		(layer "F.Cu")
		(net "P3V3_STBY")
	)
	(segment
		(start 31.5341 -181.4322)
		(end 31.8135 -181.7116)
		(width 0.381)
		(layer "F.Cu")
		(net "P3V3_STBY")
	)
	(segment
		(start 51.5239 -63.754)
		(end 50.1777 -63.754)
		(width 0.508)
		(layer "F.Cu")
		(net "P3V3_STBY")
	)
	(segment
		(start 70.6247 -162.2806)
		(end 71.5772 -162.2806)
		(width 0.508)
		(layer "F.Cu")
		(net "P3V3_STBY")
	)
	(segment
		(start 80.0862 -86.5505)
		(end 80.0862 -87.503)
		(width 0.508)
		(layer "F.Cu")
		(net "P3V3_STBY")
	)
	(segment
		(start 206.289402 -30.200092)
		(end 206.289402 -28.337002)
		(width 0.508)
		(layer "F.Cu")
		(net "P3V3_STBY")
	)
	(segment
		(start 184.023 -95.631)
		(end 230.9114 -95.631)
		(width 0.508)
		(layer "F.Cu")
		(net "P3V3_STBY")
	)
	(segment
		(start 7.4295 -108.966)
		(end 6.477 -108.966)
		(width 0.508)
		(layer "F.Cu")
		(net "P3V3_STBY")
	)
	(segment
		(start 225.17608 -2.826258)
		(end 225.672396 -2.329942)
		(width 0.508)
		(layer "F.Cu")
		(net "P3V3_STBY")
	)
	(segment
		(start 63.0809 -87.1093)
		(end 63.0809 -86.2838)
		(width 0.508)
		(layer "F.Cu")
		(net "P3V3_STBY")
	)
	(segment
		(start 85.70214 -75.66914)
		(end 85.70214 -75.16114)
		(width 0.508)
		(layer "F.Cu")
		(net "P3V3_STBY")
	)
	(segment
		(start 71.964804 -124.9045)
		(end 72.587104 -124.2822)
		(width 0.508)
		(layer "F.Cu")
		(net "P3V3_STBY")
	)
	(segment
		(start 214.917274 -2.090674)
		(end 215.138 -2.3114)
		(width 0.508)
		(layer "F.Cu")
		(net "P3V3_STBY")
	)
	(segment
		(start 204.4954 -25.690576)
		(end 204.4954 -25.8064)
		(width 0.3048)
		(layer "F.Cu")
		(net "P3V3_STBY")
	)
	(segment
		(start 248.339102 -4.721098)
		(end 250.105418 -4.721098)
		(width 0.508)
		(layer "F.Cu")
		(net "P3V3_STBY")
	)
	(segment
		(start 39.600632 -186.57824)
		(end 40.9067 -186.57824)
		(width 0.381)
		(layer "F.Cu")
		(net "P3V3_STBY")
	)
	(segment
		(start 31.156402 -92.552012)
		(end 30.936946 -92.332556)
		(width 0.508)
		(layer "F.Cu")
		(net "P3V3_STBY")
	)
	(segment
		(start 192.4939 -23.0124)
		(end 192.4939 -21.971)
		(width 0.508)
		(layer "F.Cu")
		(net "P3V3_STBY")
	)
	(segment
		(start 85.70214 -75.16114)
		(end 85.34654 -75.16114)
		(width 0.508)
		(layer "F.Cu")
		(net "P3V3_STBY")
	)
	(segment
		(start 204.4954 -25.8064)
		(end 204.8002 -26.1112)
		(width 0.3048)
		(layer "F.Cu")
		(net "P3V3_STBY")
	)
	(segment
		(start 50.8762 -49.8729)
		(end 51.0413 -49.8729)
		(width 0.508)
		(layer "F.Cu")
		(net "P3V3_STBY")
	)
	(segment
		(start 29.383736 -112.0521)
		(end 29.383736 -112.804956)
		(width 0.508)
		(layer "F.Cu")
		(net "P3V3_STBY")
	)
	(segment
		(start 142.901162 -35.783774)
		(end 142.67688 -35.559492)
		(width 0.508)
		(layer "F.Cu")
		(net "P3V3_STBY")
	)
	(segment
		(start 57.0484 -31.3817)
		(end 57.85358 -31.3817)
		(width 0.508)
		(layer "F.Cu")
		(net "P3V3_STBY")
	)
	(segment
		(start 265.028172 -9.071864)
		(end 265.151108 -9.1948)
		(width 0.508)
		(layer "F.Cu")
		(net "P3V3_STBY")
	)
	(segment
		(start 52.04714 -148.569934)
		(end 52.04714 -149.01164)
		(width 0.3556)
		(layer "F.Cu")
		(net "P3V3_STBY")
	)
	(segment
		(start 117.5258 -97.5487)
		(end 116.7003 -97.5487)
		(width 0.508)
		(layer "F.Cu")
		(net "P3V3_STBY")
	)
	(segment
		(start 51.0413 -49.8729)
		(end 51.9303 -50.7619)
		(width 0.508)
		(layer "F.Cu")
		(net "P3V3_STBY")
	)
	(segment
		(start 42.183558 -113.721134)
		(end 42.299636 -113.837212)
		(width 0.508)
		(layer "F.Cu")
		(net "P3V3_STBY")
	)
	(segment
		(start 225.4631 -13.081)
		(end 224.663 -13.081)
		(width 0.508)
		(layer "F.Cu")
		(net "P3V3_STBY")
	)
	(segment
		(start 118.086632 -95.11284)
		(end 119.3927 -95.11284)
		(width 0.381)
		(layer "F.Cu")
		(net "P3V3_STBY")
	)
	(segment
		(start 351.063052 -46.717458)
		(end 350.904556 -46.875954)
		(width 0.508)
		(layer "F.Cu")
		(net "P3V3_STBY")
	)
	(segment
		(start 31.8135 -181.7116)
		(end 31.8135 -181.868572)
		(width 0.381)
		(layer "F.Cu")
		(net "P3V3_STBY")
	)
	(segment
		(start 237.617 -19.9644)
		(end 238.0996 -19.4818)
		(width 0.508)
		(layer "F.Cu")
		(net "P3V3_STBY")
	)
	(segment
		(start 200.8632 -31.9278)
		(end 200.8632 -35.179)
		(width 0.508)
		(layer "F.Cu")
		(net "P3V3_STBY")
	)
	(segment
		(start 42.504868 -127.684784)
		(end 42.504868 -127.685292)
		(width 0.3556)
		(layer "F.Cu")
		(net "P3V3_STBY")
	)
	(segment
		(start 37.647372 -200.6981)
		(end 37.771832 -200.57364)
		(width 0.381)
		(layer "F.Cu")
		(net "P3V3_STBY")
	)
	(segment
		(start 200.9648 -31.8262)
		(end 200.8632 -31.9278)
		(width 0.508)
		(layer "F.Cu")
		(net "P3V3_STBY")
	)
	(segment
		(start 191.9478 -20.0914)
		(end 191.9478 -20.3581)
		(width 0.508)
		(layer "F.Cu")
		(net "P3V3_STBY")
	)
	(segment
		(start 219.0115 -13.4112)
		(end 218.2876 -13.4112)
		(width 0.508)
		(layer "F.Cu")
		(net "P3V3_STBY")
	)
	(segment
		(start 124.796804 -205.612492)
		(end 123.838208 -205.612492)
		(width 0.3556)
		(layer "F.Cu")
		(net "P3V3_STBY")
	)
	(segment
		(start 202.02144 -32.88284)
		(end 201.65822 -32.51962)
		(width 0.3556)
		(layer "F.Cu")
		(net "P3V3_STBY")
	)
	(segment
		(start 158.905702 -60.479432)
		(end 160.957768 -60.479432)
		(width 0.508)
		(layer "F.Cu")
		(net "P3V3_STBY")
	)
	(segment
		(start 65.084452 -146.85391)
		(end 64.957452 -146.72691)
		(width 0.508)
		(layer "F.Cu")
		(net "P3V3_STBY")
	)
	(segment
		(start 225.8441 -0.635)
		(end 227.5205 -0.635)
		(width 0.3048)
		(layer "F.Cu")
		(net "P3V3_STBY")
	)
	(segment
		(start 19.514566 -150.61438)
		(end 19.514566 -148.950934)
		(width 0.4064)
		(layer "F.Cu")
		(net "P3V3_STBY")
	)
	(segment
		(start 215.223598 -7.4676)
		(end 215.223598 -6.670802)
		(width 0.2032)
		(layer "F.Cu")
		(net "P3V3_STBY")
	)
	(segment
		(start 264.17778 -6.837934)
		(end 264.190734 -6.82498)
		(width 0.508)
		(layer "F.Cu")
		(net "P3V3_STBY")
	)
	(segment
		(start 20.574 -149.606)
		(end 20.574 -148.7805)
		(width 0.508)
		(layer "F.Cu")
		(net "P3V3_STBY")
	)
	(segment
		(start 46.355 -195.0085)
		(end 45.4025 -195.0085)
		(width 0.508)
		(layer "F.Cu")
		(net "P3V3_STBY")
	)
	(segment
		(start 321.26428 -95.885)
		(end 319.659 -95.885)
		(width 0.3556)
		(layer "F.Cu")
		(net "P3V3_STBY")
	)
	(segment
		(start 205.8035 -20.9296)
		(end 205.8035 -19.6215)
		(width 0.508)
		(layer "F.Cu")
		(net "P3V3_STBY")
	)
	(segment
		(start 51.6255 -148.148294)
		(end 52.04714 -148.569934)
		(width 0.3556)
		(layer "F.Cu")
		(net "P3V3_STBY")
	)
	(segment
		(start 22.16912 -69.5452)
		(end 22.16912 -69.94652)
		(width 0.508)
		(layer "F.Cu")
		(net "P3V3_STBY")
	)
	(segment
		(start 19.31797 -91.624658)
		(end 19.31797 -90.71483)
		(width 0.508)
		(layer "F.Cu")
		(net "P3V3_STBY")
	)
	(segment
		(start 328.835512 -184.433718)
		(end 328.022712 -184.433718)
		(width 0.508)
		(layer "F.Cu")
		(net "P3V3_STBY")
	)
	(segment
		(start 61.44768 -129.35712)
		(end 61.300106 -129.35712)
		(width 0.508)
		(layer "F.Cu")
		(net "P3V3_STBY")
	)
	(segment
		(start 143.136874 -97.55632)
		(end 143.136874 -95.71482)
		(width 0.508)
		(layer "F.Cu")
		(net "P3V3_STBY")
	)
	(segment
		(start 55.1942 -122.6312)
		(end 54.8894 -122.936)
		(width 0.508)
		(layer "F.Cu")
		(net "P3V3_STBY")
	)
	(segment
		(start 184.3024 -16.256)
		(end 184.78246 -15.77594)
		(width 0.508)
		(layer "F.Cu")
		(net "P3V3_STBY")
	)
	(segment
		(start 29.5021 -181.4322)
		(end 29.5021 -181.9783)
		(width 0.508)
		(layer "F.Cu")
		(net "P3V3_STBY")
	)
	(segment
		(start 192.4939 -21.971)
		(end 191.6938 -21.971)
		(width 0.508)
		(layer "F.Cu")
		(net "P3V3_STBY")
	)
	(segment
		(start 9.9441 -99.2251)
		(end 9.9441 -100.1014)
		(width 0.508)
		(layer "F.Cu")
		(net "P3V3_STBY")
	)
	(segment
		(start 47.804832 -180.50764)
		(end 49.1109 -180.50764)
		(width 0.381)
		(layer "F.Cu")
		(net "P3V3_STBY")
	)
	(segment
		(start 47.117 -146.6342)
		(end 47.117 -145.8595)
		(width 0.508)
		(layer "F.Cu")
		(net "P3V3_STBY")
	)
	(segment
		(start 48.641 -148.1455)
		(end 48.641 -147.858988)
		(width 0.508)
		(layer "F.Cu")
		(net "P3V3_STBY")
	)
	(segment
		(start 271.442942 -5.30733)
		(end 272.237962 -5.30733)
		(width 0.508)
		(layer "F.Cu")
		(net "P3V3_STBY")
	)
	(segment
		(start 74.099166 -90.14206)
		(end 74.035666 -90.07856)
		(width 0.508)
		(layer "F.Cu")
		(net "P3V3_STBY")
	)
	(segment
		(start 216.0016 -6.477)
		(end 216.8398 -6.477)
		(width 0.2032)
		(layer "F.Cu")
		(net "P3V3_STBY")
	)
	(segment
		(start 224.663 -13.081)
		(end 224.4598 -12.8778)
		(width 0.508)
		(layer "F.Cu")
		(net "P3V3_STBY")
	)
	(segment
		(start 23.4315 -132.715)
		(end 23.4315 -133.731)
		(width 0.508)
		(layer "F.Cu")
		(net "P3V3_STBY")
	)
	(segment
		(start 20.701 -161.9885)
		(end 21.7805 -163.068)
		(width 0.508)
		(layer "F.Cu")
		(net "P3V3_STBY")
	)
	(segment
		(start 56.7055 -121.625868)
		(end 55.602124 -122.729244)
		(width 0.508)
		(layer "F.Cu")
		(net "P3V3_STBY")
	)
	(segment
		(start 14.036294 -128.711198)
		(end 15.0495 -127.697992)
		(width 0.508)
		(layer "F.Cu")
		(net "P3V3_STBY")
	)
	(segment
		(start 122.7455 -12.66952)
		(end 122.7455 -15.10792)
		(width 0.508)
		(layer "F.Cu")
		(net "P3V3_STBY")
	)
	(segment
		(start 160.957768 -60.479432)
		(end 161.8742 -59.563)
		(width 0.508)
		(layer "F.Cu")
		(net "P3V3_STBY")
	)
	(segment
		(start 217.9574 -5.4356)
		(end 217.996008 -5.396992)
		(width 0.508)
		(layer "F.Cu")
		(net "P3V3_STBY")
	)
	(segment
		(start 273.234404 -4.639564)
		(end 272.95094 -4.923028)
		(width 0.508)
		(layer "F.Cu")
		(net "P3V3_STBY")
	)
	(segment
		(start 37.304726 -125.685042)
		(end 36.90493 -126.084838)
		(width 0.3556)
		(layer "F.Cu")
		(net "P3V3_STBY")
	)
	(segment
		(start 183.6928 -10.7442)
		(end 183.6928 -10.7696)
		(width 0.508)
		(layer "F.Cu")
		(net "P3V3_STBY")
	)
	(segment
		(start 76.581 -122.8217)
		(end 77.597 -122.8217)
		(width 0.508)
		(layer "F.Cu")
		(net "P3V3_STBY")
	)
	(segment
		(start 10.125964 -97.613978)
		(end 10.125964 -98.789236)
		(width 0.508)
		(layer "F.Cu")
		(net "P3V3_STBY")
	)
	(segment
		(start 28.633928 -68.28028)
		(end 28.633928 -69.287644)
		(width 0.508)
		(layer "F.Cu")
		(net "P3V3_STBY")
	)
	(segment
		(start 27.559 -72.9361)
		(end 27.559 -72.136)
		(width 0.508)
		(layer "F.Cu")
		(net "P3V3_STBY")
	)
	(segment
		(start 54.1655 -140.843)
		(end 54.64937 -140.843)
		(width 0.508)
		(layer "F.Cu")
		(net "P3V3_STBY")
	)
	(segment
		(start 20.574 -148.7805)
		(end 20.5105 -148.844)
		(width 0.508)
		(layer "F.Cu")
		(net "P3V3_STBY")
	)
	(segment
		(start 226.48164 -85.01126)
		(end 226.48164 -83.77936)
		(width 0.3048)
		(layer "F.Cu")
		(net "P3V3_STBY")
	)
	(segment
		(start 53.594 -147.447)
		(end 51.6255 -147.447)
		(width 0.508)
		(layer "F.Cu")
		(net "P3V3_STBY")
	)
	(segment
		(start 74.480166 -88.406224)
		(end 74.480166 -87.28456)
		(width 0.508)
		(layer "F.Cu")
		(net "P3V3_STBY")
	)
	(segment
		(start 116.604034 -30.172914)
		(end 116.698268 -30.07868)
		(width 0.3556)
		(layer "F.Cu")
		(net "P3V3_STBY")
	)
	(segment
		(start 319.405 -96.139)
		(end 319.405 -99.1235)
		(width 0.3556)
		(layer "F.Cu")
		(net "P3V3_STBY")
	)
	(segment
		(start 202.879452 -32.88284)
		(end 202.02144 -32.88284)
		(width 0.3556)
		(layer "F.Cu")
		(net "P3V3_STBY")
	)
	(segment
		(start 323.723 -86.0425)
		(end 324.739 -86.0425)
		(width 0.508)
		(layer "F.Cu")
		(net "P3V3_STBY")
	)
	(segment
		(start 143.68526 -33.90392)
		(end 144.7038 -33.90392)
		(width 0.508)
		(layer "F.Cu")
		(net "P3V3_STBY")
	)
	(segment
		(start 47.244 -195.0085)
		(end 46.355 -195.0085)
		(width 0.381)
		(layer "F.Cu")
		(net "P3V3_STBY")
	)
	(segment
		(start 184.78246 -14.818868)
		(end 184.284112 -14.32052)
		(width 0.508)
		(layer "F.Cu")
		(net "P3V3_STBY")
	)
	(segment
		(start 13.5128 -118.5291)
		(end 13.5128 -117.475)
		(width 0.508)
		(layer "F.Cu")
		(net "P3V3_STBY")
	)
	(segment
		(start 72.1868 -119.6467)
		(end 71.0311 -119.6467)
		(width 0.508)
		(layer "F.Cu")
		(net "P3V3_STBY")
	)
	(segment
		(start 194.3862 -27.3431)
		(end 193.7004 -27.3431)
		(width 0.508)
		(layer "F.Cu")
		(net "P3V3_STBY")
	)
	(segment
		(start 40.904414 -126.084838)
		(end 40.504618 -125.685042)
		(width 0.3556)
		(layer "F.Cu")
		(net "P3V3_STBY")
	)
	(segment
		(start 72.5932 -117.04574)
		(end 73.28154 -117.04574)
		(width 0.508)
		(layer "F.Cu")
		(net "P3V3_STBY")
	)
	(segment
		(start 272.8595 -17.121378)
		(end 272.8595 -17.399)
		(width 0.508)
		(layer "F.Cu")
		(net "P3V3_STBY")
	)
	(segment
		(start 26.544778 -97.604072)
		(end 26.467816 -97.52711)
		(width 0.508)
		(layer "F.Cu")
		(net "P3V3_STBY")
	)
	(segment
		(start 20.413726 -129.887472)
		(end 20.420076 -129.881122)
		(width 0.508)
		(layer "F.Cu")
		(net "P3V3_STBY")
	)
	(segment
		(start 201.65822 -32.51962)
		(end 200.9648 -31.8262)
		(width 0.4064)
		(layer "F.Cu")
		(net "P3V3_STBY")
	)
	(segment
		(start 68.1355 -74.4855)
		(end 68.9102 -75.2602)
		(width 0.508)
		(layer "F.Cu")
		(net "P3V3_STBY")
	)
	(segment
		(start 267.4239 -16.2814)
		(end 267.4239 -17.16913)
		(width 0.508)
		(layer "F.Cu")
		(net "P3V3_STBY")
	)
	(segment
		(start 326.771 -86.0425)
		(end 325.755 -86.0425)
		(width 0.508)
		(layer "F.Cu")
		(net "P3V3_STBY")
	)
	(segment
		(start 17.1704 -83.1469)
		(end 17.1704 -82.4484)
		(width 0.3048)
		(layer "F.Cu")
		(net "P3V3_STBY")
	)
	(segment
		(start 6.268212 -81.5848)
		(end 6.258306 -81.594706)
		(width 0.508)
		(layer "F.Cu")
		(net "P3V3_STBY")
	)
	(segment
		(start 56.126126 -112.207294)
		(end 56.126126 -111.359188)
		(width 0.508)
		(layer "F.Cu")
		(net "P3V3_STBY")
	)
	(segment
		(start 217.8812 -5.4356)
		(end 217.0938 -6.223)
		(width 0.508)
		(layer "F.Cu")
		(net "P3V3_STBY")
	)
	(segment
		(start 20.197826 -130.32486)
		(end 20.413726 -130.10896)
		(width 0.508)
		(layer "F.Cu")
		(net "P3V3_STBY")
	)
	(segment
		(start 27.488896 -42.780966)
		(end 27.592274 -42.884344)
		(width 0.508)
		(layer "F.Cu")
		(net "P3V3_STBY")
	)
	(segment
		(start 37.211 -200.9775)
		(end 37.4904 -200.6981)
		(width 0.381)
		(layer "F.Cu")
		(net "P3V3_STBY")
	)
	(segment
		(start 40.504618 -134.485126)
		(end 40.104822 -134.884922)
		(width 0.3556)
		(layer "F.Cu")
		(net "P3V3_STBY")
	)
	(segment
		(start 231.5845 -84.1375)
		(end 232.029 -84.582)
		(width 0.508)
		(layer "F.Cu")
		(net "P3V3_STBY")
	)
	(segment
		(start 52.3113 -113.284)
		(end 52.3113 -112.6871)
		(width 0.508)
		(layer "F.Cu")
		(net "P3V3_STBY")
	)
	(segment
		(start 326.39 -101.219)
		(end 326.39 -100.1395)
		(width 0.508)
		(layer "F.Cu")
		(net "P3V3_STBY")
	)
	(segment
		(start 55.1053 -113.284)
		(end 56.0832 -113.284)
		(width 0.508)
		(layer "F.Cu")
		(net "P3V3_STBY")
	)
	(segment
		(start 238.5314 -19.05)
		(end 238.0996 -19.4818)
		(width 0.508)
		(layer "F.Cu")
		(net "P3V3_STBY")
	)
	(segment
		(start 24.271986 -87.4141)
		(end 24.30018 -87.442294)
		(width 0.508)
		(layer "F.Cu")
		(net "P3V3_STBY")
	)
	(segment
		(start 202.850496 -24.90724)
		(end 203.470256 -25.527)
		(width 0.3048)
		(layer "F.Cu")
		(net "P3V3_STBY")
	)
	(segment
		(start 262.164068 -2.813304)
		(end 262.014462 -2.813304)
		(width 0.508)
		(layer "F.Cu")
		(net "P3V3_STBY")
	)
	(segment
		(start 116.6368 -95.5167)
		(end 115.6843 -95.5167)
		(width 0.508)
		(layer "F.Cu")
		(net "P3V3_STBY")
	)
	(segment
		(start 193.2813 -28.6512)
		(end 194.31 -28.6512)
		(width 0.508)
		(layer "F.Cu")
		(net "P3V3_STBY")
	)
	(segment
		(start 218.186 -200.914)
		(end 218.649804 -200.450196)
		(width 0.3556)
		(layer "F.Cu")
		(net "P3V3_STBY")
	)
	(segment
		(start 47.117 -146.6342)
		(end 46.863 -146.8882)
		(width 0.508)
		(layer "F.Cu")
		(net "P3V3_STBY")
	)
	(segment
		(start 188.7855 -5.3848)
		(end 188.5569 -5.1562)
		(width 0.508)
		(layer "F.Cu")
		(net "P3V3_STBY")
	)
	(segment
		(start 320.675 -84.963)
		(end 321.0814 -84.5566)
		(width 0.508)
		(layer "F.Cu")
		(net "P3V3_STBY")
	)
	(segment
		(start 37.78123 -103.1875)
		(end 37.11067 -102.51694)
		(width 0.508)
		(layer "F.Cu")
		(net "P3V3_STBY")
	)
	(segment
		(start 70.867778 -126.6952)
		(end 70.2056 -126.6952)
		(width 0.4064)
		(layer "F.Cu")
		(net "P3V3_STBY")
	)
	(segment
		(start 201.8919 -18.8468)
		(end 200.9902 -18.8468)
		(width 0.508)
		(layer "F.Cu")
		(net "P3V3_STBY")
	)
	(segment
		(start 27.5336 -99.5553)
		(end 28.4099 -99.5553)
		(width 0.508)
		(layer "F.Cu")
		(net "P3V3_STBY")
	)
	(segment
		(start 238.5314 -17.6276)
		(end 238.5314 -19.05)
		(width 0.508)
		(layer "F.Cu")
		(net "P3V3_STBY")
	)
	(segment
		(start 331.216 -10.0965)
		(end 331.216 -11.176)
		(width 0.508)
		(layer "F.Cu")
		(net "P3V3_STBY")
	)
	(segment
		(start 322.707 -86.0425)
		(end 322.707 -85.217)
		(width 0.508)
		(layer "F.Cu")
		(net "P3V3_STBY")
	)
	(segment
		(start 218.2876 -13.4112)
		(end 218.1352 -13.2588)
		(width 0.508)
		(layer "F.Cu")
		(net "P3V3_STBY")
	)
	(segment
		(start 214.917274 -1.396746)
		(end 214.917274 -2.090674)
		(width 0.508)
		(layer "F.Cu")
		(net "P3V3_STBY")
	)
	(segment
		(start 183.769 -13.01496)
		(end 184.04078 -13.28674)
		(width 0.508)
		(layer "F.Cu")
		(net "P3V3_STBY")
	)
	(segment
		(start 71.3994 -52.9717)
		(end 75.6539 -57.2262)
		(width 0.508)
		(layer "F.Cu")
		(net "P3V3_STBY")
	)
	(segment
		(start 14.0589 -121.3485)
		(end 15.0495 -122.3391)
		(width 0.508)
		(layer "F.Cu")
		(net "P3V3_STBY")
	)
	(segment
		(start 63.4873 -112.5982)
		(end 63.2333 -112.5982)
		(width 0.508)
		(layer "F.Cu")
		(net "P3V3_STBY")
	)
	(segment
		(start 258.608576 -4.665218)
		(end 257.335528 -4.665218)
		(width 0.508)
		(layer "F.Cu")
		(net "P3V3_STBY")
	)
	(segment
		(start 15.0495 -127.508)
		(end 15.10538 -127.56388)
		(width 0.508)
		(layer "F.Cu")
		(net "P3V3_STBY")
	)
	(segment
		(start 17.3736 -137.2616)
		(end 16.6624 -137.9728)
		(width 0.508)
		(layer "F.Cu")
		(net "P3V3_STBY")
	)
	(segment
		(start 227.5205 -0.635)
		(end 227.584 -0.6985)
		(width 0.3048)
		(layer "F.Cu")
		(net "P3V3_STBY")
	)
	(segment
		(start 27.271472 -101.356668)
		(end 27.271472 -99.817428)
		(width 0.3556)
		(layer "F.Cu")
		(net "P3V3_STBY")
	)
	(segment
		(start 84.634832 -74.230992)
		(end 84.539836 -74.135996)
		(width 0.508)
		(layer "F.Cu")
		(net "P3V3_STBY")
	)
	(segment
		(start 60.6552 -129.413)
		(end 59.9694 -130.0988)
		(width 0.508)
		(layer "F.Cu")
		(net "P3V3_STBY")
	)
	(segment
		(start 238.252 -6.7945)
		(end 238.252 -7.6962)
		(width 0.508)
		(layer "F.Cu")
		(net "P3V3_STBY")
	)
	(segment
		(start 51.181 -145.740628)
		(end 51.181 -145.928588)
		(width 0.508)
		(layer "F.Cu")
		(net "P3V3_STBY")
	)
	(segment
		(start 13.5128 -121.3485)
		(end 14.0589 -121.3485)
		(width 0.508)
		(layer "F.Cu")
		(net "P3V3_STBY")
	)
	(segment
		(start 191.6938 -21.971)
		(end 190.4492 -23.2156)
		(width 0.508)
		(layer "F.Cu")
		(net "P3V3_STBY")
	)
	(segment
		(start 25.7175 -152.8445)
		(end 25.908 -153.035)
		(width 0.508)
		(layer "F.Cu")
		(net "P3V3_STBY")
	)
	(segment
		(start 120.4976 -16.6243)
		(end 120.4976 -15.8242)
		(width 0.508)
		(layer "F.Cu")
		(net "P3V3_STBY")
	)
	(segment
		(start 52.328572 -50.969672)
		(end 52.328572 -53.303932)
		(width 0.508)
		(layer "F.Cu")
		(net "P3V3_STBY")
	)
	(segment
		(start 46.50486 -132.484876)
		(end 46.90491 -132.084826)
		(width 0.3556)
		(layer "F.Cu")
		(net "P3V3_STBY")
	)
	(segment
		(start 32.3596 -104.2162)
		(end 32.893 -104.7496)
		(width 0.508)
		(layer "F.Cu")
		(net "P3V3_STBY")
	)
	(segment
		(start 36.877498 -102.750112)
		(end 36.877498 -103.386636)
		(width 0.508)
		(layer "F.Cu")
		(net "P3V3_STBY")
	)
	(segment
		(start 317.3095 -99.1235)
		(end 318.516 -99.1235)
		(width 0.508)
		(layer "F.Cu")
		(net "P3V3_STBY")
	)
	(segment
		(start 46.863 -151.988266)
		(end 47.719234 -152.8445)
		(width 0.508)
		(layer "F.Cu")
		(net "P3V3_STBY")
	)
	(segment
		(start 155.882086 -33.866074)
		(end 154.914854 -33.866074)
		(width 0.508)
		(layer "F.Cu")
		(net "P3V3_STBY")
	)
	(segment
		(start 183.769 -10.8458)
		(end 183.769 -13.01496)
		(width 0.508)
		(layer "F.Cu")
		(net "P3V3_STBY")
	)
	(segment
		(start 54.1655 -144.907)
		(end 54.1655 -146.8755)
		(width 0.508)
		(layer "F.Cu")
		(net "P3V3_STBY")
	)
	(segment
		(start 19.911822 -127.635)
		(end 20.420076 -128.143254)
		(width 0.508)
		(layer "F.Cu")
		(net "P3V3_STBY")
	)
	(segment
		(start 187.7822 -2.323592)
		(end 187.7822 -3.180588)
		(width 0.508)
		(layer "F.Cu")
		(net "P3V3_STBY")
	)
	(segment
		(start 73.9267 -118.11)
		(end 73.9267 -118.760748)
		(width 0.381)
		(layer "F.Cu")
		(net "P3V3_STBY")
	)
	(segment
		(start 54.1655 -146.8755)
		(end 53.594 -147.447)
		(width 0.508)
		(layer "F.Cu")
		(net "P3V3_STBY")
	)
	(segment
		(start 270.4846 -2.6416)
		(end 269.9004 -3.2258)
		(width 0.508)
		(layer "F.Cu")
		(net "P3V3_STBY")
	)
	(segment
		(start 156.898594 -35.588194)
		(end 156.898594 -33.866074)
		(width 0.508)
		(layer "F.Cu")
		(net "P3V3_STBY")
	)
	(segment
		(start 84.634832 -74.449432)
		(end 84.634832 -74.230992)
		(width 0.508)
		(layer "F.Cu")
		(net "P3V3_STBY")
	)
	(segment
		(start 331.597 -100.0125)
		(end 332.5495 -100.0125)
		(width 0.508)
		(layer "F.Cu")
		(net "P3V3_STBY")
	)
	(segment
		(start 193.7004 -27.3431)
		(end 193.2813 -27.7622)
		(width 0.508)
		(layer "F.Cu")
		(net "P3V3_STBY")
	)
	(segment
		(start 74.035666 -88.850724)
		(end 74.480166 -88.406224)
		(width 0.508)
		(layer "F.Cu")
		(net "P3V3_STBY")
	)
	(segment
		(start 51.5239 -63.754)
		(end 51.5239 -64.4398)
		(width 0.508)
		(layer "F.Cu")
		(net "P3V3_STBY")
	)
	(segment
		(start 117.5258 -95.5167)
		(end 116.6368 -95.5167)
		(width 0.381)
		(layer "F.Cu")
		(net "P3V3_STBY")
	)
	(segment
		(start 16.1417 -83.9851)
		(end 15.9512 -83.9851)
		(width 0.508)
		(layer "F.Cu")
		(net "P3V3_STBY")
	)
	(segment
		(start 228.854 -11.684)
		(end 229.108 -11.43)
		(width 0.508)
		(layer "F.Cu")
		(net "P3V3_STBY")
	)
	(segment
		(start 39.3192 -186.7027)
		(end 39.476172 -186.7027)
		(width 0.381)
		(layer "F.Cu")
		(net "P3V3_STBY")
	)
	(segment
		(start 54.557676 -52.119276)
		(end 54.557676 -53.8734)
		(width 0.508)
		(layer "F.Cu")
		(net "P3V3_STBY")
	)
	(segment
		(start 47.117 -145.8595)
		(end 48.133 -145.8595)
		(width 0.508)
		(layer "F.Cu")
		(net "P3V3_STBY")
	)
	(segment
		(start 19.36242 -129.667)
		(end 18.8595 -129.667)
		(width 0.508)
		(layer "F.Cu")
		(net "P3V3_STBY")
	)
	(segment
		(start 231.8512 -91.7702)
		(end 231.14 -91.059)
		(width 0.508)
		(layer "F.Cu")
		(net "P3V3_STBY")
	)
	(segment
		(start 54.8894 -122.936)
		(end 54.1655 -122.936)
		(width 0.508)
		(layer "F.Cu")
		(net "P3V3_STBY")
	)
	(segment
		(start 57.4548 -146.281648)
		(end 56.816752 -146.281648)
		(width 0.508)
		(layer "F.Cu")
		(net "P3V3_STBY")
	)
	(segment
		(start 33.6423 -189.2808)
		(end 34.4678 -189.2808)
		(width 0.508)
		(layer "F.Cu")
		(net "P3V3_STBY")
	)
	(segment
		(start 40.904922 -126.084838)
		(end 40.904414 -126.084838)
		(width 0.3556)
		(layer "F.Cu")
		(net "P3V3_STBY")
	)
	(segment
		(start 183.6928 -10.7696)
		(end 183.769 -10.8458)
		(width 0.508)
		(layer "F.Cu")
		(net "P3V3_STBY")
	)
	(segment
		(start 39.304722 -126.084838)
		(end 39.304468 -126.084838)
		(width 0.3556)
		(layer "F.Cu")
		(net "P3V3_STBY")
	)
	(segment
		(start 47.858172 -48.1584)
		(end 47.350172 -48.6664)
		(width 0.508)
		(layer "F.Cu")
		(net "P3V3_STBY")
	)
	(segment
		(start 247.4214 -4.9784)
		(end 248.0818 -4.9784)
		(width 0.508)
		(layer "F.Cu")
		(net "P3V3_STBY")
	)
	(segment
		(start 69.3166 -75.3745)
		(end 69.3166 -76.6572)
		(width 0.508)
		(layer "F.Cu")
		(net "P3V3_STBY")
	)
	(segment
		(start 257.335528 -4.665218)
		(end 257.112262 -4.441952)
		(width 0.3556)
		(layer "F.Cu")
		(net "P3V3_STBY")
	)
	(segment
		(start 204.8002 -26.1112)
		(end 204.8129 -26.1112)
		(width 0.3048)
		(layer "F.Cu")
		(net "P3V3_STBY")
	)
	(segment
		(start 25.81402 -79.307944)
		(end 25.654 -79.147924)
		(width 0.508)
		(layer "F.Cu")
		(net "P3V3_STBY")
	)
	(segment
		(start 188.424312 -3.8227)
		(end 188.6458 -3.8227)
		(width 0.508)
		(layer "F.Cu")
		(net "P3V3_STBY")
	)
	(segment
		(start 34.798 -115.4938)
		(end 34.798 -116.2685)
		(width 0.508)
		(layer "F.Cu")
		(net "P3V3_STBY")
	)
	(segment
		(start 232.029 -84.582)
		(end 232.029 -88.646)
		(width 0.508)
		(layer "F.Cu")
		(net "P3V3_STBY")
	)
	(segment
		(start 121.594626 -80.253332)
		(end 121.594626 -81.096866)
		(width 0.508)
		(layer "F.Cu")
		(net "P3V3_STBY")
	)
	(segment
		(start 187.549536 -2.090928)
		(end 187.7822 -2.323592)
		(width 0.508)
		(layer "F.Cu")
		(net "P3V3_STBY")
	)
	(segment
		(start 38.904672 -125.685042)
		(end 38.504876 -126.084838)
		(width 0.3556)
		(layer "F.Cu")
		(net "P3V3_STBY")
	)
	(segment
		(start 47.5234 -180.6321)
		(end 47.680372 -180.6321)
		(width 0.381)
		(layer "F.Cu")
		(net "P3V3_STBY")
	)
	(segment
		(start 187.7822 -3.180588)
		(end 188.424312 -3.8227)
		(width 0.508)
		(layer "F.Cu")
		(net "P3V3_STBY")
	)
	(segment
		(start 20.55876 -99.73691)
		(end 20.55876 -100.581206)
		(width 0.508)
		(layer "F.Cu")
		(net "P3V3_STBY")
	)
	(segment
		(start 194.4243 -35.7505)
		(end 194.945 -36.2712)
		(width 0.508)
		(layer "F.Cu")
		(net "P3V3_STBY")
	)
	(segment
		(start 19.31797 -90.71483)
		(end 19.31797 -90.05443)
		(width 0.508)
		(layer "F.Cu")
		(net "P3V3_STBY")
	)
	(segment
		(start 89.2048 -42.2148)
		(end 89.353898 -42.2148)
		(width 0.3048)
		(layer "F.Cu")
		(net "P3V3_STBY")
	)
	(segment
		(start 39.304468 -126.084838)
		(end 38.904672 -125.685042)
		(width 0.3556)
		(layer "F.Cu")
		(net "P3V3_STBY")
	)
	(segment
		(start 25.654 -79.147924)
		(end 25.654 -78.932278)
		(width 0.508)
		(layer "F.Cu")
		(net "P3V3_STBY")
	)
	(segment
		(start 85.34654 -75.16114)
		(end 84.634832 -74.449432)
		(width 0.508)
		(layer "F.Cu")
		(net "P3V3_STBY")
	)
	(segment
		(start 9.9441 -100.1014)
		(end 10.9347 -100.1014)
		(width 0.508)
		(layer "F.Cu")
		(net "P3V3_STBY")
	)
	(segment
		(start 215.063324 -202.602592)
		(end 215.876124 -202.602592)
		(width 0.508)
		(layer "F.Cu")
		(net "P3V3_STBY")
	)
	(segment
		(start 75.623166 -90.14206)
		(end 75.623166 -89.161366)
		(width 0.508)
		(layer "F.Cu")
		(net "P3V3_STBY")
	)
	(segment
		(start 58.1152 -40.7924)
		(end 59.310778 -40.7924)
		(width 0.508)
		(layer "F.Cu")
		(net "P3V3_STBY")
	)
	(segment
		(start 229.8065 -12.319)
		(end 229.8065 -11.43)
		(width 0.508)
		(layer "F.Cu")
		(net "P3V3_STBY")
	)
	(segment
		(start 79.4766 -73.7743)
		(end 79.383128 -73.867772)
		(width 0.508)
		(layer "F.Cu")
		(net "P3V3_STBY")
	)
	(segment
		(start 331.216 -16.0655)
		(end 331.216 -17.145)
		(width 0.508)
		(layer "F.Cu")
		(net "P3V3_STBY")
	)
	(segment
		(start 180.49367 -3.800856)
		(end 182.18277 -3.800856)
		(width 0.508)
		(layer "F.Cu")
		(net "P3V3_STBY")
	)
	(segment
		(start 200.9902 -18.8468)
		(end 200.0885 -18.8468)
		(width 0.508)
		(layer "F.Cu")
		(net "P3V3_STBY")
	)
	(segment
		(start 147.9296 -53.213)
		(end 149.9362 -51.2064)
		(width 0.508)
		(layer "F.Cu")
		(net "P3V3_STBY")
	)
	(segment
		(start 319.659 -95.885)
		(end 319.405 -96.139)
		(width 0.3556)
		(layer "F.Cu")
		(net "P3V3_STBY")
	)
	(segment
		(start 29.5021 -181.9783)
		(end 29.21 -182.2704)
		(width 0.508)
		(layer "F.Cu")
		(net "P3V3_STBY")
	)
	(segment
		(start 272.622264 -4.923028)
		(end 272.492216 -5.053076)
		(width 0.508)
		(layer "F.Cu")
		(net "P3V3_STBY")
	)
	(segment
		(start 267.4239 -16.2814)
		(end 267.4239 -16.000476)
		(width 0.508)
		(layer "F.Cu")
		(net "P3V3_STBY")
	)
	(segment
		(start 81.448148 -75.44816)
		(end 81.610708 -75.2856)
		(width 0.508)
		(layer "F.Cu")
		(net "P3V3_STBY")
	)
	(segment
		(start 26.467816 -97.52711)
		(end 26.467816 -97.449894)
		(width 0.508)
		(layer "F.Cu")
		(net "P3V3_STBY")
	)
	(segment
		(start 229.661466 -12.37107)
		(end 229.713536 -12.319)
		(width 0.508)
		(layer "F.Cu")
		(net "P3V3_STBY")
	)
	(segment
		(start 47.5234 -194.7291)
		(end 47.680372 -194.7291)
		(width 0.381)
		(layer "F.Cu")
		(net "P3V3_STBY")
	)
	(segment
		(start 50.8762 -49.8729)
		(end 50.8762 -48.768)
		(width 0.508)
		(layer "F.Cu")
		(net "P3V3_STBY")
	)
	(segment
		(start 120.088914 -47.31258)
		(end 119.863108 -47.086774)
		(width 0.508)
		(layer "F.Cu")
		(net "P3V3_STBY")
	)
	(segment
		(start 267.62202 -2.846832)
		(end 267.267944 -2.846832)
		(width 0.508)
		(layer "F.Cu")
		(net "P3V3_STBY")
	)
	(segment
		(start 62.0522 -58.4835)
		(end 62.0522 -57.5818)
		(width 0.508)
		(layer "F.Cu")
		(net "P3V3_STBY")
	)
	(segment
		(start 52.6415 -199.39)
		(end 53.4162 -199.39)
		(width 0.508)
		(layer "F.Cu")
		(net "P3V3_STBY")
	)
	(segment
		(start 20.197826 -131.34086)
		(end 20.197826 -130.32486)
		(width 0.508)
		(layer "F.Cu")
		(net "P3V3_STBY")
	)
	(segment
		(start 71.7042 -127.7493)
		(end 72.445626 -127.7493)
		(width 0.4064)
		(layer "F.Cu")
		(net "P3V3_STBY")
	)
	(segment
		(start 6.610604 -77.895196)
		(end 7.153148 -77.895196)
		(width 0.508)
		(layer "F.Cu")
		(net "P3V3_STBY")
	)
	(segment
		(start 122.023124 -207.427576)
		(end 123.2662 -206.1845)
		(width 0.508)
		(layer "F.Cu")
		(net "P3V3_STBY")
	)
	(segment
		(start 25.843992 -150.494492)
		(end 25.843992 -148.745448)
		(width 0.508)
		(layer "F.Cu")
		(net "P3V3_STBY")
	)
	(segment
		(start 39.0398 -189.0141)
		(end 38.2143 -189.0141)
		(width 0.508)
		(layer "F.Cu")
		(net "P3V3_STBY")
	)
	(segment
		(start 51.6255 -147.447)
		(end 51.6255 -148.148294)
		(width 0.3556)
		(layer "F.Cu")
		(net "P3V3_STBY")
	)
	(segment
		(start 193.2813 -30.7848)
		(end 194.4243 -30.7848)
		(width 0.508)
		(layer "F.Cu")
		(net "P3V3_STBY")
	)
	(segment
		(start 258.854702 -3.8481)
		(end 258.854702 -4.419092)
		(width 0.508)
		(layer "F.Cu")
		(net "P3V3_STBY")
	)
	(segment
		(start 216.8398 -6.477)
		(end 217.0938 -6.223)
		(width 0.508)
		(layer "F.Cu")
		(net "P3V3_STBY")
	)
	(segment
		(start 231.14 -91.059)
		(end 229.5525 -91.059)
		(width 0.508)
		(layer "F.Cu")
		(net "P3V3_STBY")
	)
	(segment
		(start 67.188588 -129.96926)
		(end 66.80962 -129.590292)
		(width 0.4064)
		(layer "F.Cu")
		(net "P3V3_STBY")
	)
	(segment
		(start 42.6085 -205.359)
		(end 43.3832 -205.359)
		(width 0.508)
		(layer "F.Cu")
		(net "P3V3_STBY")
	)
	(segment
		(start 74.035666 -90.07856)
		(end 74.035666 -88.850724)
		(width 0.508)
		(layer "F.Cu")
		(net "P3V3_STBY")
	)
	(segment
		(start 330.581 -100.0125)
		(end 331.597 -100.0125)
		(width 0.508)
		(layer "F.Cu")
		(net "P3V3_STBY")
	)
	(segment
		(start 17.18818 -136.126474)
		(end 17.3736 -136.311894)
		(width 0.508)
		(layer "F.Cu")
		(net "P3V3_STBY")
	)
	(segment
		(start 191.9478 -19.7866)
		(end 191.9478 -20.0914)
		(width 0.508)
		(layer "F.Cu")
		(net "P3V3_STBY")
	)
	(segment
		(start 27.7622 -70.3961)
		(end 27.8384 -70.3199)
		(width 0.508)
		(layer "F.Cu")
		(net "P3V3_STBY")
	)
	(segment
		(start 273.667728 -16.31315)
		(end 272.8595 -17.121378)
		(width 0.508)
		(layer "F.Cu")
		(net "P3V3_STBY")
	)
	(segment
		(start 66.7766 -110.1979)
		(end 66.7766 -111.4298)
		(width 0.508)
		(layer "F.Cu")
		(net "P3V3_STBY")
	)
	(segment
		(start 54.557676 -64.5414)
		(end 54.557676 -53.8734)
		(width 0.508)
		(layer "F.Cu")
		(net "P3V3_STBY")
	)
	(segment
		(start 225.17608 -3.366008)
		(end 225.17608 -2.826258)
		(width 0.508)
		(layer "F.Cu")
		(net "P3V3_STBY")
	)
	(segment
		(start 21.4503 -134.4422)
		(end 22.4536 -134.4422)
		(width 0.508)
		(layer "F.Cu")
		(net "P3V3_STBY")
	)
	(segment
		(start 25.420066 -107.509818)
		(end 26.207466 -107.509818)
		(width 0.508)
		(layer "F.Cu")
		(net "P3V3_STBY")
	)
	(segment
		(start 22.407118 -71.242682)
		(end 21.911056 -71.242682)
		(width 0.3048)
		(layer "F.Cu")
		(net "P3V3_STBY")
	)
	(segment
		(start 121.276364 -47.31258)
		(end 120.088914 -47.31258)
		(width 0.508)
		(layer "F.Cu")
		(net "P3V3_STBY")
	)
	(segment
		(start 56.7055 -119.126)
		(end 56.7055 -121.625868)
		(width 0.508)
		(layer "F.Cu")
		(net "P3V3_STBY")
	)
	(segment
		(start 51.5239 -64.4398)
		(end 52.1335 -65.0494)
		(width 0.508)
		(layer "F.Cu")
		(net "P3V3_STBY")
	)
	(segment
		(start 14.8082 -84.0613)
		(end 14.7574 -84.1121)
		(width 0.508)
		(layer "F.Cu")
		(net "P3V3_STBY")
	)
	(segment
		(start 330.73213 -181.601618)
		(end 330.638912 -181.5084)
		(width 0.3048)
		(layer "F.Cu")
		(net "P3V3_STBY")
	)
	(segment
		(start 81.448148 -76.418948)
		(end 81.448148 -75.44816)
		(width 0.508)
		(layer "F.Cu")
		(net "P3V3_STBY")
	)
	(segment
		(start 26.763726 -76.9366)
		(end 26.4795 -76.9366)
		(width 0.508)
		(layer "F.Cu")
		(net "P3V3_STBY")
	)
	(segment
		(start 73.917048 -118.7704)
		(end 73.917048 -119.44096)
		(width 0.381)
		(layer "F.Cu")
		(net "P3V3_STBY")
	)
	(segment
		(start 227.584 -0.6985)
		(end 228.133656 -0.6985)
		(width 0.508)
		(layer "F.Cu")
		(net "P3V3_STBY")
	)
	(segment
		(start 195.8213 -16.5735)
		(end 196.088 -16.3068)
		(width 0.508)
		(layer "F.Cu")
		(net "P3V3_STBY")
	)
	(segment
		(start 122.7455 -6.7945)
		(end 122.7455 -12.66952)
		(width 0.508)
		(layer "F.Cu")
		(net "P3V3_STBY")
	)
	(segment
		(start 67.145408 -195.236592)
		(end 67.794124 -195.236592)
		(width 0.508)
		(layer "F.Cu")
		(net "P3V3_STBY")
	)
	(segment
		(start 192.6844 -31.3817)
		(end 193.2813 -30.7848)
		(width 0.508)
		(layer "F.Cu")
		(net "P3V3_STBY")
	)
	(segment
		(start 42.504868 -127.685292)
		(end 42.904664 -128.085088)
		(width 0.3556)
		(layer "F.Cu")
		(net "P3V3_STBY")
	)
	(segment
		(start 36.957254 -104.01173)
		(end 36.957254 -104.427274)
		(width 0.508)
		(layer "F.Cu")
		(net "P3V3_STBY")
	)
	(segment
		(start 59.310778 -40.7924)
		(end 59.318398 -40.80002)
		(width 0.508)
		(layer "F.Cu")
		(net "P3V3_STBY")
	)
	(segment
		(start 230.6955 -9.398)
		(end 231.5972 -9.398)
		(width 0.508)
		(layer "F.Cu")
		(net "P3V3_STBY")
	)
	(segment
		(start 182.18277 -4.661916)
		(end 181.19725 -5.647436)
		(width 0.508)
		(layer "F.Cu")
		(net "P3V3_STBY")
	)
	(segment
		(start 66.847974 -196.133974)
		(end 66.929 -196.052948)
		(width 0.508)
		(layer "F.Cu")
		(net "P3V3_STBY")
	)
	(segment
		(start 182.18277 -3.800856)
		(end 182.18277 -4.661916)
		(width 0.508)
		(layer "F.Cu")
		(net "P3V3_STBY")
	)
	(segment
		(start 329.565 -100.0125)
		(end 328.549 -100.0125)
		(width 0.508)
		(layer "F.Cu")
		(net "P3V3_STBY")
	)
	(segment
		(start 143.547846 -33.90392)
		(end 142.67688 -34.774886)
		(width 0.508)
		(layer "F.Cu")
		(net "P3V3_STBY")
	)
	(segment
		(start 229.713536 -12.319)
		(end 229.8065 -12.319)
		(width 0.508)
		(layer "F.Cu")
		(net "P3V3_STBY")
	)
	(segment
		(start 10.5537 -81.6356)
		(end 9.779 -81.6356)
		(width 0.508)
		(layer "F.Cu")
		(net "P3V3_STBY")
	)
	(segment
		(start 47.244 -180.9115)
		(end 46.355 -180.9115)
		(width 0.381)
		(layer "F.Cu")
		(net "P3V3_STBY")
	)
	(segment
		(start 229.235 -83.439)
		(end 229.9335 -84.1375)
		(width 0.3048)
		(layer "F.Cu")
		(net "P3V3_STBY")
	)
	(segment
		(start 26.937208 -85.41131)
		(end 27.106118 -85.2424)
		(width 0.508)
		(layer "F.Cu")
		(net "P3V3_STBY")
	)
	(segment
		(start 318.516 -99.1235)
		(end 319.405 -99.1235)
		(width 0.508)
		(layer "F.Cu")
		(net "P3V3_STBY")
	)
	(segment
		(start 32.522414 -136.102344)
		(end 32.522414 -136.099804)
		(width 0.254)
		(layer "F.Cu")
		(net "P3V3_STBY")
	)
	(segment
		(start 26.544778 -98.725736)
		(end 26.544778 -97.604072)
		(width 0.508)
		(layer "F.Cu")
		(net "P3V3_STBY")
	)
	(segment
		(start 6.096 -78.4098)
		(end 6.610604 -77.895196)
		(width 0.508)
		(layer "F.Cu")
		(net "P3V3_STBY")
	)
	(segment
		(start 38.1508 -186.9821)
		(end 37.1983 -186.9821)
		(width 0.508)
		(layer "F.Cu")
		(net "P3V3_STBY")
	)
	(segment
		(start 68.72224 -192.532)
		(end 68.3006 -192.11036)
		(width 0.3048)
		(layer "F.Cu")
		(net "P3V3_STBY")
	)
	(segment
		(start 116.2558 -16.6243)
		(end 116.2558 -15.8242)
		(width 0.508)
		(layer "F.Cu")
		(net "P3V3_STBY")
	)
	(segment
		(start 202.142852 -24.90724)
		(end 202.850496 -24.90724)
		(width 0.3048)
		(layer "F.Cu")
		(net "P3V3_STBY")
	)
	(segment
		(start 122.9233 -99.8982)
		(end 123.698 -99.8982)
		(width 0.508)
		(layer "F.Cu")
		(net "P3V3_STBY")
	)
	(segment
		(start 331.216 -4.944364)
		(end 331.211682 -4.948682)
		(width 0.508)
		(layer "F.Cu")
		(net "P3V3_STBY")
	)
	(segment
		(start 51.9303 -50.7619)
		(end 52.1208 -50.7619)
		(width 0.508)
		(layer "F.Cu")
		(net "P3V3_STBY")
	)
	(segment
		(start 234.503468 -6.110732)
		(end 233.5276 -7.0866)
		(width 0.508)
		(layer "F.Cu")
		(net "P3V3_STBY")
	)
	(segment
		(start 269.857982 -10.399268)
		(end 269.770352 -10.311638)
		(width 0.508)
		(layer "F.Cu")
		(net "P3V3_STBY")
	)
	(segment
		(start 231.8512 -94.6912)
		(end 231.8512 -91.7702)
		(width 0.508)
		(layer "F.Cu")
		(net "P3V3_STBY")
	)
	(segment
		(start 37.11067 -102.51694)
		(end 36.877498 -102.750112)
		(width 0.508)
		(layer "F.Cu")
		(net "P3V3_STBY")
	)
	(segment
		(start 47.719234 -152.8445)
		(end 48.641 -152.8445)
		(width 0.508)
		(layer "F.Cu")
		(net "P3V3_STBY")
	)
	(segment
		(start 179.78501 -3.092196)
		(end 180.49367 -3.800856)
		(width 0.508)
		(layer "F.Cu")
		(net "P3V3_STBY")
	)
	(segment
		(start 265.151108 -9.1948)
		(end 266.4841 -9.1948)
		(width 0.508)
		(layer "F.Cu")
		(net "P3V3_STBY")
	)
	(segment
		(start 344.44178 -43.52798)
		(end 344.251534 -43.718226)
		(width 0.508)
		(layer "F.Cu")
		(net "P3V3_STBY")
	)
	(segment
		(start 143.68526 -33.90392)
		(end 143.547846 -33.90392)
		(width 0.508)
		(layer "F.Cu")
		(net "P3V3_STBY")
	)
	(segment
		(start 9.4615 -123.6853)
		(end 9.4615 -123.063)
		(width 0.508)
		(layer "F.Cu")
		(net "P3V3_STBY")
	)
	(segment
		(start 28.548584 -91.964256)
		(end 28.548584 -92.377514)
		(width 0.508)
		(layer "F.Cu")
		(net "P3V3_STBY")
	)
	(segment
		(start 47.804832 -194.60464)
		(end 49.1109 -194.60464)
		(width 0.381)
		(layer "F.Cu")
		(net "P3V3_STBY")
	)
	(segment
		(start 24.642064 -66.59499)
		(end 24.01062 -67.226434)
		(width 0.508)
		(layer "F.Cu")
		(net "P3V3_STBY")
	)
	(segment
		(start 27.051 -70.3961)
		(end 27.7622 -70.3961)
		(width 0.508)
		(layer "F.Cu")
		(net "P3V3_STBY")
	)
	(segment
		(start 117.8052 -95.2373)
		(end 117.962172 -95.2373)
		(width 0.381)
		(layer "F.Cu")
		(net "P3V3_STBY")
	)
	(segment
		(start 142.233142 -98.460052)
		(end 144.365472 -98.460052)
		(width 0.508)
		(layer "F.Cu")
		(net "P3V3_STBY")
	)
	(segment
		(start 19.8882 -161.9885)
		(end 20.701 -161.9885)
		(width 0.508)
		(layer "F.Cu")
		(net "P3V3_STBY")
	)
	(segment
		(start 122.7455 -15.10792)
		(end 122.7455 -18.63852)
		(width 0.508)
		(layer "F.Cu")
		(net "P3V3_STBY")
	)
	(segment
		(start 54.1655 -140.843)
		(end 54.1655 -139.827)
		(width 0.508)
		(layer "F.Cu")
		(net "P3V3_STBY")
	)
	(segment
		(start 51.181 -145.928588)
		(end 51.6255 -146.373088)
		(width 0.508)
		(layer "F.Cu")
		(net "P3V3_STBY")
	)
	(segment
		(start 15.2908 -145.415)
		(end 14.2113 -145.415)
		(width 0.508)
		(layer "F.Cu")
		(net "P3V3_STBY")
	)
	(segment
		(start 149.9362 -42.550588)
		(end 156.898594 -35.588194)
		(width 0.508)
		(layer "F.Cu")
		(net "P3V3_STBY")
	)
	(segment
		(start 12.169648 -74.91476)
		(end 12.55522 -74.91476)
		(width 0.3048)
		(layer "F.Cu")
		(net "P3V3_STBY")
	)
	(segment
		(start 7.1247 -81.5848)
		(end 7.1247 -82.9691)
		(width 0.508)
		(layer "F.Cu")
		(net "P3V3_STBY")
	)
	(via
		(at 29.451554 -97.571052)
		(size 0.508)
		(drill 0.254)
		(layers "F.Cu" "B.Cu")
		(net "P3V3_STBY")
	)
	(via
		(at 62.0522 -57.5818)
		(size 0.508)
		(drill 0.254)
		(layers "F.Cu" "B.Cu")
		(net "P3V3_STBY")
	)
	(via
		(at 28.4353 -99.5807)
		(size 0.508)
		(drill 0.254)
		(layers "F.Cu" "B.Cu")
		(net "P3V3_STBY")
	)
	(via
		(at 59.9694 -131.3434)
		(size 0.508)
		(drill 0.254)
		(layers "F.Cu" "B.Cu")
		(net "P3V3_STBY")
	)
	(via
		(at 89.28481 -83.29041)
		(size 0.508)
		(drill 0.254)
		(layers "F.Cu" "B.Cu")
		(net "P3V3_STBY")
	)
	(via
		(at 59.9059 -115.5827)
		(size 0.508)
		(drill 0.254)
		(layers "F.Cu" "B.Cu")
		(net "P3V3_STBY")
	)
	(via
		(at 55.118 -193.294)
		(size 0.508)
		(drill 0.254)
		(layers "F.Cu" "B.Cu")
		(net "P3V3_STBY")
	)
	(via
		(at 121.210324 -208.444592)
		(size 0.508)
		(drill 0.254)
		(layers "F.Cu" "B.Cu")
		(net "P3V3_STBY")
	)
	(via
		(at 331.216 -22.987)
		(size 0.508)
		(drill 0.254)
		(layers "F.Cu" "B.Cu")
		(net "P3V3_STBY")
	)
	(via
		(at 55.8292 -125.3998)
		(size 0.508)
		(drill 0.254)
		(layers "F.Cu" "B.Cu")
		(net "P3V3_STBY")
	)
	(via
		(at 331.211682 -5.609082)
		(size 0.508)
		(drill 0.254)
		(layers "F.Cu" "B.Cu")
		(net "P3V3_STBY")
	)
	(via
		(at 183.900572 -1.452626)
		(size 0.508)
		(drill 0.254)
		(layers "F.Cu" "B.Cu")
		(net "P3V3_STBY")
	)
	(via
		(at 77.597 -171.8056)
		(size 0.508)
		(drill 0.254)
		(layers "F.Cu" "B.Cu")
		(net "P3V3_STBY")
	)
	(via
		(at 77.597 -122.8217)
		(size 0.508)
		(drill 0.254)
		(layers "F.Cu" "B.Cu")
		(net "P3V3_STBY")
	)
	(via
		(at 228.541326 -1.10617)
		(size 0.508)
		(drill 0.254)
		(layers "F.Cu" "B.Cu")
		(net "P3V3_STBY")
	)
	(via
		(at 76.689966 -89.1794)
		(size 0.508)
		(drill 0.254)
		(layers "F.Cu" "B.Cu")
		(net "P3V3_STBY")
	)
	(via
		(at 22.7076 -70.9422)
		(size 0.508)
		(drill 0.254)
		(layers "F.Cu" "B.Cu")
		(net "P3V3_STBY")
	)
	(via
		(at 228.727254 -12.37107)
		(size 0.508)
		(drill 0.254)
		(layers "F.Cu" "B.Cu")
		(net "P3V3_STBY")
	)
	(via
		(at 19.8882 -161.9885)
		(size 0.508)
		(drill 0.254)
		(layers "F.Cu" "B.Cu")
		(net "P3V3_STBY")
	)
	(via
		(at 92.0242 -41.2496)
		(size 0.508)
		(drill 0.254)
		(layers "F.Cu" "B.Cu")
		(net "P3V3_STBY")
	)
	(via
		(at 238.0996 -19.4818)
		(size 0.7112)
		(drill 0.3556)
		(layers "F.Cu" "B.Cu")
		(net "P3V3_STBY")
	)
	(via
		(at 70.0786 -118.6942)
		(size 0.508)
		(drill 0.254)
		(layers "F.Cu" "B.Cu")
		(net "P3V3_STBY")
	)
	(via
		(at 90.515694 -40.286686)
		(size 0.7112)
		(drill 0.3556)
		(layers "F.Cu" "B.Cu")
		(net "P3V3_STBY")
	)
	(via
		(at 22.497542 -127.99949)
		(size 0.508)
		(drill 0.254)
		(layers "F.Cu" "B.Cu")
		(net "P3V3_STBY")
	)
	(via
		(at 122.055128 -81.618328)
		(size 0.508)
		(drill 0.254)
		(layers "F.Cu" "B.Cu")
		(net "P3V3_STBY")
	)
	(via
		(at 270.4846 -2.6416)
		(size 0.508)
		(drill 0.254)
		(layers "F.Cu" "B.Cu")
		(net "P3V3_STBY")
	)
	(via
		(at 190.53302 -16.08836)
		(size 0.508)
		(drill 0.254)
		(layers "F.Cu" "B.Cu")
		(net "P3V3_STBY")
	)
	(via
		(at 228.6635 -9.6901)
		(size 0.508)
		(drill 0.254)
		(layers "F.Cu" "B.Cu")
		(net "P3V3_STBY")
	)
	(via
		(at 20.133818 -104.18699)
		(size 0.508)
		(drill 0.254)
		(layers "F.Cu" "B.Cu")
		(net "P3V3_STBY")
	)
	(via
		(at 45.4025 -195.0085)
		(size 0.508)
		(drill 0.254)
		(layers "F.Cu" "B.Cu")
		(net "P3V3_STBY")
	)
	(via
		(at 123.698 -99.8982)
		(size 0.508)
		(drill 0.254)
		(layers "F.Cu" "B.Cu")
		(net "P3V3_STBY")
	)
	(via
		(at 20.574 -149.606)
		(size 0.508)
		(drill 0.254)
		(layers "F.Cu" "B.Cu")
		(net "P3V3_STBY")
	)
	(via
		(at 24.01062 -67.226434)
		(size 0.508)
		(drill 0.254)
		(layers "F.Cu" "B.Cu")
		(net "P3V3_STBY")
	)
	(via
		(at 135.128 -201.295)
		(size 0.508)
		(drill 0.254)
		(layers "F.Cu" "B.Cu")
		(net "P3V3_STBY")
	)
	(via
		(at 91.0082 -42.3926)
		(size 0.508)
		(drill 0.254)
		(layers "F.Cu" "B.Cu")
		(net "P3V3_STBY")
	)
	(via
		(at 323.47408 -37.60978)
		(size 0.508)
		(drill 0.254)
		(layers "F.Cu" "B.Cu")
		(net "P3V3_STBY")
	)
	(via
		(at 215.063324 -202.602592)
		(size 0.508)
		(drill 0.254)
		(layers "F.Cu" "B.Cu")
		(net "P3V3_STBY")
	)
	(via
		(at 31.5341 -179.5907)
		(size 0.508)
		(drill 0.254)
		(layers "F.Cu" "B.Cu")
		(net "P3V3_STBY")
	)
	(via
		(at 319.405 -96.139)
		(size 0.7112)
		(drill 0.3556)
		(layers "F.Cu" "B.Cu")
		(net "P3V3_STBY")
	)
	(via
		(at 52.1208 -112.4966)
		(size 0.508)
		(drill 0.254)
		(layers "F.Cu" "B.Cu")
		(net "P3V3_STBY")
	)
	(via
		(at 46.4185 -197.0405)
		(size 0.508)
		(drill 0.254)
		(layers "F.Cu" "B.Cu")
		(net "P3V3_STBY")
	)
	(via
		(at 256.78765 -7.370318)
		(size 0.508)
		(drill 0.254)
		(layers "F.Cu" "B.Cu")
		(net "P3V3_STBY")
	)
	(via
		(at 256.8702 -13.462)
		(size 0.508)
		(drill 0.254)
		(layers "F.Cu" "B.Cu")
		(net "P3V3_STBY")
	)
	(via
		(at 38.2143 -189.0141)
		(size 0.508)
		(drill 0.254)
		(layers "F.Cu" "B.Cu")
		(net "P3V3_STBY")
	)
	(via
		(at 269.770352 -10.311638)
		(size 0.508)
		(drill 0.254)
		(layers "F.Cu" "B.Cu")
		(net "P3V3_STBY")
	)
	(via
		(at 218.059 -7.112)
		(size 0.508)
		(drill 0.254)
		(layers "F.Cu" "B.Cu")
		(net "P3V3_STBY")
	)
	(via
		(at 80.5942 -187.7822)
		(size 0.508)
		(drill 0.254)
		(layers "F.Cu" "B.Cu")
		(net "P3V3_STBY")
	)
	(via
		(at 344.251534 -43.718226)
		(size 0.508)
		(drill 0.254)
		(layers "F.Cu" "B.Cu")
		(net "P3V3_STBY")
	)
	(via
		(at 91.0082 -46.2026)
		(size 0.508)
		(drill 0.254)
		(layers "F.Cu" "B.Cu")
		(net "P3V3_STBY")
	)
	(via
		(at 32.510984 -136.088374)
		(size 0.4572)
		(drill 0.2032)
		(layers "F.Cu" "B.Cu")
		(net "P3V3_STBY")
	)
	(via
		(at 14.2113 -145.415)
		(size 0.508)
		(drill 0.254)
		(layers "F.Cu" "B.Cu")
		(net "P3V3_STBY")
	)
	(via
		(at 322.453 -100.838)
		(size 0.508)
		(drill 0.254)
		(layers "F.Cu" "B.Cu")
		(net "P3V3_STBY")
	)
	(via
		(at 49.022 -199.39)
		(size 0.508)
		(drill 0.254)
		(layers "F.Cu" "B.Cu")
		(net "P3V3_STBY")
	)
	(via
		(at 63.03264 -87.15756)
		(size 0.508)
		(drill 0.254)
		(layers "F.Cu" "B.Cu")
		(net "P3V3_STBY")
	)
	(via
		(at 179.590954 -3.092196)
		(size 0.508)
		(drill 0.254)
		(layers "F.Cu" "B.Cu")
		(net "P3V3_STBY")
	)
	(via
		(at 41.275 -44.069)
		(size 0.508)
		(drill 0.254)
		(layers "F.Cu" "B.Cu")
		(net "P3V3_STBY")
	)
	(via
		(at 205.74 -27.7876)
		(size 0.508)
		(drill 0.254)
		(layers "F.Cu" "B.Cu")
		(net "P3V3_STBY")
	)
	(via
		(at 92.0242 -44.9326)
		(size 0.508)
		(drill 0.254)
		(layers "F.Cu" "B.Cu")
		(net "P3V3_STBY")
	)
	(via
		(at 38.1 -178.181)
		(size 0.508)
		(drill 0.254)
		(layers "F.Cu" "B.Cu")
		(net "P3V3_STBY")
	)
	(via
		(at 27.592274 -42.884344)
		(size 0.508)
		(drill 0.254)
		(layers "F.Cu" "B.Cu")
		(net "P3V3_STBY")
	)
	(via
		(at 350.950784 -44.058586)
		(size 0.508)
		(drill 0.254)
		(layers "F.Cu" "B.Cu")
		(net "P3V3_STBY")
	)
	(via
		(at 6.258306 -81.594706)
		(size 0.508)
		(drill 0.254)
		(layers "F.Cu" "B.Cu")
		(net "P3V3_STBY")
	)
	(via
		(at 213.741 -195.834)
		(size 0.508)
		(drill 0.254)
		(layers "F.Cu" "B.Cu")
		(net "P3V3_STBY")
	)
	(via
		(at 273.667728 -16.31315)
		(size 0.508)
		(drill 0.254)
		(layers "F.Cu" "B.Cu")
		(net "P3V3_STBY")
	)
	(via
		(at 91.0082 -41.2496)
		(size 0.508)
		(drill 0.254)
		(layers "F.Cu" "B.Cu")
		(net "P3V3_STBY")
	)
	(via
		(at 90.1192 -46.2026)
		(size 0.508)
		(drill 0.254)
		(layers "F.Cu" "B.Cu")
		(net "P3V3_STBY")
	)
	(via
		(at 268.543786 -19.628104)
		(size 0.508)
		(drill 0.254)
		(layers "F.Cu" "B.Cu")
		(net "P3V3_STBY")
	)
	(via
		(at 45.0977 -103.5939)
		(size 0.508)
		(drill 0.254)
		(layers "F.Cu" "B.Cu")
		(net "P3V3_STBY")
	)
	(via
		(at 91.0082 -43.5356)
		(size 0.508)
		(drill 0.254)
		(layers "F.Cu" "B.Cu")
		(net "P3V3_STBY")
	)
	(via
		(at 261.506462 -3.551174)
		(size 0.508)
		(drill 0.254)
		(layers "F.Cu" "B.Cu")
		(net "P3V3_STBY")
	)
	(via
		(at 45.085 -199.263)
		(size 0.508)
		(drill 0.254)
		(layers "F.Cu" "B.Cu")
		(net "P3V3_STBY")
	)
	(via
		(at 27.559 -72.136)
		(size 0.508)
		(drill 0.254)
		(layers "F.Cu" "B.Cu")
		(net "P3V3_STBY")
	)
	(via
		(at 34.10458 -131.284726)
		(size 0.4572)
		(drill 0.2032)
		(layers "F.Cu" "B.Cu")
		(net "P3V3_STBY")
	)
	(via
		(at 27.698954 -164.067744)
		(size 0.508)
		(drill 0.254)
		(layers "F.Cu" "B.Cu")
		(net "P3V3_STBY")
	)
	(via
		(at 126.492 -49.3268)
		(size 0.508)
		(drill 0.254)
		(layers "F.Cu" "B.Cu")
		(net "P3V3_STBY")
	)
	(via
		(at 190.4492 -23.2156)
		(size 0.508)
		(drill 0.254)
		(layers "F.Cu" "B.Cu")
		(net "P3V3_STBY")
	)
	(via
		(at 238.252 -7.6962)
		(size 0.508)
		(drill 0.254)
		(layers "F.Cu" "B.Cu")
		(net "P3V3_STBY")
	)
	(via
		(at 42.299636 -114.508534)
		(size 0.508)
		(drill 0.254)
		(layers "F.Cu" "B.Cu")
		(net "P3V3_STBY")
	)
	(via
		(at 315.625734 -39.03726)
		(size 0.508)
		(drill 0.254)
		(layers "F.Cu" "B.Cu")
		(net "P3V3_STBY")
	)
	(via
		(at 68.721224 -182.042308)
		(size 0.508)
		(drill 0.254)
		(layers "F.Cu" "B.Cu")
		(net "P3V3_STBY")
	)
	(via
		(at 92.0242 -46.2026)
		(size 0.508)
		(drill 0.254)
		(layers "F.Cu" "B.Cu")
		(net "P3V3_STBY")
	)
	(via
		(at 28.633928 -69.287644)
		(size 0.508)
		(drill 0.254)
		(layers "F.Cu" "B.Cu")
		(net "P3V3_STBY")
	)
	(via
		(at 119.3038 -99.8982)
		(size 0.508)
		(drill 0.254)
		(layers "F.Cu" "B.Cu")
		(net "P3V3_STBY")
	)
	(via
		(at 261.3406 -14.2494)
		(size 0.7112)
		(drill 0.3556)
		(layers "F.Cu" "B.Cu")
		(net "P3V3_STBY")
	)
	(via
		(at 16.6624 -137.9728)
		(size 0.508)
		(drill 0.254)
		(layers "F.Cu" "B.Cu")
		(net "P3V3_STBY")
	)
	(via
		(at 91.0082 -44.9326)
		(size 0.508)
		(drill 0.254)
		(layers "F.Cu" "B.Cu")
		(net "P3V3_STBY")
	)
	(via
		(at 123.2662 -206.1845)
		(size 0.508)
		(drill 0.254)
		(layers "F.Cu" "B.Cu")
		(net "P3V3_STBY")
	)
	(via
		(at 194.31 -28.6512)
		(size 0.508)
		(drill 0.254)
		(layers "F.Cu" "B.Cu")
		(net "P3V3_STBY")
	)
	(via
		(at 233.5276 -8.4582)
		(size 0.508)
		(drill 0.254)
		(layers "F.Cu" "B.Cu")
		(net "P3V3_STBY")
	)
	(via
		(at 183.6928 -10.7442)
		(size 0.508)
		(drill 0.254)
		(layers "F.Cu" "B.Cu")
		(net "P3V3_STBY")
	)
	(via
		(at 73.2536 -159.0294)
		(size 0.508)
		(drill 0.254)
		(layers "F.Cu" "B.Cu")
		(net "P3V3_STBY")
	)
	(via
		(at 56.4642 -146.6342)
		(size 0.508)
		(drill 0.254)
		(layers "F.Cu" "B.Cu")
		(net "P3V3_STBY")
	)
	(via
		(at 78.953106 -87.462106)
		(size 0.508)
		(drill 0.254)
		(layers "F.Cu" "B.Cu")
		(net "P3V3_STBY")
	)
	(via
		(at 42.904664 -131.28498)
		(size 0.4572)
		(drill 0.2032)
		(layers "F.Cu" "B.Cu")
		(net "P3V3_STBY")
	)
	(via
		(at 37.304726 -125.685042)
		(size 0.4572)
		(drill 0.2032)
		(layers "F.Cu" "B.Cu")
		(net "P3V3_STBY")
	)
	(via
		(at 19.2024 -131.7244)
		(size 0.508)
		(drill 0.254)
		(layers "F.Cu" "B.Cu")
		(net "P3V3_STBY")
	)
	(via
		(at 122.8979 -196.5452)
		(size 0.508)
		(drill 0.254)
		(layers "F.Cu" "B.Cu")
		(net "P3V3_STBY")
	)
	(via
		(at 66.847974 -196.133974)
		(size 0.508)
		(drill 0.254)
		(layers "F.Cu" "B.Cu")
		(net "P3V3_STBY")
	)
	(via
		(at 81.6102 -76.581)
		(size 0.508)
		(drill 0.254)
		(layers "F.Cu" "B.Cu")
		(net "P3V3_STBY")
	)
	(via
		(at 25.908 -153.035)
		(size 0.508)
		(drill 0.254)
		(layers "F.Cu" "B.Cu")
		(net "P3V3_STBY")
	)
	(via
		(at 218.186 -11.049)
		(size 0.508)
		(drill 0.254)
		(layers "F.Cu" "B.Cu")
		(net "P3V3_STBY")
	)
	(via
		(at 125.3998 -93.8022)
		(size 0.508)
		(drill 0.254)
		(layers "F.Cu" "B.Cu")
		(net "P3V3_STBY")
	)
	(via
		(at 264.190734 -6.82498)
		(size 0.508)
		(drill 0.254)
		(layers "F.Cu" "B.Cu")
		(net "P3V3_STBY")
	)
	(via
		(at 247.4214 -4.9784)
		(size 0.508)
		(drill 0.254)
		(layers "F.Cu" "B.Cu")
		(net "P3V3_STBY")
	)
	(via
		(at 13.5128 -117.475)
		(size 0.508)
		(drill 0.254)
		(layers "F.Cu" "B.Cu")
		(net "P3V3_STBY")
	)
	(via
		(at 58.565288 -115.602512)
		(size 0.508)
		(drill 0.254)
		(layers "F.Cu" "B.Cu")
		(net "P3V3_STBY")
	)
	(via
		(at 72.686926 -127.508)
		(size 0.508)
		(drill 0.254)
		(layers "F.Cu" "B.Cu")
		(net "P3V3_STBY")
	)
	(via
		(at 32.893 -104.7496)
		(size 0.508)
		(drill 0.254)
		(layers "F.Cu" "B.Cu")
		(net "P3V3_STBY")
	)
	(via
		(at 9.779 -81.6356)
		(size 0.508)
		(drill 0.254)
		(layers "F.Cu" "B.Cu")
		(net "P3V3_STBY")
	)
	(via
		(at 29.52369 -112.94491)
		(size 0.508)
		(drill 0.254)
		(layers "F.Cu" "B.Cu")
		(net "P3V3_STBY")
	)
	(via
		(at 330.638912 -181.5084)
		(size 0.508)
		(drill 0.254)
		(layers "F.Cu" "B.Cu")
		(net "P3V3_STBY")
	)
	(via
		(at 72.644 -36.5252)
		(size 0.508)
		(drill 0.254)
		(layers "F.Cu" "B.Cu")
		(net "P3V3_STBY")
	)
	(via
		(at 188.54166 -17.4117)
		(size 0.508)
		(drill 0.254)
		(layers "F.Cu" "B.Cu")
		(net "P3V3_STBY")
	)
	(via
		(at 226.0346 -195.4784)
		(size 0.508)
		(drill 0.254)
		(layers "F.Cu" "B.Cu")
		(net "P3V3_STBY")
	)
	(via
		(at 12.169648 -74.91476)
		(size 0.508)
		(drill 0.254)
		(layers "F.Cu" "B.Cu")
		(net "P3V3_STBY")
	)
	(via
		(at 231.5972 -9.398)
		(size 0.508)
		(drill 0.254)
		(layers "F.Cu" "B.Cu")
		(net "P3V3_STBY")
	)
	(via
		(at 38.904672 -125.685042)
		(size 0.4572)
		(drill 0.2032)
		(layers "F.Cu" "B.Cu")
		(net "P3V3_STBY")
	)
	(via
		(at 216.63533 -190.156592)
		(size 0.508)
		(drill 0.254)
		(layers "F.Cu" "B.Cu")
		(net "P3V3_STBY")
	)
	(via
		(at 26.207466 -107.509818)
		(size 0.508)
		(drill 0.254)
		(layers "F.Cu" "B.Cu")
		(net "P3V3_STBY")
	)
	(via
		(at 322.707 -85.217)
		(size 0.508)
		(drill 0.254)
		(layers "F.Cu" "B.Cu")
		(net "P3V3_STBY")
	)
	(via
		(at 126.746 -201.422)
		(size 0.508)
		(drill 0.254)
		(layers "F.Cu" "B.Cu")
		(net "P3V3_STBY")
	)
	(via
		(at 53.462936 -45.59935)
		(size 0.508)
		(drill 0.254)
		(layers "F.Cu" "B.Cu")
		(net "P3V3_STBY")
	)
	(via
		(at 217.964004 -193.9544)
		(size 0.508)
		(drill 0.254)
		(layers "F.Cu" "B.Cu")
		(net "P3V3_STBY")
	)
	(via
		(at 338.135722 -46.278292)
		(size 0.508)
		(drill 0.254)
		(layers "F.Cu" "B.Cu")
		(net "P3V3_STBY")
	)
	(via
		(at 22.403816 -137.993882)
		(size 0.508)
		(drill 0.254)
		(layers "F.Cu" "B.Cu")
		(net "P3V3_STBY")
	)
	(via
		(at 59.318398 -40.80002)
		(size 0.508)
		(drill 0.254)
		(layers "F.Cu" "B.Cu")
		(net "P3V3_STBY")
	)
	(via
		(at 191.9478 -20.0914)
		(size 0.508)
		(drill 0.254)
		(layers "F.Cu" "B.Cu")
		(net "P3V3_STBY")
	)
	(via
		(at 74.422 -158.9278)
		(size 0.7112)
		(drill 0.3556)
		(layers "F.Cu" "B.Cu")
		(net "P3V3_STBY")
	)
	(via
		(at 75.46086 -79.0829)
		(size 0.508)
		(drill 0.254)
		(layers "F.Cu" "B.Cu")
		(net "P3V3_STBY")
	)
	(via
		(at 258.8006 -3.606292)
		(size 0.508)
		(drill 0.254)
		(layers "F.Cu" "B.Cu")
		(net "P3V3_STBY")
	)
	(via
		(at 190.0682 -13.6652)
		(size 0.508)
		(drill 0.254)
		(layers "F.Cu" "B.Cu")
		(net "P3V3_STBY")
	)
	(via
		(at 75.623166 -89.161366)
		(size 0.508)
		(drill 0.254)
		(layers "F.Cu" "B.Cu")
		(net "P3V3_STBY")
	)
	(via
		(at 188.84646 -28.43276)
		(size 0.508)
		(drill 0.254)
		(layers "F.Cu" "B.Cu")
		(net "P3V3_STBY")
	)
	(via
		(at 122.7455 -15.10792)
		(size 0.508)
		(drill 0.254)
		(layers "F.Cu" "B.Cu")
		(net "P3V3_STBY")
	)
	(via
		(at 16.133826 -128.35128)
		(size 0.508)
		(drill 0.254)
		(layers "F.Cu" "B.Cu")
		(net "P3V3_STBY")
	)
	(via
		(at 264.114788 -9.078722)
		(size 0.508)
		(drill 0.254)
		(layers "F.Cu" "B.Cu")
		(net "P3V3_STBY")
	)
	(via
		(at 118.364 -15.8242)
		(size 0.508)
		(drill 0.254)
		(layers "F.Cu" "B.Cu")
		(net "P3V3_STBY")
	)
	(via
		(at 25.81402 -79.307944)
		(size 0.508)
		(drill 0.254)
		(layers "F.Cu" "B.Cu")
		(net "P3V3_STBY")
	)
	(via
		(at 57.913778 -31.441898)
		(size 0.508)
		(drill 0.254)
		(layers "F.Cu" "B.Cu")
		(net "P3V3_STBY")
	)
	(via
		(at 84.8868 -76.0984)
		(size 0.508)
		(drill 0.254)
		(layers "F.Cu" "B.Cu")
		(net "P3V3_STBY")
	)
	(via
		(at 225.672396 -2.329942)
		(size 0.508)
		(drill 0.254)
		(layers "F.Cu" "B.Cu")
		(net "P3V3_STBY")
	)
	(via
		(at 115.6843 -95.5167)
		(size 0.508)
		(drill 0.254)
		(layers "F.Cu" "B.Cu")
		(net "P3V3_STBY")
	)
	(via
		(at 332.757272 -100.097336)
		(size 0.508)
		(drill 0.254)
		(layers "F.Cu" "B.Cu")
		(net "P3V3_STBY")
	)
	(via
		(at 55.602124 -122.729244)
		(size 0.508)
		(drill 0.254)
		(layers "F.Cu" "B.Cu")
		(net "P3V3_STBY")
	)
	(via
		(at 147.9296 -53.213)
		(size 0.508)
		(drill 0.254)
		(layers "F.Cu" "B.Cu")
		(net "P3V3_STBY")
	)
	(via
		(at 61.7728 -129.032)
		(size 0.508)
		(drill 0.254)
		(layers "F.Cu" "B.Cu")
		(net "P3V3_STBY")
	)
	(via
		(at 15.8496 -84.963)
		(size 0.508)
		(drill 0.254)
		(layers "F.Cu" "B.Cu")
		(net "P3V3_STBY")
	)
	(via
		(at 27.1526 -187.6044)
		(size 0.508)
		(drill 0.254)
		(layers "F.Cu" "B.Cu")
		(net "P3V3_STBY")
	)
	(via
		(at 131.0386 -195.1482)
		(size 0.508)
		(drill 0.254)
		(layers "F.Cu" "B.Cu")
		(net "P3V3_STBY")
	)
	(via
		(at 71.5772 -162.2806)
		(size 0.508)
		(drill 0.254)
		(layers "F.Cu" "B.Cu")
		(net "P3V3_STBY")
	)
	(via
		(at 120.4976 -15.8242)
		(size 0.508)
		(drill 0.254)
		(layers "F.Cu" "B.Cu")
		(net "P3V3_STBY")
	)
	(via
		(at 34.4678 -189.2808)
		(size 0.508)
		(drill 0.254)
		(layers "F.Cu" "B.Cu")
		(net "P3V3_STBY")
	)
	(via
		(at 46.9138 -185.2676)
		(size 0.508)
		(drill 0.254)
		(layers "F.Cu" "B.Cu")
		(net "P3V3_STBY")
	)
	(via
		(at 36.3855 -203.0095)
		(size 0.508)
		(drill 0.254)
		(layers "F.Cu" "B.Cu")
		(net "P3V3_STBY")
	)
	(via
		(at 70.5612 -52.959)
		(size 0.508)
		(drill 0.254)
		(layers "F.Cu" "B.Cu")
		(net "P3V3_STBY")
	)
	(via
		(at 68.453 -186.9821)
		(size 0.508)
		(drill 0.254)
		(layers "F.Cu" "B.Cu")
		(net "P3V3_STBY")
	)
	(via
		(at 56.107838 -112.225582)
		(size 0.508)
		(drill 0.254)
		(layers "F.Cu" "B.Cu")
		(net "P3V3_STBY")
	)
	(via
		(at 226.9236 -189.2554)
		(size 0.508)
		(drill 0.254)
		(layers "F.Cu" "B.Cu")
		(net "P3V3_STBY")
	)
	(via
		(at 34.798 -115.4938)
		(size 0.508)
		(drill 0.254)
		(layers "F.Cu" "B.Cu")
		(net "P3V3_STBY")
	)
	(via
		(at 76.327 -181.765702)
		(size 0.5588)
		(drill 0.3048)
		(layers "F.Cu" "B.Cu")
		(net "P3V3_STBY")
	)
	(via
		(at 9.0678 -124.079)
		(size 0.508)
		(drill 0.254)
		(layers "F.Cu" "B.Cu")
		(net "P3V3_STBY")
	)
	(via
		(at 27.106118 -85.2424)
		(size 0.508)
		(drill 0.254)
		(layers "F.Cu" "B.Cu")
		(net "P3V3_STBY")
	)
	(via
		(at 42.904664 -128.085088)
		(size 0.4572)
		(drill 0.2032)
		(layers "F.Cu" "B.Cu")
		(net "P3V3_STBY")
	)
	(via
		(at 126.182628 -34.11601)
		(size 0.508)
		(drill 0.254)
		(layers "F.Cu" "B.Cu")
		(net "P3V3_STBY")
	)
	(via
		(at 38.989 -205.359)
		(size 0.508)
		(drill 0.254)
		(layers "F.Cu" "B.Cu")
		(net "P3V3_STBY")
	)
	(via
		(at 44.681648 -114.489738)
		(size 0.508)
		(drill 0.254)
		(layers "F.Cu" "B.Cu")
		(net "P3V3_STBY")
	)
	(via
		(at 130.81 -201.295)
		(size 0.508)
		(drill 0.254)
		(layers "F.Cu" "B.Cu")
		(net "P3V3_STBY")
	)
	(via
		(at 50.2539 -111.1123)
		(size 0.508)
		(drill 0.254)
		(layers "F.Cu" "B.Cu")
		(net "P3V3_STBY")
	)
	(via
		(at 121.412 -197.485)
		(size 0.508)
		(drill 0.254)
		(layers "F.Cu" "B.Cu")
		(net "P3V3_STBY")
	)
	(via
		(at 120.64746 -31.15564)
		(size 0.508)
		(drill 0.254)
		(layers "F.Cu" "B.Cu")
		(net "P3V3_STBY")
	)
	(via
		(at 27.8384 -70.3199)
		(size 0.508)
		(drill 0.254)
		(layers "F.Cu" "B.Cu")
		(net "P3V3_STBY")
	)
	(via
		(at 19.3294 -122.7836)
		(size 0.508)
		(drill 0.254)
		(layers "F.Cu" "B.Cu")
		(net "P3V3_STBY")
	)
	(via
		(at 161.8742 -59.563)
		(size 0.508)
		(drill 0.254)
		(layers "F.Cu" "B.Cu")
		(net "P3V3_STBY")
	)
	(via
		(at 21.779992 -120.856502)
		(size 0.508)
		(drill 0.254)
		(layers "F.Cu" "B.Cu")
		(net "P3V3_STBY")
	)
	(via
		(at 90.1192 -43.5356)
		(size 0.508)
		(drill 0.254)
		(layers "F.Cu" "B.Cu")
		(net "P3V3_STBY")
	)
	(via
		(at 20.55876 -100.581206)
		(size 0.508)
		(drill 0.254)
		(layers "F.Cu" "B.Cu")
		(net "P3V3_STBY")
	)
	(via
		(at 217.9574 -5.4356)
		(size 0.508)
		(drill 0.254)
		(layers "F.Cu" "B.Cu")
		(net "P3V3_STBY")
	)
	(via
		(at 205.486 -19.304)
		(size 0.508)
		(drill 0.254)
		(layers "F.Cu" "B.Cu")
		(net "P3V3_STBY")
	)
	(via
		(at 331.216 -11.176)
		(size 0.508)
		(drill 0.254)
		(layers "F.Cu" "B.Cu")
		(net "P3V3_STBY")
	)
	(via
		(at 45.212 -191.3636)
		(size 0.508)
		(drill 0.254)
		(layers "F.Cu" "B.Cu")
		(net "P3V3_STBY")
	)
	(via
		(at 161.5821 -101.6254)
		(size 0.7112)
		(drill 0.3556)
		(layers "F.Cu" "B.Cu")
		(net "P3V3_STBY")
	)
	(via
		(at 154.454606 -33.405826)
		(size 0.508)
		(drill 0.254)
		(layers "F.Cu" "B.Cu")
		(net "P3V3_STBY")
	)
	(via
		(at 142.901162 -35.783774)
		(size 0.508)
		(drill 0.254)
		(layers "F.Cu" "B.Cu")
		(net "P3V3_STBY")
	)
	(via
		(at 187.549536 -2.090928)
		(size 0.508)
		(drill 0.254)
		(layers "F.Cu" "B.Cu")
		(net "P3V3_STBY")
	)
	(via
		(at 26.206704 -110.28172)
		(size 0.508)
		(drill 0.254)
		(layers "F.Cu" "B.Cu")
		(net "P3V3_STBY")
	)
	(via
		(at 5.4102 -109.093)
		(size 0.508)
		(drill 0.254)
		(layers "F.Cu" "B.Cu")
		(net "P3V3_STBY")
	)
	(via
		(at 15.823692 -122.9868)
		(size 0.508)
		(drill 0.254)
		(layers "F.Cu" "B.Cu")
		(net "P3V3_STBY")
	)
	(via
		(at 40.504618 -125.685042)
		(size 0.4572)
		(drill 0.2032)
		(layers "F.Cu" "B.Cu")
		(net "P3V3_STBY")
	)
	(via
		(at 323.468746 -38.480492)
		(size 0.508)
		(drill 0.254)
		(layers "F.Cu" "B.Cu")
		(net "P3V3_STBY")
	)
	(via
		(at 115.7732 -27.9908)
		(size 0.508)
		(drill 0.254)
		(layers "F.Cu" "B.Cu")
		(net "P3V3_STBY")
	)
	(via
		(at 218.1352 -13.2588)
		(size 0.508)
		(drill 0.254)
		(layers "F.Cu" "B.Cu")
		(net "P3V3_STBY")
	)
	(via
		(at 63.5508 -128.6764)
		(size 0.508)
		(drill 0.254)
		(layers "F.Cu" "B.Cu")
		(net "P3V3_STBY")
	)
	(via
		(at 329.594718 -171.987718)
		(size 0.508)
		(drill 0.254)
		(layers "F.Cu" "B.Cu")
		(net "P3V3_STBY")
	)
	(via
		(at 265.6459 -1.581912)
		(size 0.508)
		(drill 0.254)
		(layers "F.Cu" "B.Cu")
		(net "P3V3_STBY")
	)
	(via
		(at 76.708 -188.1632)
		(size 0.508)
		(drill 0.254)
		(layers "F.Cu" "B.Cu")
		(net "P3V3_STBY")
	)
	(via
		(at 29.21 -182.2704)
		(size 0.508)
		(drill 0.254)
		(layers "F.Cu" "B.Cu")
		(net "P3V3_STBY")
	)
	(via
		(at 115.551204 -30.172914)
		(size 0.508)
		(drill 0.254)
		(layers "F.Cu" "B.Cu")
		(net "P3V3_STBY")
	)
	(via
		(at 9.3345 -117.5766)
		(size 0.508)
		(drill 0.254)
		(layers "F.Cu" "B.Cu")
		(net "P3V3_STBY")
	)
	(via
		(at 116.2558 -15.8242)
		(size 0.508)
		(drill 0.254)
		(layers "F.Cu" "B.Cu")
		(net "P3V3_STBY")
	)
	(via
		(at 92.0242 -43.5356)
		(size 0.508)
		(drill 0.254)
		(layers "F.Cu" "B.Cu")
		(net "P3V3_STBY")
	)
	(via
		(at 72.5932 -117.04574)
		(size 0.508)
		(drill 0.254)
		(layers "F.Cu" "B.Cu")
		(net "P3V3_STBY")
	)
	(via
		(at 90.1192 -42.3926)
		(size 0.508)
		(drill 0.254)
		(layers "F.Cu" "B.Cu")
		(net "P3V3_STBY")
	)
	(via
		(at 52.2605 -103.6955)
		(size 0.508)
		(drill 0.254)
		(layers "F.Cu" "B.Cu")
		(net "P3V3_STBY")
	)
	(via
		(at 53.4162 -199.39)
		(size 0.508)
		(drill 0.254)
		(layers "F.Cu" "B.Cu")
		(net "P3V3_STBY")
	)
	(via
		(at 208.026 -24.6634)
		(size 0.508)
		(drill 0.254)
		(layers "F.Cu" "B.Cu")
		(net "P3V3_STBY")
	)
	(via
		(at 49.022 -185.293)
		(size 0.508)
		(drill 0.254)
		(layers "F.Cu" "B.Cu")
		(net "P3V3_STBY")
	)
	(via
		(at 221.3737 -14.3383)
		(size 0.508)
		(drill 0.254)
		(layers "F.Cu" "B.Cu")
		(net "P3V3_STBY")
	)
	(via
		(at 216.789 -202.692)
		(size 0.508)
		(drill 0.254)
		(layers "F.Cu" "B.Cu")
		(net "P3V3_STBY")
	)
	(via
		(at 135.001 -196.723)
		(size 0.508)
		(drill 0.254)
		(layers "F.Cu" "B.Cu")
		(net "P3V3_STBY")
	)
	(via
		(at 90.1192 -44.9326)
		(size 0.508)
		(drill 0.254)
		(layers "F.Cu" "B.Cu")
		(net "P3V3_STBY")
	)
	(via
		(at 53.4162 -185.293)
		(size 0.508)
		(drill 0.254)
		(layers "F.Cu" "B.Cu")
		(net "P3V3_STBY")
	)
	(via
		(at 200.9902 -18.8468)
		(size 0.508)
		(drill 0.254)
		(layers "F.Cu" "B.Cu")
		(net "P3V3_STBY")
	)
	(via
		(at 110.0836 -44.9072)
		(size 0.508)
		(drill 0.254)
		(layers "F.Cu" "B.Cu")
		(net "P3V3_STBY")
	)
	(via
		(at 272.492216 -5.053076)
		(size 0.508)
		(drill 0.254)
		(layers "F.Cu" "B.Cu")
		(net "P3V3_STBY")
	)
	(via
		(at 62.57925 -111.94415)
		(size 0.508)
		(drill 0.254)
		(layers "F.Cu" "B.Cu")
		(net "P3V3_STBY")
	)
	(via
		(at 215.138 -2.3114)
		(size 0.508)
		(drill 0.254)
		(layers "F.Cu" "B.Cu")
		(net "P3V3_STBY")
	)
	(via
		(at 45.4025 -180.9115)
		(size 0.508)
		(drill 0.254)
		(layers "F.Cu" "B.Cu")
		(net "P3V3_STBY")
	)
	(via
		(at 55.007002 -141.200632)
		(size 0.508)
		(drill 0.254)
		(layers "F.Cu" "B.Cu")
		(net "P3V3_STBY")
	)
	(via
		(at 22.352 -155.8544)
		(size 0.508)
		(drill 0.254)
		(layers "F.Cu" "B.Cu")
		(net "P3V3_STBY")
	)
	(via
		(at 297.2816 -36.6014)
		(size 0.508)
		(drill 0.254)
		(layers "F.Cu" "B.Cu")
		(net "P3V3_STBY")
	)
	(via
		(at 335.899506 -177.232818)
		(size 0.508)
		(drill 0.254)
		(layers "F.Cu" "B.Cu")
		(net "P3V3_STBY")
	)
	(via
		(at 47.117 -146.6342)
		(size 0.508)
		(drill 0.254)
		(layers "F.Cu" "B.Cu")
		(net "P3V3_STBY")
	)
	(via
		(at 34.10458 -128.085088)
		(size 0.4572)
		(drill 0.2032)
		(layers "F.Cu" "B.Cu")
		(net "P3V3_STBY")
	)
	(via
		(at 54.557676 -53.8734)
		(size 0.508)
		(drill 0.254)
		(layers "F.Cu" "B.Cu")
		(net "P3V3_STBY")
	)
	(via
		(at 19.31797 -90.71483)
		(size 0.508)
		(drill 0.254)
		(layers "F.Cu" "B.Cu")
		(net "P3V3_STBY")
	)
	(via
		(at 6.9342 -58.166)
		(size 0.508)
		(drill 0.254)
		(layers "F.Cu" "B.Cu")
		(net "P3V3_STBY")
	)
	(via
		(at 64.957452 -145.856452)
		(size 0.508)
		(drill 0.254)
		(layers "F.Cu" "B.Cu")
		(net "P3V3_STBY")
	)
	(via
		(at 258.548632 -10.555224)
		(size 0.508)
		(drill 0.254)
		(layers "F.Cu" "B.Cu")
		(net "P3V3_STBY")
	)
	(via
		(at 222.885 -5.9944)
		(size 0.508)
		(drill 0.254)
		(layers "F.Cu" "B.Cu")
		(net "P3V3_STBY")
	)
	(via
		(at 26.467816 -97.449894)
		(size 0.508)
		(drill 0.254)
		(layers "F.Cu" "B.Cu")
		(net "P3V3_STBY")
	)
	(via
		(at 25.8445 -151.2824)
		(size 0.508)
		(drill 0.254)
		(layers "F.Cu" "B.Cu")
		(net "P3V3_STBY")
	)
	(via
		(at 116.7003 -97.5487)
		(size 0.508)
		(drill 0.254)
		(layers "F.Cu" "B.Cu")
		(net "P3V3_STBY")
	)
	(via
		(at 66.7766 -111.4298)
		(size 0.508)
		(drill 0.254)
		(layers "F.Cu" "B.Cu")
		(net "P3V3_STBY")
	)
	(via
		(at 128.996694 -34.075116)
		(size 0.508)
		(drill 0.254)
		(layers "F.Cu" "B.Cu")
		(net "P3V3_STBY")
	)
	(via
		(at 47.41545 -115.19027)
		(size 0.508)
		(drill 0.254)
		(layers "F.Cu" "B.Cu")
		(net "P3V3_STBY")
	)
	(via
		(at 227.711 -2.413)
		(size 0.508)
		(drill 0.254)
		(layers "F.Cu" "B.Cu")
		(net "P3V3_STBY")
	)
	(via
		(at 208.756758 -5.35686)
		(size 0.508)
		(drill 0.254)
		(layers "F.Cu" "B.Cu")
		(net "P3V3_STBY")
	)
	(via
		(at 36.195 -180.086)
		(size 0.508)
		(drill 0.254)
		(layers "F.Cu" "B.Cu")
		(net "P3V3_STBY")
	)
	(via
		(at 45.30471 -133.685026)
		(size 0.4572)
		(drill 0.2032)
		(layers "F.Cu" "B.Cu")
		(net "P3V3_STBY")
	)
	(via
		(at 27.232102 -76.502768)
		(size 0.508)
		(drill 0.254)
		(layers "F.Cu" "B.Cu")
		(net "P3V3_STBY")
	)
	(via
		(at 56.0832 -113.284)
		(size 0.508)
		(drill 0.254)
		(layers "F.Cu" "B.Cu")
		(net "P3V3_STBY")
	)
	(via
		(at 122.682 -200.1901)
		(size 0.508)
		(drill 0.254)
		(layers "F.Cu" "B.Cu")
		(net "P3V3_STBY")
	)
	(via
		(at 35.3695 -200.9775)
		(size 0.508)
		(drill 0.254)
		(layers "F.Cu" "B.Cu")
		(net "P3V3_STBY")
	)
	(via
		(at 339.725 -177.292)
		(size 0.508)
		(drill 0.254)
		(layers "F.Cu" "B.Cu")
		(net "P3V3_STBY")
	)
	(via
		(at 22.6568 -131.7498)
		(size 0.508)
		(drill 0.254)
		(layers "F.Cu" "B.Cu")
		(net "P3V3_STBY")
	)
	(via
		(at 266.92225 -15.51686)
		(size 0.508)
		(drill 0.254)
		(layers "F.Cu" "B.Cu")
		(net "P3V3_STBY")
	)
	(via
		(at 55.118 -179.197)
		(size 0.508)
		(drill 0.254)
		(layers "F.Cu" "B.Cu")
		(net "P3V3_STBY")
	)
	(via
		(at 308.55793 -36.180522)
		(size 0.508)
		(drill 0.254)
		(layers "F.Cu" "B.Cu")
		(net "P3V3_STBY")
	)
	(via
		(at 92.0242 -42.3926)
		(size 0.508)
		(drill 0.254)
		(layers "F.Cu" "B.Cu")
		(net "P3V3_STBY")
	)
	(via
		(at 19.691858 -64.9732)
		(size 0.508)
		(drill 0.254)
		(layers "F.Cu" "B.Cu")
		(net "P3V3_STBY")
	)
	(via
		(at 72.771 -188.087)
		(size 0.508)
		(drill 0.254)
		(layers "F.Cu" "B.Cu")
		(net "P3V3_STBY")
	)
	(via
		(at 351.063052 -46.768766)
		(size 0.508)
		(drill 0.254)
		(layers "F.Cu" "B.Cu")
		(net "P3V3_STBY")
	)
	(via
		(at 9.9822 -98.947478)
		(size 0.508)
		(drill 0.254)
		(layers "F.Cu" "B.Cu")
		(net "P3V3_STBY")
	)
	(via
		(at 135.0264 -195.6308)
		(size 0.508)
		(drill 0.254)
		(layers "F.Cu" "B.Cu")
		(net "P3V3_STBY")
	)
	(via
		(at 328.022712 -184.433718)
		(size 0.508)
		(drill 0.254)
		(layers "F.Cu" "B.Cu")
		(net "P3V3_STBY")
	)
	(via
		(at 14.7574 -84.9884)
		(size 0.508)
		(drill 0.254)
		(layers "F.Cu" "B.Cu")
		(net "P3V3_STBY")
	)
	(via
		(at 331.343 -177.292)
		(size 0.508)
		(drill 0.254)
		(layers "F.Cu" "B.Cu")
		(net "P3V3_STBY")
	)
	(via
		(at 260.176772 -13.094716)
		(size 0.508)
		(drill 0.254)
		(layers "F.Cu" "B.Cu")
		(net "P3V3_STBY")
	)
	(via
		(at 191.4398 -26.1366)
		(size 0.508)
		(drill 0.254)
		(layers "F.Cu" "B.Cu")
		(net "P3V3_STBY")
	)
	(via
		(at 43.3832 -205.359)
		(size 0.508)
		(drill 0.254)
		(layers "F.Cu" "B.Cu")
		(net "P3V3_STBY")
	)
	(via
		(at 19.7358 -127.635)
		(size 0.508)
		(drill 0.254)
		(layers "F.Cu" "B.Cu")
		(net "P3V3_STBY")
	)
	(via
		(at 37.1983 -186.9821)
		(size 0.508)
		(drill 0.254)
		(layers "F.Cu" "B.Cu")
		(net "P3V3_STBY")
	)
	(via
		(at 73.2536 -161.0868)
		(size 0.508)
		(drill 0.254)
		(layers "F.Cu" "B.Cu")
		(net "P3V3_STBY")
	)
	(via
		(at 218.059 -9.144)
		(size 0.508)
		(drill 0.254)
		(layers "F.Cu" "B.Cu")
		(net "P3V3_STBY")
	)
	(via
		(at 31.15183 -93.463364)
		(size 0.508)
		(drill 0.254)
		(layers "F.Cu" "B.Cu")
		(net "P3V3_STBY")
	)
	(via
		(at 80.0862 -87.503)
		(size 0.508)
		(drill 0.254)
		(layers "F.Cu" "B.Cu")
		(net "P3V3_STBY")
	)
	(via
		(at 142.233142 -98.460052)
		(size 0.508)
		(drill 0.254)
		(layers "F.Cu" "B.Cu")
		(net "P3V3_STBY")
	)
	(via
		(at 40.8178 -191.3636)
		(size 0.508)
		(drill 0.254)
		(layers "F.Cu" "B.Cu")
		(net "P3V3_STBY")
	)
	(via
		(at 40.767 -175.133)
		(size 0.508)
		(drill 0.254)
		(layers "F.Cu" "B.Cu")
		(net "P3V3_STBY")
	)
	(via
		(at 27.1526 -183.2102)
		(size 0.508)
		(drill 0.254)
		(layers "F.Cu" "B.Cu")
		(net "P3V3_STBY")
	)
	(via
		(at 79.4766 -73.7743)
		(size 0.508)
		(drill 0.254)
		(layers "F.Cu" "B.Cu")
		(net "P3V3_STBY")
	)
	(via
		(at 333.121 -99.314)
		(size 0.508)
		(drill 0.254)
		(layers "F.Cu" "B.Cu")
		(net "P3V3_STBY")
	)
	(via
		(at 22.6568 -134.239)
		(size 0.508)
		(drill 0.254)
		(layers "F.Cu" "B.Cu")
		(net "P3V3_STBY")
	)
	(via
		(at 6.096 -78.4098)
		(size 0.508)
		(drill 0.254)
		(layers "F.Cu" "B.Cu")
		(net "P3V3_STBY")
	)
	(via
		(at 67.188588 -129.96926)
		(size 0.508)
		(drill 0.254)
		(layers "F.Cu" "B.Cu")
		(net "P3V3_STBY")
	)
	(via
		(at 48.7172 -48.1584)
		(size 0.508)
		(drill 0.254)
		(layers "F.Cu" "B.Cu")
		(net "P3V3_STBY")
	)
	(via
		(at 224.4598 -12.8778)
		(size 0.508)
		(drill 0.254)
		(layers "F.Cu" "B.Cu")
		(net "P3V3_STBY")
	)
	(via
		(at 240.7666 -17.2466)
		(size 0.508)
		(drill 0.254)
		(layers "F.Cu" "B.Cu")
		(net "P3V3_STBY")
	)
	(via
		(at 257.7338 -13.6398)
		(size 0.508)
		(drill 0.254)
		(layers "F.Cu" "B.Cu")
		(net "P3V3_STBY")
	)
	(via
		(at 40.504618 -134.485126)
		(size 0.4572)
		(drill 0.2032)
		(layers "F.Cu" "B.Cu")
		(net "P3V3_STBY")
	)
	(via
		(at 69.30644 -124.243338)
		(size 0.508)
		(drill 0.254)
		(layers "F.Cu" "B.Cu")
		(net "P3V3_STBY")
	)
	(via
		(at 54.9402 -138.7729)
		(size 0.508)
		(drill 0.254)
		(layers "F.Cu" "B.Cu")
		(net "P3V3_STBY")
	)
	(via
		(at 46.4185 -182.9435)
		(size 0.508)
		(drill 0.254)
		(layers "F.Cu" "B.Cu")
		(net "P3V3_STBY")
	)
	(via
		(at 46.90491 -132.084826)
		(size 0.4572)
		(drill 0.2032)
		(layers "F.Cu" "B.Cu")
		(net "P3V3_STBY")
	)
	(via
		(at 37.11067 -102.51694)
		(size 0.508)
		(drill 0.254)
		(layers "F.Cu" "B.Cu")
		(net "P3V3_STBY")
	)
	(via
		(at 78.486 -172.466)
		(size 0.508)
		(drill 0.254)
		(layers "F.Cu" "B.Cu")
		(net "P3V3_STBY")
	)
	(via
		(at 34.798 -181.737)
		(size 0.508)
		(drill 0.254)
		(layers "F.Cu" "B.Cu")
		(net "P3V3_STBY")
	)
	(via
		(at 72.587104 -124.2822)
		(size 0.508)
		(drill 0.254)
		(layers "F.Cu" "B.Cu")
		(net "P3V3_STBY")
	)
	(via
		(at 221.996 -196.088)
		(size 0.508)
		(drill 0.254)
		(layers "F.Cu" "B.Cu")
		(net "P3V3_STBY")
	)
	(via
		(at 317.3095 -99.1235)
		(size 0.508)
		(drill 0.254)
		(layers "F.Cu" "B.Cu")
		(net "P3V3_STBY")
	)
	(via
		(at 67.3354 -112.5982)
		(size 0.508)
		(drill 0.254)
		(layers "F.Cu" "B.Cu")
		(net "P3V3_STBY")
	)
	(via
		(at 90.1192 -41.2496)
		(size 0.508)
		(drill 0.254)
		(layers "F.Cu" "B.Cu")
		(net "P3V3_STBY")
	)
	(via
		(at 333.2988 -69.9008)
		(size 0.508)
		(drill 0.254)
		(layers "F.Cu" "B.Cu")
		(net "P3V3_STBY")
	)
	(via
		(at 74.295 -160.0708)
		(size 0.508)
		(drill 0.254)
		(layers "F.Cu" "B.Cu")
		(net "P3V3_STBY")
	)
	(via
		(at 200.9648 -31.8262)
		(size 0.508)
		(drill 0.254)
		(layers "F.Cu" "B.Cu")
		(net "P3V3_STBY")
	)
	(via
		(at 75.6285 -150.5585)
		(size 0.508)
		(drill 0.254)
		(layers "F.Cu" "B.Cu")
		(net "P3V3_STBY")
	)
	(via
		(at 331.216 -17.145)
		(size 0.508)
		(drill 0.254)
		(layers "F.Cu" "B.Cu")
		(net "P3V3_STBY")
	)
	(via
		(at 68.121022 -191.930782)
		(size 0.508)
		(drill 0.254)
		(layers "F.Cu" "B.Cu")
		(net "P3V3_STBY")
	)
	(via
		(at 196.088 -16.3068)
		(size 0.508)
		(drill 0.254)
		(layers "F.Cu" "B.Cu")
		(net "P3V3_STBY")
	)
	(segment
		(start 73.77176 -187.147708)
		(end 73.614026 -186.989974)
		(width 0.4064)
		(layer "B.Cu")
		(net "P3V3_STBY")
	)
	(segment
		(start 42.904664 -128.085088)
		(end 42.592752 -128.397)
		(width 0.508)
		(layer "B.Cu")
		(net "P3V3_STBY")
	)
	(segment
		(start 331.216 -6.2738)
		(end 331.211682 -6.269482)
		(width 0.508)
		(layer "B.Cu")
		(net "P3V3_STBY")
	)
	(segment
		(start 264.190734 -6.82498)
		(end 264.99693 -6.018784)
		(width 0.508)
		(layer "B.Cu")
		(net "P3V3_STBY")
	)
	(segment
		(start 67.945 -190.1825)
		(end 67.945 -187.4901)
		(width 0.508)
		(layer "B.Cu")
		(net "P3V3_STBY")
	)
	(segment
		(start 23.497286 -131.462018)
		(end 23.497286 -130.446018)
		(width 0.508)
		(layer "B.Cu")
		(net "P3V3_STBY")
	)
	(segment
		(start 143.002508 -34.88563)
		(end 143.002508 -35.682428)
		(width 0.508)
		(layer "B.Cu")
		(net "P3V3_STBY")
	)
	(segment
		(start 225.933 -195.58)
		(end 226.0346 -195.4784)
		(width 0.508)
		(layer "B.Cu")
		(net "P3V3_STBY")
	)
	(segment
		(start 350.183196 -46.78299)
		(end 351.035112 -46.78299)
		(width 0.4064)
		(layer "B.Cu")
		(net "P3V3_STBY")
	)
	(segment
		(start 125.994668 -33.92805)
		(end 126.182628 -34.11601)
		(width 0.508)
		(layer "B.Cu")
		(net "P3V3_STBY")
	)
	(segment
		(start 315.140086 -38.176962)
		(end 315.625734 -38.66261)
		(width 0.508)
		(layer "B.Cu")
		(net "P3V3_STBY")
	)
	(segment
		(start 54.9021 -138.811)
		(end 54.1655 -138.811)
		(width 0.508)
		(layer "B.Cu")
		(net "P3V3_STBY")
	)
	(segment
		(start 333.788512 -171.987718)
		(end 332.772512 -171.987718)
		(width 0.508)
		(layer "B.Cu")
		(net "P3V3_STBY")
	)
	(segment
		(start 256.455164 -7.702804)
		(end 256.78765 -7.370318)
		(width 0.508)
		(layer "B.Cu")
		(net "P3V3_STBY")
	)
	(segment
		(start 58.565034 -119.320818)
		(end 60.024518 -119.320818)
		(width 0.508)
		(layer "B.Cu")
		(net "P3V3_STBY")
	)
	(segment
		(start 264.99693 -5.634736)
		(end 265.216894 -5.414772)
		(width 0.508)
		(layer "B.Cu")
		(net "P3V3_STBY")
	)
	(segment
		(start 127.956818 -33.963356)
		(end 127.972058 -33.948116)
		(width 0.508)
		(layer "B.Cu")
		(net "P3V3_STBY")
	)
	(segment
		(start 47.117254 -115.488466)
		(end 47.41545 -115.19027)
		(width 0.508)
		(layer "B.Cu")
		(net "P3V3_STBY")
	)
	(segment
		(start 24.89708 -78.00848)
		(end 24.89708 -78.391004)
		(width 0.508)
		(layer "B.Cu")
		(net "P3V3_STBY")
	)
	(segment
		(start 332.773782 -185.322718)
		(end 332.7654 -185.3311)
		(width 0.508)
		(layer "B.Cu")
		(net "P3V3_STBY")
	)
	(segment
		(start 143.002508 -35.682428)
		(end 142.901162 -35.783774)
		(width 0.508)
		(layer "B.Cu")
		(net "P3V3_STBY")
	)
	(segment
		(start 269.827756 -10.369042)
		(end 269.770352 -10.311638)
		(width 0.508)
		(layer "B.Cu")
		(net "P3V3_STBY")
	)
	(segment
		(start 59.662822 -124.441966)
		(end 59.680856 -124.46)
		(width 0.508)
		(layer "B.Cu")
		(net "P3V3_STBY")
	)
	(segment
		(start 131.0386 -195.2244)
		(end 131.5212 -195.707)
		(width 0.508)
		(layer "B.Cu")
		(net "P3V3_STBY")
	)
	(segment
		(start 23.694644 -133.671564)
		(end 23.694644 -134.687564)
		(width 0.508)
		(layer "B.Cu")
		(net "P3V3_STBY")
	)
	(segment
		(start 329.594718 -171.987718)
		(end 330.740512 -171.987718)
		(width 0.508)
		(layer "B.Cu")
		(net "P3V3_STBY")
	)
	(segment
		(start 60.8965 -123.444)
		(end 60.8965 -122.428)
		(width 0.508)
		(layer "B.Cu")
		(net "P3V3_STBY")
	)
	(segment
		(start 224.040446 -204.14234)
		(end 222.999046 -204.14234)
		(width 0.508)
		(layer "B.Cu")
		(net "P3V3_STBY")
	)
	(segment
		(start 222.154496 -197.994016)
		(end 222.155004 -197.994016)
		(width 0.3048)
		(layer "B.Cu")
		(net "P3V3_STBY")
	)
	(segment
		(start 272.014696 -13.406628)
		(end 272.722848 -13.406628)
		(width 0.508)
		(layer "B.Cu")
		(net "P3V3_STBY")
	)
	(segment
		(start 131.281932 -209.3214)
		(end 130.220466 -209.3214)
		(width 0.508)
		(layer "B.Cu")
		(net "P3V3_STBY")
	)
	(segment
		(start 191.2874 -22.3774)
		(end 190.4492 -23.2156)
		(width 0.508)
		(layer "B.Cu")
		(net "P3V3_STBY")
	)
	(segment
		(start 298.489878 -35.069272)
		(end 298.489624 -35.069526)
		(width 0.508)
		(layer "B.Cu")
		(net "P3V3_STBY")
	)
	(segment
		(start 134.7089 -195.9483)
		(end 133.858 -195.9483)
		(width 0.508)
		(layer "B.Cu")
		(net "P3V3_STBY")
	)
	(segment
		(start 257.7338 -14.064996)
		(end 257.7338 -13.6398)
		(width 0.508)
		(layer "B.Cu")
		(net "P3V3_STBY")
	)
	(segment
		(start 183.6674 -10.7442)
		(end 183.6928 -10.7442)
		(width 0.508)
		(layer "B.Cu")
		(net "P3V3_STBY")
	)
	(segment
		(start 85.98027 -83.29041)
		(end 81.76768 -87.503)
		(width 0.508)
		(layer "B.Cu")
		(net "P3V3_STBY")
	)
	(segment
		(start 58.998612 -122.2248)
		(end 59.662822 -122.88901)
		(width 0.508)
		(layer "B.Cu")
		(net "P3V3_STBY")
	)
	(segment
		(start 131.93776 -200.428352)
		(end 131.843526 -200.334118)
		(width 0.4064)
		(layer "B.Cu")
		(net "P3V3_STBY")
	)
	(segment
		(start 258.342384 -14.629638)
		(end 258.298442 -14.629638)
		(width 0.508)
		(layer "B.Cu")
		(net "P3V3_STBY")
	)
	(segment
		(start 336.3849 -176.1871)
		(end 335.899506 -176.672494)
		(width 0.508)
		(layer "B.Cu")
		(net "P3V3_STBY")
	)
	(segment
		(start 130.81 -200.614534)
		(end 130.81 -201.295)
		(width 0.508)
		(layer "B.Cu")
		(net "P3V3_STBY")
	)
	(segment
		(start 222.6945 -5.9944)
		(end 222.885 -5.9944)
		(width 0.508)
		(layer "B.Cu")
		(net "P3V3_STBY")
	)
	(segment
		(start 59.1058 -25.8953)
		(end 59.0804 -25.9207)
		(width 0.508)
		(layer "B.Cu")
		(net "P3V3_STBY")
	)
	(segment
		(start 57.913778 -31.441898)
		(end 58.159142 -31.441898)
		(width 0.508)
		(layer "B.Cu")
		(net "P3V3_STBY")
	)
	(segment
		(start 61.7728 -129.032)
		(end 61.734192 -129.032)
		(width 0.508)
		(layer "B.Cu")
		(net "P3V3_STBY")
	)
	(segment
		(start 208.333848 -3.598926)
		(end 208.640172 -3.598926)
		(width 0.508)
		(layer "B.Cu")
		(net "P3V3_STBY")
	)
	(segment
		(start 336.591148 -176.253648)
		(end 336.5246 -176.1871)
		(width 0.3048)
		(layer "B.Cu")
		(net "P3V3_STBY")
	)
	(segment
		(start 69.469 -186.9821)
		(end 68.453 -186.9821)
		(width 0.508)
		(layer "B.Cu")
		(net "P3V3_STBY")
	)
	(segment
		(start 135.128 -201.005186)
		(end 135.128 -201.295)
		(width 0.508)
		(layer "B.Cu")
		(net "P3V3_STBY")
	)
	(segment
		(start 336.836512 -171.987718)
		(end 337.852512 -171.987718)
		(width 0.508)
		(layer "B.Cu")
		(net "P3V3_STBY")
	)
	(segment
		(start 225.425 -198.374)
		(end 225.933 -197.866)
		(width 0.508)
		(layer "B.Cu")
		(net "P3V3_STBY")
	)
	(segment
		(start 59.662822 -121.368566)
		(end 60.853066 -121.368566)
		(width 0.508)
		(layer "B.Cu")
		(net "P3V3_STBY")
	)
	(segment
		(start 55.80126 -125.42774)
		(end 55.626 -125.42774)
		(width 0.508)
		(layer "B.Cu")
		(net "P3V3_STBY")
	)
	(segment
		(start 213.932008 -3.6195)
		(end 212.916008 -3.6195)
		(width 0.508)
		(layer "B.Cu")
		(net "P3V3_STBY")
	)
	(segment
		(start 206.4258 -23.0124)
		(end 207.518 -23.0124)
		(width 0.508)
		(layer "B.Cu")
		(net "P3V3_STBY")
	)
	(segment
		(start 23.374096 -134.687564)
		(end 22.925532 -134.239)
		(width 0.508)
		(layer "B.Cu")
		(net "P3V3_STBY")
	)
	(segment
		(start 48.3235 -148.5265)
		(end 47.117 -147.32)
		(width 0.508)
		(layer "B.Cu")
		(net "P3V3_STBY")
	)
	(segment
		(start 308.55793 -35.64509)
		(end 307.1876 -34.27476)
		(width 0.508)
		(layer "B.Cu")
		(net "P3V3_STBY")
	)
	(segment
		(start 218.670124 -190.156592)
		(end 217.654124 -190.156592)
		(width 0.508)
		(layer "B.Cu")
		(net "P3V3_STBY")
	)
	(segment
		(start 131.294124 -209.333592)
		(end 133.326124 -209.333592)
		(width 0.508)
		(layer "B.Cu")
		(net "P3V3_STBY")
	)
	(segment
		(start 125.953012 -209.341974)
		(end 125.961394 -209.333592)
		(width 0.508)
		(layer "B.Cu")
		(net "P3V3_STBY")
	)
	(segment
		(start 308.55793 -36.180522)
		(end 308.55793 -35.64509)
		(width 0.508)
		(layer "B.Cu")
		(net "P3V3_STBY")
	)
	(segment
		(start 267.9573 -9.30021)
		(end 268.74978 -9.30021)
		(width 0.508)
		(layer "B.Cu")
		(net "P3V3_STBY")
	)
	(segment
		(start 81.129124 -195.871592)
		(end 80.95234 -195.871592)
		(width 0.381)
		(layer "B.Cu")
		(net "P3V3_STBY")
	)
	(segment
		(start 18.4912 -68.1736)
		(end 18.3134 -68.3514)
		(width 0.508)
		(layer "B.Cu")
		(net "P3V3_STBY")
	)
	(segment
		(start 331.1779 -182.0545)
		(end 331.1779 -182.047388)
		(width 0.508)
		(layer "B.Cu")
		(net "P3V3_STBY")
	)
	(segment
		(start 46.3042 -103.5939)
		(end 45.0977 -103.5939)
		(width 0.508)
		(layer "B.Cu")
		(net "P3V3_STBY")
	)
	(segment
		(start 266.92225 -15.51686)
		(end 267.05179 -15.6464)
		(width 0.508)
		(layer "B.Cu")
		(net "P3V3_STBY")
	)
	(segment
		(start 22.7076 -70.230746)
		(end 22.7076 -69.74586)
		(width 0.508)
		(layer "B.Cu")
		(net "P3V3_STBY")
	)
	(segment
		(start 135.935212 -200.197974)
		(end 135.128 -201.005186)
		(width 0.508)
		(layer "B.Cu")
		(net "P3V3_STBY")
	)
	(segment
		(start 216.28354 -199.57796)
		(end 215.55964 -199.57796)
		(width 0.508)
		(layer "B.Cu")
		(net "P3V3_STBY")
	)
	(segment
		(start 42.592752 -128.397)
		(end 42.1005 -128.397)
		(width 0.508)
		(layer "B.Cu")
		(net "P3V3_STBY")
	)
	(segment
		(start 221.3737 -14.3383)
		(end 221.3737 -13.3858)
		(width 0.508)
		(layer "B.Cu")
		(net "P3V3_STBY")
	)
	(segment
		(start 205.486 -19.304)
		(end 205.113128 -19.676872)
		(width 0.508)
		(layer "B.Cu")
		(net "P3V3_STBY")
	)
	(segment
		(start 221.996 -195.5038)
		(end 221.996 -196.088)
		(width 0.508)
		(layer "B.Cu")
		(net "P3V3_STBY")
	)
	(segment
		(start 121.2088 -202.4761)
		(end 121.2088 -201.1426)
		(width 0.508)
		(layer "B.Cu")
		(net "P3V3_STBY")
	)
	(segment
		(start 123.444508 -195.998592)
		(end 122.8979 -196.5452)
		(width 0.508)
		(layer "B.Cu")
		(net "P3V3_STBY")
	)
	(segment
		(start 80.518 -187.8584)
		(end 80.5942 -187.7822)
		(width 0.508)
		(layer "B.Cu")
		(net "P3V3_STBY")
	)
	(segment
		(start 129.179066 -209.3214)
		(end 127.115316 -209.3214)
		(width 0.508)
		(layer "B.Cu")
		(net "P3V3_STBY")
	)
	(segment
		(start 213.614 -196.7865)
		(end 214.536274 -196.7865)
		(width 0.4064)
		(layer "B.Cu")
		(net "P3V3_STBY")
	)
	(segment
		(start 222.986092 -194.284092)
		(end 222.986092 -194.513708)
		(width 0.508)
		(layer "B.Cu")
		(net "P3V3_STBY")
	)
	(segment
		(start 55.8292 -125.3998)
		(end 55.80126 -125.42774)
		(width 0.508)
		(layer "B.Cu")
		(net "P3V3_STBY")
	)
	(segment
		(start 22.7076 -70.93839)
		(end 22.6695 -70.90029)
		(width 0.508)
		(layer "B.Cu")
		(net "P3V3_STBY")
	)
	(segment
		(start 221.7674 -6.9215)
		(end 222.6945 -5.9944)
		(width 0.508)
		(layer "B.Cu")
		(net "P3V3_STBY")
	)
	(segment
		(start 206.4766 -27.5336)
		(end 205.994 -27.5336)
		(width 0.508)
		(layer "B.Cu")
		(net "P3V3_STBY")
	)
	(segment
		(start 268.731492 -15.6464)
		(end 269.580868 -16.495776)
		(width 0.508)
		(layer "B.Cu")
		(net "P3V3_STBY")
	)
	(segment
		(start 208.32699 -25.68321)
		(end 206.4766 -27.5336)
		(width 0.508)
		(layer "B.Cu")
		(net "P3V3_STBY")
	)
	(segment
		(start 22.7076 -69.74586)
		(end 22.5425 -69.58076)
		(width 0.508)
		(layer "B.Cu")
		(net "P3V3_STBY")
	)
	(segment
		(start 142.136114 -34.88563)
		(end 143.002508 -34.88563)
		(width 0.508)
		(layer "B.Cu")
		(net "P3V3_STBY")
	)
	(segment
		(start 205.486 -19.304)
		(end 205.486 -22.0726)
		(width 0.508)
		(layer "B.Cu")
		(net "P3V3_STBY")
	)
	(segment
		(start 331.95006 -44.876974)
		(end 334.509872 -47.436786)
		(width 1.016)
		(layer "B.Cu")
		(net "P3V3_STBY")
	)
	(segment
		(start 77.83576 -187.056522)
		(end 77.769212 -186.989974)
		(width 0.4064)
		(layer "B.Cu")
		(net "P3V3_STBY")
	)
	(segment
		(start 16.6624 -137.9728)
		(end 16.903446 -138.213846)
		(width 0.508)
		(layer "B.Cu")
		(net "P3V3_STBY")
	)
	(segment
		(start 74.950066 -196.1134)
		(end 72.886316 -196.1134)
		(width 0.508)
		(layer "B.Cu")
		(net "P3V3_STBY")
	)
	(segment
		(start 72.771 -189.8015)
		(end 72.771 -188.087)
		(width 0.508)
		(layer "B.Cu")
		(net "P3V3_STBY")
	)
	(segment
		(start 202.743308 -30.784292)
		(end 205.74 -27.7876)
		(width 0.508)
		(layer "B.Cu")
		(net "P3V3_STBY")
	)
	(segment
		(start 23.164038 -121.539)
		(end 22.48154 -120.856502)
		(width 0.508)
		(layer "B.Cu")
		(net "P3V3_STBY")
	)
	(segment
		(start 60.0456 -115.7224)
		(end 59.9059 -115.5827)
		(width 0.508)
		(layer "B.Cu")
		(net "P3V3_STBY")
	)
	(segment
		(start 78.293722 -195.579746)
		(end 77.747876 -196.125592)
		(width 0.381)
		(layer "B.Cu")
		(net "P3V3_STBY")
	)
	(segment
		(start 76.708 -187.96)
		(end 76.708 -188.1632)
		(width 0.508)
		(layer "B.Cu")
		(net "P3V3_STBY")
	)
	(segment
		(start 134.62 -202.1205)
		(end 134.62 -201.803)
		(width 0.508)
		(layer "B.Cu")
		(net "P3V3_STBY")
	)
	(segment
		(start 335.820512 -171.987718)
		(end 336.836512 -171.987718)
		(width 0.508)
		(layer "B.Cu")
		(net "P3V3_STBY")
	)
	(segment
		(start 55.835296 -113.531904)
		(end 55.644796 -113.531904)
		(width 0.508)
		(layer "B.Cu")
		(net "P3V3_STBY")
	)
	(segment
		(start 208.640172 -3.598926)
		(end 208.994248 -3.953002)
		(width 0.508)
		(layer "B.Cu")
		(net "P3V3_STBY")
	)
	(segment
		(start 56.107838 -112.225582)
		(end 56.0832 -112.200944)
		(width 0.508)
		(layer "B.Cu")
		(net "P3V3_STBY")
	)
	(segment
		(start 60.8965 -120.396)
		(end 60.9981 -120.2944)
		(width 0.508)
		(layer "B.Cu")
		(net "P3V3_STBY")
	)
	(segment
		(start 225.114104 -204.154532)
		(end 224.052638 -204.154532)
		(width 0.508)
		(layer "B.Cu")
		(net "P3V3_STBY")
	)
	(segment
		(start 76.848716 -182.794402)
		(end 76.948792 -182.694326)
		(width 0.508)
		(layer "B.Cu")
		(net "P3V3_STBY")
	)
	(segment
		(start 54.9402 -138.7729)
		(end 54.9021 -138.811)
		(width 0.508)
		(layer "B.Cu")
		(net "P3V3_STBY")
	)
	(segment
		(start 125.28423 -33.92805)
		(end 125.994668 -33.92805)
		(width 0.508)
		(layer "B.Cu")
		(net "P3V3_STBY")
	)
	(segment
		(start 59.662822 -124.441966)
		(end 59.662822 -123.425966)
		(width 0.508)
		(layer "B.Cu")
		(net "P3V3_STBY")
	)
	(segment
		(start 17.8689 -133.8326)
		(end 17.8689 -132.8166)
		(width 0.508)
		(layer "B.Cu")
		(net "P3V3_STBY")
	)
	(segment
		(start 22.535388 -128.037336)
		(end 23.351998 -128.037336)
		(width 0.508)
		(layer "B.Cu")
		(net "P3V3_STBY")
	)
	(segment
		(start 132.5372 -195.9483)
		(end 132.5626 -195.9229)
		(width 0.508)
		(layer "B.Cu")
		(net "P3V3_STBY")
	)
	(segment
		(start 23.6855 -122.0216)
		(end 23.164038 -121.539)
		(width 0.508)
		(layer "B.Cu")
		(net "P3V3_STBY")
	)
	(segment
		(start 183.4769 -10.5537)
		(end 183.6674 -10.7442)
		(width 0.508)
		(layer "B.Cu")
		(net "P3V3_STBY")
	)
	(segment
		(start 76.454 -188.4172)
		(end 76.708 -188.1632)
		(width 0.508)
		(layer "B.Cu")
		(net "P3V3_STBY")
	)
	(segment
		(start 55.602124 -122.729244)
		(end 56.106568 -122.2248)
		(width 0.508)
		(layer "B.Cu")
		(net "P3V3_STBY")
	)
	(segment
		(start 23.46198 -137.586974)
		(end 23.46198 -138.602974)
		(width 0.508)
		(layer "B.Cu")
		(net "P3V3_STBY")
	)
	(segment
		(start 122.1613 -200.1901)
		(end 122.682 -200.1901)
		(width 0.508)
		(layer "B.Cu")
		(net "P3V3_STBY")
	)
	(segment
		(start 221.606872 -204.14234)
		(end 220.956124 -203.491592)
		(width 0.508)
		(layer "B.Cu")
		(net "P3V3_STBY")
	)
	(segment
		(start 123.928124 -195.998592)
		(end 124.944124 -195.998592)
		(width 0.508)
		(layer "B.Cu")
		(net "P3V3_STBY")
	)
	(segment
		(start 59.662822 -121.368566)
		(end 59.662822 -120.352566)
		(width 0.508)
		(layer "B.Cu")
		(net "P3V3_STBY")
	)
	(segment
		(start 55.007002 -141.200632)
		(end 55.007002 -141.116304)
		(width 0.508)
		(layer "B.Cu")
		(net "P3V3_STBY")
	)
	(segment
		(start 202.006708 -30.784292)
		(end 202.743308 -30.784292)
		(width 0.508)
		(layer "B.Cu")
		(net "P3V3_STBY")
	)
	(segment
		(start 205.486 -22.0726)
		(end 206.4258 -23.0124)
		(width 0.508)
		(layer "B.Cu")
		(net "P3V3_STBY")
	)
	(segment
		(start 125.28423 -33.92805)
		(end 124.3838 -33.92805)
		(width 0.508)
		(layer "B.Cu")
		(net "P3V3_STBY")
	)
	(segment
		(start 336.977228 -47.436786)
		(end 338.135722 -46.278292)
		(width 1.016)
		(layer "B.Cu")
		(net "P3V3_STBY")
	)
	(segment
		(start 22.6695 -70.90029)
		(end 22.6695 -70.268846)
		(width 0.508)
		(layer "B.Cu")
		(net "P3V3_STBY")
	)
	(segment
		(start 257.319272 -7.90194)
		(end 256.78765 -7.370318)
		(width 0.3556)
		(layer "B.Cu")
		(net "P3V3_STBY")
	)
	(segment
		(start 58.159142 -31.441898)
		(end 59.0804 -30.520386)
		(width 0.508)
		(layer "B.Cu")
		(net "P3V3_STBY")
	)
	(segment
		(start 153.396696 -33.985962)
		(end 153.87447 -33.985962)
		(width 0.508)
		(layer "B.Cu")
		(net "P3V3_STBY")
	)
	(segment
		(start 77.016102 -196.174614)
		(end 77.065124 -196.125592)
		(width 0.508)
		(layer "B.Cu")
		(net "P3V3_STBY")
	)
	(segment
		(start 48.641 -148.5265)
		(end 48.3235 -148.5265)
		(width 0.508)
		(layer "B.Cu")
		(net "P3V3_STBY")
	)
	(segment
		(start 12.351512 -74.913236)
		(end 13.062712 -74.913236)
		(width 0.508)
		(layer "B.Cu")
		(net "P3V3_STBY")
	)
	(segment
		(start 225.114104 -204.154532)
		(end 226.516184 -204.154532)
		(width 0.508)
		(layer "B.Cu")
		(net "P3V3_STBY")
	)
	(segment
		(start 56.099456 -112.225582)
		(end 56.107838 -112.225582)
		(width 0.508)
		(layer "B.Cu")
		(net "P3V3_STBY")
	)
	(segment
		(start 335.899506 -176.672494)
		(end 335.899506 -177.232818)
		(width 0.508)
		(layer "B.Cu")
		(net "P3V3_STBY")
	)
	(segment
		(start 72.771 -187.833)
		(end 73.614026 -186.989974)
		(width 0.508)
		(layer "B.Cu")
		(net "P3V3_STBY")
	)
	(segment
		(start 56.0832 -110.599982)
		(end 56.092852 -110.59033)
		(width 0.508)
		(layer "B.Cu")
		(net "P3V3_STBY")
	)
	(segment
		(start 127.115316 -209.3214)
		(end 127.103124 -209.333592)
		(width 0.508)
		(layer "B.Cu")
		(net "P3V3_STBY")
	)
	(segment
		(start 131.791456 -200.386188)
		(end 131.038346 -200.386188)
		(width 0.508)
		(layer "B.Cu")
		(net "P3V3_STBY")
	)
	(segment
		(start 20.5105 -130.683)
		(end 20.5105 -129.667)
		(width 0.508)
		(layer "B.Cu")
		(net "P3V3_STBY")
	)
	(segment
		(start 22.944582 -131.462018)
		(end 22.6568 -131.7498)
		(width 0.508)
		(layer "B.Cu")
		(net "P3V3_STBY")
	)
	(segment
		(start 68.3006 -192.11036)
		(end 68.121022 -191.930782)
		(width 0.508)
		(layer "B.Cu")
		(net "P3V3_STBY")
	)
	(segment
		(start 76.327 -181.765702)
		(end 76.811124 -182.249826)
		(width 0.508)
		(layer "B.Cu")
		(net "P3V3_STBY")
	)
	(segment
		(start 14.732 -85.0138)
		(end 14.7574 -84.9884)
		(width 0.508)
		(layer "B.Cu")
		(net "P3V3_STBY")
	)
	(segment
		(start 81.386426 -186.989974)
		(end 80.5942 -187.7822)
		(width 0.508)
		(layer "B.Cu")
		(net "P3V3_STBY")
	)
	(segment
		(start 77.747876 -196.125592)
		(end 77.065124 -196.125592)
		(width 0.381)
		(layer "B.Cu")
		(net "P3V3_STBY")
	)
	(segment
		(start 188.84646 -28.43276)
		(end 189.5983 -29.1846)
		(width 0.508)
		(layer "B.Cu")
		(net "P3V3_STBY")
	)
	(segment
		(start 124.079 -206.1845)
		(end 123.2662 -206.1845)
		(width 0.508)
		(layer "B.Cu")
		(net "P3V3_STBY")
	)
	(segment
		(start 222.986092 -194.513708)
		(end 221.996 -195.5038)
		(width 0.508)
		(layer "B.Cu")
		(net "P3V3_STBY")
	)
	(segment
		(start 336.591148 -177.982626)
		(end 336.591148 -176.253648)
		(width 0.3048)
		(layer "B.Cu")
		(net "P3V3_STBY")
	)
	(segment
		(start 219.18676 -194.549522)
		(end 219.120212 -194.482974)
		(width 0.4064)
		(layer "B.Cu")
		(net "P3V3_STBY")
	)
	(segment
		(start 208.026 -23.5204)
		(end 208.026 -24.6634)
		(width 0.508)
		(layer "B.Cu")
		(net "P3V3_STBY")
	)
	(segment
		(start 72.39 -190.1825)
		(end 72.771 -189.8015)
		(width 0.508)
		(layer "B.Cu")
		(net "P3V3_STBY")
	)
	(segment
		(start 273.667728 -14.351508)
		(end 273.667728 -16.31315)
		(width 0.508)
		(layer "B.Cu")
		(net "P3V3_STBY")
	)
	(segment
		(start 126.492 -203.3905)
		(end 126.492 -201.676)
		(width 0.508)
		(layer "B.Cu")
		(net "P3V3_STBY")
	)
	(segment
		(start 82.145124 -195.871592)
		(end 81.129124 -195.871592)
		(width 0.381)
		(layer "B.Cu")
		(net "P3V3_STBY")
	)
	(segment
		(start 60.024518 -119.320818)
		(end 60.9981 -120.2944)
		(width 0.508)
		(layer "B.Cu")
		(net "P3V3_STBY")
	)
	(segment
		(start 269.761208 -10.311638)
		(end 269.770352 -10.311638)
		(width 0.508)
		(layer "B.Cu")
		(net "P3V3_STBY")
	)
	(segment
		(start 226.516184 -204.154532)
		(end 227.179124 -203.491592)
		(width 0.508)
		(layer "B.Cu")
		(net "P3V3_STBY")
	)
	(segment
		(start 74.808334 -182.794402)
		(end 75.832716 -182.794402)
		(width 0.508)
		(layer "B.Cu")
		(net "P3V3_STBY")
	)
	(segment
		(start 215.052148 -194.687952)
		(end 215.052148 -196.270626)
		(width 0.4064)
		(layer "B.Cu")
		(net "P3V3_STBY")
	)
	(segment
		(start 218.670124 -190.156592)
		(end 219.686124 -190.156592)
		(width 0.508)
		(layer "B.Cu")
		(net "P3V3_STBY")
	)
	(segment
		(start 340.782148 -176.253648)
		(end 340.7156 -176.1871)
		(width 0.4064)
		(layer "B.Cu")
		(net "P3V3_STBY")
	)
	(segment
		(start 55.644796 -113.531904)
		(end 55.3339 -113.8428)
		(width 0.508)
		(layer "B.Cu")
		(net "P3V3_STBY")
	)
	(segment
		(start 47.117254 -116.268246)
		(end 47.117254 -115.488466)
		(width 0.508)
		(layer "B.Cu")
		(net "P3V3_STBY")
	)
	(segment
		(start 219.18676 -196.1515)
		(end 219.18676 -194.549522)
		(width 0.4064)
		(layer "B.Cu")
		(net "P3V3_STBY")
	)
	(segment
		(start 208.32699 -24.96439)
		(end 208.32699 -25.68321)
		(width 0.508)
		(layer "B.Cu")
		(net "P3V3_STBY")
	)
	(segment
		(start 334.509872 -47.436786)
		(end 336.977228 -47.436786)
		(width 1.016)
		(layer "B.Cu")
		(net "P3V3_STBY")
	)
	(segment
		(start 42.48658 -131.28498)
		(end 42.904664 -131.28498)
		(width 0.508)
		(layer "B.Cu")
		(net "P3V3_STBY")
	)
	(segment
		(start 121.210324 -208.444592)
		(end 122.107706 -209.341974)
		(width 0.508)
		(layer "B.Cu")
		(net "P3V3_STBY")
	)
	(segment
		(start 127.807212 -200.197974)
		(end 127.335026 -200.197974)
		(width 0.508)
		(layer "B.Cu")
		(net "P3V3_STBY")
	)
	(segment
		(start 38.840664 -126.488444)
		(end 38.904672 -126.424436)
		(width 0.508)
		(layer "B.Cu")
		(net "P3V3_STBY")
	)
	(segment
		(start 127.87376 -201.9935)
		(end 127.87376 -200.264522)
		(width 0.4064)
		(layer "B.Cu")
		(net "P3V3_STBY")
	)
	(segment
		(start 131.294124 -209.333592)
		(end 131.281932 -209.3214)
		(width 0.508)
		(layer "B.Cu")
		(net "P3V3_STBY")
	)
	(segment
		(start 121.2088 -201.1426)
		(end 122.1613 -200.1901)
		(width 0.508)
		(layer "B.Cu")
		(net "P3V3_STBY")
	)
	(segment
		(start 122.107706 -209.341974)
		(end 125.953012 -209.341974)
		(width 0.508)
		(layer "B.Cu")
		(net "P3V3_STBY")
	)
	(segment
		(start 222.74276 -196.1515)
		(end 222.0595 -196.1515)
		(width 0.4064)
		(layer "B.Cu")
		(net "P3V3_STBY")
	)
	(segment
		(start 131.0386 -195.1482)
		(end 131.0386 -195.2244)
		(width 0.508)
		(layer "B.Cu")
		(net "P3V3_STBY")
	)
	(segment
		(start 34.803588 -128.388618)
		(end 34.40811 -128.388618)
		(width 0.508)
		(layer "B.Cu")
		(net "P3V3_STBY")
	)
	(segment
		(start 267.05179 -15.6464)
		(end 268.731492 -15.6464)
		(width 0.508)
		(layer "B.Cu")
		(net "P3V3_STBY")
	)
	(segment
		(start 331.756512 -171.987718)
		(end 330.740512 -171.987718)
		(width 0.508)
		(layer "B.Cu")
		(net "P3V3_STBY")
	)
	(segment
		(start 214.536274 -196.7865)
		(end 215.052148 -196.270626)
		(width 0.4064)
		(layer "B.Cu")
		(net "P3V3_STBY")
	)
	(segment
		(start 314.276232 -38.176962)
		(end 315.140086 -38.176962)
		(width 0.508)
		(layer "B.Cu")
		(net "P3V3_STBY")
	)
	(segment
		(start 326.206104 -37.94125)
		(end 331.95006 -43.685206)
		(width 1.016)
		(layer "B.Cu")
		(net "P3V3_STBY")
	)
	(segment
		(start 17.4244 -138.6078)
		(end 17.9197 -138.6078)
		(width 0.508)
		(layer "B.Cu")
		(net "P3V3_STBY")
	)
	(segment
		(start 213.932008 -3.6195)
		(end 214.948008 -3.6195)
		(width 0.508)
		(layer "B.Cu")
		(net "P3V3_STBY")
	)
	(segment
		(start 299.353732 -35.069272)
		(end 298.489878 -35.069272)
		(width 0.508)
		(layer "B.Cu")
		(net "P3V3_STBY")
	)
	(segment
		(start 221.3737 -12.573)
		(end 221.75724 -12.18946)
		(width 0.4064)
		(layer "B.Cu")
		(net "P3V3_STBY")
	)
	(segment
		(start 49.1998 -112.7125)
		(end 49.1744 -112.6871)
		(width 0.508)
		(layer "B.Cu")
		(net "P3V3_STBY")
	)
	(segment
		(start 76.948792 -182.694326)
		(end 78.746858 -182.694326)
		(width 0.508)
		(layer "B.Cu")
		(net "P3V3_STBY")
	)
	(segment
		(start 331.216 -22.987)
		(end 331.216 -17.145)
		(width 0.508)
		(layer "B.Cu")
		(net "P3V3_STBY")
	)
	(segment
		(start 17.8689 -132.8166)
		(end 17.9705 -132.715)
		(width 0.508)
		(layer "B.Cu")
		(net "P3V3_STBY")
	)
	(segment
		(start 349.690436 -46.29023)
		(end 350.183196 -46.78299)
		(width 0.4064)
		(layer "B.Cu")
		(net "P3V3_STBY")
	)
	(segment
		(start 331.211682 -6.269482)
		(end 331.211682 -5.609082)
		(width 0.508)
		(layer "B.Cu")
		(net "P3V3_STBY")
	)
	(segment
		(start 23.694644 -134.687564)
		(end 23.374096 -134.687564)
		(width 0.508)
		(layer "B.Cu")
		(net "P3V3_STBY")
	)
	(segment
		(start 130.556 -202.1205)
		(end 130.556 -201.549)
		(width 0.508)
		(layer "B.Cu")
		(net "P3V3_STBY")
	)
	(segment
		(start 74.950066 -196.1134)
		(end 75.01128 -196.174614)
		(width 0.508)
		(layer "B.Cu")
		(net "P3V3_STBY")
	)
	(segment
		(start 23.351998 -128.037336)
		(end 23.351998 -127.021336)
		(width 0.508)
		(layer "B.Cu")
		(net "P3V3_STBY")
	)
	(segment
		(start 218.0844 -193.9544)
		(end 217.964004 -193.9544)
		(width 0.508)
		(layer "B.Cu")
		(net "P3V3_STBY")
	)
	(segment
		(start 63.49873 -25.960832)
		(end 60.212732 -25.960832)
		(width 0.508)
		(layer "B.Cu")
		(net "P3V3_STBY")
	)
	(segment
		(start 333.915512 -185.322718)
		(end 332.773782 -185.322718)
		(width 0.508)
		(layer "B.Cu")
		(net "P3V3_STBY")
	)
	(segment
		(start 47.0535 -114.82832)
		(end 47.41545 -115.19027)
		(width 0.508)
		(layer "B.Cu")
		(net "P3V3_STBY")
	)
	(segment
		(start 89.28481 -83.29041)
		(end 85.98027 -83.29041)
		(width 0.508)
		(layer "B.Cu")
		(net "P3V3_STBY")
	)
	(segment
		(start 16.903446 -138.213846)
		(end 17.030446 -138.213846)
		(width 0.508)
		(layer "B.Cu")
		(net "P3V3_STBY")
	)
	(segment
		(start 296.724578 -36.044378)
		(end 297.2816 -36.6014)
		(width 0.508)
		(layer "B.Cu")
		(net "P3V3_STBY")
	)
	(segment
		(start 75.987656 -196.174614)
		(end 77.016102 -196.174614)
		(width 0.508)
		(layer "B.Cu")
		(net "P3V3_STBY")
	)
	(segment
		(start 221.75724 -12.18946)
		(end 221.75724 -11.1379)
		(width 0.4064)
		(layer "B.Cu")
		(net "P3V3_STBY")
	)
	(segment
		(start 270.63065 -10.369042)
		(end 269.827756 -10.369042)
		(width 0.508)
		(layer "B.Cu")
		(net "P3V3_STBY")
	)
	(segment
		(start 54.1655 -137.795)
		(end 54.1655 -136.779)
		(width 0.508)
		(layer "B.Cu")
		(net "P3V3_STBY")
	)
	(segment
		(start 47.117 -147.32)
		(end 47.117 -146.6342)
		(width 0.508)
		(layer "B.Cu")
		(net "P3V3_STBY")
	)
	(segment
		(start 337.852512 -171.987718)
		(end 339.884512 -171.987718)
		(width 0.508)
		(layer "B.Cu")
		(net "P3V3_STBY")
	)
	(segment
		(start 330.708 -177.927)
		(end 331.343 -177.292)
		(width 0.508)
		(layer "B.Cu")
		(net "P3V3_STBY")
	)
	(segment
		(start 298.489624 -35.069526)
		(end 298.229274 -35.069526)
		(width 0.508)
		(layer "B.Cu")
		(net "P3V3_STBY")
	)
	(segment
		(start 55.101236 -124.902976)
		(end 54.229 -124.902976)
		(width 0.508)
		(layer "B.Cu")
		(net "P3V3_STBY")
	)
	(segment
		(start 152.528778 -33.989772)
		(end 152.532588 -33.985962)
		(width 0.508)
		(layer "B.Cu")
		(net "P3V3_STBY")
	)
	(segment
		(start 269.217648 -19.628104)
		(end 268.543786 -19.628104)
		(width 0.508)
		(layer "B.Cu")
		(net "P3V3_STBY")
	)
	(segment
		(start 340.782148 -177.982626)
		(end 340.782148 -176.253648)
		(width 0.4064)
		(layer "B.Cu")
		(net "P3V3_STBY")
	)
	(segment
		(start 58.166 -131.6355)
		(end 58.3057 -131.4958)
		(width 0.508)
		(layer "B.Cu")
		(net "P3V3_STBY")
	)
	(segment
		(start 134.62 -201.803)
		(end 135.128 -201.295)
		(width 0.508)
		(layer "B.Cu")
		(net "P3V3_STBY")
	)
	(segment
		(start 23.497286 -131.462018)
		(end 22.944582 -131.462018)
		(width 0.508)
		(layer "B.Cu")
		(net "P3V3_STBY")
	)
	(segment
		(start 39.842948 -126.558294)
		(end 40.504618 -125.896624)
		(width 0.508)
		(layer "B.Cu")
		(net "P3V3_STBY")
	)
	(segment
		(start 331.43444 -11.39444)
		(end 331.216 -11.176)
		(width 0.508)
		(layer "B.Cu")
		(net "P3V3_STBY")
	)
	(segment
		(start 297.591988 -35.503612)
		(end 296.725086 -35.503612)
		(width 0.508)
		(layer "B.Cu")
		(net "P3V3_STBY")
	)
	(segment
		(start 22.5425 -69.58076)
		(end 21.6916 -68.72986)
		(width 0.508)
		(layer "B.Cu")
		(net "P3V3_STBY")
	)
	(segment
		(start 12.169648 -74.91476)
		(end 12.349988 -74.91476)
		(width 0.508)
		(layer "B.Cu")
		(net "P3V3_STBY")
	)
	(segment
		(start 73.614026 -186.989974)
		(end 73.705212 -186.989974)
		(width 0.508)
		(layer "B.Cu")
		(net "P3V3_STBY")
	)
	(segment
		(start 51.2572 -112.7125)
		(end 51.9049 -112.7125)
		(width 0.508)
		(layer "B.Cu")
		(net "P3V3_STBY")
	)
	(segment
		(start 77.769212 -186.989974)
		(end 77.678026 -186.989974)
		(width 0.508)
		(layer "B.Cu")
		(net "P3V3_STBY")
	)
	(segment
		(start 54.1655 -138.811)
		(end 54.1655 -137.795)
		(width 0.508)
		(layer "B.Cu")
		(net "P3V3_STBY")
	)
	(segment
		(start 210.707224 -3.442716)
		(end 210.884008 -3.6195)
		(width 0.508)
		(layer "B.Cu")
		(net "P3V3_STBY")
	)
	(segment
		(start 297.795188 -35.503612)
		(end 297.591988 -35.503612)
		(width 0.508)
		(layer "B.Cu")
		(net "P3V3_STBY")
	)
	(segment
		(start 63.5508 -127.6223)
		(end 63.754 -127.4191)
		(width 0.508)
		(layer "B.Cu")
		(net "P3V3_STBY")
	)
	(segment
		(start 270.64335 -13.277342)
		(end 271.88541 -13.277342)
		(width 0.508)
		(layer "B.Cu")
		(net "P3V3_STBY")
	)
	(segment
		(start 23.46198 -138.602974)
		(end 23.012908 -138.602974)
		(width 0.508)
		(layer "B.Cu")
		(net "P3V3_STBY")
	)
	(segment
		(start 217.8177 -197.6755)
		(end 218.353894 -197.139306)
		(width 0.4064)
		(layer "B.Cu")
		(net "P3V3_STBY")
	)
	(segment
		(start 51.9049 -112.7125)
		(end 52.1208 -112.4966)
		(width 0.508)
		(layer "B.Cu")
		(net "P3V3_STBY")
	)
	(segment
		(start 256.455164 -8.94461)
		(end 256.455164 -7.702804)
		(width 0.508)
		(layer "B.Cu")
		(net "P3V3_STBY")
	)
	(segment
		(start 205.994 -27.5336)
		(end 205.74 -27.7876)
		(width 0.508)
		(layer "B.Cu")
		(net "P3V3_STBY")
	)
	(segment
		(start 42.2656 -131.064)
		(end 42.48658 -131.28498)
		(width 0.508)
		(layer "B.Cu")
		(net "P3V3_STBY")
	)
	(segment
		(start 331.216 -17.145)
		(end 331.43444 -16.92656)
		(width 0.508)
		(layer "B.Cu")
		(net "P3V3_STBY")
	)
	(segment
		(start 13.6144 -126.8095)
		(end 14.6558 -126.8095)
		(width 0.508)
		(layer "B.Cu")
		(net "P3V3_STBY")
	)
	(segment
		(start 69.383148 -187.067952)
		(end 69.383148 -188.777626)
		(width 0.4064)
		(layer "B.Cu")
		(net "P3V3_STBY")
	)
	(segment
		(start 60.8965 -122.428)
		(end 60.8965 -121.412)
		(width 0.508)
		(layer "B.Cu")
		(net "P3V3_STBY")
	)
	(segment
		(start 268.74978 -9.30021)
		(end 269.761208 -10.311638)
		(width 0.508)
		(layer "B.Cu")
		(net "P3V3_STBY")
	)
	(segment
		(start 336.710782 -185.322718)
		(end 336.677 -185.3565)
		(width 0.508)
		(layer "B.Cu")
		(net "P3V3_STBY")
	)
	(segment
		(start 14.6558 -126.8095)
		(end 14.6558 -126.873254)
		(width 0.508)
		(layer "B.Cu")
		(net "P3V3_STBY")
	)
	(segment
		(start 225.425 -198.4375)
		(end 225.425 -198.374)
		(width 0.508)
		(layer "B.Cu")
		(net "P3V3_STBY")
	)
	(segment
		(start 73.77176 -188.7855)
		(end 73.77176 -187.147708)
		(width 0.4064)
		(layer "B.Cu")
		(net "P3V3_STBY")
	)
	(segment
		(start 269.580868 -19.264884)
		(end 269.217648 -19.628104)
		(width 0.508)
		(layer "B.Cu")
		(net "P3V3_STBY")
	)
	(segment
		(start 60.1472 -25.8953)
		(end 59.1058 -25.8953)
		(width 0.508)
		(layer "B.Cu")
		(net "P3V3_STBY")
	)
	(segment
		(start 332.146148 -177.855626)
		(end 332.146148 -176.253648)
		(width 0.3556)
		(layer "B.Cu")
		(net "P3V3_STBY")
	)
	(segment
		(start 47.117 -116.2685)
		(end 47.117254 -116.268246)
		(width 0.508)
		(layer "B.Cu")
		(net "P3V3_STBY")
	)
	(segment
		(start 190.627 -23.3934)
		(end 190.627 -25.3238)
		(width 0.508)
		(layer "B.Cu")
		(net "P3V3_STBY")
	)
	(segment
		(start 20.5105 -131.699)
		(end 20.5105 -130.683)
		(width 0.508)
		(layer "B.Cu")
		(net "P3V3_STBY")
	)
	(segment
		(start 225.933 -197.866)
		(end 225.933 -195.58)
		(width 0.508)
		(layer "B.Cu")
		(net "P3V3_STBY")
	)
	(segment
		(start 19.6723 -121.5644)
		(end 19.6723 -122.4407)
		(width 0.508)
		(layer "B.Cu")
		(net "P3V3_STBY")
	)
	(segment
		(start 226.80676 -196.1515)
		(end 226.80676 -194.422522)
		(width 0.3048)
		(layer "B.Cu")
		(net "P3V3_STBY")
	)
	(segment
		(start 58.565288 -116.551202)
		(end 58.565288 -115.602512)
		(width 0.508)
		(layer "B.Cu")
		(net "P3V3_STBY")
	)
	(segment
		(start 56.0832 -113.284)
		(end 56.0832 -112.241838)
		(width 0.508)
		(layer "B.Cu")
		(net "P3V3_STBY")
	)
	(segment
		(start 189.5983 -29.1846)
		(end 191.7192 -29.1846)
		(width 0.508)
		(layer "B.Cu")
		(net "P3V3_STBY")
	)
	(segment
		(start 136.00176 -200.264522)
		(end 135.935212 -200.197974)
		(width 0.4064)
		(layer "B.Cu")
		(net "P3V3_STBY")
	)
	(segment
		(start 76.454 -189.0395)
		(end 76.454 -188.4172)
		(width 0.508)
		(layer "B.Cu")
		(net "P3V3_STBY")
	)
	(segment
		(start 216.63533 -190.156592)
		(end 217.654124 -190.156592)
		(width 0.508)
		(layer "B.Cu")
		(net "P3V3_STBY")
	)
	(segment
		(start 221.0816 -199.066912)
		(end 222.154496 -197.994016)
		(width 0.3048)
		(layer "B.Cu")
		(net "P3V3_STBY")
	)
	(segment
		(start 77.678026 -186.989974)
		(end 76.708 -187.96)
		(width 0.508)
		(layer "B.Cu")
		(net "P3V3_STBY")
	)
	(segment
		(start 332.0796 -176.1871)
		(end 331.343 -176.9237)
		(width 0.508)
		(layer "B.Cu")
		(net "P3V3_STBY")
	)
	(segment
		(start 208.026 -24.6634)
		(end 208.32699 -24.96439)
		(width 0.508)
		(layer "B.Cu")
		(net "P3V3_STBY")
	)
	(segment
		(start 131.038346 -200.386188)
		(end 130.81 -200.614534)
		(width 0.508)
		(layer "B.Cu")
		(net "P3V3_STBY")
	)
	(segment
		(start 60.8965 -121.412)
		(end 60.8965 -120.396)
		(width 0.508)
		(layer "B.Cu")
		(net "P3V3_STBY")
	)
	(segment
		(start 351.063052 -46.81093)
		(end 351.063052 -46.768766)
		(width 0.4064)
		(layer "B.Cu")
		(net "P3V3_STBY")
	)
	(segment
		(start 18.6436 -131.7244)
		(end 17.9705 -132.3975)
		(width 0.508)
		(layer "B.Cu")
		(net "P3V3_STBY")
	)
	(segment
		(start 81.6102 -76.581)
		(end 81.6102 -75.9079)
		(width 0.508)
		(layer "B.Cu")
		(net "P3V3_STBY")
	)
	(segment
		(start 81.89976 -187.056522)
		(end 81.833212 -186.989974)
		(width 0.4064)
		(layer "B.Cu")
		(net "P3V3_STBY")
	)
	(segment
		(start 207.518 -23.0124)
		(end 208.026 -23.5204)
		(width 0.508)
		(layer "B.Cu")
		(net "P3V3_STBY")
	)
	(segment
		(start 190.4492 -23.2156)
		(end 190.627 -23.3934)
		(width 0.508)
		(layer "B.Cu")
		(net "P3V3_STBY")
	)
	(segment
		(start 48.0695 -112.5982)
		(end 48.1584 -112.6871)
		(width 0.508)
		(layer "B.Cu")
		(net "P3V3_STBY")
	)
	(segment
		(start 219.686124 -190.156592)
		(end 220.702124 -190.156592)
		(width 0.508)
		(layer "B.Cu")
		(net "P3V3_STBY")
	)
	(segment
		(start 188.84646 -28.43276)
		(end 188.84646 -27.99334)
		(width 0.508)
		(layer "B.Cu")
		(net "P3V3_STBY")
	)
	(segment
		(start 226.925124 -189.256924)
		(end 226.9236 -189.2554)
		(width 0.508)
		(layer "B.Cu")
		(net "P3V3_STBY")
	)
	(segment
		(start 258.298442 -14.629638)
		(end 257.7338 -14.064996)
		(width 0.508)
		(layer "B.Cu")
		(net "P3V3_STBY")
	)
	(segment
		(start 123.698 -200.1901)
		(end 122.682 -200.1901)
		(width 0.508)
		(layer "B.Cu")
		(net "P3V3_STBY")
	)
	(segment
		(start 47.0535 -112.5982)
		(end 47.0535 -114.82832)
		(width 0.508)
		(layer "B.Cu")
		(net "P3V3_STBY")
	)
	(segment
		(start 75.6285 -146.939)
		(end 75.6285 -148.082)
		(width 0.508)
		(layer "B.Cu")
		(net "P3V3_STBY")
	)
	(segment
		(start 271.88541 -13.277342)
		(end 272.014696 -13.406628)
		(width 0.508)
		(layer "B.Cu")
		(net "P3V3_STBY")
	)
	(segment
		(start 23.012908 -138.602974)
		(end 22.403816 -137.993882)
		(width 0.508)
		(layer "B.Cu")
		(net "P3V3_STBY")
	)
	(segment
		(start 141.0335 -34.929572)
		(end 141.02842 -34.934652)
		(width 0.508)
		(layer "B.Cu")
		(net "P3V3_STBY")
	)
	(segment
		(start 339.344 -178.2445)
		(end 339.344 -177.673)
		(width 0.508)
		(layer "B.Cu")
		(net "P3V3_STBY")
	)
	(segment
		(start 209.504534 -3.442716)
		(end 208.994248 -3.953002)
		(width 0.508)
		(layer "B.Cu")
		(net "P3V3_STBY")
	)
	(segment
		(start 226.0346 -195.048886)
		(end 226.0346 -195.4784)
		(width 0.508)
		(layer "B.Cu")
		(net "P3V3_STBY")
	)
	(segment
		(start 217.05824 -198.23684)
		(end 217.05824 -198.80326)
		(width 0.4572)
		(layer "B.Cu")
		(net "P3V3_STBY")
	)
	(segment
		(start 212.916008 -3.6195)
		(end 211.900008 -3.6195)
		(width 0.508)
		(layer "B.Cu")
		(net "P3V3_STBY")
	)
	(segment
		(start 59.662822 -122.88901)
		(end 59.662822 -123.425966)
		(width 0.508)
		(layer "B.Cu")
		(net "P3V3_STBY")
	)
	(segment
		(start 131.93776 -201.9935)
		(end 131.93776 -200.428352)
		(width 0.4064)
		(layer "B.Cu")
		(net "P3V3_STBY")
	)
	(segment
		(start 257.830066 -7.90194)
		(end 257.319272 -7.90194)
		(width 0.3556)
		(layer "B.Cu")
		(net "P3V3_STBY")
	)
	(segment
		(start 131.5212 -195.707)
		(end 131.5212 -195.9483)
		(width 0.508)
		(layer "B.Cu")
		(net "P3V3_STBY")
	)
	(segment
		(start 42.1005 -128.397)
		(end 42.1005 -129.286)
		(width 0.508)
		(layer "B.Cu")
		(net "P3V3_STBY")
	)
	(segment
		(start 66.847974 -196.133974)
		(end 71.724012 -196.133974)
		(width 0.508)
		(layer "B.Cu")
		(net "P3V3_STBY")
	)
	(segment
		(start 221.996 -196.690488)
		(end 221.996 -196.088)
		(width 0.3048)
		(layer "B.Cu")
		(net "P3V3_STBY")
	)
	(segment
		(start 128.869694 -33.948116)
		(end 127.972058 -33.948116)
		(width 0.508)
		(layer "B.Cu")
		(net "P3V3_STBY")
	)
	(segment
		(start 72.771 -188.087)
		(end 72.771 -187.833)
		(width 0.508)
		(layer "B.Cu")
		(net "P3V3_STBY")
	)
	(segment
		(start 218.612974 -194.482974)
		(end 218.0844 -193.9544)
		(width 0.508)
		(layer "B.Cu")
		(net "P3V3_STBY")
	)
	(segment
		(start 296.724578 -35.503104)
		(end 296.724578 -36.044378)
		(width 0.508)
		(layer "B.Cu")
		(net "P3V3_STBY")
	)
	(segment
		(start 69.469 -186.9821)
		(end 69.383148 -187.067952)
		(width 0.4064)
		(layer "B.Cu")
		(net "P3V3_STBY")
	)
	(segment
		(start 191.9478 -20.0914)
		(end 191.2874 -20.7518)
		(width 0.508)
		(layer "B.Cu")
		(net "P3V3_STBY")
	)
	(segment
		(start 37.32784 -126.51232)
		(end 37.32784 -125.708156)
		(width 0.508)
		(layer "B.Cu")
		(net "P3V3_STBY")
	)
	(segment
		(start 265.0363 -9.30021)
		(end 264.814812 -9.078722)
		(width 0.508)
		(layer "B.Cu")
		(net "P3V3_STBY")
	)
	(segment
		(start 40.259 -134.239508)
		(end 40.504618 -134.485126)
		(width 0.508)
		(layer "B.Cu")
		(net "P3V3_STBY")
	)
	(segment
		(start 151.649176 -33.989772)
		(end 150.783544 -33.989772)
		(width 0.508)
		(layer "B.Cu")
		(net "P3V3_STBY")
	)
	(segment
		(start 68.3895 -192.786)
		(end 68.3006 -192.6971)
		(width 0.508)
		(layer "B.Cu")
		(net "P3V3_STBY")
	)
	(segment
		(start 56.0832 -112.200944)
		(end 56.0832 -110.599982)
		(width 0.508)
		(layer "B.Cu")
		(net "P3V3_STBY")
	)
	(segment
		(start 315.625734 -38.66261)
		(end 315.625734 -39.03726)
		(width 0.508)
		(layer "B.Cu")
		(net "P3V3_STBY")
	)
	(segment
		(start 19.2024 -131.7244)
		(end 18.6436 -131.7244)
		(width 0.508)
		(layer "B.Cu")
		(net "P3V3_STBY")
	)
	(segment
		(start 59.680856 -124.46)
		(end 60.8965 -124.46)
		(width 0.508)
		(layer "B.Cu")
		(net "P3V3_STBY")
	)
	(segment
		(start 307.1876 -34.27476)
		(end 306.76723 -34.27476)
		(width 0.508)
		(layer "B.Cu")
		(net "P3V3_STBY")
	)
	(segment
		(start 133.326124 -209.333592)
		(end 134.342124 -209.333592)
		(width 0.508)
		(layer "B.Cu")
		(net "P3V3_STBY")
	)
	(segment
		(start 328.022712 -184.433718)
		(end 328.920094 -185.3311)
		(width 0.508)
		(layer "B.Cu")
		(net "P3V3_STBY")
	)
	(segment
		(start 222.155004 -196.849492)
		(end 221.996 -196.690488)
		(width 0.3048)
		(layer "B.Cu")
		(net "P3V3_STBY")
	)
	(segment
		(start 221.0816 -199.5551)
		(end 221.0816 -199.066912)
		(width 0.3048)
		(layer "B.Cu")
		(net "P3V3_STBY")
	)
	(segment
		(start 19.2278 -131.699)
		(end 19.2024 -131.7244)
		(width 0.508)
		(layer "B.Cu")
		(net "P3V3_STBY")
	)
	(segment
		(start 128.996694 -34.075116)
		(end 128.869694 -33.948116)
		(width 0.508)
		(layer "B.Cu")
		(net "P3V3_STBY")
	)
	(segment
		(start 40.504618 -125.896624)
		(end 40.504618 -125.685042)
		(width 0.508)
		(layer "B.Cu")
		(net "P3V3_STBY")
	)
	(segment
		(start 338.868512 -185.322718)
		(end 336.710782 -185.322718)
		(width 0.508)
		(layer "B.Cu")
		(net "P3V3_STBY")
	)
	(segment
		(start 71.724012 -196.133974)
		(end 71.732394 -196.125592)
		(width 0.508)
		(layer "B.Cu")
		(net "P3V3_STBY")
	)
	(segment
		(start 152.532588 -33.985962)
		(end 153.396696 -33.985962)
		(width 0.508)
		(layer "B.Cu")
		(net "P3V3_STBY")
	)
	(segment
		(start 69.469508 -182.790592)
		(end 69.699124 -182.790592)
		(width 0.508)
		(layer "B.Cu")
		(net "P3V3_STBY")
	)
	(segment
		(start 126.746 -200.787)
		(end 126.746 -201.422)
		(width 0.508)
		(layer "B.Cu")
		(net "P3V3_STBY")
	)
	(segment
		(start 190.627 -25.3238)
		(end 191.4398 -26.1366)
		(width 0.508)
		(layer "B.Cu")
		(net "P3V3_STBY")
	)
	(segment
		(start 123.612148 -200.275952)
		(end 123.612148 -201.985626)
		(width 0.4064)
		(layer "B.Cu")
		(net "P3V3_STBY")
	)
	(segment
		(start 20.5105 -127.635)
		(end 19.7358 -127.635)
		(width 0.508)
		(layer "B.Cu")
		(net "P3V3_STBY")
	)
	(segment
		(start 17.9705 -132.3975)
		(end 17.9705 -132.715)
		(width 0.508)
		(layer "B.Cu")
		(net "P3V3_STBY")
	)
	(segment
		(start 80.95234 -195.871592)
		(end 80.660494 -195.579746)
		(width 0.381)
		(layer "B.Cu")
		(net "P3V3_STBY")
	)
	(segment
		(start 75.6285 -150.5585)
		(end 75.6285 -149.479)
		(width 0.508)
		(layer "B.Cu")
		(net "P3V3_STBY")
	)
	(segment
		(start 34.168334 -131.34848)
		(end 34.10458 -131.284726)
		(width 0.508)
		(layer "B.Cu")
		(net "P3V3_STBY")
	)
	(segment
		(start 72.886316 -196.1134)
		(end 72.874124 -196.125592)
		(width 0.508)
		(layer "B.Cu")
		(net "P3V3_STBY")
	)
	(segment
		(start 191.7192 -29.1846)
		(end 192.2526 -28.6512)
		(width 0.508)
		(layer "B.Cu")
		(net "P3V3_STBY")
	)
	(segment
		(start 226.8474 -9.6901)
		(end 228.6635 -9.6901)
		(width 0.508)
		(layer "B.Cu")
		(net "P3V3_STBY")
	)
	(segment
		(start 219.814394 -203.491592)
		(end 220.956124 -203.491592)
		(width 0.508)
		(layer "B.Cu")
		(net "P3V3_STBY")
	)
	(segment
		(start 81.833212 -186.989974)
		(end 81.386426 -186.989974)
		(width 0.508)
		(layer "B.Cu")
		(net "P3V3_STBY")
	)
	(segment
		(start 324.737476 -37.94125)
		(end 326.206104 -37.94125)
		(width 1.016)
		(layer "B.Cu")
		(net "P3V3_STBY")
	)
	(segment
		(start 208.994248 -3.953002)
		(end 208.994248 -5.11937)
		(width 0.508)
		(layer "B.Cu")
		(net "P3V3_STBY")
	)
	(segment
		(start 21.6916 -68.72986)
		(end 21.6916 -68.1736)
		(width 0.508)
		(layer "B.Cu")
		(net "P3V3_STBY")
	)
	(segment
		(start 84.8868 -76.0984)
		(end 83.9216 -77.0636)
		(width 0.508)
		(layer "B.Cu")
		(net "P3V3_STBY")
	)
	(segment
		(start 272.722848 -13.406628)
		(end 273.667728 -14.351508)
		(width 0.508)
		(layer "B.Cu")
		(net "P3V3_STBY")
	)
	(segment
		(start 70.715124 -182.790592)
		(end 71.731124 -182.790592)
		(width 0.508)
		(layer "B.Cu")
		(net "P3V3_STBY")
	)
	(segment
		(start 20.5105 -127.635)
		(end 20.5105 -128.651)
		(width 0.508)
		(layer "B.Cu")
		(net "P3V3_STBY")
	)
	(segment
		(start 225.883724 -190.156592)
		(end 226.925124 -190.156592)
		(width 0.508)
		(layer "B.Cu")
		(net "P3V3_STBY")
	)
	(segment
		(start 330.708 -178.6255)
		(end 330.708 -177.927)
		(width 0.508)
		(layer "B.Cu")
		(net "P3V3_STBY")
	)
	(segment
		(start 213.741 -195.834)
		(end 213.614 -195.961)
		(width 0.4064)
		(layer "B.Cu")
		(net "P3V3_STBY")
	)
	(segment
		(start 339.725 -177.1777)
		(end 339.725 -177.292)
		(width 0.508)
		(layer "B.Cu")
		(net "P3V3_STBY")
	)
	(segment
		(start 335.820512 -171.987718)
		(end 333.788512 -171.987718)
		(width 0.508)
		(layer "B.Cu")
		(net "P3V3_STBY")
	)
	(segment
		(start 331.724 -182.0545)
		(end 331.1779 -182.0545)
		(width 0.508)
		(layer "B.Cu")
		(net "P3V3_STBY")
	)
	(segment
		(start 331.216 -11.176)
		(end 331.216 -6.2738)
		(width 0.508)
		(layer "B.Cu")
		(net "P3V3_STBY")
	)
	(segment
		(start 224.052638 -204.154532)
		(end 224.040446 -204.14234)
		(width 0.508)
		(layer "B.Cu")
		(net "P3V3_STBY")
	)
	(segment
		(start 200.9648 -31.8262)
		(end 202.006708 -30.784292)
		(width 0.508)
		(layer "B.Cu")
		(net "P3V3_STBY")
	)
	(segment
		(start 153.87447 -33.985962)
		(end 154.454606 -33.405826)
		(width 0.508)
		(layer "B.Cu")
		(net "P3V3_STBY")
	)
	(segment
		(start 127.335026 -200.197974)
		(end 126.746 -200.787)
		(width 0.508)
		(layer "B.Cu")
		(net "P3V3_STBY")
	)
	(segment
		(start 52.1208 -112.4966)
		(end 52.521104 -112.896904)
		(width 0.508)
		(layer "B.Cu")
		(net "P3V3_STBY")
	)
	(segment
		(start 123.698 -200.1901)
		(end 123.612148 -200.275952)
		(width 0.4064)
		(layer "B.Cu")
		(net "P3V3_STBY")
	)
	(segment
		(start 264.814812 -9.078722)
		(end 264.114788 -9.078722)
		(width 0.508)
		(layer "B.Cu")
		(net "P3V3_STBY")
	)
	(segment
		(start 76.811124 -182.249826)
		(end 76.811124 -182.75681)
		(width 0.508)
		(layer "B.Cu")
		(net "P3V3_STBY")
	)
	(segment
		(start 218.21775 -5.09905)
		(end 217.9574 -5.3594)
		(width 0.508)
		(layer "B.Cu")
		(net "P3V3_STBY")
	)
	(segment
		(start 208.994248 -5.11937)
		(end 208.756758 -5.35686)
		(width 0.508)
		(layer "B.Cu")
		(net "P3V3_STBY")
	)
	(segment
		(start 213.614 -195.961)
		(end 213.614 -196.7865)
		(width 0.4064)
		(layer "B.Cu")
		(net "P3V3_STBY")
	)
	(segment
		(start 256.276348 -9.123426)
		(end 256.455164 -8.94461)
		(width 0.508)
		(layer "B.Cu")
		(net "P3V3_STBY")
	)
	(segment
		(start 217.805 -197.6755)
		(end 217.8177 -197.6755)
		(width 0.508)
		(layer "B.Cu")
		(net "P3V3_STBY")
	)
	(segment
		(start 336.5246 -176.1871)
		(end 336.3849 -176.1871)
		(width 0.508)
		(layer "B.Cu")
		(net "P3V3_STBY")
	)
	(segment
		(start 306.766976 -34.275014)
		(end 306.76723 -34.27476)
		(width 0.508)
		(layer "B.Cu")
		(net "P3V3_STBY")
	)
	(segment
		(start 190.7032 -26.1366)
		(end 191.4398 -26.1366)
		(width 0.508)
		(layer "B.Cu")
		(net "P3V3_STBY")
	)
	(segment
		(start 22.925532 -134.239)
		(end 22.6568 -134.239)
		(width 0.508)
		(layer "B.Cu")
		(net "P3V3_STBY")
	)
	(segment
		(start 22.6695 -70.268846)
		(end 22.7076 -70.230746)
		(width 0.508)
		(layer "B.Cu")
		(net "P3V3_STBY")
	)
	(segment
		(start 351.035112 -46.78299)
		(end 351.063052 -46.81093)
		(width 0.4064)
		(layer "B.Cu")
		(net "P3V3_STBY")
	)
	(segment
		(start 83.9216 -77.0636)
		(end 82.0928 -77.0636)
		(width 0.508)
		(layer "B.Cu")
		(net "P3V3_STBY")
	)
	(segment
		(start 135.0264 -195.6308)
		(end 134.7089 -195.9483)
		(width 0.508)
		(layer "B.Cu")
		(net "P3V3_STBY")
	)
	(segment
		(start 222.155004 -197.994016)
		(end 222.155004 -196.849492)
		(width 0.3048)
		(layer "B.Cu")
		(net "P3V3_STBY")
	)
	(segment
		(start 196.088 -17.8816)
		(end 196.088 -16.3068)
		(width 0.508)
		(layer "B.Cu")
		(net "P3V3_STBY")
	)
	(segment
		(start 24.89708 -78.391004)
		(end 25.81402 -79.307944)
		(width 0.508)
		(layer "B.Cu")
		(net "P3V3_STBY")
	)
	(segment
		(start 55.626 -125.42774)
		(end 55.101236 -124.902976)
		(width 0.508)
		(layer "B.Cu")
		(net "P3V3_STBY")
	)
	(segment
		(start 20.5105 -128.651)
		(end 20.5105 -129.667)
		(width 0.508)
		(layer "B.Cu")
		(net "P3V3_STBY")
	)
	(segment
		(start 50.2539 -111.1123)
		(end 50.29073 -111.14913)
		(width 0.508)
		(layer "B.Cu")
		(net "P3V3_STBY")
	)
	(segment
		(start 130.220466 -209.3214)
		(end 129.179066 -209.3214)
		(width 0.508)
		(layer "B.Cu")
		(net "P3V3_STBY")
	)
	(segment
		(start 221.3737 -13.3858)
		(end 221.3737 -12.573)
		(width 0.4064)
		(layer "B.Cu")
		(net "P3V3_STBY")
	)
	(segment
		(start 214.948008 -3.6195)
		(end 214.948008 -2.501392)
		(width 0.508)
		(layer "B.Cu")
		(net "P3V3_STBY")
	)
	(segment
		(start 127.084328 -33.963356)
		(end 127.956818 -33.963356)
		(width 0.508)
		(layer "B.Cu")
		(net "P3V3_STBY")
	)
	(segment
		(start 131.843526 -200.334118)
		(end 131.791456 -200.386188)
		(width 0.508)
		(layer "B.Cu")
		(net "P3V3_STBY")
	)
	(segment
		(start 339.344 -177.673)
		(end 339.725 -177.292)
		(width 0.508)
		(layer "B.Cu")
		(net "P3V3_STBY")
	)
	(segment
		(start 130.4798 -195.9483)
		(end 131.5212 -195.9483)
		(width 0.508)
		(layer "B.Cu")
		(net "P3V3_STBY")
	)
	(segment
		(start 218.78036 -196.1515)
		(end 219.18676 -196.1515)
		(width 0.4064)
		(layer "B.Cu")
		(net "P3V3_STBY")
	)
	(segment
		(start 336.710782 -185.322718)
		(end 333.915512 -185.322718)
		(width 0.508)
		(layer "B.Cu")
		(net "P3V3_STBY")
	)
	(segment
		(start 82.0928 -77.0636)
		(end 81.6102 -76.581)
		(width 0.508)
		(layer "B.Cu")
		(net "P3V3_STBY")
	)
	(segment
		(start 125.960124 -195.998592)
		(end 124.944124 -195.998592)
		(width 0.508)
		(layer "B.Cu")
		(net "P3V3_STBY")
	)
	(segment
		(start 296.725086 -35.503612)
		(end 296.724578 -35.503104)
		(width 0.508)
		(layer "B.Cu")
		(net "P3V3_STBY")
	)
	(segment
		(start 264.99693 -6.018784)
		(end 264.99693 -5.634736)
		(width 0.508)
		(layer "B.Cu")
		(net "P3V3_STBY")
	)
	(segment
		(start 226.740212 -194.355974)
		(end 226.727512 -194.355974)
		(width 0.508)
		(layer "B.Cu")
		(net "P3V3_STBY")
	)
	(segment
		(start 215.063324 -202.602592)
		(end 215.960706 -203.499974)
		(width 0.508)
		(layer "B.Cu")
		(net "P3V3_STBY")
	)
	(segment
		(start 131.5212 -195.9483)
		(end 132.5372 -195.9483)
		(width 0.508)
		(layer "B.Cu")
		(net "P3V3_STBY")
	)
	(segment
		(start 34.40811 -128.388618)
		(end 34.10458 -128.085088)
		(width 0.508)
		(layer "B.Cu")
		(net "P3V3_STBY")
	)
	(segment
		(start 37.32784 -125.708156)
		(end 37.304726 -125.685042)
		(width 0.508)
		(layer "B.Cu")
		(net "P3V3_STBY")
	)
	(segment
		(start 192.2526 -28.6512)
		(end 194.31 -28.6512)
		(width 0.508)
		(layer "B.Cu")
		(net "P3V3_STBY")
	)
	(segment
		(start 22.497542 -127.99949)
		(end 22.535388 -128.037336)
		(width 0.508)
		(layer "B.Cu")
		(net "P3V3_STBY")
	)
	(segment
		(start 188.84646 -27.99334)
		(end 190.7032 -26.1366)
		(width 0.508)
		(layer "B.Cu")
		(net "P3V3_STBY")
	)
	(segment
		(start 217.05824 -198.80326)
		(end 216.28354 -199.57796)
		(width 0.508)
		(layer "B.Cu")
		(net "P3V3_STBY")
	)
	(segment
		(start 298.229274 -35.069526)
		(end 297.795188 -35.503612)
		(width 0.508)
		(layer "B.Cu")
		(net "P3V3_STBY")
	)
	(segment
		(start 214.948008 -2.501392)
		(end 215.138 -2.3114)
		(width 0.508)
		(layer "B.Cu")
		(net "P3V3_STBY")
	)
	(segment
		(start 219.120212 -194.482974)
		(end 218.612974 -194.482974)
		(width 0.508)
		(layer "B.Cu")
		(net "P3V3_STBY")
	)
	(segment
		(start 56.0832 -112.241838)
		(end 56.099456 -112.225582)
		(width 0.508)
		(layer "B.Cu")
		(net "P3V3_STBY")
	)
	(segment
		(start 81.76768 -87.503)
		(end 80.0862 -87.503)
		(width 0.508)
		(layer "B.Cu")
		(net "P3V3_STBY")
	)
	(segment
		(start 332.146148 -176.253648)
		(end 332.0796 -176.1871)
		(width 0.3556)
		(layer "B.Cu")
		(net "P3V3_STBY")
	)
	(segment
		(start 335.153 -179.2605)
		(end 335.153 -177.979324)
		(width 0.508)
		(layer "B.Cu")
		(net "P3V3_STBY")
	)
	(segment
		(start 182.9054 -10.5537)
		(end 183.4769 -10.5537)
		(width 0.508)
		(layer "B.Cu")
		(net "P3V3_STBY")
	)
	(segment
		(start 224.867724 -190.156592)
		(end 223.851724 -190.156592)
		(width 0.508)
		(layer "B.Cu")
		(net "P3V3_STBY")
	)
	(segment
		(start 77.83576 -188.7855)
		(end 77.83576 -187.056522)
		(width 0.4064)
		(layer "B.Cu")
		(net "P3V3_STBY")
	)
	(segment
		(start 21.6916 -68.1736)
		(end 18.4912 -68.1736)
		(width 0.508)
		(layer "B.Cu")
		(net "P3V3_STBY")
	)
	(segment
		(start 75.6285 -149.479)
		(end 75.6285 -148.082)
		(width 0.508)
		(layer "B.Cu")
		(net "P3V3_STBY")
	)
	(segment
		(start 141.0335 -34.059876)
		(end 141.0335 -34.929572)
		(width 0.508)
		(layer "B.Cu")
		(net "P3V3_STBY")
	)
	(segment
		(start 19.6723 -122.4407)
		(end 19.3294 -122.7836)
		(width 0.508)
		(layer "B.Cu")
		(net "P3V3_STBY")
	)
	(segment
		(start 35.119564 -131.34848)
		(end 34.168334 -131.34848)
		(width 0.508)
		(layer "B.Cu")
		(net "P3V3_STBY")
	)
	(segment
		(start 270.63065 -13.290042)
		(end 270.64335 -13.277342)
		(width 0.508)
		(layer "B.Cu")
		(net "P3V3_STBY")
	)
	(segment
		(start 23.46198 -139.618974)
		(end 23.46198 -138.602974)
		(width 0.508)
		(layer "B.Cu")
		(net "P3V3_STBY")
	)
	(segment
		(start 179.590954 -3.092196)
		(end 180.03393 -2.64922)
		(width 0.508)
		(layer "B.Cu")
		(net "P3V3_STBY")
	)
	(segment
		(start 217.9574 -5.3594)
		(end 217.9574 -5.4356)
		(width 0.508)
		(layer "B.Cu")
		(net "P3V3_STBY")
	)
	(segment
		(start 226.80676 -194.422522)
		(end 226.740212 -194.355974)
		(width 0.3048)
		(layer "B.Cu")
		(net "P3V3_STBY")
	)
	(segment
		(start 126.976124 -195.998592)
		(end 125.960124 -195.998592)
		(width 0.508)
		(layer "B.Cu")
		(net "P3V3_STBY")
	)
	(segment
		(start 222.0595 -196.1515)
		(end 221.996 -196.088)
		(width 0.4064)
		(layer "B.Cu")
		(net "P3V3_STBY")
	)
	(segment
		(start 227.179124 -203.491592)
		(end 228.195124 -203.491592)
		(width 0.508)
		(layer "B.Cu")
		(net "P3V3_STBY")
	)
	(segment
		(start 328.920094 -185.3311)
		(end 332.7654 -185.3311)
		(width 0.508)
		(layer "B.Cu")
		(net "P3V3_STBY")
	)
	(segment
		(start 340.7156 -176.1871)
		(end 339.725 -177.1777)
		(width 0.508)
		(layer "B.Cu")
		(net "P3V3_STBY")
	)
	(segment
		(start 331.43444 -16.92656)
		(end 331.43444 -11.39444)
		(width 0.508)
		(layer "B.Cu")
		(net "P3V3_STBY")
	)
	(segment
		(start 60.853066 -121.368566)
		(end 60.8965 -121.412)
		(width 0.508)
		(layer "B.Cu")
		(net "P3V3_STBY")
	)
	(segment
		(start 51.2572 -112.7125)
		(end 50.2412 -112.7125)
		(width 0.508)
		(layer "B.Cu")
		(net "P3V3_STBY")
	)
	(segment
		(start 190.53302 -18.67662)
		(end 190.53302 -16.08836)
		(width 0.508)
		(layer "B.Cu")
		(net "P3V3_STBY")
	)
	(segment
		(start 124.3838 -33.92805)
		(end 124.37872 -33.92297)
		(width 0.508)
		(layer "B.Cu")
		(net "P3V3_STBY")
	)
	(segment
		(start 215.960706 -203.499974)
		(end 219.806012 -203.499974)
		(width 0.508)
		(layer "B.Cu")
		(net "P3V3_STBY")
	)
	(segment
		(start 50.29073 -111.14913)
		(end 51.470052 -111.14913)
		(width 0.508)
		(layer "B.Cu")
		(net "P3V3_STBY")
	)
	(segment
		(start 331.1779 -182.047388)
		(end 330.638912 -181.5084)
		(width 0.508)
		(layer "B.Cu")
		(net "P3V3_STBY")
	)
	(segment
		(start 209.839052 -3.442716)
		(end 209.504534 -3.442716)
		(width 0.508)
		(layer "B.Cu")
		(net "P3V3_STBY")
	)
	(segment
		(start 38.904672 -126.424436)
		(end 38.904672 -125.685042)
		(width 0.508)
		(layer "B.Cu")
		(net "P3V3_STBY")
	)
	(segment
		(start 215.265 -194.4751)
		(end 215.052148 -194.687952)
		(width 0.4064)
		(layer "B.Cu")
		(net "P3V3_STBY")
	)
	(segment
		(start 70.715124 -182.790592)
		(end 69.699124 -182.790592)
		(width 0.508)
		(layer "B.Cu")
		(net "P3V3_STBY")
	)
	(segment
		(start 42.1005 -131.064)
		(end 42.2656 -131.064)
		(width 0.508)
		(layer "B.Cu")
		(net "P3V3_STBY")
	)
	(segment
		(start 217.805 -197.6755)
		(end 217.61958 -197.6755)
		(width 0.4572)
		(layer "B.Cu")
		(net "P3V3_STBY")
	)
	(segment
		(start 222.999046 -204.14234)
		(end 221.606872 -204.14234)
		(width 0.508)
		(layer "B.Cu")
		(net "P3V3_STBY")
	)
	(segment
		(start 125.961394 -209.333592)
		(end 127.103124 -209.333592)
		(width 0.508)
		(layer "B.Cu")
		(net "P3V3_STBY")
	)
	(segment
		(start 63.5508 -128.6764)
		(end 63.5508 -127.6223)
		(width 0.508)
		(layer "B.Cu")
		(net "P3V3_STBY")
	)
	(segment
		(start 55.280306 -140.843)
		(end 56.5785 -140.843)
		(width 0.508)
		(layer "B.Cu")
		(net "P3V3_STBY")
	)
	(segment
		(start 226.925124 -190.156592)
		(end 226.925124 -189.256924)
		(width 0.508)
		(layer "B.Cu")
		(net "P3V3_STBY")
	)
	(segment
		(start 331.95006 -43.685206)
		(end 331.95006 -44.876974)
		(width 1.016)
		(layer "B.Cu")
		(net "P3V3_STBY")
	)
	(segment
		(start 80.518 -189.1665)
		(end 80.518 -187.8584)
		(width 0.508)
		(layer "B.Cu")
		(net "P3V3_STBY")
	)
	(segment
		(start 219.806012 -203.499974)
		(end 219.814394 -203.491592)
		(width 0.508)
		(layer "B.Cu")
		(net "P3V3_STBY")
	)
	(segment
		(start 12.9032 -85.0138)
		(end 14.732 -85.0138)
		(width 0.508)
		(layer "B.Cu")
		(net "P3V3_STBY")
	)
	(segment
		(start 218.353894 -197.139306)
		(end 218.353894 -196.577966)
		(width 0.4064)
		(layer "B.Cu")
		(net "P3V3_STBY")
	)
	(segment
		(start 81.6102 -75.9079)
		(end 79.4766 -73.7743)
		(width 0.508)
		(layer "B.Cu")
		(net "P3V3_STBY")
	)
	(segment
		(start 61.226192 -128.524)
		(end 59.6519 -128.524)
		(width 0.508)
		(layer "B.Cu")
		(net "P3V3_STBY")
	)
	(segment
		(start 180.03393 -2.64922)
		(end 180.72354 -2.64922)
		(width 0.508)
		(layer "B.Cu")
		(net "P3V3_STBY")
	)
	(segment
		(start 266.186666 -2.122678)
		(end 265.6459 -1.581912)
		(width 0.508)
		(layer "B.Cu")
		(net "P3V3_STBY")
	)
	(segment
		(start 123.928124 -195.998592)
		(end 123.444508 -195.998592)
		(width 0.508)
		(layer "B.Cu")
		(net "P3V3_STBY")
	)
	(segment
		(start 217.61958 -197.6755)
		(end 217.05824 -198.23684)
		(width 0.4572)
		(layer "B.Cu")
		(net "P3V3_STBY")
	)
	(segment
		(start 219.4941 -5.09905)
		(end 218.21775 -5.09905)
		(width 0.508)
		(layer "B.Cu")
		(net "P3V3_STBY")
	)
	(segment
		(start 59.0804 -30.520386)
		(end 59.0804 -25.9207)
		(width 0.508)
		(layer "B.Cu")
		(net "P3V3_STBY")
	)
	(segment
		(start 305.90109 -34.275014)
		(end 306.766976 -34.275014)
		(width 0.508)
		(layer "B.Cu")
		(net "P3V3_STBY")
	)
	(segment
		(start 331.343 -176.9237)
		(end 331.343 -177.292)
		(width 0.508)
		(layer "B.Cu")
		(net "P3V3_STBY")
	)
	(segment
		(start 76.811124 -182.75681)
		(end 76.848716 -182.794402)
		(width 0.508)
		(layer "B.Cu")
		(net "P3V3_STBY")
	)
	(segment
		(start 197.883272 -19.676872)
		(end 196.088 -17.8816)
		(width 0.508)
		(layer "B.Cu")
		(net "P3V3_STBY")
	)
	(segment
		(start 50.2412 -112.7125)
		(end 49.1998 -112.7125)
		(width 0.508)
		(layer "B.Cu")
		(net "P3V3_STBY")
	)
	(segment
		(start 56.0832 -113.284)
		(end 55.835296 -113.531904)
		(width 0.508)
		(layer "B.Cu")
		(net "P3V3_STBY")
	)
	(segment
		(start 74.804524 -182.790592)
		(end 74.808334 -182.794402)
		(width 0.508)
		(layer "B.Cu")
		(net "P3V3_STBY")
	)
	(segment
		(start 218.353894 -196.577966)
		(end 218.78036 -196.1515)
		(width 0.4064)
		(layer "B.Cu")
		(net "P3V3_STBY")
	)
	(segment
		(start 59.6519 -128.524)
		(end 59.6519 -127.508)
		(width 0.508)
		(layer "B.Cu")
		(net "P3V3_STBY")
	)
	(segment
		(start 61.734192 -129.032)
		(end 61.226192 -128.524)
		(width 0.508)
		(layer "B.Cu")
		(net "P3V3_STBY")
	)
	(segment
		(start 141.02842 -34.934652)
		(end 142.087092 -34.934652)
		(width 0.508)
		(layer "B.Cu")
		(net "P3V3_STBY")
	)
	(segment
		(start 14.6558 -126.873254)
		(end 16.133826 -128.35128)
		(width 0.508)
		(layer "B.Cu")
		(net "P3V3_STBY")
	)
	(segment
		(start 224.867724 -190.156592)
		(end 225.883724 -190.156592)
		(width 0.508)
		(layer "B.Cu")
		(net "P3V3_STBY")
	)
	(segment
		(start 60.8965 -123.444)
		(end 60.8965 -124.46)
		(width 0.508)
		(layer "B.Cu")
		(net "P3V3_STBY")
	)
	(segment
		(start 12.349988 -74.91476)
		(end 12.351512 -74.913236)
		(width 0.508)
		(layer "B.Cu")
		(net "P3V3_STBY")
	)
	(segment
		(start 47.0535 -112.5982)
		(end 48.0695 -112.5982)
		(width 0.508)
		(layer "B.Cu")
		(net "P3V3_STBY")
	)
	(segment
		(start 56.106568 -122.2248)
		(end 58.998612 -122.2248)
		(width 0.508)
		(layer "B.Cu")
		(net "P3V3_STBY")
	)
	(segment
		(start 241.9985 -17.2466)
		(end 240.7666 -17.2466)
		(width 0.508)
		(layer "B.Cu")
		(net "P3V3_STBY")
	)
	(segment
		(start 81.89976 -188.7855)
		(end 81.89976 -187.056522)
		(width 0.4064)
		(layer "B.Cu")
		(net "P3V3_STBY")
	)
	(segment
		(start 151.649176 -33.989772)
		(end 152.528778 -33.989772)
		(width 0.508)
		(layer "B.Cu")
		(net "P3V3_STBY")
	)
	(segment
		(start 67.945 -187.4901)
		(end 68.453 -186.9821)
		(width 0.508)
		(layer "B.Cu")
		(net "P3V3_STBY")
	)
	(segment
		(start 205.113128 -19.676872)
		(end 197.883272 -19.676872)
		(width 0.508)
		(layer "B.Cu")
		(net "P3V3_STBY")
	)
	(segment
		(start 60.9981 -115.7224)
		(end 60.0456 -115.7224)
		(width 0.508)
		(layer "B.Cu")
		(net "P3V3_STBY")
	)
	(segment
		(start 76.848716 -182.794402)
		(end 75.832716 -182.794402)
		(width 0.508)
		(layer "B.Cu")
		(net "P3V3_STBY")
	)
	(segment
		(start 211.900008 -3.6195)
		(end 210.884008 -3.6195)
		(width 0.508)
		(layer "B.Cu")
		(net "P3V3_STBY")
	)
	(segment
		(start 20.5105 -131.699)
		(end 19.2278 -131.699)
		(width 0.508)
		(layer "B.Cu")
		(net "P3V3_STBY")
	)
	(segment
		(start 22.7076 -70.9422)
		(end 22.7076 -70.93839)
		(width 0.508)
		(layer "B.Cu")
		(net "P3V3_STBY")
	)
	(segment
		(start 55.007002 -141.116304)
		(end 55.280306 -140.843)
		(width 0.508)
		(layer "B.Cu")
		(net "P3V3_STBY")
	)
	(segment
		(start 122.1232 -203.3905)
		(end 121.2088 -202.4761)
		(width 0.508)
		(layer "B.Cu")
		(net "P3V3_STBY")
	)
	(segment
		(start 331.756512 -171.987718)
		(end 332.772512 -171.987718)
		(width 0.508)
		(layer "B.Cu")
		(net "P3V3_STBY")
	)
	(segment
		(start 59.817 -131.4958)
		(end 59.9694 -131.3434)
		(width 0.508)
		(layer "B.Cu")
		(net "P3V3_STBY")
	)
	(segment
		(start 75.01128 -196.174614)
		(end 75.987656 -196.174614)
		(width 0.508)
		(layer "B.Cu")
		(net "P3V3_STBY")
	)
	(segment
		(start 40.259 -133.6675)
		(end 40.259 -134.239508)
		(width 0.508)
		(layer "B.Cu")
		(net "P3V3_STBY")
	)
	(segment
		(start 80.660494 -195.579746)
		(end 78.293722 -195.579746)
		(width 0.381)
		(layer "B.Cu")
		(net "P3V3_STBY")
	)
	(segment
		(start 22.48154 -120.856502)
		(end 21.779992 -120.856502)
		(width 0.508)
		(layer "B.Cu")
		(net "P3V3_STBY")
	)
	(segment
		(start 335.153 -177.979324)
		(end 335.899506 -177.232818)
		(width 0.508)
		(layer "B.Cu")
		(net "P3V3_STBY")
	)
	(segment
		(start 60.212732 -25.960832)
		(end 60.1472 -25.8953)
		(width 0.508)
		(layer "B.Cu")
		(net "P3V3_STBY")
	)
	(segment
		(start 191.9478 -20.0914)
		(end 190.53302 -18.67662)
		(width 0.508)
		(layer "B.Cu")
		(net "P3V3_STBY")
	)
	(segment
		(start 136.00176 -201.9935)
		(end 136.00176 -200.264522)
		(width 0.4064)
		(layer "B.Cu")
		(net "P3V3_STBY")
	)
	(segment
		(start 68.721224 -182.042308)
		(end 69.469508 -182.790592)
		(width 0.508)
		(layer "B.Cu")
		(net "P3V3_STBY")
	)
	(segment
		(start 71.732394 -196.125592)
		(end 72.874124 -196.125592)
		(width 0.508)
		(layer "B.Cu")
		(net "P3V3_STBY")
	)
	(segment
		(start 23.351998 -127.021336)
		(end 23.351998 -126.005336)
		(width 0.508)
		(layer "B.Cu")
		(net "P3V3_STBY")
	)
	(segment
		(start 266.486894 -2.122678)
		(end 266.186666 -2.122678)
		(width 0.508)
		(layer "B.Cu")
		(net "P3V3_STBY")
	)
	(segment
		(start 130.556 -201.549)
		(end 130.81 -201.295)
		(width 0.508)
		(layer "B.Cu")
		(net "P3V3_STBY")
	)
	(segment
		(start 339.884512 -185.322718)
		(end 338.868512 -185.322718)
		(width 0.508)
		(layer "B.Cu")
		(net "P3V3_STBY")
	)
	(segment
		(start 17.030446 -138.213846)
		(end 17.4244 -138.6078)
		(width 0.508)
		(layer "B.Cu")
		(net "P3V3_STBY")
	)
	(segment
		(start 52.521104 -112.896904)
		(end 52.521104 -113.83391)
		(width 0.508)
		(layer "B.Cu")
		(net "P3V3_STBY")
	)
	(segment
		(start 71.731124 -182.790592)
		(end 72.747124 -182.790592)
		(width 0.508)
		(layer "B.Cu")
		(net "P3V3_STBY")
	)
	(segment
		(start 68.3006 -192.6971)
		(end 68.3006 -192.11036)
		(width 0.508)
		(layer "B.Cu")
		(net "P3V3_STBY")
	)
	(segment
		(start 58.3057 -131.4958)
		(end 59.817 -131.4958)
		(width 0.508)
		(layer "B.Cu")
		(net "P3V3_STBY")
	)
	(segment
		(start 142.087092 -34.934652)
		(end 142.136114 -34.88563)
		(width 0.508)
		(layer "B.Cu")
		(net "P3V3_STBY")
	)
	(segment
		(start 127.87376 -200.264522)
		(end 127.807212 -200.197974)
		(width 0.4064)
		(layer "B.Cu")
		(net "P3V3_STBY")
	)
	(segment
		(start 191.2874 -20.7518)
		(end 191.2874 -22.3774)
		(width 0.508)
		(layer "B.Cu")
		(net "P3V3_STBY")
	)
	(segment
		(start 126.492 -201.676)
		(end 126.746 -201.422)
		(width 0.508)
		(layer "B.Cu")
		(net "P3V3_STBY")
	)
	(segment
		(start 49.1744 -112.6871)
		(end 48.1584 -112.6871)
		(width 0.508)
		(layer "B.Cu")
		(net "P3V3_STBY")
	)
	(segment
		(start 209.839052 -3.442716)
		(end 210.707224 -3.442716)
		(width 0.508)
		(layer "B.Cu")
		(net "P3V3_STBY")
	)
	(segment
		(start 226.727512 -194.355974)
		(end 226.0346 -195.048886)
		(width 0.508)
		(layer "B.Cu")
		(net "P3V3_STBY")
	)
	(segment
		(start 78.746858 -182.694326)
		(end 78.843124 -182.790592)
		(width 0.508)
		(layer "B.Cu")
		(net "P3V3_STBY")
	)
	(segment
		(start 50.927 -103.6955)
		(end 52.2605 -103.6955)
		(width 0.508)
		(layer "B.Cu")
		(net "P3V3_STBY")
	)
	(segment
		(start 63.1952 -57.5818)
		(end 62.0522 -57.5818)
		(width 0.508)
		(layer "In2.Cu")
		(net "P3V3_STBY")
	)
	(segment
		(start 122.055128 -75.252072)
		(end 122.055128 -81.618328)
		(width 0.508)
		(layer "In2.Cu")
		(net "P3V3_STBY")
	)
	(segment
		(start 321.437 -100.838)
		(end 319.913 -99.314)
		(width 0.508)
		(layer "In2.Cu")
		(net "P3V3_STBY")
	)
	(segment
		(start 61.0108 -57.5818)
		(end 62.0522 -57.5818)
		(width 0.508)
		(layer "In2.Cu")
		(net "P3V3_STBY")
	)
	(segment
		(start 125.476 -63.023242)
		(end 125.476 -67.31)
		(width 0.508)
		(layer "In2.Cu")
		(net "P3V3_STBY")
	)
	(segment
		(start 142.233142 -98.460052)
		(end 140.191998 -98.460052)
		(width 0.508)
		(layer "In2.Cu")
		(net "P3V3_STBY")
	)
	(segment
		(start 126.182628 -34.11601)
		(end 123.60783 -34.11601)
		(width 0.508)
		(layer "In2.Cu")
		(net "P3V3_STBY")
	)
	(segment
		(start 123.490482 -43.5356)
		(end 121.915682 -45.1104)
		(width 0.508)
		(layer "In2.Cu")
		(net "P3V3_STBY")
	)
	(segment
		(start 70.5612 -52.959)
		(end 67.818 -52.959)
		(width 0.508)
		(layer "In2.Cu")
		(net "P3V3_STBY")
	)
	(segment
		(start 112.1156 -44.5516)
		(end 111.76 -44.9072)
		(width 0.508)
		(layer "In2.Cu")
		(net "P3V3_STBY")
	)
	(segment
		(start 123.5837 -73.7235)
		(end 122.055128 -75.252072)
		(width 0.508)
		(layer "In2.Cu")
		(net "P3V3_STBY")
	)
	(segment
		(start 332.5495 -100.0125)
		(end 332.634336 -100.097336)
		(width 0.508)
		(layer "In2.Cu")
		(net "P3V3_STBY")
	)
	(segment
		(start 147.9296 -53.1622)
		(end 147.9296 -53.213)
		(width 0.508)
		(layer "In2.Cu")
		(net "P3V3_STBY")
	)
	(segment
		(start 121.915682 -45.1104)
		(end 119.9388 -45.1104)
		(width 0.508)
		(layer "In2.Cu")
		(net "P3V3_STBY")
	)
	(segment
		(start 161.8742 -58.2422)
		(end 160.67786 -57.04586)
		(width 0.508)
		(layer "In2.Cu")
		(net "P3V3_STBY")
	)
	(segment
		(start 126.492 -49.3268)
		(end 126.492 -44.958)
		(width 0.508)
		(layer "In2.Cu")
		(net "P3V3_STBY")
	)
	(segment
		(start 130.287268 -99.8982)
		(end 123.698 -99.8982)
		(width 0.508)
		(layer "In2.Cu")
		(net "P3V3_STBY")
	)
	(segment
		(start 143.756126 -57.335674)
		(end 131.163568 -57.335674)
		(width 0.508)
		(layer "In2.Cu")
		(net "P3V3_STBY")
	)
	(segment
		(start 135.229092 -94.956376)
		(end 130.287268 -99.8982)
		(width 0.508)
		(layer "In2.Cu")
		(net "P3V3_STBY")
	)
	(segment
		(start 322.453 -100.838)
		(end 323.2785 -100.0125)
		(width 0.508)
		(layer "In2.Cu")
		(net "P3V3_STBY")
	)
	(segment
		(start 123.5837 -69.2023)
		(end 123.5837 -73.7235)
		(width 0.508)
		(layer "In2.Cu")
		(net "P3V3_STBY")
	)
	(segment
		(start 139.0396 -96.630998)
		(end 137.364978 -94.956376)
		(width 0.508)
		(layer "In2.Cu")
		(net "P3V3_STBY")
	)
	(segment
		(start 137.364978 -94.956376)
		(end 135.229092 -94.956376)
		(width 0.508)
		(layer "In2.Cu")
		(net "P3V3_STBY")
	)
	(segment
		(start 119.9388 -45.1104)
		(end 119.38 -44.5516)
		(width 0.508)
		(layer "In2.Cu")
		(net "P3V3_STBY")
	)
	(segment
		(start 125.984 -44.45)
		(end 125.984 -44.1706)
		(width 0.508)
		(layer "In2.Cu")
		(net "P3V3_STBY")
	)
	(segment
		(start 54.557676 -53.8734)
		(end 57.3024 -53.8734)
		(width 0.508)
		(layer "In2.Cu")
		(net "P3V3_STBY")
	)
	(segment
		(start 319.913 -99.314)
		(end 317.5 -99.314)
		(width 0.508)
		(layer "In2.Cu")
		(net "P3V3_STBY")
	)
	(segment
		(start 323.2785 -100.0125)
		(end 332.5495 -100.0125)
		(width 0.508)
		(layer "In2.Cu")
		(net "P3V3_STBY")
	)
	(segment
		(start 125.349 -43.5356)
		(end 123.490482 -43.5356)
		(width 0.508)
		(layer "In2.Cu")
		(net "P3V3_STBY")
	)
	(segment
		(start 126.492 -44.958)
		(end 125.984 -44.45)
		(width 0.508)
		(layer "In2.Cu")
		(net "P3V3_STBY")
	)
	(segment
		(start 205.0288 -18.8468)
		(end 205.486 -19.304)
		(width 0.508)
		(layer "In2.Cu")
		(net "P3V3_STBY")
	)
	(segment
		(start 200.9902 -18.8468)
		(end 205.0288 -18.8468)
		(width 0.508)
		(layer "In2.Cu")
		(net "P3V3_STBY")
	)
	(segment
		(start 123.60783 -34.11601)
		(end 120.64746 -31.15564)
		(width 0.508)
		(layer "In2.Cu")
		(net "P3V3_STBY")
	)
	(segment
		(start 332.634336 -100.097336)
		(end 332.757272 -100.097336)
		(width 0.508)
		(layer "In2.Cu")
		(net "P3V3_STBY")
	)
	(segment
		(start 322.453 -100.838)
		(end 321.437 -100.838)
		(width 0.508)
		(layer "In2.Cu")
		(net "P3V3_STBY")
	)
	(segment
		(start 57.3024 -53.8734)
		(end 61.0108 -57.5818)
		(width 0.508)
		(layer "In2.Cu")
		(net "P3V3_STBY")
	)
	(segment
		(start 131.163568 -57.335674)
		(end 125.476 -63.023242)
		(width 0.508)
		(layer "In2.Cu")
		(net "P3V3_STBY")
	)
	(segment
		(start 111.76 -44.9072)
		(end 110.0836 -44.9072)
		(width 0.508)
		(layer "In2.Cu")
		(net "P3V3_STBY")
	)
	(segment
		(start 125.984 -44.1706)
		(end 125.349 -43.5356)
		(width 0.508)
		(layer "In2.Cu")
		(net "P3V3_STBY")
	)
	(segment
		(start 161.8742 -59.563)
		(end 161.8742 -58.2422)
		(width 0.508)
		(layer "In2.Cu")
		(net "P3V3_STBY")
	)
	(segment
		(start 149.1234 -51.9684)
		(end 147.9296 -53.1622)
		(width 0.508)
		(layer "In2.Cu")
		(net "P3V3_STBY")
	)
	(segment
		(start 119.38 -44.5516)
		(end 112.1156 -44.5516)
		(width 0.508)
		(layer "In2.Cu")
		(net "P3V3_STBY")
	)
	(segment
		(start 157.07106 -51.9684)
		(end 149.1234 -51.9684)
		(width 0.508)
		(layer "In2.Cu")
		(net "P3V3_STBY")
	)
	(segment
		(start 125.476 -67.31)
		(end 123.5837 -69.2023)
		(width 0.508)
		(layer "In2.Cu")
		(net "P3V3_STBY")
	)
	(segment
		(start 317.5 -99.314)
		(end 317.3095 -99.1235)
		(width 0.508)
		(layer "In2.Cu")
		(net "P3V3_STBY")
	)
	(segment
		(start 139.0396 -97.307654)
		(end 139.0396 -96.630998)
		(width 0.508)
		(layer "In2.Cu")
		(net "P3V3_STBY")
	)
	(segment
		(start 140.191998 -98.460052)
		(end 139.0396 -97.307654)
		(width 0.508)
		(layer "In2.Cu")
		(net "P3V3_STBY")
	)
	(segment
		(start 67.818 -52.959)
		(end 63.1952 -57.5818)
		(width 0.508)
		(layer "In2.Cu")
		(net "P3V3_STBY")
	)
	(segment
		(start 160.67786 -55.5752)
		(end 157.07106 -51.9684)
		(width 0.508)
		(layer "In2.Cu")
		(net "P3V3_STBY")
	)
	(segment
		(start 147.9296 -53.1622)
		(end 143.756126 -57.335674)
		(width 0.508)
		(layer "In2.Cu")
		(net "P3V3_STBY")
	)
	(segment
		(start 160.67786 -57.04586)
		(end 160.67786 -55.5752)
		(width 0.508)
		(layer "In2.Cu")
		(net "P3V3_STBY")
	)
	(segment
		(start 128.996694 -34.075116)
		(end 129.19075 -33.88106)
		(width 0.508)
		(layer "In5.Cu")
		(net "P3V3_STBY")
	)
	(segment
		(start 126.182628 -34.11601)
		(end 128.9558 -34.11601)
		(width 0.508)
		(layer "In5.Cu")
		(net "P3V3_STBY")
	)
	(segment
		(start 154.454606 -33.405826)
		(end 145.27911 -33.405826)
		(width 0.508)
		(layer "In5.Cu")
		(net "P3V3_STBY")
	)
	(segment
		(start 119.3038 -99.8982)
		(end 119.26951 -99.93249)
		(width 0.508)
		(layer "In5.Cu")
		(net "P3V3_STBY")
	)
	(segment
		(start 337.1342 -81.0514)
		(end 337.1342 -74.2188)
		(width 0.3048)
		(layer "In5.Cu")
		(net "P3V3_STBY")
	)
	(segment
		(start 128.9558 -34.11601)
		(end 128.996694 -34.075116)
		(width 0.508)
		(layer "In5.Cu")
		(net "P3V3_STBY")
	)
	(segment
		(start 337.1342 -74.2188)
		(end 333.2988 -70.3834)
		(width 0.3048)
		(layer "In5.Cu")
		(net "P3V3_STBY")
	)
	(segment
		(start 121.120916 -81.618328)
		(end 119.056912 -83.682332)
		(width 0.508)
		(layer "In5.Cu")
		(net "P3V3_STBY")
	)
	(segment
		(start 140.998448 -33.88106)
		(end 142.901162 -35.783774)
		(width 0.508)
		(layer "In5.Cu")
		(net "P3V3_STBY")
	)
	(segment
		(start 67.945 -187.4901)
		(end 67.945 -190.119)
		(width 0.508)
		(layer "In5.Cu")
		(net "P3V3_STBY")
	)
	(segment
		(start 27.592274 -42.884344)
		(end 40.090344 -42.884344)
		(width 0.508)
		(layer "In5.Cu")
		(net "P3V3_STBY")
	)
	(segment
		(start 66.847974 -191.216026)
		(end 66.847974 -196.133974)
		(width 0.508)
		(layer "In5.Cu")
		(net "P3V3_STBY")
	)
	(segment
		(start 68.453 -186.9821)
		(end 67.945 -187.4901)
		(width 0.508)
		(layer "In5.Cu")
		(net "P3V3_STBY")
	)
	(segment
		(start 119.3038 -99.8982)
		(end 123.698 -99.8982)
		(width 0.508)
		(layer "In5.Cu")
		(net "P3V3_STBY")
	)
	(segment
		(start 116.7003 -98.0821)
		(end 116.7003 -97.5487)
		(width 0.508)
		(layer "In5.Cu")
		(net "P3V3_STBY")
	)
	(segment
		(start 125.3998 -92.555568)
		(end 125.3998 -93.8022)
		(width 0.508)
		(layer "In5.Cu")
		(net "P3V3_STBY")
	)
	(segment
		(start 119.056912 -86.21268)
		(end 125.3998 -92.555568)
		(width 0.508)
		(layer "In5.Cu")
		(net "P3V3_STBY")
	)
	(segment
		(start 78.5876 -75.6412)
		(end 78.5876 -74.6633)
		(width 0.508)
		(layer "In5.Cu")
		(net "P3V3_STBY")
	)
	(segment
		(start 115.6843 -96.5327)
		(end 116.7003 -97.5487)
		(width 0.508)
		(layer "In5.Cu")
		(net "P3V3_STBY")
	)
	(segment
		(start 116.4844 -94.7166)
		(end 124.4854 -94.7166)
		(width 0.508)
		(layer "In5.Cu")
		(net "P3V3_STBY")
	)
	(segment
		(start 67.945 -190.119)
		(end 66.847974 -191.216026)
		(width 0.508)
		(layer "In5.Cu")
		(net "P3V3_STBY")
	)
	(segment
		(start 119.26951 -99.93249)
		(end 118.55069 -99.93249)
		(width 0.508)
		(layer "In5.Cu")
		(net "P3V3_STBY")
	)
	(segment
		(start 40.090344 -42.884344)
		(end 41.275 -44.069)
		(width 0.508)
		(layer "In5.Cu")
		(net "P3V3_STBY")
	)
	(segment
		(start 118.55069 -99.93249)
		(end 116.7003 -98.0821)
		(width 0.508)
		(layer "In5.Cu")
		(net "P3V3_STBY")
	)
	(segment
		(start 115.6843 -95.5167)
		(end 116.4844 -94.7166)
		(width 0.508)
		(layer "In5.Cu")
		(net "P3V3_STBY")
	)
	(segment
		(start 333.2988 -70.3834)
		(end 333.2988 -69.9008)
		(width 0.3048)
		(layer "In5.Cu")
		(net "P3V3_STBY")
	)
	(segment
		(start 115.6843 -95.5167)
		(end 115.6843 -96.5327)
		(width 0.508)
		(layer "In5.Cu")
		(net "P3V3_STBY")
	)
	(segment
		(start 145.27911 -33.405826)
		(end 142.901162 -35.783774)
		(width 0.508)
		(layer "In5.Cu")
		(net "P3V3_STBY")
	)
	(segment
		(start 75.46086 -79.0829)
		(end 75.46086 -78.76794)
		(width 0.508)
		(layer "In5.Cu")
		(net "P3V3_STBY")
	)
	(segment
		(start 75.46086 -78.76794)
		(end 78.5876 -75.6412)
		(width 0.508)
		(layer "In5.Cu")
		(net "P3V3_STBY")
	)
	(segment
		(start 78.5876 -74.6633)
		(end 79.4766 -73.7743)
		(width 0.508)
		(layer "In5.Cu")
		(net "P3V3_STBY")
	)
	(segment
		(start 124.4854 -94.7166)
		(end 125.3998 -93.8022)
		(width 0.508)
		(layer "In5.Cu")
		(net "P3V3_STBY")
	)
	(segment
		(start 129.19075 -33.88106)
		(end 140.998448 -33.88106)
		(width 0.508)
		(layer "In5.Cu")
		(net "P3V3_STBY")
	)
	(segment
		(start 119.056912 -83.682332)
		(end 119.056912 -86.21268)
		(width 0.508)
		(layer "In5.Cu")
		(net "P3V3_STBY")
	)
	(segment
		(start 122.055128 -81.618328)
		(end 121.120916 -81.618328)
		(width 0.508)
		(layer "In5.Cu")
		(net "P3V3_STBY")
	)
	(segment
		(start 133.5659 -87.51697)
		(end 133.932422 -87.883492)
		(width 0.508)
		(layer "F.Cu")
		(net "P3V3_RTC")
	)
	(segment
		(start 123.288806 -82.34934)
		(end 120.748806 -82.34934)
		(width 0.508)
		(layer "F.Cu")
		(net "P3V3_RTC")
	)
	(segment
		(start 125.452886 -82.306414)
		(end 125.40996 -82.34934)
		(width 0.508)
		(layer "F.Cu")
		(net "P3V3_RTC")
	)
	(segment
		(start 125.452886 -82.306414)
		(end 127.050292 -82.306414)
		(width 0.508)
		(layer "F.Cu")
		(net "P3V3_RTC")
	)
	(segment
		(start 133.932422 -87.883492)
		(end 134.398004 -87.41791)
		(width 0.508)
		(layer "F.Cu")
		(net "P3V3_RTC")
	)
	(segment
		(start 133.5659 -86.487)
		(end 133.5659 -87.51697)
		(width 0.508)
		(layer "F.Cu")
		(net "P3V3_RTC")
	)
	(segment
		(start 134.398004 -87.41791)
		(end 134.398004 -86.953344)
		(width 0.508)
		(layer "F.Cu")
		(net "P3V3_RTC")
	)
	(segment
		(start 123.288806 -79.479902)
		(end 123.499626 -79.269082)
		(width 0.508)
		(layer "F.Cu")
		(net "P3V3_RTC")
	)
	(segment
		(start 123.288806 -82.34934)
		(end 123.288806 -79.479902)
		(width 0.508)
		(layer "F.Cu")
		(net "P3V3_RTC")
	)
	(segment
		(start 125.40996 -82.34934)
		(end 123.288806 -82.34934)
		(width 0.508)
		(layer "F.Cu")
		(net "P3V3_RTC")
	)
	(via
		(at 134.398004 -86.953344)
		(size 0.508)
		(drill 0.254)
		(layers "F.Cu" "B.Cu")
		(net "P3V3_RTC")
	)
	(via
		(at 133.932422 -87.883492)
		(size 0.7112)
		(drill 0.3556)
		(layers "F.Cu" "B.Cu")
		(net "P3V3_RTC")
	)
	(via
		(at 127.050292 -82.306414)
		(size 0.508)
		(drill 0.254)
		(layers "F.Cu" "B.Cu")
		(net "P3V3_RTC")
	)
	(segment
		(start 134.398004 -86.953344)
		(end 131.697222 -86.953344)
		(width 0.508)
		(layer "In2.Cu")
		(net "P3V3_RTC")
	)
	(segment
		(start 131.697222 -86.953344)
		(end 127.050292 -82.306414)
		(width 0.508)
		(layer "In2.Cu")
		(net "P3V3_RTC")
	)
	(segment
		(start 76.972922 -42.291)
		(end 76.947522 -42.291)
		(width 0.254)
		(layer "F.Cu")
		(net "P3V3_PWR")
	)
	(segment
		(start 74.549 -42.037)
		(end 74.549 -38.989)
		(width 0.254)
		(layer "F.Cu")
		(net "P3V3_PWR")
	)
	(segment
		(start 88.5952 -41.275)
		(end 88.445594 -41.275)
		(width 0.3048)
		(layer "F.Cu")
		(net "P3V3_PWR")
	)
	(segment
		(start 76.947522 -42.291)
		(end 74.803 -42.291)
		(width 0.254)
		(layer "F.Cu")
		(net "P3V3_PWR")
	)
	(segment
		(start 88.5952 -42.2148)
		(end 88.414606 -42.2148)
		(width 0.3048)
		(layer "F.Cu")
		(net "P3V3_PWR")
	)
	(segment
		(start 88.5952 -44.0944)
		(end 88.395048 -44.0944)
		(width 0.3048)
		(layer "F.Cu")
		(net "P3V3_PWR")
	)
	(segment
		(start 88.5952 -43.1546)
		(end 88.454992 -43.1546)
		(width 0.3048)
		(layer "F.Cu")
		(net "P3V3_PWR")
	)
	(segment
		(start 74.803 -42.291)
		(end 74.549 -42.037)
		(width 0.254)
		(layer "F.Cu")
		(net "P3V3_PWR")
	)
	(segment
		(start 88.5952 -45.0342)
		(end 88.433656 -45.0342)
		(width 0.3048)
		(layer "F.Cu")
		(net "P3V3_PWR")
	)
	(segment
		(start 88.5952 -45.974)
		(end 88.394794 -45.974)
		(width 0.3048)
		(layer "F.Cu")
		(net "P3V3_PWR")
	)
	(segment
		(start 74.168 -32.004)
		(end 74.168 -33.02)
		(width 0.254)
		(layer "F.Cu")
		(net "P3V3_PWR")
	)
	(segment
		(start 74.549 -38.989)
		(end 74.803 -38.735)
		(width 0.254)
		(layer "F.Cu")
		(net "P3V3_PWR")
	)
	(via
		(at 74.168 -33.02)
		(size 0.508)
		(drill 0.254)
		(layers "F.Cu" "B.Cu")
		(net "P3V3_PWR")
	)
	(via
		(at 85.598 -41.148)
		(size 0.508)
		(drill 0.254)
		(layers "F.Cu" "B.Cu")
		(net "P3V3_PWR")
	)
	(via
		(at 85.02777 -36.00577)
		(size 0.7112)
		(drill 0.3556)
		(layers "F.Cu" "B.Cu")
		(net "P3V3_PWR")
	)
	(via
		(at 74.803 -38.735)
		(size 0.508)
		(drill 0.254)
		(layers "F.Cu" "B.Cu")
		(net "P3V3_PWR")
	)
	(segment
		(start 82.042 -33.02)
		(end 85.02777 -36.00577)
		(width 0.254)
		(layer "B.Cu")
		(net "P3V3_PWR")
	)
	(segment
		(start 74.803 -37.9095)
		(end 74.803 -38.735)
		(width 0.254)
		(layer "B.Cu")
		(net "P3V3_PWR")
	)
	(segment
		(start 85.02777 -36.00577)
		(end 85.598 -36.576)
		(width 0.254)
		(layer "B.Cu")
		(net "P3V3_PWR")
	)
	(segment
		(start 74.168 -33.02)
		(end 82.042 -33.02)
		(width 0.254)
		(layer "B.Cu")
		(net "P3V3_PWR")
	)
	(segment
		(start 85.598 -36.576)
		(end 85.598 -41.148)
		(width 0.254)
		(layer "B.Cu")
		(net "P3V3_PWR")
	)
	(segment
		(start 35.433254 -104.427274)
		(end 34.995612 -103.989632)
		(width 0.3048)
		(layer "F.Cu")
		(net "P3V3_I2C_MUX")
	)
	(segment
		(start 35.231578 -101.797866)
		(end 36.628324 -101.797866)
		(width 0.3048)
		(layer "F.Cu")
		(net "P3V3_I2C_MUX")
	)
	(segment
		(start 36.628324 -101.797866)
		(end 37.072062 -101.354128)
		(width 0.3048)
		(layer "F.Cu")
		(net "P3V3_I2C_MUX")
	)
	(segment
		(start 37.072062 -101.354128)
		(end 37.072062 -100.5713)
		(width 0.3048)
		(layer "F.Cu")
		(net "P3V3_I2C_MUX")
	)
	(segment
		(start 34.995612 -103.989632)
		(end 34.995612 -102.033832)
		(width 0.3048)
		(layer "F.Cu")
		(net "P3V3_I2C_MUX")
	)
	(segment
		(start 34.995612 -102.033832)
		(end 35.231578 -101.797866)
		(width 0.3048)
		(layer "F.Cu")
		(net "P3V3_I2C_MUX")
	)
	(via
		(at 34.995612 -102.033832)
		(size 0.7112)
		(drill 0.3556)
		(layers "F.Cu" "B.Cu")
		(net "P3V3_I2C_MUX")
	)
	(segment
		(start 121.14911 -78.730348)
		(end 119.806974 -78.730348)
		(width 0.508)
		(layer "F.Cu")
		(net "P3V0_BAT_R")
	)
	(segment
		(start 121.594626 -78.284832)
		(end 121.14911 -78.730348)
		(width 0.508)
		(layer "F.Cu")
		(net "P3V0_BAT_R")
	)
	(segment
		(start 119.806974 -77.841348)
		(end 119.806974 -72.445372)
		(width 0.508)
		(layer "F.Cu")
		(net "P3V0_BAT")
	)
	(segment
		(start 120.200674 -72.051672)
		(end 120.200674 -69.83222)
		(width 0.508)
		(layer "F.Cu")
		(net "P3V0_BAT")
	)
	(segment
		(start 119.806974 -72.445372)
		(end 120.200674 -72.051672)
		(width 0.508)
		(layer "F.Cu")
		(net "P3V0_BAT")
	)
	(segment
		(start 120.200674 -69.83222)
		(end 120.200674 -59.83224)
		(width 0.508)
		(layer "In2.Cu")
		(net "P3V0_BAT")
	)
	(segment
		(start 85.379814 -82.79003)
		(end 83.821524 -82.79003)
		(width 0.3048)
		(layer "F.Cu")
		(net "P1V8_STBY")
	)
	(segment
		(start 156.718 -99.1489)
		(end 154.686 -99.1489)
		(width 0.508)
		(layer "F.Cu")
		(net "P1V8_STBY")
	)
	(segment
		(start 60.1599 -136.4234)
		(end 63.5254 -136.4234)
		(width 0.508)
		(layer "F.Cu")
		(net "P1V8_STBY")
	)
	(segment
		(start 150.680674 -86.25332)
		(end 150.967186 -86.25332)
		(width 0.3048)
		(layer "F.Cu")
		(net "P1V8_STBY")
	)
	(segment
		(start 91.219528 -83.745324)
		(end 90.573352 -84.3915)
		(width 0.508)
		(layer "F.Cu")
		(net "P1V8_STBY")
	)
	(segment
		(start 58.166 -134.4295)
		(end 60.1599 -136.4234)
		(width 0.508)
		(layer "F.Cu")
		(net "P1V8_STBY")
	)
	(segment
		(start 158.242 -99.1489)
		(end 156.718 -99.1489)
		(width 0.508)
		(layer "F.Cu")
		(net "P1V8_STBY")
	)
	(segment
		(start 83.627214 -82.59572)
		(end 82.90052 -82.59572)
		(width 0.508)
		(layer "F.Cu")
		(net "P1V8_STBY")
	)
	(segment
		(start 83.821524 -82.79003)
		(end 83.627214 -82.59572)
		(width 0.3048)
		(layer "F.Cu")
		(net "P1V8_STBY")
	)
	(segment
		(start 82.90052 -82.59572)
		(end 82.8548 -82.55)
		(width 0.508)
		(layer "F.Cu")
		(net "P1V8_STBY")
	)
	(segment
		(start 82.8548 -82.55)
		(end 82.814414 -82.55)
		(width 0.508)
		(layer "F.Cu")
		(net "P1V8_STBY")
	)
	(segment
		(start 90.573352 -84.3915)
		(end 90.2208 -84.3915)
		(width 0.508)
		(layer "F.Cu")
		(net "P1V8_STBY")
	)
	(segment
		(start 91.219528 -82.968338)
		(end 91.219528 -83.745324)
		(width 0.508)
		(layer "F.Cu")
		(net "P1V8_STBY")
	)
	(via
		(at 76.1492 -77.597)
		(size 0.7112)
		(drill 0.3556)
		(layers "F.Cu" "B.Cu")
		(net "P1V8_STBY")
	)
	(via
		(at 129.322322 -72.235314)
		(size 0.508)
		(drill 0.254)
		(layers "F.Cu" "B.Cu")
		(net "P1V8_STBY")
	)
	(via
		(at 129.657348 -66.37401)
		(size 0.508)
		(drill 0.254)
		(layers "F.Cu" "B.Cu")
		(net "P1V8_STBY")
	)
	(via
		(at 63.5254 -136.4234)
		(size 0.508)
		(drill 0.254)
		(layers "F.Cu" "B.Cu")
		(net "P1V8_STBY")
	)
	(via
		(at 82.814414 -82.55)
		(size 0.508)
		(drill 0.254)
		(layers "F.Cu" "B.Cu")
		(net "P1V8_STBY")
	)
	(via
		(at 91.219528 -82.968338)
		(size 0.508)
		(drill 0.254)
		(layers "F.Cu" "B.Cu")
		(net "P1V8_STBY")
	)
	(via
		(at 151.7904 -86.1314)
		(size 0.508)
		(drill 0.254)
		(layers "F.Cu" "B.Cu")
		(net "P1V8_STBY")
	)
	(via
		(at 152.6032 -85.6996)
		(size 0.508)
		(drill 0.254)
		(layers "F.Cu" "B.Cu")
		(net "P1V8_STBY")
	)
	(via
		(at 154.686 -99.1489)
		(size 0.508)
		(drill 0.254)
		(layers "F.Cu" "B.Cu")
		(net "P1V8_STBY")
	)
	(via
		(at 73.1012 -79.1464)
		(size 0.508)
		(drill 0.254)
		(layers "F.Cu" "B.Cu")
		(net "P1V8_STBY")
	)
	(segment
		(start 154.686 -99.1489)
		(end 154.686 -93.347032)
		(width 0.508)
		(layer "B.Cu")
		(net "P1V8_STBY")
	)
	(segment
		(start 154.686 -93.347032)
		(end 154.106626 -92.767658)
		(width 0.508)
		(layer "B.Cu")
		(net "P1V8_STBY")
	)
	(segment
		(start 74.6506 -77.597)
		(end 76.1492 -77.597)
		(width 0.508)
		(layer "B.Cu")
		(net "P1V8_STBY")
	)
	(segment
		(start 154.686 -89.946226)
		(end 154.686 -88.3158)
		(width 0.508)
		(layer "B.Cu")
		(net "P1V8_STBY")
	)
	(segment
		(start 154.106626 -92.767658)
		(end 154.106626 -90.5256)
		(width 0.508)
		(layer "B.Cu")
		(net "P1V8_STBY")
	)
	(segment
		(start 73.1012 -79.1464)
		(end 74.6506 -77.597)
		(width 0.508)
		(layer "B.Cu")
		(net "P1V8_STBY")
	)
	(segment
		(start 154.686 -88.3158)
		(end 152.6032 -86.233)
		(width 0.508)
		(layer "B.Cu")
		(net "P1V8_STBY")
	)
	(segment
		(start 152.6032 -86.233)
		(end 152.6032 -85.6996)
		(width 0.508)
		(layer "B.Cu")
		(net "P1V8_STBY")
	)
	(segment
		(start 154.106626 -90.5256)
		(end 154.686 -89.946226)
		(width 0.508)
		(layer "B.Cu")
		(net "P1V8_STBY")
	)
	(segment
		(start 82.814414 -80.274414)
		(end 82.814414 -82.55)
		(width 0.508)
		(layer "B.Cu")
		(net "P1V8_STBY")
	)
	(segment
		(start 76.1492 -77.597)
		(end 80.137 -77.597)
		(width 0.508)
		(layer "B.Cu")
		(net "P1V8_STBY")
	)
	(segment
		(start 80.137 -77.597)
		(end 82.814414 -80.274414)
		(width 0.508)
		(layer "B.Cu")
		(net "P1V8_STBY")
	)
	(segment
		(start 132.404358 -63.627)
		(end 129.657348 -66.37401)
		(width 0.635)
		(layer "In2.Cu")
		(net "P1V8_STBY")
	)
	(segment
		(start 138.2014 -63.627)
		(end 132.404358 -63.627)
		(width 0.635)
		(layer "In2.Cu")
		(net "P1V8_STBY")
	)
	(segment
		(start 151.7904 -86.1314)
		(end 140.8684 -75.2094)
		(width 0.635)
		(layer "In2.Cu")
		(net "P1V8_STBY")
	)
	(segment
		(start 140.8684 -75.2094)
		(end 140.8684 -66.294)
		(width 0.635)
		(layer "In2.Cu")
		(net "P1V8_STBY")
	)
	(segment
		(start 140.8684 -66.294)
		(end 138.2014 -63.627)
		(width 0.635)
		(layer "In2.Cu")
		(net "P1V8_STBY")
	)
	(segment
		(start 129.107438 -72.450198)
		(end 127.437896 -72.450198)
		(width 0.508)
		(layer "In5.Cu")
		(net "P1V8_STBY")
	)
	(segment
		(start 71.0311 -128.43764)
		(end 69.5706 -129.89814)
		(width 0.508)
		(layer "In5.Cu")
		(net "P1V8_STBY")
	)
	(segment
		(start 69.5706 -131.921758)
		(end 65.068958 -136.4234)
		(width 0.508)
		(layer "In5.Cu")
		(net "P1V8_STBY")
	)
	(segment
		(start 89.89695 -82.968338)
		(end 91.219528 -82.968338)
		(width 0.508)
		(layer "In5.Cu")
		(net "P1V8_STBY")
	)
	(segment
		(start 82.814414 -82.55)
		(end 82.894424 -82.63001)
		(width 0.508)
		(layer "In5.Cu")
		(net "P1V8_STBY")
	)
	(segment
		(start 65.068958 -136.4234)
		(end 63.5254 -136.4234)
		(width 0.508)
		(layer "In5.Cu")
		(net "P1V8_STBY")
	)
	(segment
		(start 89.558622 -82.63001)
		(end 89.89695 -82.968338)
		(width 0.508)
		(layer "In5.Cu")
		(net "P1V8_STBY")
	)
	(segment
		(start 78.638146 -71.0692)
		(end 73.1012 -76.606146)
		(width 0.508)
		(layer "In5.Cu")
		(net "P1V8_STBY")
	)
	(segment
		(start 127.437896 -72.450198)
		(end 126.173738 -73.714356)
		(width 0.508)
		(layer "In5.Cu")
		(net "P1V8_STBY")
	)
	(segment
		(start 115.199668 -73.714356)
		(end 112.554512 -71.0692)
		(width 0.508)
		(layer "In5.Cu")
		(net "P1V8_STBY")
	)
	(segment
		(start 129.322322 -72.235314)
		(end 129.107438 -72.450198)
		(width 0.508)
		(layer "In5.Cu")
		(net "P1V8_STBY")
	)
	(segment
		(start 112.554512 -71.0692)
		(end 78.638146 -71.0692)
		(width 0.508)
		(layer "In5.Cu")
		(net "P1V8_STBY")
	)
	(segment
		(start 73.1012 -76.606146)
		(end 73.1012 -79.1464)
		(width 0.508)
		(layer "In5.Cu")
		(net "P1V8_STBY")
	)
	(segment
		(start 126.173738 -73.714356)
		(end 115.199668 -73.714356)
		(width 0.508)
		(layer "In5.Cu")
		(net "P1V8_STBY")
	)
	(segment
		(start 82.894424 -82.63001)
		(end 89.558622 -82.63001)
		(width 0.508)
		(layer "In5.Cu")
		(net "P1V8_STBY")
	)
	(segment
		(start 71.0311 -81.2165)
		(end 71.0311 -128.43764)
		(width 0.508)
		(layer "In5.Cu")
		(net "P1V8_STBY")
	)
	(segment
		(start 69.5706 -129.89814)
		(end 69.5706 -131.921758)
		(width 0.508)
		(layer "In5.Cu")
		(net "P1V8_STBY")
	)
	(segment
		(start 73.1012 -79.1464)
		(end 71.0311 -81.2165)
		(width 0.508)
		(layer "In5.Cu")
		(net "P1V8_STBY")
	)
	(segment
		(start 147.0152 -84.0994)
		(end 147.0152 -84.396834)
		(width 0.3048)
		(layer "F.Cu")
		(net "P1V8_PWR")
	)
	(segment
		(start 146.2532 -84.0994)
		(end 146.2532 -84.396834)
		(width 0.3048)
		(layer "F.Cu")
		(net "P1V8_PWR")
	)
	(segment
		(start 150.071074 -86.25332)
		(end 149.750018 -86.25332)
		(width 0.3048)
		(layer "F.Cu")
		(net "P1V8_PWR")
	)
	(via
		(at 143.7386 -86.106)
		(size 0.7112)
		(drill 0.3556)
		(layers "F.Cu" "B.Cu")
		(net "P1V8_PWR")
	)
	(segment
		(start 164.105336 -90.826336)
		(end 164.320474 -91.041474)
		(width 0.254)
		(layer "F.Cu")
		(net "P1V8_CLKGEN_A")
	)
	(segment
		(start 163.269422 -90.826336)
		(end 164.105336 -90.826336)
		(width 0.254)
		(layer "F.Cu")
		(net "P1V8_CLKGEN_A")
	)
	(segment
		(start 164.320474 -91.041474)
		(end 164.793168 -91.041474)
		(width 0.254)
		(layer "F.Cu")
		(net "P1V8_CLKGEN_A")
	)
	(segment
		(start 164.793168 -91.041474)
		(end 165.004242 -90.8304)
		(width 0.254)
		(layer "F.Cu")
		(net "P1V8_CLKGEN_A")
	)
	(segment
		(start 165.004242 -90.8304)
		(end 165.735 -90.8304)
		(width 0.254)
		(layer "F.Cu")
		(net "P1V8_CLKGEN_A")
	)
	(via
		(at 164.2364 -92.3036)
		(size 0.7112)
		(drill 0.3556)
		(layers "F.Cu" "B.Cu")
		(net "P1V8_CLKGEN_A")
	)
	(via
		(at 164.793168 -91.041474)
		(size 0.508)
		(drill 0.254)
		(layers "F.Cu" "B.Cu")
		(net "P1V8_CLKGEN_A")
	)
	(segment
		(start 164.2364 -92.3036)
		(end 164.793168 -91.746832)
		(width 0.254)
		(layer "B.Cu")
		(net "P1V8_CLKGEN_A")
	)
	(segment
		(start 163.3855 -91.4527)
		(end 164.2364 -92.3036)
		(width 0.254)
		(layer "B.Cu")
		(net "P1V8_CLKGEN_A")
	)
	(segment
		(start 164.793168 -91.746832)
		(end 164.793168 -91.041474)
		(width 0.254)
		(layer "B.Cu")
		(net "P1V8_CLKGEN_A")
	)
	(segment
		(start 163.3855 -90.3224)
		(end 163.3855 -91.3384)
		(width 0.254)
		(layer "B.Cu")
		(net "P1V8_CLKGEN_A")
	)
	(segment
		(start 163.3855 -91.3384)
		(end 163.3855 -91.4527)
		(width 0.254)
		(layer "B.Cu")
		(net "P1V8_CLKGEN_A")
	)
	(segment
		(start 163.322 -85.105494)
		(end 163.322 -87.122)
		(width 0.508)
		(layer "F.Cu")
		(net "P1V8_CLKGEN")
	)
	(segment
		(start 164.116512 -84.310982)
		(end 163.322 -85.105494)
		(width 0.508)
		(layer "F.Cu")
		(net "P1V8_CLKGEN")
	)
	(segment
		(start 168.646602 -91.159076)
		(end 168.3004 -90.812874)
		(width 0.508)
		(layer "F.Cu")
		(net "P1V8_CLKGEN")
	)
	(segment
		(start 162.53206 -87.65794)
		(end 162.53206 -88.038178)
		(width 0.254)
		(layer "F.Cu")
		(net "P1V8_CLKGEN")
	)
	(segment
		(start 169.768266 -90.308684)
		(end 169.768266 -86.964266)
		(width 0.508)
		(layer "F.Cu")
		(net "P1V8_CLKGEN")
	)
	(segment
		(start 168.3004 -90.812874)
		(end 167.276526 -90.812874)
		(width 0.508)
		(layer "F.Cu")
		(net "P1V8_CLKGEN")
	)
	(segment
		(start 157.374336 -90.826336)
		(end 158.294578 -90.826336)
		(width 0.254)
		(layer "F.Cu")
		(net "P1V8_CLKGEN")
	)
	(segment
		(start 157.1244 -90.5256)
		(end 157.1244 -90.7034)
		(width 0.254)
		(layer "F.Cu")
		(net "P1V8_CLKGEN")
	)
	(segment
		(start 167.95496 -84.310982)
		(end 164.116512 -84.310982)
		(width 0.508)
		(layer "F.Cu")
		(net "P1V8_CLKGEN")
	)
	(segment
		(start 168.917874 -91.159076)
		(end 168.646602 -91.159076)
		(width 0.508)
		(layer "F.Cu")
		(net "P1V8_CLKGEN")
	)
	(segment
		(start 160.528 -98.933)
		(end 159.9819 -98.3869)
		(width 0.508)
		(layer "F.Cu")
		(net "P1V8_CLKGEN")
	)
	(segment
		(start 168.4655 -95.6564)
		(end 168.4655 -96.9645)
		(width 0.508)
		(layer "F.Cu")
		(net "P1V8_CLKGEN")
	)
	(segment
		(start 159.9819 -98.3869)
		(end 159.385 -98.3869)
		(width 0.508)
		(layer "F.Cu")
		(net "P1V8_CLKGEN")
	)
	(segment
		(start 163.068 -87.122)
		(end 162.53206 -87.65794)
		(width 0.254)
		(layer "F.Cu")
		(net "P1V8_CLKGEN")
	)
	(segment
		(start 157.323536 -90.326464)
		(end 157.1244 -90.5256)
		(width 0.254)
		(layer "F.Cu")
		(net "P1V8_CLKGEN")
	)
	(segment
		(start 169.1894 -86.3854)
		(end 168.4655 -86.3854)
		(width 0.508)
		(layer "F.Cu")
		(net "P1V8_CLKGEN")
	)
	(segment
		(start 158.294578 -90.326464)
		(end 157.323536 -90.326464)
		(width 0.254)
		(layer "F.Cu")
		(net "P1V8_CLKGEN")
	)
	(segment
		(start 168.4655 -84.821522)
		(end 167.95496 -84.310982)
		(width 0.508)
		(layer "F.Cu")
		(net "P1V8_CLKGEN")
	)
	(segment
		(start 166.497 -98.933)
		(end 160.528 -98.933)
		(width 0.508)
		(layer "F.Cu")
		(net "P1V8_CLKGEN")
	)
	(segment
		(start 169.768266 -86.964266)
		(end 169.1894 -86.3854)
		(width 0.508)
		(layer "F.Cu")
		(net "P1V8_CLKGEN")
	)
	(segment
		(start 168.917874 -95.204026)
		(end 168.917874 -91.159076)
		(width 0.508)
		(layer "F.Cu")
		(net "P1V8_CLKGEN")
	)
	(segment
		(start 168.4655 -96.9645)
		(end 166.497 -98.933)
		(width 0.508)
		(layer "F.Cu")
		(net "P1V8_CLKGEN")
	)
	(segment
		(start 163.068 -93.853)
		(end 163.322 -93.853)
		(width 0.254)
		(layer "F.Cu")
		(net "P1V8_CLKGEN")
	)
	(segment
		(start 168.917874 -91.159076)
		(end 169.768266 -90.308684)
		(width 0.508)
		(layer "F.Cu")
		(net "P1V8_CLKGEN")
	)
	(segment
		(start 168.4655 -86.3854)
		(end 168.4655 -84.821522)
		(width 0.508)
		(layer "F.Cu")
		(net "P1V8_CLKGEN")
	)
	(segment
		(start 162.53206 -93.114622)
		(end 162.53206 -93.31706)
		(width 0.254)
		(layer "F.Cu")
		(net "P1V8_CLKGEN")
	)
	(segment
		(start 163.322 -87.122)
		(end 163.068 -87.122)
		(width 0.254)
		(layer "F.Cu")
		(net "P1V8_CLKGEN")
	)
	(segment
		(start 168.4655 -95.6564)
		(end 168.917874 -95.204026)
		(width 0.508)
		(layer "F.Cu")
		(net "P1V8_CLKGEN")
	)
	(segment
		(start 167.276526 -90.812874)
		(end 167.259 -90.8304)
		(width 0.508)
		(layer "F.Cu")
		(net "P1V8_CLKGEN")
	)
	(segment
		(start 157.1244 -90.7034)
		(end 157.2514 -90.7034)
		(width 0.254)
		(layer "F.Cu")
		(net "P1V8_CLKGEN")
	)
	(segment
		(start 162.53206 -93.31706)
		(end 163.068 -93.853)
		(width 0.254)
		(layer "F.Cu")
		(net "P1V8_CLKGEN")
	)
	(segment
		(start 157.2514 -90.7034)
		(end 157.374336 -90.826336)
		(width 0.254)
		(layer "F.Cu")
		(net "P1V8_CLKGEN")
	)
	(via
		(at 156.62656 -86.92642)
		(size 0.508)
		(drill 0.254)
		(layers "F.Cu" "B.Cu")
		(net "P1V8_CLKGEN")
	)
	(via
		(at 160.7566 -86.2838)
		(size 0.7112)
		(drill 0.3556)
		(layers "F.Cu" "B.Cu")
		(net "P1V8_CLKGEN")
	)
	(via
		(at 158.147766 -87.53729)
		(size 0.508)
		(drill 0.254)
		(layers "F.Cu" "B.Cu")
		(net "P1V8_CLKGEN")
	)
	(via
		(at 157.1244 -90.7034)
		(size 0.508)
		(drill 0.254)
		(layers "F.Cu" "B.Cu")
		(net "P1V8_CLKGEN")
	)
	(via
		(at 163.322 -93.853)
		(size 0.508)
		(drill 0.254)
		(layers "F.Cu" "B.Cu")
		(net "P1V8_CLKGEN")
	)
	(via
		(at 163.322 -87.122)
		(size 0.508)
		(drill 0.254)
		(layers "F.Cu" "B.Cu")
		(net "P1V8_CLKGEN")
	)
	(via
		(at 157.48 -86.741)
		(size 0.508)
		(drill 0.254)
		(layers "F.Cu" "B.Cu")
		(net "P1V8_CLKGEN")
	)
	(segment
		(start 38.904672 -134.485126)
		(end 38.504876 -134.884922)
		(width 0.3556)
		(layer "F.Cu")
		(net "P1V53_STBY")
	)
	(segment
		(start 41.768014 -157.179772)
		(end 42.16781 -157.579568)
		(width 0.3556)
		(layer "F.Cu")
		(net "P1V53_STBY")
	)
	(segment
		(start 29.660342 -148.495258)
		(end 30.061154 -148.094446)
		(width 0.3556)
		(layer "F.Cu")
		(net "P1V53_STBY")
	)
	(segment
		(start 31.194502 -149.573488)
		(end 30.968188 -149.573488)
		(width 0.3556)
		(layer "F.Cu")
		(net "P1V53_STBY")
	)
	(segment
		(start 31.508954 -163.178744)
		(end 31.762954 -162.924744)
		(width 0.508)
		(layer "F.Cu")
		(net "P1V53_STBY")
	)
	(segment
		(start 33.560512 -164.702744)
		(end 33.985454 -164.702744)
		(width 0.5588)
		(layer "F.Cu")
		(net "P1V53_STBY")
	)
	(segment
		(start 36.10483 -134.884922)
		(end 36.104322 -134.884922)
		(width 0.3556)
		(layer "F.Cu")
		(net "P1V53_STBY")
	)
	(segment
		(start 38.568122 -150.779988)
		(end 38.568376 -150.779988)
		(width 0.3556)
		(layer "F.Cu")
		(net "P1V53_STBY")
	)
	(segment
		(start 39.304468 -134.884922)
		(end 38.904672 -134.485126)
		(width 0.3556)
		(layer "F.Cu")
		(net "P1V53_STBY")
	)
	(segment
		(start 36.967922 -152.379934)
		(end 37.367718 -152.77973)
		(width 0.3556)
		(layer "F.Cu")
		(net "P1V53_STBY")
	)
	(segment
		(start 30.568138 -157.179772)
		(end 30.967934 -157.579568)
		(width 0.3556)
		(layer "F.Cu")
		(net "P1V53_STBY")
	)
	(segment
		(start 36.168076 -156.379926)
		(end 36.168076 -156.386022)
		(width 0.3556)
		(layer "F.Cu")
		(net "P1V53_STBY")
	)
	(segment
		(start 44.64812 -151.47163)
		(end 45.179234 -152.002744)
		(width 0.3556)
		(layer "F.Cu")
		(net "P1V53_STBY")
	)
	(segment
		(start 16.764 -152.8445)
		(end 16.764 -153.6192)
		(width 0.508)
		(layer "F.Cu")
		(net "P1V53_STBY")
	)
	(segment
		(start 31.768288 -157.579568)
		(end 32.168084 -157.179772)
		(width 0.3556)
		(layer "F.Cu")
		(net "P1V53_STBY")
	)
	(segment
		(start 37.773102 -157.179772)
		(end 38.184074 -157.590744)
		(width 0.3556)
		(layer "F.Cu")
		(net "P1V53_STBY")
	)
	(segment
		(start 31.828994 -164.692584)
		(end 33.032954 -164.692584)
		(width 0.5588)
		(layer "F.Cu")
		(net "P1V53_STBY")
	)
	(segment
		(start 39.367968 -150.779988)
		(end 38.968172 -150.380192)
		(width 0.3556)
		(layer "F.Cu")
		(net "P1V53_STBY")
	)
	(segment
		(start 38.184074 -157.590744)
		(end 38.189154 -157.590744)
		(width 0.3556)
		(layer "F.Cu")
		(net "P1V53_STBY")
	)
	(segment
		(start 31.508954 -164.372544)
		(end 31.508954 -163.178744)
		(width 0.508)
		(layer "F.Cu")
		(net "P1V53_STBY")
	)
	(segment
		(start 36.567872 -150.380192)
		(end 37.1348 -149.813264)
		(width 0.3556)
		(layer "F.Cu")
		(net "P1V53_STBY")
	)
	(segment
		(start 29.951172 -150.297388)
		(end 29.660342 -150.006558)
		(width 0.3556)
		(layer "F.Cu")
		(net "P1V53_STBY")
	)
	(segment
		(start 62.0014 -154.2796)
		(end 61.693806 -154.2796)
		(width 0.3048)
		(layer "F.Cu")
		(net "P1V53_STBY")
	)
	(segment
		(start 30.061154 -146.859244)
		(end 28.918154 -146.859244)
		(width 0.3556)
		(layer "F.Cu")
		(net "P1V53_STBY")
	)
	(segment
		(start 41.768014 -151.579834)
		(end 41.876218 -151.47163)
		(width 0.3556)
		(layer "F.Cu")
		(net "P1V53_STBY")
	)
	(segment
		(start 37.768022 -157.179772)
		(end 37.773102 -157.179772)
		(width 0.3556)
		(layer "F.Cu")
		(net "P1V53_STBY")
	)
	(segment
		(start 58.166 -131.6609)
		(end 58.166 -130.81)
		(width 0.508)
		(layer "F.Cu")
		(net "P1V53_STBY")
	)
	(segment
		(start 62.0014 -153.5176)
		(end 61.693806 -153.5176)
		(width 0.3048)
		(layer "F.Cu")
		(net "P1V53_STBY")
	)
	(segment
		(start 39.304722 -134.884922)
		(end 39.304468 -134.884922)
		(width 0.3556)
		(layer "F.Cu")
		(net "P1V53_STBY")
	)
	(segment
		(start 29.96819 -150.297388)
		(end 29.951172 -150.297388)
		(width 0.3556)
		(layer "F.Cu")
		(net "P1V53_STBY")
	)
	(segment
		(start 34.56813 -156.379926)
		(end 34.56813 -156.38526)
		(width 0.3048)
		(layer "F.Cu")
		(net "P1V53_STBY")
	)
	(segment
		(start 39.367968 -156.38018)
		(end 39.767764 -156.779976)
		(width 0.3556)
		(layer "F.Cu")
		(net "P1V53_STBY")
	)
	(segment
		(start 30.061154 -148.094446)
		(end 30.061154 -146.859244)
		(width 0.3556)
		(layer "F.Cu")
		(net "P1V53_STBY")
	)
	(segment
		(start 38.568376 -150.779988)
		(end 38.968172 -150.380192)
		(width 0.3556)
		(layer "F.Cu")
		(net "P1V53_STBY")
	)
	(segment
		(start 40.967914 -156.379926)
		(end 40.567864 -156.779976)
		(width 0.3556)
		(layer "F.Cu")
		(net "P1V53_STBY")
	)
	(segment
		(start 40.168068 -150.779988)
		(end 40.567864 -150.380192)
		(width 0.3556)
		(layer "F.Cu")
		(net "P1V53_STBY")
	)
	(segment
		(start 33.550352 -164.692584)
		(end 33.560512 -164.702744)
		(width 0.5588)
		(layer "F.Cu")
		(net "P1V53_STBY")
	)
	(segment
		(start 30.568138 -150.779988)
		(end 30.168342 -150.380192)
		(width 0.3556)
		(layer "F.Cu")
		(net "P1V53_STBY")
	)
	(segment
		(start 35.704526 -134.485126)
		(end 35.30473 -134.884922)
		(width 0.3556)
		(layer "F.Cu")
		(net "P1V53_STBY")
	)
	(segment
		(start 31.762954 -162.924744)
		(end 31.897574 -162.924744)
		(width 0.508)
		(layer "F.Cu")
		(net "P1V53_STBY")
	)
	(segment
		(start 30.050994 -150.380192)
		(end 29.96819 -150.297388)
		(width 0.3556)
		(layer "F.Cu")
		(net "P1V53_STBY")
	)
	(segment
		(start 33.032954 -164.692584)
		(end 33.550352 -164.692584)
		(width 0.5588)
		(layer "F.Cu")
		(net "P1V53_STBY")
	)
	(segment
		(start 58.166 -130.81)
		(end 58.2168 -130.7592)
		(width 0.508)
		(layer "F.Cu")
		(net "P1V53_STBY")
	)
	(segment
		(start 36.168076 -150.779988)
		(end 36.567872 -150.380192)
		(width 0.3556)
		(layer "F.Cu")
		(net "P1V53_STBY")
	)
	(segment
		(start 32.168084 -157.179772)
		(end 32.56788 -157.579568)
		(width 0.3556)
		(layer "F.Cu")
		(net "P1V53_STBY")
	)
	(segment
		(start 40.576754 -150.371302)
		(end 40.567864 -150.380192)
		(width 0.3556)
		(layer "F.Cu")
		(net "P1V53_STBY")
	)
	(segment
		(start 45.6438 -151.1808)
		(end 45.974 -151.1808)
		(width 0.508)
		(layer "F.Cu")
		(net "P1V53_STBY")
	)
	(segment
		(start 37.1348 -147.007834)
		(end 37.035486 -146.90852)
		(width 0.3556)
		(layer "F.Cu")
		(net "P1V53_STBY")
	)
	(segment
		(start 45.179234 -151.645366)
		(end 45.6438 -151.1808)
		(width 0.508)
		(layer "F.Cu")
		(net "P1V53_STBY")
	)
	(segment
		(start 32.168084 -150.779988)
		(end 32.168084 -150.54707)
		(width 0.3556)
		(layer "F.Cu")
		(net "P1V53_STBY")
	)
	(segment
		(start 40.576754 -146.910044)
		(end 40.576754 -150.371302)
		(width 0.3556)
		(layer "F.Cu")
		(net "P1V53_STBY")
	)
	(segment
		(start 33.985454 -164.702744)
		(end 33.985454 -163.559744)
		(width 0.5588)
		(layer "F.Cu")
		(net "P1V53_STBY")
	)
	(segment
		(start 31.508954 -164.372544)
		(end 31.828994 -164.692584)
		(width 0.5588)
		(layer "F.Cu")
		(net "P1V53_STBY")
	)
	(segment
		(start 39.367968 -156.379926)
		(end 39.367968 -156.38018)
		(width 0.3556)
		(layer "F.Cu")
		(net "P1V53_STBY")
	)
	(segment
		(start 37.1348 -149.813264)
		(end 37.1348 -147.007834)
		(width 0.3556)
		(layer "F.Cu")
		(net "P1V53_STBY")
	)
	(segment
		(start 40.168068 -157.179772)
		(end 40.567864 -157.579568)
		(width 0.3556)
		(layer "F.Cu")
		(net "P1V53_STBY")
	)
	(segment
		(start 34.56813 -156.38526)
		(end 34.968434 -156.785564)
		(width 0.3048)
		(layer "F.Cu")
		(net "P1V53_STBY")
	)
	(segment
		(start 34.56813 -151.579834)
		(end 34.168334 -151.97963)
		(width 0.3556)
		(layer "F.Cu")
		(net "P1V53_STBY")
	)
	(segment
		(start 30.168342 -150.380192)
		(end 30.050994 -150.380192)
		(width 0.3556)
		(layer "F.Cu")
		(net "P1V53_STBY")
	)
	(segment
		(start 29.660342 -150.006558)
		(end 29.660342 -148.495258)
		(width 0.3556)
		(layer "F.Cu")
		(net "P1V53_STBY")
	)
	(segment
		(start 36.168076 -156.386022)
		(end 35.768534 -156.785564)
		(width 0.3556)
		(layer "F.Cu")
		(net "P1V53_STBY")
	)
	(segment
		(start 32.168084 -150.54707)
		(end 31.194502 -149.573488)
		(width 0.3556)
		(layer "F.Cu")
		(net "P1V53_STBY")
	)
	(segment
		(start 41.876218 -151.47163)
		(end 44.64812 -151.47163)
		(width 0.3556)
		(layer "F.Cu")
		(net "P1V53_STBY")
	)
	(segment
		(start 38.968172 -150.380192)
		(end 38.968172 -147.210526)
		(width 0.3556)
		(layer "F.Cu")
		(net "P1V53_STBY")
	)
	(segment
		(start 38.968172 -147.210526)
		(end 38.689026 -146.93138)
		(width 0.3556)
		(layer "F.Cu")
		(net "P1V53_STBY")
	)
	(segment
		(start 45.179234 -152.002744)
		(end 45.179234 -151.645366)
		(width 0.508)
		(layer "F.Cu")
		(net "P1V53_STBY")
	)
	(segment
		(start 36.104322 -134.884922)
		(end 35.704526 -134.485126)
		(width 0.3556)
		(layer "F.Cu")
		(net "P1V53_STBY")
	)
	(via
		(at 30.967934 -157.579568)
		(size 0.4572)
		(drill 0.2032)
		(layers "F.Cu" "B.Cu")
		(net "P1V53_STBY")
	)
	(via
		(at 39.767764 -156.779976)
		(size 0.4572)
		(drill 0.2032)
		(layers "F.Cu" "B.Cu")
		(net "P1V53_STBY")
	)
	(via
		(at 35.768534 -156.785564)
		(size 0.4572)
		(drill 0.2032)
		(layers "F.Cu" "B.Cu")
		(net "P1V53_STBY")
	)
	(via
		(at 34.168334 -151.97963)
		(size 0.4572)
		(drill 0.2032)
		(layers "F.Cu" "B.Cu")
		(net "P1V53_STBY")
	)
	(via
		(at 16.764 -153.6192)
		(size 0.508)
		(drill 0.254)
		(layers "F.Cu" "B.Cu")
		(net "P1V53_STBY")
	)
	(via
		(at 36.567872 -150.380192)
		(size 0.4572)
		(drill 0.2032)
		(layers "F.Cu" "B.Cu")
		(net "P1V53_STBY")
	)
	(via
		(at 38.968172 -150.380192)
		(size 0.4572)
		(drill 0.2032)
		(layers "F.Cu" "B.Cu")
		(net "P1V53_STBY")
	)
	(via
		(at 58.2168 -130.7592)
		(size 0.508)
		(drill 0.254)
		(layers "F.Cu" "B.Cu")
		(net "P1V53_STBY")
	)
	(via
		(at 35.704526 -134.485126)
		(size 0.4572)
		(drill 0.2032)
		(layers "F.Cu" "B.Cu")
		(net "P1V53_STBY")
	)
	(via
		(at 34.968434 -156.785564)
		(size 0.4572)
		(drill 0.2032)
		(layers "F.Cu" "B.Cu")
		(net "P1V53_STBY")
	)
	(via
		(at 42.16781 -157.579568)
		(size 0.508)
		(drill 0.254)
		(layers "F.Cu" "B.Cu")
		(net "P1V53_STBY")
	)
	(via
		(at 40.567864 -157.579568)
		(size 0.508)
		(drill 0.254)
		(layers "F.Cu" "B.Cu")
		(net "P1V53_STBY")
	)
	(via
		(at 38.904672 -134.485126)
		(size 0.4572)
		(drill 0.2032)
		(layers "F.Cu" "B.Cu")
		(net "P1V53_STBY")
	)
	(via
		(at 60.96 -154.5844)
		(size 0.7112)
		(drill 0.4064)
		(layers "F.Cu" "B.Cu")
		(net "P1V53_STBY")
	)
	(via
		(at 30.968188 -149.573488)
		(size 0.4572)
		(drill 0.2032)
		(layers "F.Cu" "B.Cu")
		(net "P1V53_STBY")
	)
	(via
		(at 40.567864 -156.779976)
		(size 0.4572)
		(drill 0.2032)
		(layers "F.Cu" "B.Cu")
		(net "P1V53_STBY")
	)
	(via
		(at 45.974 -151.1808)
		(size 0.508)
		(drill 0.254)
		(layers "F.Cu" "B.Cu")
		(net "P1V53_STBY")
	)
	(via
		(at 37.367718 -152.77973)
		(size 0.4572)
		(drill 0.2032)
		(layers "F.Cu" "B.Cu")
		(net "P1V53_STBY")
	)
	(via
		(at 42.867326 -158.17088)
		(size 0.508)
		(drill 0.254)
		(layers "F.Cu" "B.Cu")
		(net "P1V53_STBY")
	)
	(via
		(at 60.9346 -152.4254)
		(size 0.7112)
		(drill 0.4064)
		(layers "F.Cu" "B.Cu")
		(net "P1V53_STBY")
	)
	(via
		(at 38.189154 -157.590744)
		(size 0.4572)
		(drill 0.2032)
		(layers "F.Cu" "B.Cu")
		(net "P1V53_STBY")
	)
	(via
		(at 38.866826 -158.17088)
		(size 0.508)
		(drill 0.254)
		(layers "F.Cu" "B.Cu")
		(net "P1V53_STBY")
	)
	(via
		(at 30.168342 -150.380192)
		(size 0.4572)
		(drill 0.2032)
		(layers "F.Cu" "B.Cu")
		(net "P1V53_STBY")
	)
	(via
		(at 57.785 -153.289)
		(size 0.508)
		(drill 0.254)
		(layers "F.Cu" "B.Cu")
		(net "P1V53_STBY")
	)
	(via
		(at 60.96 -153.5176)
		(size 0.7112)
		(drill 0.4064)
		(layers "F.Cu" "B.Cu")
		(net "P1V53_STBY")
	)
	(via
		(at 32.56788 -157.579568)
		(size 0.508)
		(drill 0.254)
		(layers "F.Cu" "B.Cu")
		(net "P1V53_STBY")
	)
	(via
		(at 36.449 -158.115)
		(size 0.7112)
		(drill 0.3556)
		(layers "F.Cu" "B.Cu")
		(net "P1V53_STBY")
	)
	(via
		(at 40.567864 -150.380192)
		(size 0.4572)
		(drill 0.2032)
		(layers "F.Cu" "B.Cu")
		(net "P1V53_STBY")
	)
	(via
		(at 31.768288 -157.579568)
		(size 0.4572)
		(drill 0.2032)
		(layers "F.Cu" "B.Cu")
		(net "P1V53_STBY")
	)
	(via
		(at 31.897574 -162.924744)
		(size 0.508)
		(drill 0.254)
		(layers "F.Cu" "B.Cu")
		(net "P1V53_STBY")
	)
	(segment
		(start 45.179234 -143.087598)
		(end 40.420036 -138.3284)
		(width 0.508)
		(layer "B.Cu")
		(net "P1V53_STBY")
	)
	(segment
		(start 40.321992 -138.3284)
		(end 39.751 -137.757408)
		(width 0.508)
		(layer "B.Cu")
		(net "P1V53_STBY")
	)
	(segment
		(start 45.974 -151.1808)
		(end 45.179234 -150.386034)
		(width 0.508)
		(layer "B.Cu")
		(net "P1V53_STBY")
	)
	(segment
		(start 40.420036 -138.3284)
		(end 40.321992 -138.3284)
		(width 0.508)
		(layer "B.Cu")
		(net "P1V53_STBY")
	)
	(segment
		(start 38.931342 -134.485126)
		(end 38.904672 -134.485126)
		(width 0.508)
		(layer "B.Cu")
		(net "P1V53_STBY")
	)
	(segment
		(start 39.751 -135.304784)
		(end 38.931342 -134.485126)
		(width 0.508)
		(layer "B.Cu")
		(net "P1V53_STBY")
	)
	(segment
		(start 45.179234 -150.386034)
		(end 45.179234 -143.087598)
		(width 0.508)
		(layer "B.Cu")
		(net "P1V53_STBY")
	)
	(segment
		(start 39.751 -137.757408)
		(end 39.751 -135.304784)
		(width 0.508)
		(layer "B.Cu")
		(net "P1V53_STBY")
	)
	(segment
		(start 38.383972 -133.964426)
		(end 36.225226 -133.964426)
		(width 0.381)
		(layer "In2.Cu")
		(net "P1V53_STBY")
	)
	(segment
		(start 36.225226 -133.964426)
		(end 35.704526 -134.485126)
		(width 0.381)
		(layer "In2.Cu")
		(net "P1V53_STBY")
	)
	(segment
		(start 38.904672 -134.485126)
		(end 38.383972 -133.964426)
		(width 0.381)
		(layer "In2.Cu")
		(net "P1V53_STBY")
	)
	(segment
		(start 58.2168 -130.7592)
		(end 58.166 -130.81)
		(width 0.508)
		(layer "In5.Cu")
		(net "P1V53_STBY")
	)
	(segment
		(start 57.785 -148.691092)
		(end 57.785 -153.289)
		(width 0.508)
		(layer "In5.Cu")
		(net "P1V53_STBY")
	)
	(segment
		(start 58.166 -130.81)
		(end 58.166 -134.6708)
		(width 0.508)
		(layer "In5.Cu")
		(net "P1V53_STBY")
	)
	(segment
		(start 60.528962 -145.94713)
		(end 57.785 -148.691092)
		(width 0.508)
		(layer "In5.Cu")
		(net "P1V53_STBY")
	)
	(segment
		(start 58.166 -134.6708)
		(end 60.528962 -137.033762)
		(width 0.508)
		(layer "In5.Cu")
		(net "P1V53_STBY")
	)
	(segment
		(start 60.528962 -137.033762)
		(end 60.528962 -145.94713)
		(width 0.508)
		(layer "In5.Cu")
		(net "P1V53_STBY")
	)
	(segment
		(start 62.992 -159.8676)
		(end 61.6204 -159.8676)
		(width 0.508)
		(layer "F.Cu")
		(net "P1V53_PWR")
	)
	(segment
		(start 61.6204 -159.8676)
		(end 61.2902 -160.1978)
		(width 0.508)
		(layer "F.Cu")
		(net "P1V53_PWR")
	)
	(segment
		(start 61.2902 -160.1978)
		(end 61.2902 -161.4551)
		(width 0.508)
		(layer "F.Cu")
		(net "P1V53_PWR")
	)
	(segment
		(start 62.611 -153.5176)
		(end 62.918594 -153.5176)
		(width 0.3048)
		(layer "F.Cu")
		(net "P1V53_PWR")
	)
	(segment
		(start 60.2742 -161.4551)
		(end 61.2902 -161.4551)
		(width 0.508)
		(layer "F.Cu")
		(net "P1V53_PWR")
	)
	(segment
		(start 62.611 -154.2796)
		(end 62.918594 -154.2796)
		(width 0.3048)
		(layer "F.Cu")
		(net "P1V53_PWR")
	)
	(via
		(at 63.0174 -157.988)
		(size 0.7112)
		(drill 0.3556)
		(layers "F.Cu" "B.Cu")
		(net "P1V53_PWR")
	)
	(segment
		(start 33.704784 -132.485384)
		(end 34.10458 -132.88518)
		(width 0.3556)
		(layer "F.Cu")
		(net "P1V26_STBY")
	)
	(segment
		(start 32.904938 -137.284968)
		(end 32.505142 -136.885172)
		(width 0.3556)
		(layer "F.Cu")
		(net "P1V26_STBY")
	)
	(segment
		(start 42.504868 -132.485384)
		(end 42.904664 -132.88518)
		(width 0.3556)
		(layer "F.Cu")
		(net "P1V26_STBY")
	)
	(segment
		(start 34.10458 -129.685034)
		(end 33.704784 -130.08483)
		(width 0.3556)
		(layer "F.Cu")
		(net "P1V26_STBY")
	)
	(segment
		(start 35.704526 -125.685042)
		(end 35.30473 -126.084838)
		(width 0.3556)
		(layer "F.Cu")
		(net "P1V26_STBY")
	)
	(segment
		(start 33.704784 -129.284984)
		(end 33.704784 -129.285238)
		(width 0.3556)
		(layer "F.Cu")
		(net "P1V26_STBY")
	)
	(segment
		(start 42.904664 -129.685034)
		(end 42.504868 -129.285238)
		(width 0.3556)
		(layer "F.Cu")
		(net "P1V26_STBY")
	)
	(segment
		(start 14.224 -113.7158)
		(end 14.224 -114.06378)
		(width 0.3048)
		(layer "F.Cu")
		(net "P1V26_STBY")
	)
	(segment
		(start 32.104838 -135.684768)
		(end 31.705042 -136.084564)
		(width 0.3556)
		(layer "F.Cu")
		(net "P1V26_STBY")
	)
	(segment
		(start 42.504868 -129.285238)
		(end 42.504868 -129.284984)
		(width 0.3556)
		(layer "F.Cu")
		(net "P1V26_STBY")
	)
	(segment
		(start 33.704784 -129.285238)
		(end 34.10458 -129.685034)
		(width 0.3556)
		(layer "F.Cu")
		(net "P1V26_STBY")
	)
	(segment
		(start 37.304726 -134.485126)
		(end 36.90493 -134.884922)
		(width 0.3556)
		(layer "F.Cu")
		(net "P1V26_STBY")
	)
	(segment
		(start 36.10483 -126.084838)
		(end 36.104322 -126.084838)
		(width 0.3556)
		(layer "F.Cu")
		(net "P1V26_STBY")
	)
	(segment
		(start 37.704522 -134.884922)
		(end 37.304726 -134.485126)
		(width 0.3556)
		(layer "F.Cu")
		(net "P1V26_STBY")
	)
	(segment
		(start 14.986 -113.7158)
		(end 14.986 -114.06378)
		(width 0.3048)
		(layer "F.Cu")
		(net "P1V26_STBY")
	)
	(segment
		(start 81.0641 -137.795)
		(end 81.0641 -139.59332)
		(width 0.508)
		(layer "F.Cu")
		(net "P1V26_STBY")
	)
	(segment
		(start 36.104322 -126.084838)
		(end 35.704526 -125.685042)
		(width 0.3556)
		(layer "F.Cu")
		(net "P1V26_STBY")
	)
	(segment
		(start 33.704784 -132.484876)
		(end 33.704784 -132.485384)
		(width 0.3556)
		(layer "F.Cu")
		(net "P1V26_STBY")
	)
	(segment
		(start 42.904664 -132.88518)
		(end 42.504868 -133.284976)
		(width 0.3556)
		(layer "F.Cu")
		(net "P1V26_STBY")
	)
	(segment
		(start 15.2908 -143.383)
		(end 14.2113 -143.383)
		(width 0.508)
		(layer "F.Cu")
		(net "P1V26_STBY")
	)
	(segment
		(start 78.04912 -142.6083)
		(end 73.914 -142.6083)
		(width 0.508)
		(layer "F.Cu")
		(net "P1V26_STBY")
	)
	(segment
		(start 81.0641 -139.59332)
		(end 78.04912 -142.6083)
		(width 0.508)
		(layer "F.Cu")
		(net "P1V26_STBY")
	)
	(segment
		(start 42.504868 -130.08483)
		(end 42.904664 -129.685034)
		(width 0.3556)
		(layer "F.Cu")
		(net "P1V26_STBY")
	)
	(segment
		(start 42.504868 -132.484876)
		(end 42.504868 -132.485384)
		(width 0.3556)
		(layer "F.Cu")
		(net "P1V26_STBY")
	)
	(segment
		(start 34.10458 -132.88518)
		(end 33.704784 -133.284976)
		(width 0.3556)
		(layer "F.Cu")
		(net "P1V26_STBY")
	)
	(segment
		(start 37.704776 -134.884922)
		(end 37.704522 -134.884922)
		(width 0.3556)
		(layer "F.Cu")
		(net "P1V26_STBY")
	)
	(via
		(at 16.42872 -114.906806)
		(size 0.508)
		(drill 0.254)
		(layers "F.Cu" "B.Cu")
		(net "P1V26_STBY")
	)
	(via
		(at 73.914 -142.6083)
		(size 0.508)
		(drill 0.254)
		(layers "F.Cu" "B.Cu")
		(net "P1V26_STBY")
	)
	(via
		(at 16.383 -116.6876)
		(size 0.508)
		(drill 0.254)
		(layers "F.Cu" "B.Cu")
		(net "P1V26_STBY")
	)
	(via
		(at 14.986 -115.443)
		(size 0.7112)
		(drill 0.3556)
		(layers "F.Cu" "B.Cu")
		(net "P1V26_STBY")
	)
	(via
		(at 14.2113 -143.383)
		(size 0.508)
		(drill 0.254)
		(layers "F.Cu" "B.Cu")
		(net "P1V26_STBY")
	)
	(via
		(at 35.704526 -125.685042)
		(size 0.4572)
		(drill 0.2032)
		(layers "F.Cu" "B.Cu")
		(net "P1V26_STBY")
	)
	(via
		(at 16.46428 -115.795298)
		(size 0.508)
		(drill 0.254)
		(layers "F.Cu" "B.Cu")
		(net "P1V26_STBY")
	)
	(via
		(at 42.904664 -132.88518)
		(size 0.4572)
		(drill 0.2032)
		(layers "F.Cu" "B.Cu")
		(net "P1V26_STBY")
	)
	(via
		(at 34.10458 -129.685034)
		(size 0.4572)
		(drill 0.2032)
		(layers "F.Cu" "B.Cu")
		(net "P1V26_STBY")
	)
	(via
		(at 31.705042 -136.084564)
		(size 0.4572)
		(drill 0.2032)
		(layers "F.Cu" "B.Cu")
		(net "P1V26_STBY")
	)
	(via
		(at 37.304726 -134.485126)
		(size 0.4572)
		(drill 0.2032)
		(layers "F.Cu" "B.Cu")
		(net "P1V26_STBY")
	)
	(via
		(at 42.904664 -129.685034)
		(size 0.4572)
		(drill 0.2032)
		(layers "F.Cu" "B.Cu")
		(net "P1V26_STBY")
	)
	(via
		(at 34.10458 -132.88518)
		(size 0.4572)
		(drill 0.2032)
		(layers "F.Cu" "B.Cu")
		(net "P1V26_STBY")
	)
	(via
		(at 32.505142 -136.885172)
		(size 0.4572)
		(drill 0.2032)
		(layers "F.Cu" "B.Cu")
		(net "P1V26_STBY")
	)
	(segment
		(start 34.122614 -129.667)
		(end 34.10458 -129.685034)
		(width 0.508)
		(layer "B.Cu")
		(net "P1V26_STBY")
	)
	(segment
		(start 42.831258 -129.685034)
		(end 42.904664 -129.685034)
		(width 0.508)
		(layer "B.Cu")
		(net "P1V26_STBY")
	)
	(segment
		(start 34.8615 -129.667)
		(end 34.122614 -129.667)
		(width 0.508)
		(layer "B.Cu")
		(net "P1V26_STBY")
	)
	(segment
		(start 42.1005 -130.175)
		(end 42.2656 -130.175)
		(width 0.508)
		(layer "B.Cu")
		(net "P1V26_STBY")
	)
	(segment
		(start 42.4688 -129.9718)
		(end 42.544492 -129.9718)
		(width 0.508)
		(layer "B.Cu")
		(net "P1V26_STBY")
	)
	(segment
		(start 42.544492 -129.9718)
		(end 42.831258 -129.685034)
		(width 0.508)
		(layer "B.Cu")
		(net "P1V26_STBY")
	)
	(segment
		(start 42.536364 -132.51688)
		(end 42.904664 -132.88518)
		(width 0.508)
		(layer "B.Cu")
		(net "P1V26_STBY")
	)
	(segment
		(start 35.2425 -132.588)
		(end 34.40176 -132.588)
		(width 0.508)
		(layer "B.Cu")
		(net "P1V26_STBY")
	)
	(segment
		(start 36.377118 -126.357634)
		(end 35.704526 -125.685042)
		(width 0.508)
		(layer "B.Cu")
		(net "P1V26_STBY")
	)
	(segment
		(start 34.40176 -132.588)
		(end 34.10458 -132.88518)
		(width 0.508)
		(layer "B.Cu")
		(net "P1V26_STBY")
	)
	(segment
		(start 36.377118 -126.54534)
		(end 36.377118 -126.357634)
		(width 0.508)
		(layer "B.Cu")
		(net "P1V26_STBY")
	)
	(segment
		(start 42.105326 -132.51688)
		(end 42.536364 -132.51688)
		(width 0.508)
		(layer "B.Cu")
		(net "P1V26_STBY")
	)
	(segment
		(start 42.2656 -130.175)
		(end 42.4688 -129.9718)
		(width 0.508)
		(layer "B.Cu")
		(net "P1V26_STBY")
	)
	(segment
		(start 37.719 -134.070852)
		(end 37.304726 -134.485126)
		(width 0.508)
		(layer "B.Cu")
		(net "P1V26_STBY")
	)
	(segment
		(start 37.719 -133.4135)
		(end 37.719 -134.070852)
		(width 0.508)
		(layer "B.Cu")
		(net "P1V26_STBY")
	)
	(segment
		(start 39.915846 -137.922254)
		(end 40.321992 -138.3284)
		(width 0.508)
		(layer "In2.Cu")
		(net "P1V26_STBY")
	)
	(segment
		(start 31.705042 -136.085072)
		(end 31.705042 -136.084564)
		(width 0.381)
		(layer "In2.Cu")
		(net "P1V26_STBY")
	)
	(segment
		(start 41.0718 -138.3284)
		(end 45.4152 -142.6718)
		(width 0.508)
		(layer "In2.Cu")
		(net "P1V26_STBY")
	)
	(segment
		(start 70.59549 -142.6083)
		(end 73.914 -142.6083)
		(width 0.508)
		(layer "In2.Cu")
		(net "P1V26_STBY")
	)
	(segment
		(start 40.321992 -138.3284)
		(end 41.0718 -138.3284)
		(width 0.508)
		(layer "In2.Cu")
		(net "P1V26_STBY")
	)
	(segment
		(start 46.30928 -144.93748)
		(end 68.26631 -144.93748)
		(width 0.508)
		(layer "In2.Cu")
		(net "P1V26_STBY")
	)
	(segment
		(start 45.4152 -144.0434)
		(end 46.30928 -144.93748)
		(width 0.508)
		(layer "In2.Cu")
		(net "P1V26_STBY")
	)
	(segment
		(start 45.4152 -142.6718)
		(end 45.4152 -144.0434)
		(width 0.508)
		(layer "In2.Cu")
		(net "P1V26_STBY")
	)
	(segment
		(start 41.278302 -132.88518)
		(end 39.915846 -134.247636)
		(width 0.508)
		(layer "In2.Cu")
		(net "P1V26_STBY")
	)
	(segment
		(start 42.904664 -132.88518)
		(end 41.278302 -132.88518)
		(width 0.508)
		(layer "In2.Cu")
		(net "P1V26_STBY")
	)
	(segment
		(start 68.26631 -144.93748)
		(end 70.59549 -142.6083)
		(width 0.508)
		(layer "In2.Cu")
		(net "P1V26_STBY")
	)
	(segment
		(start 32.505142 -136.885172)
		(end 31.705042 -136.085072)
		(width 0.381)
		(layer "In2.Cu")
		(net "P1V26_STBY")
	)
	(segment
		(start 39.915846 -134.247636)
		(end 39.915846 -137.922254)
		(width 0.508)
		(layer "In2.Cu")
		(net "P1V26_STBY")
	)
	(segment
		(start 22.865334 -143.10995)
		(end 23.537926 -142.437358)
		(width 0.381)
		(layer "In5.Cu")
		(net "P1V26_STBY")
	)
	(segment
		(start 33.025842 -138.396218)
		(end 33.025842 -137.469118)
		(width 0.381)
		(layer "In5.Cu")
		(net "P1V26_STBY")
	)
	(segment
		(start 33.025588 -137.468864)
		(end 33.025588 -137.405618)
		(width 0.381)
		(layer "In5.Cu")
		(net "P1V26_STBY")
	)
	(segment
		(start 14.2113 -143.383)
		(end 14.2494 -143.3449)
		(width 0.381)
		(layer "In5.Cu")
		(net "P1V26_STBY")
	)
	(segment
		(start 33.025588 -137.405618)
		(end 32.505142 -136.885172)
		(width 0.381)
		(layer "In5.Cu")
		(net "P1V26_STBY")
	)
	(segment
		(start 33.025842 -137.469118)
		(end 33.025588 -137.468864)
		(width 0.381)
		(layer "In5.Cu")
		(net "P1V26_STBY")
	)
	(segment
		(start 32.416496 -139.005564)
		(end 33.025842 -138.396218)
		(width 0.381)
		(layer "In5.Cu")
		(net "P1V26_STBY")
	)
	(segment
		(start 33.888934 -133.126734)
		(end 33.888934 -133.100826)
		(width 0.508)
		(layer "In5.Cu")
		(net "P1V26_STBY")
	)
	(segment
		(start 21.89734 -143.100044)
		(end 21.979128 -143.100044)
		(width 0.381)
		(layer "In5.Cu")
		(net "P1V26_STBY")
	)
	(segment
		(start 27.950668 -138.193018)
		(end 27.950668 -135.012684)
		(width 0.508)
		(layer "In5.Cu")
		(net "P1V26_STBY")
	)
	(segment
		(start 24.6126 -141.05128)
		(end 26.15692 -141.05128)
		(width 0.381)
		(layer "In5.Cu")
		(net "P1V26_STBY")
	)
	(segment
		(start 21.09597 -143.11249)
		(end 21.884894 -143.11249)
		(width 0.381)
		(layer "In5.Cu")
		(net "P1V26_STBY")
	)
	(segment
		(start 22.488906 -143.10995)
		(end 22.865334 -143.10995)
		(width 0.381)
		(layer "In5.Cu")
		(net "P1V26_STBY")
	)
	(segment
		(start 20.67306 -143.5354)
		(end 21.09597 -143.11249)
		(width 0.381)
		(layer "In5.Cu")
		(net "P1V26_STBY")
	)
	(segment
		(start 23.537926 -142.125954)
		(end 24.6126 -141.05128)
		(width 0.381)
		(layer "In5.Cu")
		(net "P1V26_STBY")
	)
	(segment
		(start 33.546288 -133.46938)
		(end 33.888934 -133.126734)
		(width 0.508)
		(layer "In5.Cu")
		(net "P1V26_STBY")
	)
	(segment
		(start 29.493972 -133.46938)
		(end 33.546288 -133.46938)
		(width 0.508)
		(layer "In5.Cu")
		(net "P1V26_STBY")
	)
	(segment
		(start 22.486366 -143.11249)
		(end 22.488906 -143.10995)
		(width 0.381)
		(layer "In5.Cu")
		(net "P1V26_STBY")
	)
	(segment
		(start 21.979128 -143.100044)
		(end 21.991574 -143.11249)
		(width 0.381)
		(layer "In5.Cu")
		(net "P1V26_STBY")
	)
	(segment
		(start 14.2494 -143.3449)
		(end 14.4399 -143.5354)
		(width 0.381)
		(layer "In5.Cu")
		(net "P1V26_STBY")
	)
	(segment
		(start 21.991574 -143.11249)
		(end 22.486366 -143.11249)
		(width 0.381)
		(layer "In5.Cu")
		(net "P1V26_STBY")
	)
	(segment
		(start 21.884894 -143.11249)
		(end 21.89734 -143.100044)
		(width 0.381)
		(layer "In5.Cu")
		(net "P1V26_STBY")
	)
	(segment
		(start 26.15692 -141.05128)
		(end 28.202636 -139.005564)
		(width 0.381)
		(layer "In5.Cu")
		(net "P1V26_STBY")
	)
	(segment
		(start 27.950668 -138.753596)
		(end 27.950668 -138.193018)
		(width 0.381)
		(layer "In5.Cu")
		(net "P1V26_STBY")
	)
	(segment
		(start 33.888934 -133.100826)
		(end 34.10458 -132.88518)
		(width 0.508)
		(layer "In5.Cu")
		(net "P1V26_STBY")
	)
	(segment
		(start 14.4399 -143.5354)
		(end 20.67306 -143.5354)
		(width 0.381)
		(layer "In5.Cu")
		(net "P1V26_STBY")
	)
	(segment
		(start 23.537926 -142.437358)
		(end 23.537926 -142.125954)
		(width 0.381)
		(layer "In5.Cu")
		(net "P1V26_STBY")
	)
	(segment
		(start 28.202636 -139.005564)
		(end 32.416496 -139.005564)
		(width 0.381)
		(layer "In5.Cu")
		(net "P1V26_STBY")
	)
	(segment
		(start 27.950668 -135.012684)
		(end 29.493972 -133.46938)
		(width 0.508)
		(layer "In5.Cu")
		(net "P1V26_STBY")
	)
	(segment
		(start 28.202636 -139.005564)
		(end 27.950668 -138.753596)
		(width 0.381)
		(layer "In5.Cu")
		(net "P1V26_STBY")
	)
	(segment
		(start 14.986 -113.1062)
		(end 14.986 -112.75822)
		(width 0.3048)
		(layer "F.Cu")
		(net "P1V26_PWR")
	)
	(segment
		(start 14.224 -113.1062)
		(end 14.224 -112.75822)
		(width 0.3048)
		(layer "F.Cu")
		(net "P1V26_PWR")
	)
	(via
		(at 15.367 -111.633)
		(size 0.7112)
		(drill 0.3556)
		(layers "F.Cu" "B.Cu")
		(net "P1V26_PWR")
	)
	(segment
		(start 24.4856 -183.7436)
		(end 24.4856 -181.0004)
		(width 0.508)
		(layer "F.Cu")
		(net "P12V_PCIE")
	)
	(segment
		(start 23.5458 -184.6834)
		(end 24.4856 -183.7436)
		(width 0.508)
		(layer "F.Cu")
		(net "P12V_PCIE")
	)
	(segment
		(start 38.878256 -81.545176)
		(end 38.878256 -81.858358)
		(width 0.508)
		(layer "F.Cu")
		(net "P12V_PCIE")
	)
	(segment
		(start 15.2019 -173.4693)
		(end 15.4178 -173.2534)
		(width 0.508)
		(layer "F.Cu")
		(net "P12V_PCIE")
	)
	(segment
		(start 30.099 -223.901)
		(end 30.100016 -223.902016)
		(width 0.508)
		(layer "F.Cu")
		(net "P12V_PCIE")
	)
	(segment
		(start 23.2283 -179.7431)
		(end 23.2283 -178.3461)
		(width 0.254)
		(layer "F.Cu")
		(net "P12V_PCIE")
	)
	(segment
		(start 30.861 -223.901)
		(end 30.900116 -223.940116)
		(width 0.508)
		(layer "F.Cu")
		(net "P12V_PCIE")
	)
	(segment
		(start 21.0947 -194.7926)
		(end 23.1902 -194.7926)
		(width 0.508)
		(layer "F.Cu")
		(net "P12V_PCIE")
	)
	(segment
		(start 29.464 -223.774)
		(end 29.30017 -223.93783)
		(width 0.508)
		(layer "F.Cu")
		(net "P12V_PCIE")
	)
	(segment
		(start 36.72713 -79.466694)
		(end 36.799774 -79.466694)
		(width 0.508)
		(layer "F.Cu")
		(net "P12V_PCIE")
	)
	(segment
		(start 30.100016 -223.902016)
		(end 30.100016 -225.54438)
		(width 0.508)
		(layer "F.Cu")
		(net "P12V_PCIE")
	)
	(segment
		(start 25.4762 -210.6676)
		(end 23.3172 -210.6676)
		(width 0.508)
		(layer "F.Cu")
		(net "P12V_PCIE")
	)
	(segment
		(start 24.4856 -181.0004)
		(end 23.2283 -179.7431)
		(width 0.508)
		(layer "F.Cu")
		(net "P12V_PCIE")
	)
	(segment
		(start 23.622 -193.802)
		(end 23.1902 -194.2338)
		(width 0.508)
		(layer "F.Cu")
		(net "P12V_PCIE")
	)
	(segment
		(start 23.1902 -196.667374)
		(end 23.1902 -194.7926)
		(width 0.508)
		(layer "F.Cu")
		(net "P12V_PCIE")
	)
	(segment
		(start 52.671726 -38.413436)
		(end 53.453538 -38.413436)
		(width 0.508)
		(layer "F.Cu")
		(net "P12V_PCIE")
	)
	(segment
		(start 30.900116 -223.940116)
		(end 30.900116 -225.54438)
		(width 0.508)
		(layer "F.Cu")
		(net "P12V_PCIE")
	)
	(segment
		(start 23.1902 -194.2338)
		(end 23.1902 -194.7926)
		(width 0.508)
		(layer "F.Cu")
		(net "P12V_PCIE")
	)
	(segment
		(start 36.799774 -79.466694)
		(end 38.878256 -81.545176)
		(width 0.508)
		(layer "F.Cu")
		(net "P12V_PCIE")
	)
	(segment
		(start 33.300162 -223.868742)
		(end 33.300162 -225.54438)
		(width 0.508)
		(layer "F.Cu")
		(net "P12V_PCIE")
	)
	(segment
		(start 21.0947 -188.1886)
		(end 21.0947 -189.2046)
		(width 0.508)
		(layer "F.Cu")
		(net "P12V_PCIE")
	)
	(segment
		(start 14.5288 -173.4693)
		(end 15.2019 -173.4693)
		(width 0.508)
		(layer "F.Cu")
		(net "P12V_PCIE")
	)
	(segment
		(start 23.241 -189.2046)
		(end 23.5458 -188.8998)
		(width 0.508)
		(layer "F.Cu")
		(net "P12V_PCIE")
	)
	(segment
		(start 22.200362 -197.657212)
		(end 23.1902 -196.667374)
		(width 0.508)
		(layer "F.Cu")
		(net "P12V_PCIE")
	)
	(segment
		(start 31.75 -223.901)
		(end 31.699962 -223.951038)
		(width 0.508)
		(layer "F.Cu")
		(net "P12V_PCIE")
	)
	(segment
		(start 31.699962 -223.951038)
		(end 31.699962 -225.54438)
		(width 0.508)
		(layer "F.Cu")
		(net "P12V_PCIE")
	)
	(segment
		(start 9.5758 -176.149)
		(end 9.81456 -176.38776)
		(width 0.508)
		(layer "F.Cu")
		(net "P12V_PCIE")
	)
	(segment
		(start 24.1173 -173.2026)
		(end 23.1013 -173.2026)
		(width 0.508)
		(layer "F.Cu")
		(net "P12V_PCIE")
	)
	(segment
		(start 23.241 -189.6618)
		(end 23.622 -190.0428)
		(width 0.508)
		(layer "F.Cu")
		(net "P12V_PCIE")
	)
	(segment
		(start 22.200362 -209.550762)
		(end 22.200362 -197.657212)
		(width 0.508)
		(layer "F.Cu")
		(net "P12V_PCIE")
	)
	(segment
		(start 24.1173 -172.1739)
		(end 24.1173 -173.2026)
		(width 0.508)
		(layer "F.Cu")
		(net "P12V_PCIE")
	)
	(segment
		(start 23.3172 -210.6676)
		(end 22.200362 -209.550762)
		(width 0.508)
		(layer "F.Cu")
		(net "P12V_PCIE")
	)
	(segment
		(start 53.453538 -38.413436)
		(end 53.461412 -38.405562)
		(width 0.508)
		(layer "F.Cu")
		(net "P12V_PCIE")
	)
	(segment
		(start 23.241 -189.2046)
		(end 23.241 -189.6618)
		(width 0.508)
		(layer "F.Cu")
		(net "P12V_PCIE")
	)
	(segment
		(start 23.5458 -188.8998)
		(end 23.5458 -184.6834)
		(width 0.508)
		(layer "F.Cu")
		(net "P12V_PCIE")
	)
	(segment
		(start 32.500062 -223.777302)
		(end 32.500062 -225.54438)
		(width 0.508)
		(layer "F.Cu")
		(net "P12V_PCIE")
	)
	(segment
		(start 21.0947 -189.2046)
		(end 23.241 -189.2046)
		(width 0.508)
		(layer "F.Cu")
		(net "P12V_PCIE")
	)
	(segment
		(start 23.622 -190.0428)
		(end 23.622 -193.802)
		(width 0.508)
		(layer "F.Cu")
		(net "P12V_PCIE")
	)
	(segment
		(start 9.81456 -176.38776)
		(end 10.70102 -176.38776)
		(width 0.508)
		(layer "F.Cu")
		(net "P12V_PCIE")
	)
	(segment
		(start 29.30017 -223.93783)
		(end 29.30017 -225.54438)
		(width 0.508)
		(layer "F.Cu")
		(net "P12V_PCIE")
	)
	(via
		(at 30.48 -214.249)
		(size 0.508)
		(drill 0.254)
		(layers "F.Cu" "B.Cu")
		(net "P12V_PCIE")
	)
	(via
		(at 53.461412 -38.405562)
		(size 0.508)
		(drill 0.254)
		(layers "F.Cu" "B.Cu")
		(net "P12V_PCIE")
	)
	(via
		(at 32.131 -221.234)
		(size 0.508)
		(drill 0.254)
		(layers "F.Cu" "B.Cu")
		(net "P12V_PCIE")
	)
	(via
		(at 30.48 -222.25)
		(size 0.508)
		(drill 0.254)
		(layers "F.Cu" "B.Cu")
		(net "P12V_PCIE")
	)
	(via
		(at 21.717 -205.1558)
		(size 0.7112)
		(drill 0.3556)
		(layers "F.Cu" "B.Cu")
		(net "P12V_PCIE")
	)
	(via
		(at 39.376604 -53.99532)
		(size 0.508)
		(drill 0.254)
		(layers "F.Cu" "B.Cu")
		(net "P12V_PCIE")
	)
	(via
		(at 30.48 -219.71)
		(size 0.508)
		(drill 0.254)
		(layers "F.Cu" "B.Cu")
		(net "P12V_PCIE")
	)
	(via
		(at 27.813 -212.471)
		(size 0.7112)
		(drill 0.3556)
		(layers "F.Cu" "B.Cu")
		(net "P12V_PCIE")
	)
	(via
		(at 15.4178 -173.2534)
		(size 0.508)
		(drill 0.254)
		(layers "F.Cu" "B.Cu")
		(net "P12V_PCIE")
	)
	(via
		(at 4.445 -179.4002)
		(size 0.508)
		(drill 0.254)
		(layers "F.Cu" "B.Cu")
		(net "P12V_PCIE")
	)
	(via
		(at 27.3304 -209.677)
		(size 0.508)
		(drill 0.254)
		(layers "F.Cu" "B.Cu")
		(net "P12V_PCIE")
	)
	(via
		(at 32.766 -222.25)
		(size 0.508)
		(drill 0.254)
		(layers "F.Cu" "B.Cu")
		(net "P12V_PCIE")
	)
	(via
		(at 24.1173 -172.1739)
		(size 0.508)
		(drill 0.254)
		(layers "F.Cu" "B.Cu")
		(net "P12V_PCIE")
	)
	(via
		(at 30.48 -216.789)
		(size 0.508)
		(drill 0.254)
		(layers "F.Cu" "B.Cu")
		(net "P12V_PCIE")
	)
	(via
		(at 26.2128 -209.6516)
		(size 0.508)
		(drill 0.254)
		(layers "F.Cu" "B.Cu")
		(net "P12V_PCIE")
	)
	(via
		(at 32.131 -223.0628)
		(size 0.508)
		(drill 0.254)
		(layers "F.Cu" "B.Cu")
		(net "P12V_PCIE")
	)
	(via
		(at 10.70102 -176.38776)
		(size 0.508)
		(drill 0.254)
		(layers "F.Cu" "B.Cu")
		(net "P12V_PCIE")
	)
	(via
		(at 31.623 -222.25)
		(size 0.508)
		(drill 0.254)
		(layers "F.Cu" "B.Cu")
		(net "P12V_PCIE")
	)
	(via
		(at 29.845 -223.0628)
		(size 0.508)
		(drill 0.254)
		(layers "F.Cu" "B.Cu")
		(net "P12V_PCIE")
	)
	(via
		(at 29.337 -209.677)
		(size 0.508)
		(drill 0.254)
		(layers "F.Cu" "B.Cu")
		(net "P12V_PCIE")
	)
	(via
		(at 23.2283 -179.7431)
		(size 0.508)
		(drill 0.254)
		(layers "F.Cu" "B.Cu")
		(net "P12V_PCIE")
	)
	(via
		(at 30.988 -223.0628)
		(size 0.508)
		(drill 0.254)
		(layers "F.Cu" "B.Cu")
		(net "P12V_PCIE")
	)
	(via
		(at 26.7716 -210.4898)
		(size 0.508)
		(drill 0.254)
		(layers "F.Cu" "B.Cu")
		(net "P12V_PCIE")
	)
	(via
		(at 27.9146 -210.5152)
		(size 0.508)
		(drill 0.254)
		(layers "F.Cu" "B.Cu")
		(net "P12V_PCIE")
	)
	(via
		(at 31.0388 -211.2518)
		(size 0.7112)
		(drill 0.3556)
		(layers "F.Cu" "B.Cu")
		(net "P12V_PCIE")
	)
	(via
		(at 4.445 -104.742996)
		(size 0.508)
		(drill 0.254)
		(layers "F.Cu" "B.Cu")
		(net "P12V_PCIE")
	)
	(via
		(at 36.72713 -79.466694)
		(size 0.508)
		(drill 0.254)
		(layers "F.Cu" "B.Cu")
		(net "P12V_PCIE")
	)
	(arc
		(start 33.1978 -223.6216)
		(mid 33.273565 -223.73499)
		(end 33.300162 -223.868742)
		(width 0.508)
		(layer "F.Cu")
		(net "P12V_PCIE")
	)
	(arc
		(start 32.512 -223.7486)
		(mid 32.503201 -223.761769)
		(end 32.500062 -223.777302)
		(width 0.508)
		(layer "F.Cu")
		(net "P12V_PCIE")
	)
	(segment
		(start 21.717 -208.0514)
		(end 21.717 -205.1558)
		(width 0.254)
		(layer "B.Cu")
		(net "P12V_PCIE")
	)
	(segment
		(start 29.30017 -223.81083)
		(end 29.30017 -225.92538)
		(width 0.508)
		(layer "B.Cu")
		(net "P12V_PCIE")
	)
	(segment
		(start 33.147 -223.774)
		(end 33.300162 -223.927162)
		(width 0.508)
		(layer "B.Cu")
		(net "P12V_PCIE")
	)
	(segment
		(start 30.900116 -225.92538)
		(end 30.900116 -223.27489)
		(width 0.508)
		(layer "B.Cu")
		(net "P12V_PCIE")
	)
	(segment
		(start 32.512 -223.774)
		(end 32.500062 -223.785938)
		(width 0.508)
		(layer "B.Cu")
		(net "P12V_PCIE")
	)
	(segment
		(start 33.300162 -223.927162)
		(end 33.300162 -225.92538)
		(width 0.508)
		(layer "B.Cu")
		(net "P12V_PCIE")
	)
	(segment
		(start 39.376604 -53.99532)
		(end 36.72713 -56.644794)
		(width 0.508)
		(layer "B.Cu")
		(net "P12V_PCIE")
	)
	(segment
		(start 26.2128 -209.6516)
		(end 23.3172 -209.6516)
		(width 0.254)
		(layer "B.Cu")
		(net "P12V_PCIE")
	)
	(segment
		(start 30.100016 -223.317816)
		(end 30.100016 -225.92538)
		(width 0.508)
		(layer "B.Cu")
		(net "P12V_PCIE")
	)
	(segment
		(start 32.500062 -223.785938)
		(end 32.500062 -225.92538)
		(width 0.508)
		(layer "B.Cu")
		(net "P12V_PCIE")
	)
	(segment
		(start 29.845 -223.0628)
		(end 30.100016 -223.317816)
		(width 0.508)
		(layer "B.Cu")
		(net "P12V_PCIE")
	)
	(segment
		(start 23.3172 -209.6516)
		(end 21.717 -208.0514)
		(width 0.254)
		(layer "B.Cu")
		(net "P12V_PCIE")
	)
	(segment
		(start 29.845 -223.0628)
		(end 29.443934 -223.46412)
		(width 0.508)
		(layer "B.Cu")
		(net "P12V_PCIE")
	)
	(segment
		(start 31.699962 -225.92538)
		(end 31.699962 -223.697038)
		(width 0.508)
		(layer "B.Cu")
		(net "P12V_PCIE")
	)
	(segment
		(start 36.72713 -56.644794)
		(end 36.72713 -79.466694)
		(width 0.508)
		(layer "B.Cu")
		(net "P12V_PCIE")
	)
	(arc
		(start 30.900116 -223.27489)
		(mid 30.92295 -223.160095)
		(end 30.988 -223.0628)
		(width 0.508)
		(layer "B.Cu")
		(net "P12V_PCIE")
	)
	(arc
		(start 29.443934 -223.46412)
		(mid 29.337563 -223.623177)
		(end 29.30017 -223.81083)
		(width 0.508)
		(layer "B.Cu")
		(net "P12V_PCIE")
	)
	(segment
		(start 10.487152 -80.01)
		(end 11.426952 -80.9498)
		(width 0.508)
		(layer "In2.Cu")
		(net "P12V_PCIE")
	)
	(segment
		(start 26.411682 -78.2574)
		(end 27.61361 -77.055472)
		(width 0.508)
		(layer "In2.Cu")
		(net "P12V_PCIE")
	)
	(segment
		(start 34.319718 -77.055472)
		(end 36.72713 -79.462884)
		(width 0.508)
		(layer "In2.Cu")
		(net "P12V_PCIE")
	)
	(segment
		(start 10.70102 -176.38776)
		(end 9.85012 -177.23866)
		(width 0.508)
		(layer "In2.Cu")
		(net "P12V_PCIE")
	)
	(segment
		(start 36.72713 -79.462884)
		(end 36.72713 -79.466694)
		(width 0.508)
		(layer "In2.Cu")
		(net "P12V_PCIE")
	)
	(segment
		(start 8.909812 -80.01)
		(end 10.487152 -80.01)
		(width 0.508)
		(layer "In2.Cu")
		(net "P12V_PCIE")
	)
	(segment
		(start 6.406642 -80.01)
		(end 7.194042 -80.01)
		(width 0.508)
		(layer "In2.Cu")
		(net "P12V_PCIE")
	)
	(segment
		(start 53.461412 -38.405562)
		(end 53.461412 -39.910512)
		(width 0.508)
		(layer "In2.Cu")
		(net "P12V_PCIE")
	)
	(segment
		(start 53.461412 -39.910512)
		(end 39.376604 -53.99532)
		(width 0.508)
		(layer "In2.Cu")
		(net "P12V_PCIE")
	)
	(segment
		(start 4.445 -81.971642)
		(end 6.406642 -80.01)
		(width 0.508)
		(layer "In2.Cu")
		(net "P12V_PCIE")
	)
	(segment
		(start 24.1173 -172.1739)
		(end 24.1173 -178.8541)
		(width 0.508)
		(layer "In2.Cu")
		(net "P12V_PCIE")
	)
	(segment
		(start 9.85012 -177.23866)
		(end 7.51586 -177.23866)
		(width 0.508)
		(layer "In2.Cu")
		(net "P12V_PCIE")
	)
	(segment
		(start 11.426952 -80.9498)
		(end 22.456394 -80.9498)
		(width 0.508)
		(layer "In2.Cu")
		(net "P12V_PCIE")
	)
	(segment
		(start 8.325612 -80.5942)
		(end 8.909812 -80.01)
		(width 0.508)
		(layer "In2.Cu")
		(net "P12V_PCIE")
	)
	(segment
		(start 7.194042 -80.01)
		(end 7.778242 -80.5942)
		(width 0.508)
		(layer "In2.Cu")
		(net "P12V_PCIE")
	)
	(segment
		(start 22.456394 -80.9498)
		(end 25.148794 -78.2574)
		(width 0.508)
		(layer "In2.Cu")
		(net "P12V_PCIE")
	)
	(segment
		(start 7.778242 -80.5942)
		(end 8.325612 -80.5942)
		(width 0.508)
		(layer "In2.Cu")
		(net "P12V_PCIE")
	)
	(segment
		(start 4.445 -104.742996)
		(end 4.445 -81.971642)
		(width 0.508)
		(layer "In2.Cu")
		(net "P12V_PCIE")
	)
	(segment
		(start 7.51586 -177.23866)
		(end 5.35432 -179.4002)
		(width 0.508)
		(layer "In2.Cu")
		(net "P12V_PCIE")
	)
	(segment
		(start 25.148794 -78.2574)
		(end 26.411682 -78.2574)
		(width 0.508)
		(layer "In2.Cu")
		(net "P12V_PCIE")
	)
	(segment
		(start 5.35432 -179.4002)
		(end 4.445 -179.4002)
		(width 0.508)
		(layer "In2.Cu")
		(net "P12V_PCIE")
	)
	(segment
		(start 27.61361 -77.055472)
		(end 34.319718 -77.055472)
		(width 0.508)
		(layer "In2.Cu")
		(net "P12V_PCIE")
	)
	(segment
		(start 24.1173 -178.8541)
		(end 23.2283 -179.7431)
		(width 0.508)
		(layer "In2.Cu")
		(net "P12V_PCIE")
	)
	(segment
		(start 16.4973 -172.1739)
		(end 24.1173 -172.1739)
		(width 0.508)
		(layer "In2.Cu")
		(net "P12V_PCIE")
	)
	(segment
		(start 15.4178 -173.2534)
		(end 16.4973 -172.1739)
		(width 0.508)
		(layer "In2.Cu")
		(net "P12V_PCIE")
	)
	(segment
		(start 4.445 -104.742996)
		(end 4.445 -179.4002)
		(width 0.508)
		(layer "In5.Cu")
		(net "P12V_PCIE")
	)
	(segment
		(start 10.70102 -175.91278)
		(end 13.3604 -173.2534)
		(width 0.508)
		(layer "In5.Cu")
		(net "P12V_PCIE")
	)
	(segment
		(start 10.70102 -176.38776)
		(end 10.70102 -175.91278)
		(width 0.508)
		(layer "In5.Cu")
		(net "P12V_PCIE")
	)
	(segment
		(start 13.3604 -173.2534)
		(end 15.4178 -173.2534)
		(width 0.508)
		(layer "In5.Cu")
		(net "P12V_PCIE")
	)
	(segment
		(start 7.9248 -178.6636)
		(end 7.9248 -180.1241)
		(width 0.508)
		(layer "F.Cu")
		(net "P12V")
	)
	(segment
		(start 12.2428 -177.927)
		(end 8.6614 -177.927)
		(width 0.508)
		(layer "F.Cu")
		(net "P12V")
	)
	(segment
		(start 15.0114 -179.2224)
		(end 13.5382 -179.2224)
		(width 0.508)
		(layer "F.Cu")
		(net "P12V")
	)
	(segment
		(start 13.5382 -179.2224)
		(end 13.0302 -179.7304)
		(width 0.508)
		(layer "F.Cu")
		(net "P12V")
	)
	(segment
		(start 13.0302 -179.7304)
		(end 13.0302 -180.2511)
		(width 0.508)
		(layer "F.Cu")
		(net "P12V")
	)
	(segment
		(start 28.6258 -196.9262)
		(end 28.702 -196.85)
		(width 0.508)
		(layer "F.Cu")
		(net "P12V")
	)
	(segment
		(start 14.9479 -180.0606)
		(end 14.9479 -179.2859)
		(width 0.508)
		(layer "F.Cu")
		(net "P12V")
	)
	(segment
		(start 159.350202 -58.002932)
		(end 159.350202 -56.986932)
		(width 0.508)
		(layer "F.Cu")
		(net "P12V")
	)
	(segment
		(start 8.6614 -177.927)
		(end 7.9248 -178.6636)
		(width 0.508)
		(layer "F.Cu")
		(net "P12V")
	)
	(segment
		(start 28.702 -196.85)
		(end 30.0355 -196.85)
		(width 0.508)
		(layer "F.Cu")
		(net "P12V")
	)
	(segment
		(start 13.5382 -179.2224)
		(end 12.2428 -177.927)
		(width 0.508)
		(layer "F.Cu")
		(net "P12V")
	)
	(segment
		(start 65.532 -132.3975)
		(end 66.3194 -132.3975)
		(width 0.508)
		(layer "F.Cu")
		(net "P12V")
	)
	(segment
		(start 14.9479 -179.2859)
		(end 15.0114 -179.2224)
		(width 0.508)
		(layer "F.Cu")
		(net "P12V")
	)
	(segment
		(start 332.994 -72.39)
		(end 332.867 -72.517)
		(width 0.508)
		(layer "F.Cu")
		(net "P12V")
	)
	(segment
		(start 332.994 -71.6915)
		(end 332.994 -72.39)
		(width 0.508)
		(layer "F.Cu")
		(net "P12V")
	)
	(via
		(at 348.996 -49.9618)
		(size 0.7112)
		(drill 0.4064)
		(layers "F.Cu" "B.Cu")
		(net "P12V")
	)
	(via
		(at 28.6258 -195.7832)
		(size 0.7112)
		(drill 0.4064)
		(layers "F.Cu" "B.Cu")
		(net "P12V")
	)
	(via
		(at 26.3398 -194.6402)
		(size 0.7112)
		(drill 0.4064)
		(layers "F.Cu" "B.Cu")
		(net "P12V")
	)
	(via
		(at 55.977536 -45.226986)
		(size 0.7112)
		(drill 0.3556)
		(layers "F.Cu" "B.Cu")
		(net "P12V")
	)
	(via
		(at 348.996 -48.895)
		(size 0.7112)
		(drill 0.4064)
		(layers "F.Cu" "B.Cu")
		(net "P12V")
	)
	(via
		(at 57.15 -48.895)
		(size 0.7112)
		(drill 0.4064)
		(layers "F.Cu" "B.Cu")
		(net "P12V")
	)
	(via
		(at 140.605002 -78.894432)
		(size 0.7112)
		(drill 0.4064)
		(layers "F.Cu" "B.Cu")
		(net "P12V")
	)
	(via
		(at 28.6258 -194.6402)
		(size 0.7112)
		(drill 0.4064)
		(layers "F.Cu" "B.Cu")
		(net "P12V")
	)
	(via
		(at 27.4828 -197.0532)
		(size 0.7112)
		(drill 0.4064)
		(layers "F.Cu" "B.Cu")
		(net "P12V")
	)
	(via
		(at 26.3398 -197.0532)
		(size 0.7112)
		(drill 0.4064)
		(layers "F.Cu" "B.Cu")
		(net "P12V")
	)
	(via
		(at 70.4342 -77.4192)
		(size 0.508)
		(drill 0.254)
		(layers "F.Cu" "B.Cu")
		(net "P12V")
	)
	(via
		(at 56.642 -46.736)
		(size 0.7112)
		(drill 0.4064)
		(layers "F.Cu" "B.Cu")
		(net "P12V")
	)
	(via
		(at 144.653 -61.01715)
		(size 0.508)
		(drill 0.254)
		(layers "F.Cu" "B.Cu")
		(net "P12V")
	)
	(via
		(at 58.2168 -48.895)
		(size 0.7112)
		(drill 0.4064)
		(layers "F.Cu" "B.Cu")
		(net "P12V")
	)
	(via
		(at 27.4828 -195.7832)
		(size 0.7112)
		(drill 0.4064)
		(layers "F.Cu" "B.Cu")
		(net "P12V")
	)
	(via
		(at 33.4518 -71.12)
		(size 0.5588)
		(drill 0.3048)
		(layers "F.Cu" "B.Cu")
		(net "P12V")
	)
	(via
		(at 15.0114 -179.2224)
		(size 0.508)
		(drill 0.254)
		(layers "F.Cu" "B.Cu")
		(net "P12V")
	)
	(via
		(at 27.4828 -194.6402)
		(size 0.7112)
		(drill 0.4064)
		(layers "F.Cu" "B.Cu")
		(net "P12V")
	)
	(via
		(at 159.350202 -56.986932)
		(size 0.508)
		(drill 0.254)
		(layers "F.Cu" "B.Cu")
		(net "P12V")
	)
	(via
		(at 347.8022 -65.8622)
		(size 0.508)
		(drill 0.254)
		(layers "F.Cu" "B.Cu")
		(net "P12V")
	)
	(via
		(at 33.4518 -70.0278)
		(size 0.5588)
		(drill 0.3048)
		(layers "F.Cu" "B.Cu")
		(net "P12V")
	)
	(via
		(at 350.139 -50.292)
		(size 0.7112)
		(drill 0.4064)
		(layers "F.Cu" "B.Cu")
		(net "P12V")
	)
	(via
		(at 351.155 -47.752)
		(size 0.7112)
		(drill 0.4064)
		(layers "F.Cu" "B.Cu")
		(net "P12V")
	)
	(via
		(at 28.1686 -197.9168)
		(size 0.7112)
		(drill 0.3556)
		(layers "F.Cu" "B.Cu")
		(net "P12V")
	)
	(via
		(at 351.155 -49.149)
		(size 0.7112)
		(drill 0.4064)
		(layers "F.Cu" "B.Cu")
		(net "P12V")
	)
	(via
		(at 56.642 -47.879)
		(size 0.7112)
		(drill 0.4064)
		(layers "F.Cu" "B.Cu")
		(net "P12V")
	)
	(via
		(at 25.0952 -194.2846)
		(size 0.7112)
		(drill 0.3556)
		(layers "F.Cu" "B.Cu")
		(net "P12V")
	)
	(via
		(at 140.605002 -77.751432)
		(size 0.7112)
		(drill 0.4064)
		(layers "F.Cu" "B.Cu")
		(net "P12V")
	)
	(via
		(at 28.6258 -196.9262)
		(size 0.7112)
		(drill 0.4064)
		(layers "F.Cu" "B.Cu")
		(net "P12V")
	)
	(via
		(at 140.579602 -81.053432)
		(size 0.7112)
		(drill 0.4064)
		(layers "F.Cu" "B.Cu")
		(net "P12V")
	)
	(via
		(at 31.7754 -71.755)
		(size 0.5588)
		(drill 0.3048)
		(layers "F.Cu" "B.Cu")
		(net "P12V")
	)
	(via
		(at 66.3194 -132.3975)
		(size 0.508)
		(drill 0.254)
		(layers "F.Cu" "B.Cu")
		(net "P12V")
	)
	(via
		(at 140.57757 -79.960978)
		(size 0.7112)
		(drill 0.4064)
		(layers "F.Cu" "B.Cu")
		(net "P12V")
	)
	(via
		(at 351.309432 -50.412142)
		(size 0.7112)
		(drill 0.3556)
		(layers "F.Cu" "B.Cu")
		(net "P12V")
	)
	(via
		(at 139.446 -80.899)
		(size 0.7112)
		(drill 0.3556)
		(layers "F.Cu" "B.Cu")
		(net "P12V")
	)
	(via
		(at 350.04121 -49.109376)
		(size 0.7112)
		(drill 0.4064)
		(layers "F.Cu" "B.Cu")
		(net "P12V")
	)
	(via
		(at 348.996 -47.8282)
		(size 0.7112)
		(drill 0.4064)
		(layers "F.Cu" "B.Cu")
		(net "P12V")
	)
	(via
		(at 350.04121 -48.042576)
		(size 0.7112)
		(drill 0.4064)
		(layers "F.Cu" "B.Cu")
		(net "P12V")
	)
	(via
		(at 142.779242 -81.066132)
		(size 0.7112)
		(drill 0.4064)
		(layers "F.Cu" "B.Cu")
		(net "P12V")
	)
	(via
		(at 141.697202 -81.053432)
		(size 0.7112)
		(drill 0.4064)
		(layers "F.Cu" "B.Cu")
		(net "P12V")
	)
	(via
		(at 332.867 -72.517)
		(size 0.508)
		(drill 0.254)
		(layers "F.Cu" "B.Cu")
		(net "P12V")
	)
	(via
		(at 26.3398 -195.7832)
		(size 0.7112)
		(drill 0.4064)
		(layers "F.Cu" "B.Cu")
		(net "P12V")
	)
	(segment
		(start 350.139 -50.292)
		(end 350.5708 -50.7238)
		(width 0.508)
		(layer "B.Cu")
		(net "P12V")
	)
	(segment
		(start 144.653 -61.01715)
		(end 144.878806 -61.01715)
		(width 0.508)
		(layer "B.Cu")
		(net "P12V")
	)
	(segment
		(start 55.977536 -45.226986)
		(end 55.977536 -42.180764)
		(width 0.508)
		(layer "B.Cu")
		(net "P12V")
	)
	(segment
		(start 55.977536 -46.071536)
		(end 56.642 -46.736)
		(width 0.508)
		(layer "B.Cu")
		(net "P12V")
	)
	(segment
		(start 350.5708 -50.7238)
		(end 350.5708 -63.6524)
		(width 0.508)
		(layer "B.Cu")
		(net "P12V")
	)
	(segment
		(start 57.0103 -41.148)
		(end 58.039 -41.148)
		(width 0.508)
		(layer "B.Cu")
		(net "P12V")
	)
	(segment
		(start 31.7754 -72.0852)
		(end 31.7754 -71.755)
		(width 0.508)
		(layer "B.Cu")
		(net "P12V")
	)
	(segment
		(start 349.5802 -64.643)
		(end 347.8022 -64.643)
		(width 0.508)
		(layer "B.Cu")
		(net "P12V")
	)
	(segment
		(start 55.977536 -42.180764)
		(end 57.0103 -41.148)
		(width 0.508)
		(layer "B.Cu")
		(net "P12V")
	)
	(segment
		(start 144.878806 -61.01715)
		(end 145.652236 -61.79058)
		(width 0.508)
		(layer "B.Cu")
		(net "P12V")
	)
	(segment
		(start 55.977536 -45.226986)
		(end 55.977536 -46.071536)
		(width 0.508)
		(layer "B.Cu")
		(net "P12V")
	)
	(segment
		(start 347.8022 -64.643)
		(end 347.8022 -65.8622)
		(width 0.508)
		(layer "B.Cu")
		(net "P12V")
	)
	(segment
		(start 350.5708 -63.6524)
		(end 349.5802 -64.643)
		(width 0.508)
		(layer "B.Cu")
		(net "P12V")
	)
	(segment
		(start 29.9339 -73.1774)
		(end 30.6832 -73.1774)
		(width 0.508)
		(layer "B.Cu")
		(net "P12V")
	)
	(segment
		(start 30.6832 -73.1774)
		(end 31.7754 -72.0852)
		(width 0.508)
		(layer "B.Cu")
		(net "P12V")
	)
	(segment
		(start 144.653 -58.099452)
		(end 145.65122 -57.101232)
		(width 0.508)
		(layer "In2.Cu")
		(net "P12V")
	)
	(segment
		(start 346.1258 -73.533)
		(end 339.725 -73.533)
		(width 0.508)
		(layer "In2.Cu")
		(net "P12V")
	)
	(segment
		(start 152.529032 -57.837832)
		(end 158.60776 -57.837832)
		(width 0.508)
		(layer "In2.Cu")
		(net "P12V")
	)
	(segment
		(start 151.792432 -57.101232)
		(end 152.529032 -57.837832)
		(width 0.508)
		(layer "In2.Cu")
		(net "P12V")
	)
	(segment
		(start 144.653 -61.01715)
		(end 144.653 -58.099452)
		(width 0.508)
		(layer "In2.Cu")
		(net "P12V")
	)
	(segment
		(start 158.994602 -57.342532)
		(end 159.350202 -56.986932)
		(width 0.508)
		(layer "In2.Cu")
		(net "P12V")
	)
	(segment
		(start 334.029812 -72.1106)
		(end 333.2734 -72.1106)
		(width 0.508)
		(layer "In2.Cu")
		(net "P12V")
	)
	(segment
		(start 338.6836 -72.4916)
		(end 334.410812 -72.4916)
		(width 0.508)
		(layer "In2.Cu")
		(net "P12V")
	)
	(segment
		(start 348.2086 -67.1576)
		(end 348.2086 -71.4502)
		(width 0.508)
		(layer "In2.Cu")
		(net "P12V")
	)
	(segment
		(start 347.8022 -65.8622)
		(end 347.8022 -66.7512)
		(width 0.508)
		(layer "In2.Cu")
		(net "P12V")
	)
	(segment
		(start 347.8022 -66.7512)
		(end 348.2086 -67.1576)
		(width 0.508)
		(layer "In2.Cu")
		(net "P12V")
	)
	(segment
		(start 339.725 -73.533)
		(end 338.6836 -72.4916)
		(width 0.508)
		(layer "In2.Cu")
		(net "P12V")
	)
	(segment
		(start 334.410812 -72.4916)
		(end 334.029812 -72.1106)
		(width 0.508)
		(layer "In2.Cu")
		(net "P12V")
	)
	(segment
		(start 348.2086 -71.4502)
		(end 346.1258 -73.533)
		(width 0.508)
		(layer "In2.Cu")
		(net "P12V")
	)
	(segment
		(start 333.2734 -72.1106)
		(end 332.867 -72.517)
		(width 0.508)
		(layer "In2.Cu")
		(net "P12V")
	)
	(segment
		(start 158.994602 -57.45099)
		(end 158.994602 -57.342532)
		(width 0.508)
		(layer "In2.Cu")
		(net "P12V")
	)
	(segment
		(start 158.60776 -57.837832)
		(end 158.994602 -57.45099)
		(width 0.508)
		(layer "In2.Cu")
		(net "P12V")
	)
	(segment
		(start 145.65122 -57.101232)
		(end 151.792432 -57.101232)
		(width 0.508)
		(layer "In2.Cu")
		(net "P12V")
	)
	(segment
		(start 66.90995 -129.1463)
		(end 66.90995 -129.1336)
		(width 0.508)
		(layer "In5.Cu")
		(net "P12V")
	)
	(segment
		(start 67.073526 -128.57861)
		(end 68.526406 -127.12573)
		(width 0.508)
		(layer "In5.Cu")
		(net "P12V")
	)
	(segment
		(start 144.323562 -61.01715)
		(end 140.605002 -64.73571)
		(width 0.508)
		(layer "In5.Cu")
		(net "P12V")
	)
	(segment
		(start 66.90995 -129.1336)
		(end 67.073526 -128.970024)
		(width 0.508)
		(layer "In5.Cu")
		(net "P12V")
	)
	(segment
		(start 16.0274 -178.2064)
		(end 15.0114 -179.2224)
		(width 1.016)
		(layer "In5.Cu")
		(net "P12V")
	)
	(segment
		(start 68.526406 -117.559836)
		(end 69.5706 -116.515642)
		(width 0.508)
		(layer "In5.Cu")
		(net "P12V")
	)
	(segment
		(start 144.653 -61.01715)
		(end 144.323562 -61.01715)
		(width 0.508)
		(layer "In5.Cu")
		(net "P12V")
	)
	(segment
		(start 68.526406 -127.12573)
		(end 68.526406 -117.559836)
		(width 0.508)
		(layer "In5.Cu")
		(net "P12V")
	)
	(segment
		(start 27.249882 -178.2064)
		(end 16.0274 -178.2064)
		(width 1.016)
		(layer "In5.Cu")
		(net "P12V")
	)
	(segment
		(start 140.605002 -64.73571)
		(end 140.605002 -77.751432)
		(width 0.508)
		(layer "In5.Cu")
		(net "P12V")
	)
	(segment
		(start 67.073526 -128.970024)
		(end 67.073526 -128.57861)
		(width 0.508)
		(layer "In5.Cu")
		(net "P12V")
	)
	(segment
		(start 31.575756 -191.690244)
		(end 31.575756 -182.532274)
		(width 1.016)
		(layer "In5.Cu")
		(net "P12V")
	)
	(segment
		(start 66.3194 -129.73685)
		(end 66.90995 -129.1463)
		(width 0.508)
		(layer "In5.Cu")
		(net "P12V")
	)
	(segment
		(start 69.5706 -116.515642)
		(end 69.5706 -79.711042)
		(width 0.508)
		(layer "In5.Cu")
		(net "P12V")
	)
	(segment
		(start 69.5706 -79.711042)
		(end 70.4342 -78.847442)
		(width 0.508)
		(layer "In5.Cu")
		(net "P12V")
	)
	(segment
		(start 66.3194 -132.3975)
		(end 66.3194 -129.73685)
		(width 0.508)
		(layer "In5.Cu")
		(net "P12V")
	)
	(segment
		(start 31.575756 -182.532274)
		(end 27.249882 -178.2064)
		(width 1.016)
		(layer "In5.Cu")
		(net "P12V")
	)
	(segment
		(start 28.6258 -194.6402)
		(end 31.575756 -191.690244)
		(width 1.016)
		(layer "In5.Cu")
		(net "P12V")
	)
	(segment
		(start 70.4342 -78.847442)
		(end 70.4342 -77.4192)
		(width 0.508)
		(layer "In5.Cu")
		(net "P12V")
	)
	(segment
		(start 147.220686 -60.5536)
		(end 147.365212 -60.698126)
		(width 0.254)
		(layer "F.Cu")
		(net "P0V9_VREG")
	)
	(segment
		(start 146.2659 -60.5536)
		(end 147.220686 -60.5536)
		(width 0.254)
		(layer "F.Cu")
		(net "P0V9_VREG")
	)
	(segment
		(start 149.50821 -61.17082)
		(end 150.001732 -60.677806)
		(width 0.254)
		(layer "F.Cu")
		(net "P0V9_VREG")
	)
	(segment
		(start 147.837906 -61.17082)
		(end 148.468588 -61.17082)
		(width 0.254)
		(layer "F.Cu")
		(net "P0V9_VREG")
	)
	(segment
		(start 147.365212 -60.698126)
		(end 147.837906 -61.17082)
		(width 0.254)
		(layer "F.Cu")
		(net "P0V9_VREG")
	)
	(segment
		(start 148.468588 -61.17082)
		(end 149.50821 -61.17082)
		(width 0.254)
		(layer "F.Cu")
		(net "P0V9_VREG")
	)
	(segment
		(start 150.001732 -60.677806)
		(end 150.65248 -60.677806)
		(width 0.254)
		(layer "F.Cu")
		(net "P0V9_VREG")
	)
	(via
		(at 148.468588 -61.17082)
		(size 0.7112)
		(drill 0.3556)
		(layers "F.Cu" "B.Cu")
		(net "P0V9_VREG")
	)
	(via
		(at 149.347936 -62.521592)
		(size 0.7112)
		(drill 0.4064)
		(layers "F.Cu" "B.Cu")
		(net "P0V9_VIN")
	)
	(via
		(at 147.463002 -78.386432)
		(size 0.7112)
		(drill 0.4064)
		(layers "F.Cu" "B.Cu")
		(net "P0V9_VIN")
	)
	(via
		(at 148.72081 -70.220586)
		(size 0.7112)
		(drill 0.4064)
		(layers "F.Cu" "B.Cu")
		(net "P0V9_VIN")
	)
	(via
		(at 148.015452 -69.4182)
		(size 0.7112)
		(drill 0.4064)
		(layers "F.Cu" "B.Cu")
		(net "P0V9_VIN")
	)
	(via
		(at 147.920202 -74.525632)
		(size 0.7112)
		(drill 0.4064)
		(layers "F.Cu" "B.Cu")
		(net "P0V9_VIN")
	)
	(via
		(at 148.084286 -67.085718)
		(size 0.7112)
		(drill 0.4064)
		(layers "F.Cu" "B.Cu")
		(net "P0V9_VIN")
	)
	(via
		(at 149.34692 -64.00165)
		(size 0.7112)
		(drill 0.4064)
		(layers "F.Cu" "B.Cu")
		(net "P0V9_VIN")
	)
	(via
		(at 149.114002 -65.432432)
		(size 0.7112)
		(drill 0.4064)
		(layers "F.Cu" "B.Cu")
		(net "P0V9_VIN")
	)
	(via
		(at 148.181314 -75.91298)
		(size 0.7112)
		(drill 0.4064)
		(layers "F.Cu" "B.Cu")
		(net "P0V9_VIN")
	)
	(via
		(at 149.7076 -78.391004)
		(size 0.7112)
		(drill 0.4064)
		(layers "F.Cu" "B.Cu")
		(net "P0V9_VIN")
	)
	(via
		(at 148.679154 -68.400168)
		(size 0.7112)
		(drill 0.4064)
		(layers "F.Cu" "B.Cu")
		(net "P0V9_VIN")
	)
	(via
		(at 149.647656 -67.0941)
		(size 0.7112)
		(drill 0.4064)
		(layers "F.Cu" "B.Cu")
		(net "P0V9_VIN")
	)
	(via
		(at 148.777198 -73.560432)
		(size 0.7112)
		(drill 0.4064)
		(layers "F.Cu" "B.Cu")
		(net "P0V9_VIN")
	)
	(via
		(at 144.440402 -73.33996)
		(size 0.7112)
		(drill 0.3556)
		(layers "F.Cu" "B.Cu")
		(net "P0V9_VIN")
	)
	(via
		(at 148.153628 -76.985114)
		(size 0.7112)
		(drill 0.4064)
		(layers "F.Cu" "B.Cu")
		(net "P0V9_VIN")
	)
	(via
		(at 148.777198 -71.909432)
		(size 0.7112)
		(drill 0.4064)
		(layers "F.Cu" "B.Cu")
		(net "P0V9_VIN")
	)
	(via
		(at 148.001482 -71.022972)
		(size 0.7112)
		(drill 0.4064)
		(layers "F.Cu" "B.Cu")
		(net "P0V9_VIN")
	)
	(via
		(at 148.154644 -64.001396)
		(size 0.7112)
		(drill 0.4064)
		(layers "F.Cu" "B.Cu")
		(net "P0V9_VIN")
	)
	(via
		(at 148.075904 -62.521592)
		(size 0.7112)
		(drill 0.4064)
		(layers "F.Cu" "B.Cu")
		(net "P0V9_VIN")
	)
	(via
		(at 147.932394 -72.793606)
		(size 0.7112)
		(drill 0.4064)
		(layers "F.Cu" "B.Cu")
		(net "P0V9_VIN")
	)
	(via
		(at 148.001228 -65.433956)
		(size 0.7112)
		(drill 0.4064)
		(layers "F.Cu" "B.Cu")
		(net "P0V9_VIN")
	)
	(segment
		(start 159.362902 -55.272432)
		(end 158.270702 -55.272432)
		(width 0.254)
		(layer "F.Cu")
		(net "P0V9_VFB_R")
	)
	(segment
		(start 158.321502 -54.256432)
		(end 158.321502 -55.221632)
		(width 0.254)
		(layer "F.Cu")
		(net "P0V9_VFB_R")
	)
	(segment
		(start 158.321502 -55.221632)
		(end 158.270702 -55.272432)
		(width 0.254)
		(layer "F.Cu")
		(net "P0V9_VFB_R")
	)
	(segment
		(start 159.362902 -54.231032)
		(end 159.362902 -53.189632)
		(width 0.254)
		(layer "F.Cu")
		(net "P0V9_VFB_R")
	)
	(segment
		(start 159.362902 -54.231032)
		(end 159.362902 -55.272432)
		(width 0.254)
		(layer "F.Cu")
		(net "P0V9_VFB_R")
	)
	(segment
		(start 157.432502 -54.256432)
		(end 157.432502 -55.221632)
		(width 0.254)
		(layer "F.Cu")
		(net "P0V9_VFB")
	)
	(segment
		(start 155.551124 -57.54751)
		(end 156.810202 -56.288432)
		(width 0.254)
		(layer "F.Cu")
		(net "P0V9_VFB")
	)
	(segment
		(start 156.810202 -56.288432)
		(end 157.381702 -56.288432)
		(width 0.254)
		(layer "F.Cu")
		(net "P0V9_VFB")
	)
	(segment
		(start 157.432502 -53.240432)
		(end 157.432502 -54.256432)
		(width 0.254)
		(layer "F.Cu")
		(net "P0V9_VFB")
	)
	(segment
		(start 156.365702 -54.256432)
		(end 156.365702 -53.542438)
		(width 0.254)
		(layer "F.Cu")
		(net "P0V9_VFB")
	)
	(segment
		(start 157.381702 -55.272432)
		(end 157.381702 -56.288432)
		(width 0.254)
		(layer "F.Cu")
		(net "P0V9_VFB")
	)
	(segment
		(start 155.551124 -58.67781)
		(end 155.551124 -57.54751)
		(width 0.254)
		(layer "F.Cu")
		(net "P0V9_VFB")
	)
	(segment
		(start 157.432502 -55.221632)
		(end 157.381702 -55.272432)
		(width 0.254)
		(layer "F.Cu")
		(net "P0V9_VFB")
	)
	(segment
		(start 157.305502 -53.113432)
		(end 157.432502 -53.240432)
		(width 0.254)
		(layer "F.Cu")
		(net "P0V9_VFB")
	)
	(segment
		(start 156.794708 -53.113432)
		(end 157.305502 -53.113432)
		(width 0.254)
		(layer "F.Cu")
		(net "P0V9_VFB")
	)
	(segment
		(start 156.365702 -53.542438)
		(end 156.794708 -53.113432)
		(width 0.254)
		(layer "F.Cu")
		(net "P0V9_VFB")
	)
	(segment
		(start 149.524466 -60.177934)
		(end 149.1996 -60.5028)
		(width 0.254)
		(layer "F.Cu")
		(net "P0V9_VDD")
	)
	(segment
		(start 150.65248 -60.177934)
		(end 149.524466 -60.177934)
		(width 0.254)
		(layer "F.Cu")
		(net "P0V9_VDD")
	)
	(via
		(at 149.1996 -60.5028)
		(size 0.508)
		(drill 0.254)
		(layers "F.Cu" "B.Cu")
		(net "P0V9_VDD")
	)
	(via
		(at 146.3548 -60.5536)
		(size 0.7112)
		(drill 0.3556)
		(layers "F.Cu" "B.Cu")
		(net "P0V9_VDD")
	)
	(segment
		(start 146.336258 -60.572142)
		(end 146.336258 -61.024516)
		(width 0.254)
		(layer "B.Cu")
		(net "P0V9_VDD")
	)
	(segment
		(start 147.176236 -61.79058)
		(end 148.742654 -61.79058)
		(width 0.254)
		(layer "B.Cu")
		(net "P0V9_VDD")
	)
	(segment
		(start 149.08149 -61.451744)
		(end 149.08149 -60.62091)
		(width 0.254)
		(layer "B.Cu")
		(net "P0V9_VDD")
	)
	(segment
		(start 147.102322 -61.79058)
		(end 147.176236 -61.79058)
		(width 0.254)
		(layer "B.Cu")
		(net "P0V9_VDD")
	)
	(segment
		(start 146.3548 -60.5536)
		(end 146.336258 -60.572142)
		(width 0.254)
		(layer "B.Cu")
		(net "P0V9_VDD")
	)
	(segment
		(start 147.920202 -60.301632)
		(end 146.606768 -60.301632)
		(width 0.254)
		(layer "B.Cu")
		(net "P0V9_VDD")
	)
	(segment
		(start 146.606768 -60.301632)
		(end 146.3548 -60.5536)
		(width 0.254)
		(layer "B.Cu")
		(net "P0V9_VDD")
	)
	(segment
		(start 149.08149 -60.62091)
		(end 149.1996 -60.5028)
		(width 0.254)
		(layer "B.Cu")
		(net "P0V9_VDD")
	)
	(segment
		(start 148.742654 -61.79058)
		(end 149.08149 -61.451744)
		(width 0.254)
		(layer "B.Cu")
		(net "P0V9_VDD")
	)
	(segment
		(start 146.336258 -61.024516)
		(end 147.102322 -61.79058)
		(width 0.254)
		(layer "B.Cu")
		(net "P0V9_VDD")
	)
	(segment
		(start 159.147002 -60.479432)
		(end 159.274002 -60.352432)
		(width 0.254)
		(layer "B.Cu")
		(net "P0V9_VBST_RC")
	)
	(segment
		(start 159.274002 -60.352432)
		(end 159.274002 -59.209432)
		(width 0.254)
		(layer "B.Cu")
		(net "P0V9_VBST_RC")
	)
	(segment
		(start 156.646372 -60.442602)
		(end 156.646372 -60.555632)
		(width 0.254)
		(layer "F.Cu")
		(net "P0V9_VBST")
	)
	(segment
		(start 155.551124 -60.177934)
		(end 156.381704 -60.177934)
		(width 0.254)
		(layer "F.Cu")
		(net "P0V9_VBST")
	)
	(segment
		(start 156.381704 -60.177934)
		(end 156.646372 -60.442602)
		(width 0.254)
		(layer "F.Cu")
		(net "P0V9_VBST")
	)
	(via
		(at 156.646372 -60.555632)
		(size 0.508)
		(drill 0.254)
		(layers "F.Cu" "B.Cu")
		(net "P0V9_VBST")
	)
	(segment
		(start 157.332172 -60.555632)
		(end 157.800802 -60.087002)
		(width 0.254)
		(layer "B.Cu")
		(net "P0V9_VBST")
	)
	(segment
		(start 156.646372 -60.555632)
		(end 157.332172 -60.555632)
		(width 0.254)
		(layer "B.Cu")
		(net "P0V9_VBST")
	)
	(segment
		(start 157.800802 -59.260232)
		(end 157.750002 -59.209432)
		(width 0.254)
		(layer "B.Cu")
		(net "P0V9_VBST")
	)
	(segment
		(start 157.800802 -60.087002)
		(end 157.800802 -59.260232)
		(width 0.254)
		(layer "B.Cu")
		(net "P0V9_VBST")
	)
	(segment
		(start 149.850602 -58.955432)
		(end 149.850602 -58.946542)
		(width 0.254)
		(layer "F.Cu")
		(net "P0V9_TRIP")
	)
	(segment
		(start 150.073106 -59.177936)
		(end 149.850602 -58.955432)
		(width 0.254)
		(layer "F.Cu")
		(net "P0V9_TRIP")
	)
	(segment
		(start 150.65248 -59.177936)
		(end 150.073106 -59.177936)
		(width 0.254)
		(layer "F.Cu")
		(net "P0V9_TRIP")
	)
	(segment
		(start 149.850602 -58.946542)
		(end 149.83968 -58.93562)
		(width 0.254)
		(layer "F.Cu")
		(net "P0V9_TRIP")
	)
	(segment
		(start 149.83968 -58.93562)
		(end 149.83968 -58.00471)
		(width 0.254)
		(layer "F.Cu")
		(net "P0V9_TRIP")
	)
	(segment
		(start 149.83968 -58.00471)
		(end 149.596602 -57.761632)
		(width 0.254)
		(layer "F.Cu")
		(net "P0V9_TRIP")
	)
	(via
		(at 150.332694 -59.028584)
		(size 0.7112)
		(drill 0.3556)
		(layers "F.Cu" "B.Cu")
		(net "P0V9_TRIP")
	)
	(via
		(at 149.596602 -57.761632)
		(size 0.508)
		(drill 0.254)
		(layers "F.Cu" "B.Cu")
		(net "P0V9_TRIP")
	)
	(segment
		(start 149.596602 -57.761632)
		(end 149.733 -57.89803)
		(width 0.254)
		(layer "B.Cu")
		(net "P0V9_TRIP")
	)
	(segment
		(start 149.733 -58.42889)
		(end 150.332694 -59.028584)
		(width 0.254)
		(layer "B.Cu")
		(net "P0V9_TRIP")
	)
	(segment
		(start 149.444202 -57.609232)
		(end 149.596602 -57.761632)
		(width 0.254)
		(layer "B.Cu")
		(net "P0V9_TRIP")
	)
	(segment
		(start 149.444202 -56.986932)
		(end 149.444202 -57.609232)
		(width 0.254)
		(layer "B.Cu")
		(net "P0V9_TRIP")
	)
	(segment
		(start 149.733 -57.89803)
		(end 149.733 -58.42889)
		(width 0.254)
		(layer "B.Cu")
		(net "P0V9_TRIP")
	)
	(segment
		(start 158.270702 -56.288432)
		(end 159.909002 -56.288432)
		(width 0.254)
		(layer "F.Cu")
		(net "P0V9_SW_R")
	)
	(segment
		(start 159.909002 -56.288432)
		(end 159.934402 -56.313832)
		(width 0.254)
		(layer "F.Cu")
		(net "P0V9_SW_R")
	)
	(via
		(at 159.934402 -56.313832)
		(size 0.508)
		(drill 0.254)
		(layers "F.Cu" "B.Cu")
		(net "P0V9_SW_R")
	)
	(segment
		(start 160.910524 -57.289954)
		(end 159.934402 -56.313832)
		(width 0.254)
		(layer "B.Cu")
		(net "P0V9_SW_R")
	)
	(segment
		(start 163.998402 -58.91911)
		(end 162.369246 -57.289954)
		(width 0.254)
		(layer "B.Cu")
		(net "P0V9_SW_R")
	)
	(segment
		(start 163.998402 -59.628532)
		(end 163.998402 -58.91911)
		(width 0.254)
		(layer "B.Cu")
		(net "P0V9_SW_R")
	)
	(segment
		(start 162.369246 -57.289954)
		(end 160.910524 -57.289954)
		(width 0.254)
		(layer "B.Cu")
		(net "P0V9_SW_R")
	)
	(segment
		(start 163.973002 -59.653932)
		(end 163.058602 -59.653932)
		(width 0.254)
		(layer "B.Cu")
		(net "P0V9_SW_R")
	)
	(segment
		(start 163.998402 -59.628532)
		(end 163.973002 -59.653932)
		(width 0.254)
		(layer "B.Cu")
		(net "P0V9_SW_R")
	)
	(segment
		(start 156.416502 -64.289432)
		(end 156.797502 -64.670432)
		(width 0.254)
		(layer "B.Cu")
		(net "P0V9_SNB")
	)
	(segment
		(start 156.797502 -64.670432)
		(end 157.800802 -64.670432)
		(width 0.254)
		(layer "B.Cu")
		(net "P0V9_SNB")
	)
	(segment
		(start 145.182336 -60.359036)
		(end 145.182336 -57.749694)
		(width 0.254)
		(layer "F.Cu")
		(net "P0V9_RF")
	)
	(segment
		(start 150.65248 -58.67781)
		(end 150.65248 -58.13171)
		(width 0.254)
		(layer "F.Cu")
		(net "P0V9_RF")
	)
	(segment
		(start 150.511002 -57.921652)
		(end 150.511002 -57.990232)
		(width 0.254)
		(layer "F.Cu")
		(net "P0V9_RF")
	)
	(segment
		(start 150.65248 -58.13171)
		(end 150.511002 -57.990232)
		(width 0.254)
		(layer "F.Cu")
		(net "P0V9_RF")
	)
	(segment
		(start 145.703798 -57.228232)
		(end 149.817582 -57.228232)
		(width 0.254)
		(layer "F.Cu")
		(net "P0V9_RF")
	)
	(segment
		(start 145.182336 -57.749694)
		(end 145.703798 -57.228232)
		(width 0.254)
		(layer "F.Cu")
		(net "P0V9_RF")
	)
	(segment
		(start 145.3769 -60.5536)
		(end 145.182336 -60.359036)
		(width 0.254)
		(layer "F.Cu")
		(net "P0V9_RF")
	)
	(segment
		(start 149.817582 -57.228232)
		(end 150.511002 -57.921652)
		(width 0.254)
		(layer "F.Cu")
		(net "P0V9_RF")
	)
	(via
		(at 150.511002 -57.990232)
		(size 0.508)
		(drill 0.254)
		(layers "F.Cu" "B.Cu")
		(net "P0V9_RF")
	)
	(via
		(at 151.511 -57.4294)
		(size 0.7112)
		(drill 0.3556)
		(layers "F.Cu" "B.Cu")
		(net "P0V9_RF")
	)
	(segment
		(start 151.068532 -56.986932)
		(end 150.460202 -56.986932)
		(width 0.254)
		(layer "B.Cu")
		(net "P0V9_RF")
	)
	(segment
		(start 151.511 -57.785)
		(end 151.511 -57.4294)
		(width 0.254)
		(layer "B.Cu")
		(net "P0V9_RF")
	)
	(segment
		(start 151.305768 -57.990232)
		(end 151.511 -57.785)
		(width 0.254)
		(layer "B.Cu")
		(net "P0V9_RF")
	)
	(segment
		(start 151.511 -57.4294)
		(end 151.068532 -56.986932)
		(width 0.254)
		(layer "B.Cu")
		(net "P0V9_RF")
	)
	(segment
		(start 150.511002 -57.990232)
		(end 151.305768 -57.990232)
		(width 0.254)
		(layer "B.Cu")
		(net "P0V9_RF")
	)
	(segment
		(start 146.851878 -58.481722)
		(end 146.867626 -58.481722)
		(width 0.12065)
		(layer "F.Cu")
		(net "P0V9_PG")
	)
	(segment
		(start 146.3294 -59.563)
		(end 146.3294 -59.0042)
		(width 0.12065)
		(layer "F.Cu")
		(net "P0V9_PG")
	)
	(segment
		(start 146.867626 -58.481722)
		(end 147.282916 -58.066432)
		(width 0.12065)
		(layer "F.Cu")
		(net "P0V9_PG")
	)
	(segment
		(start 147.282916 -58.066432)
		(end 147.653502 -58.066432)
		(width 0.12065)
		(layer "F.Cu")
		(net "P0V9_PG")
	)
	(segment
		(start 146.3294 -59.0042)
		(end 146.851878 -58.481722)
		(width 0.12065)
		(layer "F.Cu")
		(net "P0V9_PG")
	)
	(segment
		(start 327.6727 -71.6915)
		(end 318.77 -80.5942)
		(width 0.12065)
		(layer "F.Cu")
		(net "P0V9_PG")
	)
	(segment
		(start 155.551124 -59.677808)
		(end 156.668978 -59.677808)
		(width 0.12065)
		(layer "F.Cu")
		(net "P0V9_PG")
	)
	(segment
		(start 156.733494 -59.717432)
		(end 156.71038 -59.694318)
		(width 0.12065)
		(layer "F.Cu")
		(net "P0V9_PG")
	)
	(segment
		(start 157.254702 -59.717432)
		(end 156.733494 -59.717432)
		(width 0.12065)
		(layer "F.Cu")
		(net "P0V9_PG")
	)
	(segment
		(start 156.685488 -59.694318)
		(end 156.71038 -59.694318)
		(width 0.12065)
		(layer "F.Cu")
		(net "P0V9_PG")
	)
	(segment
		(start 331.978 -71.6915)
		(end 327.6727 -71.6915)
		(width 0.12065)
		(layer "F.Cu")
		(net "P0V9_PG")
	)
	(segment
		(start 156.668978 -59.677808)
		(end 156.685488 -59.694318)
		(width 0.12065)
		(layer "F.Cu")
		(net "P0V9_PG")
	)
	(segment
		(start 158.016702 -60.479432)
		(end 157.254702 -59.717432)
		(width 0.12065)
		(layer "F.Cu")
		(net "P0V9_PG")
	)
	(via
		(at 318.77 -80.5942)
		(size 0.508)
		(drill 0.254)
		(layers "F.Cu" "B.Cu")
		(net "P0V9_PG")
	)
	(via
		(at 318.77 -82.042)
		(size 0.7112)
		(drill 0.3556)
		(layers "F.Cu" "B.Cu")
		(net "P0V9_PG")
	)
	(via
		(at 146.3294 -59.563)
		(size 0.508)
		(drill 0.254)
		(layers "F.Cu" "B.Cu")
		(net "P0V9_PG")
	)
	(via
		(at 156.71038 -59.694318)
		(size 0.508)
		(drill 0.254)
		(layers "F.Cu" "B.Cu")
		(net "P0V9_PG")
	)
	(segment
		(start 139.924028 -94.051374)
		(end 139.924028 -77.372972)
		(width 0.12065)
		(layer "B.Cu")
		(net "P0V9_PG")
	)
	(segment
		(start 141.173454 -76.123546)
		(end 141.173454 -63.629794)
		(width 0.12065)
		(layer "B.Cu")
		(net "P0V9_PG")
	)
	(segment
		(start 145.6182 -60.0456)
		(end 146.1008 -59.563)
		(width 0.12065)
		(layer "B.Cu")
		(net "P0V9_PG")
	)
	(segment
		(start 153.498804 -107.62615)
		(end 139.924028 -94.051374)
		(width 0.12065)
		(layer "B.Cu")
		(net "P0V9_PG")
	)
	(segment
		(start 314.27547 -107.62615)
		(end 153.498804 -107.62615)
		(width 0.12065)
		(layer "B.Cu")
		(net "P0V9_PG")
	)
	(segment
		(start 139.924028 -77.372972)
		(end 141.173454 -76.123546)
		(width 0.12065)
		(layer "B.Cu")
		(net "P0V9_PG")
	)
	(segment
		(start 144.757648 -60.0456)
		(end 145.6182 -60.0456)
		(width 0.12065)
		(layer "B.Cu")
		(net "P0V9_PG")
	)
	(segment
		(start 318.77 -86.2584)
		(end 319.887092 -87.375492)
		(width 0.12065)
		(layer "B.Cu")
		(net "P0V9_PG")
	)
	(segment
		(start 319.887092 -102.014528)
		(end 314.27547 -107.62615)
		(width 0.12065)
		(layer "B.Cu")
		(net "P0V9_PG")
	)
	(segment
		(start 318.77 -82.042)
		(end 318.77 -86.2584)
		(width 0.12065)
		(layer "B.Cu")
		(net "P0V9_PG")
	)
	(segment
		(start 146.1008 -59.563)
		(end 146.3294 -59.563)
		(width 0.12065)
		(layer "B.Cu")
		(net "P0V9_PG")
	)
	(segment
		(start 318.77 -80.5942)
		(end 318.77 -82.042)
		(width 0.12065)
		(layer "B.Cu")
		(net "P0V9_PG")
	)
	(segment
		(start 319.887092 -87.375492)
		(end 319.887092 -102.014528)
		(width 0.12065)
		(layer "B.Cu")
		(net "P0V9_PG")
	)
	(segment
		(start 141.173454 -63.629794)
		(end 144.757648 -60.0456)
		(width 0.12065)
		(layer "B.Cu")
		(net "P0V9_PG")
	)
	(segment
		(start 146.788124 -59.4233)
		(end 146.877024 -59.3344)
		(width 0.127)
		(layer "In5.Cu")
		(net "P0V9_PG")
	)
	(segment
		(start 146.4691 -59.4233)
		(end 146.788124 -59.4233)
		(width 0.127)
		(layer "In5.Cu")
		(net "P0V9_PG")
	)
	(segment
		(start 150.47722 -57.291732)
		(end 151.414988 -58.2295)
		(width 0.127)
		(layer "In5.Cu")
		(net "P0V9_PG")
	)
	(segment
		(start 155.24607 -58.230008)
		(end 156.71038 -59.694318)
		(width 0.127)
		(layer "In5.Cu")
		(net "P0V9_PG")
	)
	(segment
		(start 151.414988 -58.2295)
		(end 153.808684 -58.2295)
		(width 0.127)
		(layer "In5.Cu")
		(net "P0V9_PG")
	)
	(segment
		(start 147.359116 -59.3344)
		(end 149.401784 -57.291732)
		(width 0.127)
		(layer "In5.Cu")
		(net "P0V9_PG")
	)
	(segment
		(start 146.877024 -59.3344)
		(end 147.359116 -59.3344)
		(width 0.127)
		(layer "In5.Cu")
		(net "P0V9_PG")
	)
	(segment
		(start 153.808684 -58.2295)
		(end 153.809192 -58.230008)
		(width 0.127)
		(layer "In5.Cu")
		(net "P0V9_PG")
	)
	(segment
		(start 153.809192 -58.230008)
		(end 155.24607 -58.230008)
		(width 0.127)
		(layer "In5.Cu")
		(net "P0V9_PG")
	)
	(segment
		(start 146.3294 -59.563)
		(end 146.4691 -59.4233)
		(width 0.127)
		(layer "In5.Cu")
		(net "P0V9_PG")
	)
	(segment
		(start 149.401784 -57.291732)
		(end 150.47722 -57.291732)
		(width 0.127)
		(layer "In5.Cu")
		(net "P0V9_PG")
	)
	(segment
		(start 149.444202 -59.114944)
		(end 149.444202 -59.123834)
		(width 0.254)
		(layer "F.Cu")
		(net "P0V9_MODE")
	)
	(segment
		(start 149.209252 -58.6359)
		(end 149.2758 -58.702448)
		(width 0.254)
		(layer "F.Cu")
		(net "P0V9_MODE")
	)
	(segment
		(start 149.937978 -59.677808)
		(end 150.65248 -59.677808)
		(width 0.254)
		(layer "F.Cu")
		(net "P0V9_MODE")
	)
	(segment
		(start 149.2758 -58.946542)
		(end 149.444202 -59.114944)
		(width 0.254)
		(layer "F.Cu")
		(net "P0V9_MODE")
	)
	(segment
		(start 149.460458 -59.14009)
		(end 149.460458 -59.200288)
		(width 0.254)
		(layer "F.Cu")
		(net "P0V9_MODE")
	)
	(segment
		(start 149.2758 -58.702448)
		(end 149.2758 -58.946542)
		(width 0.254)
		(layer "F.Cu")
		(net "P0V9_MODE")
	)
	(segment
		(start 149.460458 -59.200288)
		(end 149.937978 -59.677808)
		(width 0.254)
		(layer "F.Cu")
		(net "P0V9_MODE")
	)
	(segment
		(start 148.939758 -58.366406)
		(end 148.939758 -58.222642)
		(width 0.254)
		(layer "F.Cu")
		(net "P0V9_MODE")
	)
	(segment
		(start 148.783548 -58.066432)
		(end 148.542502 -58.066432)
		(width 0.254)
		(layer "F.Cu")
		(net "P0V9_MODE")
	)
	(segment
		(start 148.939758 -58.222642)
		(end 148.783548 -58.066432)
		(width 0.254)
		(layer "F.Cu")
		(net "P0V9_MODE")
	)
	(segment
		(start 149.444202 -59.123834)
		(end 149.460458 -59.14009)
		(width 0.254)
		(layer "F.Cu")
		(net "P0V9_MODE")
	)
	(segment
		(start 149.209252 -58.6359)
		(end 148.939758 -58.366406)
		(width 0.254)
		(layer "F.Cu")
		(net "P0V9_MODE")
	)
	(via
		(at 149.209252 -58.6359)
		(size 0.508)
		(drill 0.254)
		(layers "F.Cu" "B.Cu")
		(net "P0V9_MODE")
	)
	(via
		(at 147.3708 -56.896)
		(size 0.7112)
		(drill 0.3556)
		(layers "F.Cu" "B.Cu")
		(net "P0V9_MODE")
	)
	(segment
		(start 148.428202 -57.249822)
		(end 148.872702 -57.694322)
		(width 0.254)
		(layer "B.Cu")
		(net "P0V9_MODE")
	)
	(segment
		(start 147.755102 -56.986932)
		(end 148.428202 -56.986932)
		(width 0.254)
		(layer "B.Cu")
		(net "P0V9_MODE")
	)
	(segment
		(start 147.66417 -56.896)
		(end 147.755102 -56.986932)
		(width 0.254)
		(layer "B.Cu")
		(net "P0V9_MODE")
	)
	(segment
		(start 147.3708 -56.896)
		(end 147.66417 -56.896)
		(width 0.254)
		(layer "B.Cu")
		(net "P0V9_MODE")
	)
	(segment
		(start 148.872702 -58.29935)
		(end 149.209252 -58.6359)
		(width 0.254)
		(layer "B.Cu")
		(net "P0V9_MODE")
	)
	(segment
		(start 148.872702 -57.694322)
		(end 148.872702 -58.29935)
		(width 0.254)
		(layer "B.Cu")
		(net "P0V9_MODE")
	)
	(segment
		(start 148.428202 -56.986932)
		(end 148.428202 -57.249822)
		(width 0.254)
		(layer "B.Cu")
		(net "P0V9_MODE")
	)
	(segment
		(start 158.733236 -65.432432)
		(end 162.296602 -65.432432)
		(width 0.254)
		(layer "F.Cu")
		(net "P0V9_LX")
	)
	(segment
		(start 162.550602 -61.622432)
		(end 162.296602 -61.368432)
		(width 0.254)
		(layer "F.Cu")
		(net "P0V9_LX")
	)
	(segment
		(start 162.550602 -65.178432)
		(end 162.550602 -61.622432)
		(width 0.254)
		(layer "F.Cu")
		(net "P0V9_LX")
	)
	(segment
		(start 162.296602 -65.432432)
		(end 162.550602 -65.178432)
		(width 0.254)
		(layer "F.Cu")
		(net "P0V9_LX")
	)
	(via
		(at 159.655002 -63.273432)
		(size 0.508)
		(drill 0.254)
		(layers "F.Cu" "B.Cu")
		(net "P0V9_LX")
	)
	(via
		(at 162.296602 -61.368432)
		(size 0.508)
		(drill 0.254)
		(layers "F.Cu" "B.Cu")
		(net "P0V9_LX")
	)
	(via
		(at 160.290002 -61.495432)
		(size 0.508)
		(drill 0.254)
		(layers "F.Cu" "B.Cu")
		(net "P0V9_LX")
	)
	(segment
		(start 159.731202 -64.670432)
		(end 159.731202 -63.349632)
		(width 0.254)
		(layer "B.Cu")
		(net "P0V9_LX")
	)
	(segment
		(start 160.671002 -61.114432)
		(end 160.290002 -61.495432)
		(width 0.254)
		(layer "B.Cu")
		(net "P0V9_LX")
	)
	(segment
		(start 163.058602 -60.606432)
		(end 162.296602 -61.368432)
		(width 0.254)
		(layer "B.Cu")
		(net "P0V9_LX")
	)
	(segment
		(start 160.671002 -60.479432)
		(end 160.671002 -61.114432)
		(width 0.254)
		(layer "B.Cu")
		(net "P0V9_LX")
	)
	(segment
		(start 163.058602 -60.542932)
		(end 163.058602 -60.606432)
		(width 0.254)
		(layer "B.Cu")
		(net "P0V9_LX")
	)
	(segment
		(start 159.731202 -63.349632)
		(end 159.655002 -63.273432)
		(width 0.254)
		(layer "B.Cu")
		(net "P0V9_LX")
	)
	(segment
		(start 158.334202 -58.891932)
		(end 157.318202 -58.891932)
		(width 0.12065)
		(layer "F.Cu")
		(net "P0V9_EN")
	)
	(segment
		(start 159.350202 -58.891932)
		(end 160.366202 -58.891932)
		(width 0.12065)
		(layer "F.Cu")
		(net "P0V9_EN")
	)
	(segment
		(start 161.191702 -58.891932)
		(end 161.814002 -58.269632)
		(width 0.12065)
		(layer "F.Cu")
		(net "P0V9_EN")
	)
	(segment
		(start 160.366202 -58.891932)
		(end 161.191702 -58.891932)
		(width 0.12065)
		(layer "F.Cu")
		(net "P0V9_EN")
	)
	(segment
		(start 155.551124 -59.177936)
		(end 156.384498 -59.177936)
		(width 0.12065)
		(layer "F.Cu")
		(net "P0V9_EN")
	)
	(segment
		(start 156.384498 -59.177936)
		(end 156.670502 -58.891932)
		(width 0.12065)
		(layer "F.Cu")
		(net "P0V9_EN")
	)
	(segment
		(start 156.670502 -58.891932)
		(end 157.318202 -58.891932)
		(width 0.12065)
		(layer "F.Cu")
		(net "P0V9_EN")
	)
	(segment
		(start 159.350202 -58.891932)
		(end 158.334202 -58.891932)
		(width 0.12065)
		(layer "F.Cu")
		(net "P0V9_EN")
	)
	(via
		(at 161.814002 -58.269632)
		(size 0.7112)
		(drill 0.3556)
		(layers "F.Cu" "B.Cu")
		(net "P0V9_EN")
	)
	(segment
		(start 345.49207 -66.9798)
		(end 345.1352 -66.9798)
		(width 0.254)
		(layer "F.Cu")
		(net "P0V9_E_VREG")
	)
	(segment
		(start 344.5256 -67.2846)
		(end 343.31402 -67.2846)
		(width 0.254)
		(layer "F.Cu")
		(net "P0V9_E_VREG")
	)
	(segment
		(start 346.008706 -66.786506)
		(end 345.685364 -66.786506)
		(width 0.254)
		(layer "F.Cu")
		(net "P0V9_E_VREG")
	)
	(segment
		(start 343.31402 -67.2846)
		(end 343.232994 -67.365626)
		(width 0.254)
		(layer "F.Cu")
		(net "P0V9_E_VREG")
	)
	(segment
		(start 345.685364 -66.786506)
		(end 345.49207 -66.9798)
		(width 0.254)
		(layer "F.Cu")
		(net "P0V9_E_VREG")
	)
	(segment
		(start 345.1352 -66.9798)
		(end 344.678 -67.437)
		(width 0.254)
		(layer "F.Cu")
		(net "P0V9_E_VREG")
	)
	(segment
		(start 344.678 -67.437)
		(end 344.5256 -67.2846)
		(width 0.254)
		(layer "F.Cu")
		(net "P0V9_E_VREG")
	)
	(segment
		(start 346.008706 -67.566794)
		(end 346.008706 -66.786506)
		(width 0.254)
		(layer "F.Cu")
		(net "P0V9_E_VREG")
	)
	(segment
		(start 345.821 -67.7545)
		(end 346.008706 -67.566794)
		(width 0.254)
		(layer "F.Cu")
		(net "P0V9_E_VREG")
	)
	(segment
		(start 343.232994 -67.365626)
		(end 342.047322 -67.365626)
		(width 0.254)
		(layer "F.Cu")
		(net "P0V9_E_VREG")
	)
	(via
		(at 346.008706 -66.786506)
		(size 0.7112)
		(drill 0.3556)
		(layers "F.Cu" "B.Cu")
		(net "P0V9_E_VREG")
	)
	(via
		(at 343.1413 -61.214)
		(size 0.7112)
		(drill 0.4064)
		(layers "F.Cu" "B.Cu")
		(net "P0V9_E_VIN")
	)
	(via
		(at 343.29243 -50.43805)
		(size 0.7112)
		(drill 0.4064)
		(layers "F.Cu" "B.Cu")
		(net "P0V9_E_VIN")
	)
	(via
		(at 345.654376 -53.432964)
		(size 0.7112)
		(drill 0.4064)
		(layers "F.Cu" "B.Cu")
		(net "P0V9_E_VIN")
	)
	(via
		(at 343.29243 -51.531266)
		(size 0.7112)
		(drill 0.4064)
		(layers "F.Cu" "B.Cu")
		(net "P0V9_E_VIN")
	)
	(via
		(at 343.1413 -62.5094)
		(size 0.7112)
		(drill 0.4064)
		(layers "F.Cu" "B.Cu")
		(net "P0V9_E_VIN")
	)
	(via
		(at 345.603576 -56.865774)
		(size 0.7112)
		(drill 0.4064)
		(layers "F.Cu" "B.Cu")
		(net "P0V9_E_VIN")
	)
	(via
		(at 344.167206 -60.710064)
		(size 0.7112)
		(drill 0.4064)
		(layers "F.Cu" "B.Cu")
		(net "P0V9_E_VIN")
	)
	(via
		(at 343.396316 -54.678072)
		(size 0.7112)
		(drill 0.4064)
		(layers "F.Cu" "B.Cu")
		(net "P0V9_E_VIN")
	)
	(via
		(at 343.892632 -49.496218)
		(size 0.7112)
		(drill 0.3556)
		(layers "F.Cu" "B.Cu")
		(net "P0V9_E_VIN")
	)
	(via
		(at 343.351358 -57.867042)
		(size 0.7112)
		(drill 0.4064)
		(layers "F.Cu" "B.Cu")
		(net "P0V9_E_VIN")
	)
	(via
		(at 342.721692 -56.829198)
		(size 0.7112)
		(drill 0.4064)
		(layers "F.Cu" "B.Cu")
		(net "P0V9_E_VIN")
	)
	(via
		(at 344.409776 -53.419502)
		(size 0.7112)
		(drill 0.4064)
		(layers "F.Cu" "B.Cu")
		(net "P0V9_E_VIN")
	)
	(via
		(at 344.1827 -62.8142)
		(size 0.7112)
		(drill 0.4064)
		(layers "F.Cu" "B.Cu")
		(net "P0V9_E_VIN")
	)
	(via
		(at 343.382346 -55.777892)
		(size 0.7112)
		(drill 0.4064)
		(layers "F.Cu" "B.Cu")
		(net "P0V9_E_VIN")
	)
	(via
		(at 343.28735 -52.604416)
		(size 0.7112)
		(drill 0.4064)
		(layers "F.Cu" "B.Cu")
		(net "P0V9_E_VIN")
	)
	(via
		(at 342.808306 -53.688996)
		(size 0.7112)
		(drill 0.4064)
		(layers "F.Cu" "B.Cu")
		(net "P0V9_E_VIN")
	)
	(via
		(at 343.323672 -58.95975)
		(size 0.7112)
		(drill 0.4064)
		(layers "F.Cu" "B.Cu")
		(net "P0V9_E_VIN")
	)
	(via
		(at 343.150698 -60.135516)
		(size 0.7112)
		(drill 0.4064)
		(layers "F.Cu" "B.Cu")
		(net "P0V9_E_VIN")
	)
	(via
		(at 344.333576 -56.865774)
		(size 0.7112)
		(drill 0.4064)
		(layers "F.Cu" "B.Cu")
		(net "P0V9_E_VIN")
	)
	(segment
		(start 334.5815 -73.66)
		(end 334.518 -73.5965)
		(width 0.254)
		(layer "F.Cu")
		(net "P0V9_E_VFB_R")
	)
	(segment
		(start 334.5815 -74.676)
		(end 334.5815 -75.7174)
		(width 0.254)
		(layer "F.Cu")
		(net "P0V9_E_VFB_R")
	)
	(segment
		(start 334.518 -73.5965)
		(end 333.502 -73.5965)
		(width 0.254)
		(layer "F.Cu")
		(net "P0V9_E_VFB_R")
	)
	(segment
		(start 334.5815 -74.676)
		(end 334.5815 -73.66)
		(width 0.254)
		(layer "F.Cu")
		(net "P0V9_E_VFB_R")
	)
	(segment
		(start 334.5815 -75.7174)
		(end 334.5942 -75.7301)
		(width 0.254)
		(layer "F.Cu")
		(net "P0V9_E_VFB_R")
	)
	(segment
		(start 337.456272 -70.079616)
		(end 337.148678 -69.772022)
		(width 0.254)
		(layer "F.Cu")
		(net "P0V9_E_VFB")
	)
	(segment
		(start 335.4705 -73.66)
		(end 335.4705 -74.676)
		(width 0.254)
		(layer "F.Cu")
		(net "P0V9_E_VFB")
	)
	(segment
		(start 336.6135 -73.787)
		(end 336.6135 -75.483212)
		(width 0.254)
		(layer "F.Cu")
		(net "P0V9_E_VFB")
	)
	(segment
		(start 336.366612 -75.7301)
		(end 335.6356 -75.7301)
		(width 0.254)
		(layer "F.Cu")
		(net "P0V9_E_VFB")
	)
	(segment
		(start 335.4705 -75.565)
		(end 335.6356 -75.7301)
		(width 0.254)
		(layer "F.Cu")
		(net "P0V9_E_VFB")
	)
	(segment
		(start 336.6135 -75.483212)
		(end 336.366612 -75.7301)
		(width 0.254)
		(layer "F.Cu")
		(net "P0V9_E_VFB")
	)
	(segment
		(start 337.148678 -69.772022)
		(end 337.148678 -69.365622)
		(width 0.254)
		(layer "F.Cu")
		(net "P0V9_E_VFB")
	)
	(segment
		(start 335.4705 -72.771)
		(end 337.104482 -72.771)
		(width 0.254)
		(layer "F.Cu")
		(net "P0V9_E_VFB")
	)
	(segment
		(start 337.456272 -72.41921)
		(end 337.456272 -70.079616)
		(width 0.254)
		(layer "F.Cu")
		(net "P0V9_E_VFB")
	)
	(segment
		(start 335.4705 -74.676)
		(end 335.4705 -75.565)
		(width 0.254)
		(layer "F.Cu")
		(net "P0V9_E_VFB")
	)
	(segment
		(start 335.4705 -73.66)
		(end 335.4705 -72.771)
		(width 0.254)
		(layer "F.Cu")
		(net "P0V9_E_VFB")
	)
	(segment
		(start 337.104482 -72.771)
		(end 337.456272 -72.41921)
		(width 0.254)
		(layer "F.Cu")
		(net "P0V9_E_VFB")
	)
	(segment
		(start 343.487502 -67.865498)
		(end 343.535 -67.818)
		(width 0.254)
		(layer "F.Cu")
		(net "P0V9_E_VDD")
	)
	(segment
		(start 342.047322 -67.865498)
		(end 343.487502 -67.865498)
		(width 0.254)
		(layer "F.Cu")
		(net "P0V9_E_VDD")
	)
	(via
		(at 344.223086 -67.002914)
		(size 0.7112)
		(drill 0.3556)
		(layers "F.Cu" "B.Cu")
		(net "P0V9_E_VDD")
	)
	(via
		(at 343.535 -67.818)
		(size 0.508)
		(drill 0.254)
		(layers "F.Cu" "B.Cu")
		(net "P0V9_E_VDD")
	)
	(segment
		(start 344.223086 -67.002914)
		(end 345.1352 -66.0908)
		(width 0.254)
		(layer "B.Cu")
		(net "P0V9_E_VDD")
	)
	(segment
		(start 343.535 -67.691)
		(end 344.223086 -67.002914)
		(width 0.254)
		(layer "B.Cu")
		(net "P0V9_E_VDD")
	)
	(segment
		(start 346.2782 -64.643)
		(end 346.329 -64.6938)
		(width 0.254)
		(layer "B.Cu")
		(net "P0V9_E_VDD")
	)
	(segment
		(start 343.535 -67.818)
		(end 343.535 -67.691)
		(width 0.254)
		(layer "B.Cu")
		(net "P0V9_E_VDD")
	)
	(segment
		(start 345.1352 -66.0908)
		(end 346.329 -66.0908)
		(width 0.254)
		(layer "B.Cu")
		(net "P0V9_E_VDD")
	)
	(segment
		(start 346.329 -64.6938)
		(end 346.329 -66.0908)
		(width 0.254)
		(layer "B.Cu")
		(net "P0V9_E_VDD")
	)
	(segment
		(start 333.375 -67.7926)
		(end 333.4766 -67.691)
		(width 0.254)
		(layer "B.Cu")
		(net "P0V9_E_VBST_RC")
	)
	(segment
		(start 333.375 -68.9356)
		(end 333.375 -67.7926)
		(width 0.254)
		(layer "B.Cu")
		(net "P0V9_E_VBST_RC")
	)
	(segment
		(start 336.013298 -67.865498)
		(end 335.915 -67.7672)
		(width 0.254)
		(layer "F.Cu")
		(net "P0V9_E_VBST")
	)
	(segment
		(start 337.148678 -67.865498)
		(end 336.013298 -67.865498)
		(width 0.254)
		(layer "F.Cu")
		(net "P0V9_E_VBST")
	)
	(via
		(at 335.915 -67.7672)
		(size 0.508)
		(drill 0.254)
		(layers "F.Cu" "B.Cu")
		(net "P0V9_E_VBST")
	)
	(segment
		(start 335.8388 -67.691)
		(end 335.915 -67.7672)
		(width 0.254)
		(layer "B.Cu")
		(net "P0V9_E_VBST")
	)
	(segment
		(start 335.0006 -67.691)
		(end 335.8388 -67.691)
		(width 0.254)
		(layer "B.Cu")
		(net "P0V9_E_VBST")
	)
	(segment
		(start 343.408 -70.2818)
		(end 343.408 -70.669404)
		(width 0.254)
		(layer "F.Cu")
		(net "P0V9_E_TRIP")
	)
	(segment
		(start 343.408 -70.669404)
		(end 342.947244 -71.13016)
		(width 0.254)
		(layer "F.Cu")
		(net "P0V9_E_TRIP")
	)
	(segment
		(start 343.408 -69.215)
		(end 343.408 -70.2818)
		(width 0.254)
		(layer "F.Cu")
		(net "P0V9_E_TRIP")
	)
	(segment
		(start 343.058496 -68.865496)
		(end 343.408 -69.215)
		(width 0.254)
		(layer "F.Cu")
		(net "P0V9_E_TRIP")
	)
	(segment
		(start 342.047322 -68.865496)
		(end 343.058496 -68.865496)
		(width 0.254)
		(layer "F.Cu")
		(net "P0V9_E_TRIP")
	)
	(via
		(at 342.947244 -71.13016)
		(size 0.7112)
		(drill 0.3556)
		(layers "F.Cu" "B.Cu")
		(net "P0V9_E_TRIP")
	)
	(via
		(at 343.408 -70.2818)
		(size 0.508)
		(drill 0.254)
		(layers "F.Cu" "B.Cu")
		(net "P0V9_E_TRIP")
	)
	(segment
		(start 343.408 -70.358)
		(end 343.408 -70.2818)
		(width 0.254)
		(layer "B.Cu")
		(net "P0V9_E_TRIP")
	)
	(segment
		(start 344.1065 -71.0565)
		(end 343.408 -70.358)
		(width 0.254)
		(layer "B.Cu")
		(net "P0V9_E_TRIP")
	)
	(segment
		(start 344.17 -71.0565)
		(end 344.1065 -71.0565)
		(width 0.254)
		(layer "B.Cu")
		(net "P0V9_E_TRIP")
	)
	(segment
		(start 334.5815 -72.771)
		(end 333.756 -72.771)
		(width 0.254)
		(layer "F.Cu")
		(net "P0V9_E_SW_R")
	)
	(via
		(at 333.756 -72.771)
		(size 0.508)
		(drill 0.254)
		(layers "F.Cu" "B.Cu")
		(net "P0V9_E_SW_R")
	)
	(segment
		(start 333.756 -72.65162)
		(end 332.838552 -71.734172)
		(width 0.254)
		(layer "B.Cu")
		(net "P0V9_E_SW_R")
	)
	(segment
		(start 333.756 -72.771)
		(end 333.756 -72.65162)
		(width 0.254)
		(layer "B.Cu")
		(net "P0V9_E_SW_R")
	)
	(segment
		(start 328.591672 -71.734172)
		(end 327.533 -70.6755)
		(width 0.254)
		(layer "B.Cu")
		(net "P0V9_E_SW_R")
	)
	(segment
		(start 327.533 -70.5485)
		(end 328.549 -70.5485)
		(width 0.254)
		(layer "B.Cu")
		(net "P0V9_E_SW_R")
	)
	(segment
		(start 327.533 -70.6755)
		(end 327.533 -70.5485)
		(width 0.254)
		(layer "B.Cu")
		(net "P0V9_E_SW_R")
	)
	(segment
		(start 332.838552 -71.734172)
		(end 328.591672 -71.734172)
		(width 0.254)
		(layer "B.Cu")
		(net "P0V9_E_SW_R")
	)
	(segment
		(start 335.1022 -63.5)
		(end 334.9752 -63.627)
		(width 0.254)
		(layer "B.Cu")
		(net "P0V9_E_SNB")
	)
	(segment
		(start 336.3595 -63.5)
		(end 335.1022 -63.5)
		(width 0.254)
		(layer "B.Cu")
		(net "P0V9_E_SNB")
	)
	(segment
		(start 345.821 -68.6435)
		(end 345.821 -69.469)
		(width 0.254)
		(layer "F.Cu")
		(net "P0V9_E_RF")
	)
	(segment
		(start 342.047322 -69.759322)
		(end 342.519 -70.231)
		(width 0.254)
		(layer "F.Cu")
		(net "P0V9_E_RF")
	)
	(segment
		(start 342.047322 -69.365622)
		(end 342.047322 -69.759322)
		(width 0.254)
		(layer "F.Cu")
		(net "P0V9_E_RF")
	)
	(via
		(at 342.519 -70.231)
		(size 0.508)
		(drill 0.254)
		(layers "F.Cu" "B.Cu")
		(net "P0V9_E_RF")
	)
	(via
		(at 345.821 -69.469)
		(size 0.508)
		(drill 0.254)
		(layers "F.Cu" "B.Cu")
		(net "P0V9_E_RF")
	)
	(via
		(at 344.043 -68.834)
		(size 0.7112)
		(drill 0.3556)
		(layers "F.Cu" "B.Cu")
		(net "P0V9_E_RF")
	)
	(segment
		(start 342.519 -69.723)
		(end 343.408 -68.834)
		(width 0.254)
		(layer "B.Cu")
		(net "P0V9_E_RF")
	)
	(segment
		(start 345.821 -69.469)
		(end 345.186 -68.834)
		(width 0.254)
		(layer "B.Cu")
		(net "P0V9_E_RF")
	)
	(segment
		(start 342.519 -70.231)
		(end 342.519 -69.723)
		(width 0.254)
		(layer "B.Cu")
		(net "P0V9_E_RF")
	)
	(segment
		(start 343.154 -71.0565)
		(end 343.154 -70.866)
		(width 0.254)
		(layer "B.Cu")
		(net "P0V9_E_RF")
	)
	(segment
		(start 345.186 -68.834)
		(end 344.043 -68.834)
		(width 0.254)
		(layer "B.Cu")
		(net "P0V9_E_RF")
	)
	(segment
		(start 343.154 -70.866)
		(end 342.519 -70.231)
		(width 0.254)
		(layer "B.Cu")
		(net "P0V9_E_RF")
	)
	(segment
		(start 343.408 -68.834)
		(end 344.043 -68.834)
		(width 0.254)
		(layer "B.Cu")
		(net "P0V9_E_RF")
	)
	(segment
		(start 25.527 -114.0714)
		(end 27.3558 -114.0714)
		(width 0.12065)
		(layer "F.Cu")
		(net "P0V9_E_PG")
	)
	(segment
		(start 334.9625 -69.723)
		(end 334.9625 -69.7865)
		(width 0.12065)
		(layer "F.Cu")
		(net "P0V9_E_PG")
	)
	(segment
		(start 334.9625 -69.7865)
		(end 335.407 -70.231)
		(width 0.12065)
		(layer "F.Cu")
		(net "P0V9_E_PG")
	)
	(segment
		(start 335.407 -70.231)
		(end 335.788 -70.231)
		(width 0.12065)
		(layer "F.Cu")
		(net "P0V9_E_PG")
	)
	(segment
		(start 345.5035 -70.739)
		(end 345.948 -70.739)
		(width 0.12065)
		(layer "F.Cu")
		(net "P0V9_E_PG")
	)
	(segment
		(start 337.148678 -68.365624)
		(end 336.608928 -68.365624)
		(width 0.12065)
		(layer "F.Cu")
		(net "P0V9_E_PG")
	)
	(segment
		(start 23.368 -120.813068)
		(end 22.551136 -120.813068)
		(width 0.12065)
		(layer "F.Cu")
		(net "P0V9_E_PG")
	)
	(segment
		(start 23.774146 -121.219214)
		(end 23.368 -120.813068)
		(width 0.12065)
		(layer "F.Cu")
		(net "P0V9_E_PG")
	)
	(segment
		(start 336.608928 -68.365624)
		(end 335.505552 -69.469)
		(width 0.12065)
		(layer "F.Cu")
		(net "P0V9_E_PG")
	)
	(segment
		(start 27.3558 -114.0714)
		(end 27.4066 -114.0206)
		(width 0.12065)
		(layer "F.Cu")
		(net "P0V9_E_PG")
	)
	(segment
		(start 345.948 -70.739)
		(end 346.456 -71.247)
		(width 0.12065)
		(layer "F.Cu")
		(net "P0V9_E_PG")
	)
	(segment
		(start 335.505552 -69.469)
		(end 335.2165 -69.469)
		(width 0.12065)
		(layer "F.Cu")
		(net "P0V9_E_PG")
	)
	(segment
		(start 23.659846 -115.938554)
		(end 25.527 -114.0714)
		(width 0.12065)
		(layer "F.Cu")
		(net "P0V9_E_PG")
	)
	(segment
		(start 23.659846 -116.17198)
		(end 23.659846 -115.938554)
		(width 0.12065)
		(layer "F.Cu")
		(net "P0V9_E_PG")
	)
	(segment
		(start 21.938234 -117.893592)
		(end 23.659846 -116.17198)
		(width 0.12065)
		(layer "F.Cu")
		(net "P0V9_E_PG")
	)
	(segment
		(start 335.2165 -69.469)
		(end 334.9625 -69.723)
		(width 0.12065)
		(layer "F.Cu")
		(net "P0V9_E_PG")
	)
	(segment
		(start 22.551136 -120.813068)
		(end 21.938234 -120.200166)
		(width 0.12065)
		(layer "F.Cu")
		(net "P0V9_E_PG")
	)
	(segment
		(start 21.938234 -120.200166)
		(end 21.938234 -117.893592)
		(width 0.12065)
		(layer "F.Cu")
		(net "P0V9_E_PG")
	)
	(via
		(at 346.456 -71.247)
		(size 0.508)
		(drill 0.254)
		(layers "F.Cu" "B.Cu")
		(net "P0V9_E_PG")
	)
	(via
		(at 346.456 -76.073)
		(size 0.7112)
		(drill 0.3556)
		(layers "F.Cu" "B.Cu")
		(net "P0V9_E_PG")
	)
	(via
		(at 335.788 -70.231)
		(size 0.508)
		(drill 0.254)
		(layers "F.Cu" "B.Cu")
		(net "P0V9_E_PG")
	)
	(via
		(at 27.4066 -114.0206)
		(size 0.508)
		(drill 0.254)
		(layers "F.Cu" "B.Cu")
		(net "P0V9_E_PG")
	)
	(via
		(at 142.4686 -105.0798)
		(size 0.508)
		(drill 0.254)
		(layers "F.Cu" "B.Cu")
		(net "P0V9_E_PG")
	)
	(segment
		(start 142.9639 -105.5751)
		(end 142.4686 -105.0798)
		(width 0.12065)
		(layer "B.Cu")
		(net "P0V9_E_PG")
	)
	(segment
		(start 150.645622 -112.315752)
		(end 149.756622 -112.315752)
		(width 0.12065)
		(layer "B.Cu")
		(net "P0V9_E_PG")
	)
	(segment
		(start 346.456 -76.073)
		(end 346.456 -100.22713)
		(width 0.12065)
		(layer "B.Cu")
		(net "P0V9_E_PG")
	)
	(segment
		(start 143.01597 -105.5751)
		(end 142.9639 -105.5751)
		(width 0.12065)
		(layer "B.Cu")
		(net "P0V9_E_PG")
	)
	(segment
		(start 149.756622 -112.315752)
		(end 143.01597 -105.5751)
		(width 0.12065)
		(layer "B.Cu")
		(net "P0V9_E_PG")
	)
	(segment
		(start 334.367124 -112.316006)
		(end 150.645622 -112.315752)
		(width 0.12065)
		(layer "B.Cu")
		(net "P0V9_E_PG")
	)
	(segment
		(start 346.456 -100.22713)
		(end 334.367124 -112.316006)
		(width 0.12065)
		(layer "B.Cu")
		(net "P0V9_E_PG")
	)
	(segment
		(start 346.456 -76.073)
		(end 346.456 -71.247)
		(width 0.12065)
		(layer "B.Cu")
		(net "P0V9_E_PG")
	)
	(segment
		(start 63.614046 -106.2355)
		(end 63.7032 -106.146346)
		(width 0.127)
		(layer "In2.Cu")
		(net "P0V9_E_PG")
	)
	(segment
		(start 336.8167 -71.2597)
		(end 343.81313 -71.2597)
		(width 0.127)
		(layer "In2.Cu")
		(net "P0V9_E_PG")
	)
	(segment
		(start 33.8582 -108.058458)
		(end 33.8582 -106.1212)
		(width 0.127)
		(layer "In2.Cu")
		(net "P0V9_E_PG")
	)
	(segment
		(start 343.82583 -71.247)
		(end 346.456 -71.247)
		(width 0.127)
		(layer "In2.Cu")
		(net "P0V9_E_PG")
	)
	(segment
		(start 79.465678 -106.019346)
		(end 80.492346 -106.019346)
		(width 0.127)
		(layer "In2.Cu")
		(net "P0V9_E_PG")
	)
	(segment
		(start 59.478418 -105.4862)
		(end 60.646818 -106.6546)
		(width 0.127)
		(layer "In2.Cu")
		(net "P0V9_E_PG")
	)
	(segment
		(start 79.338678 -106.146346)
		(end 79.465678 -106.019346)
		(width 0.127)
		(layer "In2.Cu")
		(net "P0V9_E_PG")
	)
	(segment
		(start 63.578994 -106.2355)
		(end 63.614046 -106.2355)
		(width 0.127)
		(layer "In2.Cu")
		(net "P0V9_E_PG")
	)
	(segment
		(start 32.512 -110.916212)
		(end 32.512 -109.404658)
		(width 0.127)
		(layer "In2.Cu")
		(net "P0V9_E_PG")
	)
	(segment
		(start 56.629554 -104.198166)
		(end 57.917588 -105.4862)
		(width 0.127)
		(layer "In2.Cu")
		(net "P0V9_E_PG")
	)
	(segment
		(start 27.8892 -113.538)
		(end 29.890212 -113.538)
		(width 0.127)
		(layer "In2.Cu")
		(net "P0V9_E_PG")
	)
	(segment
		(start 63.159894 -106.6546)
		(end 63.578994 -106.2355)
		(width 0.127)
		(layer "In2.Cu")
		(net "P0V9_E_PG")
	)
	(segment
		(start 63.7032 -106.146346)
		(end 79.338678 -106.146346)
		(width 0.127)
		(layer "In2.Cu")
		(net "P0V9_E_PG")
	)
	(segment
		(start 46.39945 -104.198166)
		(end 56.629554 -104.198166)
		(width 0.127)
		(layer "In2.Cu")
		(net "P0V9_E_PG")
	)
	(segment
		(start 136.273286 -111.275114)
		(end 142.4686 -105.0798)
		(width 0.127)
		(layer "In2.Cu")
		(net "P0V9_E_PG")
	)
	(segment
		(start 60.646818 -106.6546)
		(end 63.159894 -106.6546)
		(width 0.127)
		(layer "In2.Cu")
		(net "P0V9_E_PG")
	)
	(segment
		(start 32.512 -109.404658)
		(end 33.8582 -108.058458)
		(width 0.127)
		(layer "In2.Cu")
		(net "P0V9_E_PG")
	)
	(segment
		(start 33.8582 -106.1212)
		(end 34.728658 -105.250742)
		(width 0.127)
		(layer "In2.Cu")
		(net "P0V9_E_PG")
	)
	(segment
		(start 34.728658 -105.250742)
		(end 45.346874 -105.250742)
		(width 0.127)
		(layer "In2.Cu")
		(net "P0V9_E_PG")
	)
	(segment
		(start 29.890212 -113.538)
		(end 32.512 -110.916212)
		(width 0.127)
		(layer "In2.Cu")
		(net "P0V9_E_PG")
	)
	(segment
		(start 80.492346 -106.019346)
		(end 85.748114 -111.275114)
		(width 0.127)
		(layer "In2.Cu")
		(net "P0V9_E_PG")
	)
	(segment
		(start 45.346874 -105.250742)
		(end 46.39945 -104.198166)
		(width 0.127)
		(layer "In2.Cu")
		(net "P0V9_E_PG")
	)
	(segment
		(start 27.4066 -114.0206)
		(end 27.8892 -113.538)
		(width 0.127)
		(layer "In2.Cu")
		(net "P0V9_E_PG")
	)
	(segment
		(start 85.748114 -111.275114)
		(end 136.273286 -111.275114)
		(width 0.127)
		(layer "In2.Cu")
		(net "P0V9_E_PG")
	)
	(segment
		(start 335.788 -70.231)
		(end 336.8167 -71.2597)
		(width 0.127)
		(layer "In2.Cu")
		(net "P0V9_E_PG")
	)
	(segment
		(start 343.81313 -71.2597)
		(end 343.82583 -71.247)
		(width 0.127)
		(layer "In2.Cu")
		(net "P0V9_E_PG")
	)
	(segment
		(start 57.917588 -105.4862)
		(end 59.478418 -105.4862)
		(width 0.127)
		(layer "In2.Cu")
		(net "P0V9_E_PG")
	)
	(segment
		(start 343.9922 -69.713348)
		(end 344.186764 -69.907912)
		(width 0.254)
		(layer "F.Cu")
		(net "P0V9_E_MODE")
	)
	(segment
		(start 344.186764 -69.907912)
		(end 344.23985 -69.960998)
		(width 0.254)
		(layer "F.Cu")
		(net "P0V9_E_MODE")
	)
	(segment
		(start 343.320624 -68.365624)
		(end 343.9922 -69.0372)
		(width 0.254)
		(layer "F.Cu")
		(net "P0V9_E_MODE")
	)
	(segment
		(start 344.23985 -69.960998)
		(end 344.23985 -70.36435)
		(width 0.254)
		(layer "F.Cu")
		(net "P0V9_E_MODE")
	)
	(segment
		(start 344.23985 -70.36435)
		(end 344.6145 -70.739)
		(width 0.254)
		(layer "F.Cu")
		(net "P0V9_E_MODE")
	)
	(segment
		(start 343.9922 -69.0372)
		(end 343.9922 -69.713348)
		(width 0.254)
		(layer "F.Cu")
		(net "P0V9_E_MODE")
	)
	(segment
		(start 342.047322 -68.365624)
		(end 343.320624 -68.365624)
		(width 0.254)
		(layer "F.Cu")
		(net "P0V9_E_MODE")
	)
	(segment
		(start 344.6145 -70.739)
		(end 344.5256 -70.8279)
		(width 0.254)
		(layer "F.Cu")
		(net "P0V9_E_MODE")
	)
	(segment
		(start 344.5256 -70.8279)
		(end 344.5256 -71.7296)
		(width 0.254)
		(layer "F.Cu")
		(net "P0V9_E_MODE")
	)
	(via
		(at 344.5256 -71.7296)
		(size 0.7112)
		(drill 0.3556)
		(layers "F.Cu" "B.Cu")
		(net "P0V9_E_MODE")
	)
	(via
		(at 344.186764 -69.907912)
		(size 0.508)
		(drill 0.254)
		(layers "F.Cu" "B.Cu")
		(net "P0V9_E_MODE")
	)
	(segment
		(start 345.186 -71.0565)
		(end 345.186 -70.907148)
		(width 0.254)
		(layer "B.Cu")
		(net "P0V9_E_MODE")
	)
	(segment
		(start 345.186 -70.907148)
		(end 344.186764 -69.907912)
		(width 0.254)
		(layer "B.Cu")
		(net "P0V9_E_MODE")
	)
	(segment
		(start 328.295 -62.23)
		(end 328.295 -68.58)
		(width 0.254)
		(layer "F.Cu")
		(net "P0V9_E_LX")
	)
	(segment
		(start 333.886556 -61.849)
		(end 328.676 -61.849)
		(width 0.254)
		(layer "F.Cu")
		(net "P0V9_E_LX")
	)
	(segment
		(start 328.295 -68.58)
		(end 328.549 -68.834)
		(width 0.254)
		(layer "F.Cu")
		(net "P0V9_E_LX")
	)
	(segment
		(start 328.676 -61.849)
		(end 328.295 -62.23)
		(width 0.254)
		(layer "F.Cu")
		(net "P0V9_E_LX")
	)
	(via
		(at 332.359 -66.675)
		(size 0.508)
		(drill 0.254)
		(layers "F.Cu" "B.Cu")
		(net "P0V9_E_LX")
	)
	(via
		(at 328.549 -68.834)
		(size 0.508)
		(drill 0.254)
		(layers "F.Cu" "B.Cu")
		(net "P0V9_E_LX")
	)
	(via
		(at 333.0448 -65.151)
		(size 0.508)
		(drill 0.254)
		(layers "F.Cu" "B.Cu")
		(net "P0V9_E_LX")
	)
	(segment
		(start 331.906372 -68.880228)
		(end 331.851 -68.9356)
		(width 0.254)
		(layer "B.Cu")
		(net "P0V9_E_LX")
	)
	(segment
		(start 331.906372 -67.127628)
		(end 331.906372 -68.880228)
		(width 0.254)
		(layer "B.Cu")
		(net "P0V9_E_LX")
	)
	(segment
		(start 328.549 -69.6595)
		(end 328.549 -68.834)
		(width 0.254)
		(layer "B.Cu")
		(net "P0V9_E_LX")
	)
	(segment
		(start 333.0448 -63.627)
		(end 333.0448 -65.151)
		(width 0.254)
		(layer "B.Cu")
		(net "P0V9_E_LX")
	)
	(segment
		(start 332.359 -66.675)
		(end 331.906372 -67.127628)
		(width 0.254)
		(layer "B.Cu")
		(net "P0V9_E_LX")
	)
	(segment
		(start 335.0387 -70.7898)
		(end 335.026 -70.8025)
		(width 0.12065)
		(layer "F.Cu")
		(net "P0V9_E_EN")
	)
	(segment
		(start 335.242154 -70.7898)
		(end 335.0387 -70.7898)
		(width 0.12065)
		(layer "F.Cu")
		(net "P0V9_E_EN")
	)
	(segment
		(start 337.148678 -68.865496)
		(end 336.62112 -68.865496)
		(width 0.12065)
		(layer "F.Cu")
		(net "P0V9_E_EN")
	)
	(segment
		(start 332.994 -70.8025)
		(end 334.01 -70.8025)
		(width 0.12065)
		(layer "F.Cu")
		(net "P0V9_E_EN")
	)
	(segment
		(start 336.590894 -70.186042)
		(end 336.590894 -70.907148)
		(width 0.12065)
		(layer "F.Cu")
		(net "P0V9_E_EN")
	)
	(segment
		(start 336.590894 -70.907148)
		(end 336.439256 -71.058786)
		(width 0.12065)
		(layer "F.Cu")
		(net "P0V9_E_EN")
	)
	(segment
		(start 336.254852 -69.85)
		(end 336.590894 -70.186042)
		(width 0.12065)
		(layer "F.Cu")
		(net "P0V9_E_EN")
	)
	(segment
		(start 336.254852 -69.231764)
		(end 336.254852 -69.85)
		(width 0.12065)
		(layer "F.Cu")
		(net "P0V9_E_EN")
	)
	(segment
		(start 331.978 -70.8025)
		(end 332.994 -70.8025)
		(width 0.12065)
		(layer "F.Cu")
		(net "P0V9_E_EN")
	)
	(segment
		(start 334.01 -70.8025)
		(end 335.026 -70.8025)
		(width 0.12065)
		(layer "F.Cu")
		(net "P0V9_E_EN")
	)
	(segment
		(start 336.62112 -68.865496)
		(end 336.254852 -69.231764)
		(width 0.12065)
		(layer "F.Cu")
		(net "P0V9_E_EN")
	)
	(segment
		(start 335.51114 -71.058786)
		(end 335.242154 -70.7898)
		(width 0.12065)
		(layer "F.Cu")
		(net "P0V9_E_EN")
	)
	(segment
		(start 336.439256 -71.058786)
		(end 335.51114 -71.058786)
		(width 0.12065)
		(layer "F.Cu")
		(net "P0V9_E_EN")
	)
	(via
		(at 336.590894 -70.907148)
		(size 0.7112)
		(drill 0.3556)
		(layers "F.Cu" "B.Cu")
		(net "P0V9_E_EN")
	)
	(segment
		(start 310.3118 -62.4586)
		(end 310.616092 -62.4586)
		(width 0.3048)
		(layer "F.Cu")
		(net "P0V9_E")
	)
	(segment
		(start 310.3118 -66.2686)
		(end 310.616092 -66.2686)
		(width 0.3048)
		(layer "F.Cu")
		(net "P0V9_E")
	)
	(segment
		(start 310.3118 -60.1726)
		(end 310.616092 -60.1726)
		(width 0.3048)
		(layer "F.Cu")
		(net "P0V9_E")
	)
	(segment
		(start 310.3118 -63.9826)
		(end 310.616092 -63.9826)
		(width 0.3048)
		(layer "F.Cu")
		(net "P0V9_E")
	)
	(segment
		(start 333.502 -74.4855)
		(end 332.9305 -74.4855)
		(width 0.254)
		(layer "F.Cu")
		(net "P0V9_E")
	)
	(segment
		(start 327.8886 -68.6054)
		(end 327.66 -68.834)
		(width 0.254)
		(layer "F.Cu")
		(net "P0V9_E")
	)
	(segment
		(start 310.3118 -59.4106)
		(end 310.616092 -59.4106)
		(width 0.3048)
		(layer "F.Cu")
		(net "P0V9_E")
	)
	(segment
		(start 310.3118 -64.7446)
		(end 310.616092 -64.7446)
		(width 0.3048)
		(layer "F.Cu")
		(net "P0V9_E")
	)
	(segment
		(start 327.6346 -61.849)
		(end 327.8886 -62.103)
		(width 0.254)
		(layer "F.Cu")
		(net "P0V9_E")
	)
	(segment
		(start 310.3118 -60.9346)
		(end 310.616092 -60.9346)
		(width 0.3048)
		(layer "F.Cu")
		(net "P0V9_E")
	)
	(segment
		(start 310.3118 -57.1246)
		(end 310.616092 -57.1246)
		(width 0.3048)
		(layer "F.Cu")
		(net "P0V9_E")
	)
	(segment
		(start 310.3118 -68.5546)
		(end 310.616092 -68.5546)
		(width 0.3048)
		(layer "F.Cu")
		(net "P0V9_E")
	)
	(segment
		(start 327.8886 -62.103)
		(end 327.8886 -68.6054)
		(width 0.254)
		(layer "F.Cu")
		(net "P0V9_E")
	)
	(segment
		(start 310.3118 -57.8866)
		(end 310.616092 -57.8866)
		(width 0.3048)
		(layer "F.Cu")
		(net "P0V9_E")
	)
	(segment
		(start 310.3118 -67.0306)
		(end 310.616092 -67.0306)
		(width 0.3048)
		(layer "F.Cu")
		(net "P0V9_E")
	)
	(segment
		(start 323.465444 -61.849)
		(end 327.6346 -61.849)
		(width 0.254)
		(layer "F.Cu")
		(net "P0V9_E")
	)
	(segment
		(start 310.3118 -63.2206)
		(end 310.616092 -63.2206)
		(width 0.3048)
		(layer "F.Cu")
		(net "P0V9_E")
	)
	(segment
		(start 310.3118 -67.7926)
		(end 310.616092 -67.7926)
		(width 0.3048)
		(layer "F.Cu")
		(net "P0V9_E")
	)
	(segment
		(start 310.3118 -61.6966)
		(end 310.616092 -61.6966)
		(width 0.3048)
		(layer "F.Cu")
		(net "P0V9_E")
	)
	(segment
		(start 332.9305 -74.4855)
		(end 332.7146 -74.2696)
		(width 0.254)
		(layer "F.Cu")
		(net "P0V9_E")
	)
	(segment
		(start 310.3118 -58.6486)
		(end 310.616092 -58.6486)
		(width 0.3048)
		(layer "F.Cu")
		(net "P0V9_E")
	)
	(segment
		(start 310.3118 -65.5066)
		(end 310.616092 -65.5066)
		(width 0.3048)
		(layer "F.Cu")
		(net "P0V9_E")
	)
	(via
		(at 311.404 -66.3702)
		(size 0.508)
		(drill 0.254)
		(layers "F.Cu" "B.Cu")
		(net "P0V9_E")
	)
	(via
		(at 313.436 -59.69)
		(size 0.7112)
		(drill 0.4064)
		(layers "F.Cu" "B.Cu")
		(net "P0V9_E")
	)
	(via
		(at 327.66 -68.834)
		(size 0.508)
		(drill 0.254)
		(layers "F.Cu" "B.Cu")
		(net "P0V9_E")
	)
	(via
		(at 313.3852 -62.6364)
		(size 0.7112)
		(drill 0.4064)
		(layers "F.Cu" "B.Cu")
		(net "P0V9_E")
	)
	(via
		(at 314.9092 -62.6364)
		(size 0.7112)
		(drill 0.4064)
		(layers "F.Cu" "B.Cu")
		(net "P0V9_E")
	)
	(via
		(at 57.15 -137.4902)
		(size 0.508)
		(drill 0.254)
		(layers "F.Cu" "B.Cu")
		(net "P0V9_E")
	)
	(via
		(at 317.5 -59.69)
		(size 0.7112)
		(drill 0.4064)
		(layers "F.Cu" "B.Cu")
		(net "P0V9_E")
	)
	(via
		(at 317.4746 -61.1378)
		(size 0.7112)
		(drill 0.4064)
		(layers "F.Cu" "B.Cu")
		(net "P0V9_E")
	)
	(via
		(at 312.166 -64.008)
		(size 0.7112)
		(drill 0.4064)
		(layers "F.Cu" "B.Cu")
		(net "P0V9_E")
	)
	(via
		(at 314.9346 -61.1378)
		(size 0.7112)
		(drill 0.4064)
		(layers "F.Cu" "B.Cu")
		(net "P0V9_E")
	)
	(via
		(at 320.294 -58.42)
		(size 0.7112)
		(drill 0.3556)
		(layers "F.Cu" "B.Cu")
		(net "P0V9_E")
	)
	(via
		(at 147.2946 -108.5596)
		(size 0.508)
		(drill 0.254)
		(layers "F.Cu" "B.Cu")
		(net "P0V9_E")
	)
	(via
		(at 317.5 -64.008)
		(size 0.7112)
		(drill 0.4064)
		(layers "F.Cu" "B.Cu")
		(net "P0V9_E")
	)
	(via
		(at 313.436 -64.008)
		(size 0.7112)
		(drill 0.4064)
		(layers "F.Cu" "B.Cu")
		(net "P0V9_E")
	)
	(via
		(at 320.675 -59.69)
		(size 0.7112)
		(drill 0.4064)
		(layers "F.Cu" "B.Cu")
		(net "P0V9_E")
	)
	(via
		(at 316.23 -59.69)
		(size 0.7112)
		(drill 0.4064)
		(layers "F.Cu" "B.Cu")
		(net "P0V9_E")
	)
	(via
		(at 312.1406 -61.1378)
		(size 0.7112)
		(drill 0.4064)
		(layers "F.Cu" "B.Cu")
		(net "P0V9_E")
	)
	(via
		(at 319.024 -64.008)
		(size 0.7112)
		(drill 0.4064)
		(layers "F.Cu" "B.Cu")
		(net "P0V9_E")
	)
	(via
		(at 323.977 -67.183)
		(size 0.508)
		(drill 0.254)
		(layers "F.Cu" "B.Cu")
		(net "P0V9_E")
	)
	(via
		(at 319.024 -59.69)
		(size 0.7112)
		(drill 0.4064)
		(layers "F.Cu" "B.Cu")
		(net "P0V9_E")
	)
	(via
		(at 320.548 -64.008)
		(size 0.7112)
		(drill 0.4064)
		(layers "F.Cu" "B.Cu")
		(net "P0V9_E")
	)
	(via
		(at 316.1792 -62.6364)
		(size 0.7112)
		(drill 0.4064)
		(layers "F.Cu" "B.Cu")
		(net "P0V9_E")
	)
	(via
		(at 317.4492 -62.6364)
		(size 0.7112)
		(drill 0.4064)
		(layers "F.Cu" "B.Cu")
		(net "P0V9_E")
	)
	(via
		(at 316.2046 -61.1378)
		(size 0.7112)
		(drill 0.4064)
		(layers "F.Cu" "B.Cu")
		(net "P0V9_E")
	)
	(via
		(at 314.96 -64.008)
		(size 0.7112)
		(drill 0.4064)
		(layers "F.Cu" "B.Cu")
		(net "P0V9_E")
	)
	(via
		(at 318.9986 -61.1378)
		(size 0.7112)
		(drill 0.4064)
		(layers "F.Cu" "B.Cu")
		(net "P0V9_E")
	)
	(via
		(at 314.96 -59.69)
		(size 0.7112)
		(drill 0.4064)
		(layers "F.Cu" "B.Cu")
		(net "P0V9_E")
	)
	(via
		(at 313.4106 -61.1378)
		(size 0.7112)
		(drill 0.4064)
		(layers "F.Cu" "B.Cu")
		(net "P0V9_E")
	)
	(via
		(at 332.7146 -74.2696)
		(size 0.508)
		(drill 0.254)
		(layers "F.Cu" "B.Cu")
		(net "P0V9_E")
	)
	(via
		(at 316.23 -64.008)
		(size 0.7112)
		(drill 0.4064)
		(layers "F.Cu" "B.Cu")
		(net "P0V9_E")
	)
	(via
		(at 318.9732 -62.6364)
		(size 0.7112)
		(drill 0.4064)
		(layers "F.Cu" "B.Cu")
		(net "P0V9_E")
	)
	(via
		(at 312.039 -59.69)
		(size 0.7112)
		(drill 0.4064)
		(layers "F.Cu" "B.Cu")
		(net "P0V9_E")
	)
	(via
		(at 312.1152 -62.6364)
		(size 0.7112)
		(drill 0.4064)
		(layers "F.Cu" "B.Cu")
		(net "P0V9_E")
	)
	(segment
		(start 341.376 -82.97164)
		(end 335.068164 -76.663804)
		(width 0.254)
		(layer "B.Cu")
		(net "P0V9_E")
	)
	(segment
		(start 335.068164 -76.663804)
		(end 331.466444 -76.663804)
		(width 0.254)
		(layer "B.Cu")
		(net "P0V9_E")
	)
	(segment
		(start 331.466444 -76.663804)
		(end 323.977 -69.17436)
		(width 0.254)
		(layer "B.Cu")
		(net "P0V9_E")
	)
	(segment
		(start 310.3118 -63.119)
		(end 310.694832 -63.119)
		(width 0.3048)
		(layer "B.Cu")
		(net "P0V9_E")
	)
	(segment
		(start 310.3118 -57.023)
		(end 310.694832 -57.023)
		(width 0.3048)
		(layer "B.Cu")
		(net "P0V9_E")
	)
	(segment
		(start 150.495 -111.76)
		(end 334.137 -111.76)
		(width 0.254)
		(layer "B.Cu")
		(net "P0V9_E")
	)
	(segment
		(start 310.3118 -67.691)
		(end 310.694832 -67.691)
		(width 0.3048)
		(layer "B.Cu")
		(net "P0V9_E")
	)
	(segment
		(start 310.3118 -62.357)
		(end 310.694832 -62.357)
		(width 0.3048)
		(layer "B.Cu")
		(net "P0V9_E")
	)
	(segment
		(start 334.137 -111.76)
		(end 341.376 -104.521)
		(width 0.254)
		(layer "B.Cu")
		(net "P0V9_E")
	)
	(segment
		(start 310.3118 -63.881)
		(end 310.694832 -63.881)
		(width 0.3048)
		(layer "B.Cu")
		(net "P0V9_E")
	)
	(segment
		(start 341.376 -104.521)
		(end 341.376 -82.97164)
		(width 0.254)
		(layer "B.Cu")
		(net "P0V9_E")
	)
	(segment
		(start 310.3118 -66.929)
		(end 310.694832 -66.929)
		(width 0.3048)
		(layer "B.Cu")
		(net "P0V9_E")
	)
	(segment
		(start 327.533 -69.6595)
		(end 327.533 -68.961)
		(width 0.254)
		(layer "B.Cu")
		(net "P0V9_E")
	)
	(segment
		(start 323.977 -69.17436)
		(end 323.977 -67.183)
		(width 0.254)
		(layer "B.Cu")
		(net "P0V9_E")
	)
	(segment
		(start 310.3118 -60.833)
		(end 310.694832 -60.833)
		(width 0.3048)
		(layer "B.Cu")
		(net "P0V9_E")
	)
	(segment
		(start 57.15 -136.7155)
		(end 57.15 -137.4902)
		(width 0.254)
		(layer "B.Cu")
		(net "P0V9_E")
	)
	(segment
		(start 310.3118 -56.261)
		(end 310.694832 -56.261)
		(width 0.3048)
		(layer "B.Cu")
		(net "P0V9_E")
	)
	(segment
		(start 310.3118 -65.405)
		(end 310.694832 -65.405)
		(width 0.3048)
		(layer "B.Cu")
		(net "P0V9_E")
	)
	(segment
		(start 327.533 -68.961)
		(end 327.66 -68.834)
		(width 0.254)
		(layer "B.Cu")
		(net "P0V9_E")
	)
	(segment
		(start 310.3118 -59.309)
		(end 310.694832 -59.309)
		(width 0.3048)
		(layer "B.Cu")
		(net "P0V9_E")
	)
	(segment
		(start 310.3118 -61.595)
		(end 310.694832 -61.595)
		(width 0.3048)
		(layer "B.Cu")
		(net "P0V9_E")
	)
	(segment
		(start 310.3118 -64.643)
		(end 310.694832 -64.643)
		(width 0.3048)
		(layer "B.Cu")
		(net "P0V9_E")
	)
	(segment
		(start 310.3118 -60.071)
		(end 310.694832 -60.071)
		(width 0.3048)
		(layer "B.Cu")
		(net "P0V9_E")
	)
	(segment
		(start 147.2946 -108.5596)
		(end 150.495 -111.76)
		(width 0.254)
		(layer "B.Cu")
		(net "P0V9_E")
	)
	(segment
		(start 310.3118 -58.547)
		(end 310.694832 -58.547)
		(width 0.3048)
		(layer "B.Cu")
		(net "P0V9_E")
	)
	(segment
		(start 310.3118 -57.785)
		(end 310.694832 -57.785)
		(width 0.3048)
		(layer "B.Cu")
		(net "P0V9_E")
	)
	(segment
		(start 310.3118 -66.167)
		(end 310.694832 -66.167)
		(width 0.3048)
		(layer "B.Cu")
		(net "P0V9_E")
	)
	(segment
		(start 95.942404 -113.103152)
		(end 142.751048 -113.103152)
		(width 0.254)
		(layer "In2.Cu")
		(net "P0V9_E")
	)
	(segment
		(start 57.15 -137.4902)
		(end 71.555356 -137.4902)
		(width 0.254)
		(layer "In2.Cu")
		(net "P0V9_E")
	)
	(segment
		(start 71.555356 -137.4902)
		(end 95.942404 -113.103152)
		(width 0.254)
		(layer "In2.Cu")
		(net "P0V9_E")
	)
	(segment
		(start 142.751048 -113.103152)
		(end 147.2946 -108.5596)
		(width 0.254)
		(layer "In2.Cu")
		(net "P0V9_E")
	)
	(segment
		(start 310.2102 -67.564)
		(end 310.2102 -76.327)
		(width 0.254)
		(layer "In5.Cu")
		(net "P0V9_E")
	)
	(segment
		(start 310.2102 -76.327)
		(end 312.039 -78.1558)
		(width 0.254)
		(layer "In5.Cu")
		(net "P0V9_E")
	)
	(segment
		(start 311.404 -66.3702)
		(end 310.2102 -67.564)
		(width 0.254)
		(layer "In5.Cu")
		(net "P0V9_E")
	)
	(segment
		(start 312.039 -78.1558)
		(end 328.8284 -78.1558)
		(width 0.254)
		(layer "In5.Cu")
		(net "P0V9_E")
	)
	(segment
		(start 328.8284 -78.1558)
		(end 332.7146 -74.2696)
		(width 0.254)
		(layer "In5.Cu")
		(net "P0V9_E")
	)
	(segment
		(start 177.8 -65.405)
		(end 177.48123 -65.405)
		(width 0.3048)
		(layer "F.Cu")
		(net "P0V9")
	)
	(segment
		(start 67.183 -132.467858)
		(end 67.183 -132.412486)
		(width 0.508)
		(layer "F.Cu")
		(net "P0V9")
	)
	(segment
		(start 177.8 -66.167)
		(end 177.48123 -66.167)
		(width 0.3048)
		(layer "F.Cu")
		(net "P0V9")
	)
	(segment
		(start 162.957002 -65.143634)
		(end 162.957002 -61.597032)
		(width 0.254)
		(layer "F.Cu")
		(net "P0V9")
	)
	(segment
		(start 177.8 -68.453)
		(end 177.48123 -68.453)
		(width 0.3048)
		(layer "F.Cu")
		(net "P0V9")
	)
	(segment
		(start 66.604388 -133.0198)
		(end 66.631058 -133.0198)
		(width 0.508)
		(layer "F.Cu")
		(net "P0V9")
	)
	(segment
		(start 177.485802 -70.766432)
		(end 177.485802 -70.443598)
		(width 0.3048)
		(layer "F.Cu")
		(net "P0V9")
	)
	(segment
		(start 177.8 -64.643)
		(end 177.48123 -64.643)
		(width 0.3048)
		(layer "F.Cu")
		(net "P0V9")
	)
	(segment
		(start 176.723802 -70.766432)
		(end 176.723802 -70.443598)
		(width 0.3048)
		(layer "F.Cu")
		(net "P0V9")
	)
	(segment
		(start 177.8 -67.691)
		(end 177.48123 -67.691)
		(width 0.3048)
		(layer "F.Cu")
		(net "P0V9")
	)
	(segment
		(start 160.620202 -55.272432)
		(end 160.251902 -55.272432)
		(width 0.254)
		(layer "F.Cu")
		(net "P0V9")
	)
	(segment
		(start 161.33826 -55.788814)
		(end 161.200846 -55.6514)
		(width 0.254)
		(layer "F.Cu")
		(net "P0V9")
	)
	(segment
		(start 166.774368 -65.432432)
		(end 163.2458 -65.432432)
		(width 0.254)
		(layer "F.Cu")
		(net "P0V9")
	)
	(segment
		(start 161.200846 -55.6514)
		(end 160.99917 -55.6514)
		(width 0.254)
		(layer "F.Cu")
		(net "P0V9")
	)
	(segment
		(start 177.8 -69.215)
		(end 177.48123 -69.215)
		(width 0.3048)
		(layer "F.Cu")
		(net "P0V9")
	)
	(segment
		(start 177.8 -63.881)
		(end 177.48123 -63.881)
		(width 0.3048)
		(layer "F.Cu")
		(net "P0V9")
	)
	(segment
		(start 162.957002 -61.597032)
		(end 163.185602 -61.368432)
		(width 0.254)
		(layer "F.Cu")
		(net "P0V9")
	)
	(segment
		(start 66.631058 -133.0198)
		(end 67.183 -132.467858)
		(width 0.508)
		(layer "F.Cu")
		(net "P0V9")
	)
	(segment
		(start 177.8 -66.929)
		(end 177.48123 -66.929)
		(width 0.3048)
		(layer "F.Cu")
		(net "P0V9")
	)
	(segment
		(start 163.2458 -65.432432)
		(end 162.957002 -65.143634)
		(width 0.254)
		(layer "F.Cu")
		(net "P0V9")
	)
	(segment
		(start 175.961802 -70.766432)
		(end 175.961802 -70.443598)
		(width 0.3048)
		(layer "F.Cu")
		(net "P0V9")
	)
	(segment
		(start 65.405 -133.5405)
		(end 66.083688 -133.5405)
		(width 0.508)
		(layer "F.Cu")
		(net "P0V9")
	)
	(segment
		(start 66.083688 -133.5405)
		(end 66.604388 -133.0198)
		(width 0.508)
		(layer "F.Cu")
		(net "P0V9")
	)
	(segment
		(start 160.99917 -55.6514)
		(end 160.620202 -55.272432)
		(width 0.254)
		(layer "F.Cu")
		(net "P0V9")
	)
	(via
		(at 175.189642 -69.785992)
		(size 0.7112)
		(drill 0.4064)
		(layers "F.Cu" "B.Cu")
		(net "P0V9")
	)
	(via
		(at 171.339002 -69.775832)
		(size 0.7112)
		(drill 0.4064)
		(layers "F.Cu" "B.Cu")
		(net "P0V9")
	)
	(via
		(at 176.53 -64.9732)
		(size 0.7112)
		(drill 0.4064)
		(layers "F.Cu" "B.Cu")
		(net "P0V9")
	)
	(via
		(at 175.164242 -68.490592)
		(size 0.7112)
		(drill 0.4064)
		(layers "F.Cu" "B.Cu")
		(net "P0V9")
	)
	(via
		(at 175.319182 -64.959992)
		(size 0.7112)
		(drill 0.4064)
		(layers "F.Cu" "B.Cu")
		(net "P0V9")
	)
	(via
		(at 170.086782 -65.823592)
		(size 0.7112)
		(drill 0.4064)
		(layers "F.Cu" "B.Cu")
		(net "P0V9")
	)
	(via
		(at 172.649642 -69.785992)
		(size 0.7112)
		(drill 0.4064)
		(layers "F.Cu" "B.Cu")
		(net "P0V9")
	)
	(via
		(at 175.293782 -66.128392)
		(size 0.7112)
		(drill 0.4064)
		(layers "F.Cu" "B.Cu")
		(net "P0V9")
	)
	(via
		(at 176.332642 -69.785992)
		(size 0.7112)
		(drill 0.4064)
		(layers "F.Cu" "B.Cu")
		(net "P0V9")
	)
	(via
		(at 170.196002 -69.775832)
		(size 0.7112)
		(drill 0.4064)
		(layers "F.Cu" "B.Cu")
		(net "P0V9")
	)
	(via
		(at 157.2514 -106.172)
		(size 0.508)
		(drill 0.254)
		(layers "F.Cu" "B.Cu")
		(net "P0V9")
	)
	(via
		(at 161.33826 -55.788814)
		(size 0.508)
		(drill 0.254)
		(layers "F.Cu" "B.Cu")
		(net "P0V9")
	)
	(via
		(at 163.185602 -61.368432)
		(size 0.508)
		(drill 0.254)
		(layers "F.Cu" "B.Cu")
		(net "P0V9")
	)
	(via
		(at 176.520602 -68.480432)
		(size 0.7112)
		(drill 0.4064)
		(layers "F.Cu" "B.Cu")
		(net "P0V9")
	)
	(via
		(at 176.436782 -66.128392)
		(size 0.7112)
		(drill 0.4064)
		(layers "F.Cu" "B.Cu")
		(net "P0V9")
	)
	(via
		(at 173.792642 -69.785992)
		(size 0.7112)
		(drill 0.4064)
		(layers "F.Cu" "B.Cu")
		(net "P0V9")
	)
	(via
		(at 67.183 -132.412486)
		(size 0.508)
		(drill 0.254)
		(layers "F.Cu" "B.Cu")
		(net "P0V9")
	)
	(via
		(at 171.229782 -65.823592)
		(size 0.7112)
		(drill 0.4064)
		(layers "F.Cu" "B.Cu")
		(net "P0V9")
	)
	(via
		(at 170.29811 -67.71259)
		(size 0.7112)
		(drill 0.3556)
		(layers "F.Cu" "B.Cu")
		(net "P0V9")
	)
	(via
		(at 172.753782 -65.823592)
		(size 0.7112)
		(drill 0.4064)
		(layers "F.Cu" "B.Cu")
		(net "P0V9")
	)
	(via
		(at 173.896782 -65.823592)
		(size 0.7112)
		(drill 0.4064)
		(layers "F.Cu" "B.Cu")
		(net "P0V9")
	)
	(segment
		(start 177.7746 -63.881)
		(end 177.45583 -63.881)
		(width 0.3048)
		(layer "B.Cu")
		(net "P0V9")
	)
	(segment
		(start 177.7746 -66.929)
		(end 177.45583 -66.929)
		(width 0.3048)
		(layer "B.Cu")
		(net "P0V9")
	)
	(segment
		(start 177.7746 -66.167)
		(end 177.45583 -66.167)
		(width 0.3048)
		(layer "B.Cu")
		(net "P0V9")
	)
	(segment
		(start 177.7746 -67.691)
		(end 177.45583 -67.691)
		(width 0.3048)
		(layer "B.Cu")
		(net "P0V9")
	)
	(segment
		(start 175.961802 -70.766432)
		(end 175.961802 -70.392798)
		(width 0.3048)
		(layer "B.Cu")
		(net "P0V9")
	)
	(segment
		(start 177.485802 -70.766432)
		(end 177.485802 -70.392798)
		(width 0.3048)
		(layer "B.Cu")
		(net "P0V9")
	)
	(segment
		(start 168.021 -80.264)
		(end 168.021 -71.798434)
		(width 0.508)
		(layer "B.Cu")
		(net "P0V9")
	)
	(segment
		(start 177.7746 -68.453)
		(end 177.45583 -68.453)
		(width 0.3048)
		(layer "B.Cu")
		(net "P0V9")
	)
	(segment
		(start 177.7746 -64.643)
		(end 177.45583 -64.643)
		(width 0.3048)
		(layer "B.Cu")
		(net "P0V9")
	)
	(segment
		(start 157.2514 -106.172)
		(end 157.6324 -106.172)
		(width 0.508)
		(layer "B.Cu")
		(net "P0V9")
	)
	(segment
		(start 170.043602 -69.775832)
		(end 170.196002 -69.775832)
		(width 0.508)
		(layer "B.Cu")
		(net "P0V9")
	)
	(segment
		(start 163.316412 -61.368432)
		(end 163.185602 -61.368432)
		(width 0.254)
		(layer "B.Cu")
		(net "P0V9")
	)
	(segment
		(start 176.723802 -70.766432)
		(end 176.723802 -70.392798)
		(width 0.3048)
		(layer "B.Cu")
		(net "P0V9")
	)
	(segment
		(start 168.021 -71.798434)
		(end 170.043602 -69.775832)
		(width 0.508)
		(layer "B.Cu")
		(net "P0V9")
	)
	(segment
		(start 171.069 -92.7354)
		(end 171.069 -83.312)
		(width 0.508)
		(layer "B.Cu")
		(net "P0V9")
	)
	(segment
		(start 157.6324 -106.172)
		(end 171.069 -92.7354)
		(width 0.508)
		(layer "B.Cu")
		(net "P0V9")
	)
	(segment
		(start 163.998402 -60.517532)
		(end 163.998402 -60.686442)
		(width 0.254)
		(layer "B.Cu")
		(net "P0V9")
	)
	(segment
		(start 177.7746 -65.405)
		(end 177.45583 -65.405)
		(width 0.3048)
		(layer "B.Cu")
		(net "P0V9")
	)
	(segment
		(start 177.7746 -69.215)
		(end 177.45583 -69.215)
		(width 0.3048)
		(layer "B.Cu")
		(net "P0V9")
	)
	(segment
		(start 171.069 -83.312)
		(end 168.021 -80.264)
		(width 0.508)
		(layer "B.Cu")
		(net "P0V9")
	)
	(segment
		(start 163.998402 -60.686442)
		(end 163.316412 -61.368432)
		(width 0.254)
		(layer "B.Cu")
		(net "P0V9")
	)
	(segment
		(start 82.74812 -120.527826)
		(end 82.74812 -119.781066)
		(width 0.508)
		(layer "In2.Cu")
		(net "P0V9")
	)
	(segment
		(start 147.086828 -106.045)
		(end 157.1244 -106.045)
		(width 0.508)
		(layer "In2.Cu")
		(net "P0V9")
	)
	(segment
		(start 163.185602 -61.368432)
		(end 163.185602 -57.636156)
		(width 0.254)
		(layer "In2.Cu")
		(net "P0V9")
	)
	(segment
		(start 163.185602 -57.636156)
		(end 161.33826 -55.788814)
		(width 0.254)
		(layer "In2.Cu")
		(net "P0V9")
	)
	(segment
		(start 67.982592 -132.412486)
		(end 71.794878 -128.6002)
		(width 0.508)
		(layer "In2.Cu")
		(net "P0V9")
	)
	(segment
		(start 67.183 -132.412486)
		(end 67.982592 -132.412486)
		(width 0.508)
		(layer "In2.Cu")
		(net "P0V9")
	)
	(segment
		(start 74.675746 -128.6002)
		(end 82.74812 -120.527826)
		(width 0.508)
		(layer "In2.Cu")
		(net "P0V9")
	)
	(segment
		(start 157.1244 -106.045)
		(end 157.2514 -106.172)
		(width 0.508)
		(layer "In2.Cu")
		(net "P0V9")
	)
	(segment
		(start 140.74648 -112.385348)
		(end 147.086828 -106.045)
		(width 0.508)
		(layer "In2.Cu")
		(net "P0V9")
	)
	(segment
		(start 82.74812 -119.781066)
		(end 90.143838 -112.385348)
		(width 0.508)
		(layer "In2.Cu")
		(net "P0V9")
	)
	(segment
		(start 71.794878 -128.6002)
		(end 74.675746 -128.6002)
		(width 0.508)
		(layer "In2.Cu")
		(net "P0V9")
	)
	(segment
		(start 90.143838 -112.385348)
		(end 140.74648 -112.385348)
		(width 0.508)
		(layer "In2.Cu")
		(net "P0V9")
	)
	(segment
		(start 25.843992 -144.653508)
		(end 25.843992 -146.402552)
		(width 0.1524)
		(layer "F.Cu")
		(net "OSC2_OUT")
	)
	(segment
		(start 25.8445 -144.653)
		(end 25.843992 -144.653508)
		(width 0.1524)
		(layer "F.Cu")
		(net "OSC2_OUT")
	)
	(segment
		(start 24.384 -150.495)
		(end 24.194008 -150.305008)
		(width 0.1524)
		(layer "F.Cu")
		(net "OSC2_CONT")
	)
	(segment
		(start 24.194008 -150.305008)
		(end 24.194008 -148.745448)
		(width 0.1524)
		(layer "F.Cu")
		(net "OSC2_CONT")
	)
	(segment
		(start 24.9555 -150.495)
		(end 24.384 -150.495)
		(width 0.1524)
		(layer "F.Cu")
		(net "OSC2_CONT")
	)
	(segment
		(start 26.0096 -141.2494)
		(end 25.2476 -141.2494)
		(width 0.1524)
		(layer "F.Cu")
		(net "OSC0_AS_CLKIN")
	)
	(segment
		(start 29.704792 -138.884914)
		(end 28.780486 -138.884914)
		(width 0.1524)
		(layer "F.Cu")
		(net "OSC0_AS_CLKIN")
	)
	(segment
		(start 24.4856 -144.1831)
		(end 24.9555 -144.653)
		(width 0.1524)
		(layer "F.Cu")
		(net "OSC0_AS_CLKIN")
	)
	(segment
		(start 28.780486 -138.884914)
		(end 26.5684 -141.097)
		(width 0.1524)
		(layer "F.Cu")
		(net "OSC0_AS_CLKIN")
	)
	(segment
		(start 25.2476 -141.2494)
		(end 24.95296 -141.54404)
		(width 0.1524)
		(layer "F.Cu")
		(net "OSC0_AS_CLKIN")
	)
	(segment
		(start 24.4856 -143.8148)
		(end 24.4856 -144.1831)
		(width 0.1524)
		(layer "F.Cu")
		(net "OSC0_AS_CLKIN")
	)
	(segment
		(start 24.9809 -142.280132)
		(end 24.9809 -143.3195)
		(width 0.1524)
		(layer "F.Cu")
		(net "OSC0_AS_CLKIN")
	)
	(segment
		(start 24.95296 -141.54404)
		(end 24.95296 -142.252192)
		(width 0.1524)
		(layer "F.Cu")
		(net "OSC0_AS_CLKIN")
	)
	(segment
		(start 26.162 -141.097)
		(end 26.0096 -141.2494)
		(width 0.1524)
		(layer "F.Cu")
		(net "OSC0_AS_CLKIN")
	)
	(segment
		(start 26.5684 -141.097)
		(end 26.162 -141.097)
		(width 0.1524)
		(layer "F.Cu")
		(net "OSC0_AS_CLKIN")
	)
	(segment
		(start 24.95296 -142.252192)
		(end 24.9809 -142.280132)
		(width 0.1524)
		(layer "F.Cu")
		(net "OSC0_AS_CLKIN")
	)
	(segment
		(start 24.9809 -143.3195)
		(end 24.4856 -143.8148)
		(width 0.1524)
		(layer "F.Cu")
		(net "OSC0_AS_CLKIN")
	)
	(via
		(at 26.162 -141.097)
		(size 0.7112)
		(drill 0.3556)
		(layers "F.Cu" "B.Cu")
		(net "OSC0_AS_CLKIN")
	)
	(segment
		(start 12.665964 -92.533978)
		(end 12.665964 -93.031564)
		(width 0.12065)
		(layer "F.Cu")
		(net "NCSI_10G_RCLK")
	)
	(segment
		(start 12.665964 -93.031564)
		(end 14.351 -94.7166)
		(width 0.12065)
		(layer "F.Cu")
		(net "NCSI_10G_RCLK")
	)
	(segment
		(start 22.183598 -144.594072)
		(end 21.80717 -144.9705)
		(width 0.508)
		(layer "F.Cu")
		(net "MPLLAV33")
	)
	(segment
		(start 20.447 -144.9705)
		(end 19.177 -144.9705)
		(width 0.508)
		(layer "F.Cu")
		(net "MPLLAV33")
	)
	(segment
		(start 21.336 -144.9705)
		(end 20.447 -144.9705)
		(width 0.508)
		(layer "F.Cu")
		(net "MPLLAV33")
	)
	(segment
		(start 32.104838 -138.884914)
		(end 31.704788 -138.484864)
		(width 0.3556)
		(layer "F.Cu")
		(net "MPLLAV33")
	)
	(segment
		(start 19.177 -144.9705)
		(end 18.796 -145.3515)
		(width 0.508)
		(layer "F.Cu")
		(net "MPLLAV33")
	)
	(segment
		(start 21.80717 -144.9705)
		(end 21.336 -144.9705)
		(width 0.508)
		(layer "F.Cu")
		(net "MPLLAV33")
	)
	(segment
		(start 33.704784 -135.684768)
		(end 33.304988 -135.284972)
		(width 0.3556)
		(layer "F.Cu")
		(net "MPLLAV33")
	)
	(segment
		(start 17.2212 -145.415)
		(end 18.7325 -145.415)
		(width 0.508)
		(layer "F.Cu")
		(net "MPLLAV33")
	)
	(segment
		(start 18.7325 -145.415)
		(end 18.796 -145.3515)
		(width 0.508)
		(layer "F.Cu")
		(net "MPLLAV33")
	)
	(via
		(at 33.304988 -135.284972)
		(size 0.4572)
		(drill 0.2032)
		(layers "F.Cu" "B.Cu")
		(net "MPLLAV33")
	)
	(via
		(at 31.704788 -138.484864)
		(size 0.4572)
		(drill 0.2032)
		(layers "F.Cu" "B.Cu")
		(net "MPLLAV33")
	)
	(via
		(at 31.2674 -139.1412)
		(size 0.7112)
		(drill 0.3556)
		(layers "F.Cu" "B.Cu")
		(net "MPLLAV33")
	)
	(via
		(at 22.183598 -144.594072)
		(size 0.508)
		(drill 0.254)
		(layers "F.Cu" "B.Cu")
		(net "MPLLAV33")
	)
	(segment
		(start 31.704788 -138.484864)
		(end 31.704788 -138.703812)
		(width 0.254)
		(layer "B.Cu")
		(net "MPLLAV33")
	)
	(segment
		(start 31.704788 -138.703812)
		(end 31.2674 -139.1412)
		(width 0.254)
		(layer "B.Cu")
		(net "MPLLAV33")
	)
	(segment
		(start 24.438102 -141.95552)
		(end 24.438102 -140.730478)
		(width 0.381)
		(layer "In2.Cu")
		(net "MPLLAV33")
	)
	(segment
		(start 31.116524 -137.8966)
		(end 31.704788 -138.484864)
		(width 0.381)
		(layer "In2.Cu")
		(net "MPLLAV33")
	)
	(segment
		(start 32.48787 -138.484864)
		(end 33.304988 -137.667746)
		(width 0.381)
		(layer "In2.Cu")
		(net "MPLLAV33")
	)
	(segment
		(start 31.704788 -138.484864)
		(end 32.48787 -138.484864)
		(width 0.381)
		(layer "In2.Cu")
		(net "MPLLAV33")
	)
	(segment
		(start 33.304988 -137.667746)
		(end 33.304988 -135.284972)
		(width 0.381)
		(layer "In2.Cu")
		(net "MPLLAV33")
	)
	(segment
		(start 24.438102 -140.730478)
		(end 27.27198 -137.8966)
		(width 0.381)
		(layer "In2.Cu")
		(net "MPLLAV33")
	)
	(segment
		(start 22.183598 -144.594072)
		(end 22.7457 -144.03197)
		(width 0.381)
		(layer "In2.Cu")
		(net "MPLLAV33")
	)
	(segment
		(start 22.7457 -143.647922)
		(end 24.438102 -141.95552)
		(width 0.381)
		(layer "In2.Cu")
		(net "MPLLAV33")
	)
	(segment
		(start 22.7457 -144.03197)
		(end 22.7457 -143.647922)
		(width 0.381)
		(layer "In2.Cu")
		(net "MPLLAV33")
	)
	(segment
		(start 27.27198 -137.8966)
		(end 31.116524 -137.8966)
		(width 0.381)
		(layer "In2.Cu")
		(net "MPLLAV33")
	)
	(segment
		(start 36.90493 -137.284968)
		(end 36.897056 -137.284968)
		(width 0.12065)
		(layer "F.Cu")
		(net "MEMWEN")
	)
	(segment
		(start 36.897056 -137.284968)
		(end 36.496244 -137.68578)
		(width 0.12065)
		(layer "F.Cu")
		(net "MEMWEN")
	)
	(segment
		(start 33.76803 -155.579826)
		(end 34.16808 -155.179776)
		(width 0.12065)
		(layer "F.Cu")
		(net "MEMWEN")
	)
	(via
		(at 36.496244 -137.68578)
		(size 0.4572)
		(drill 0.2032)
		(layers "F.Cu" "B.Cu")
		(net "MEMWEN")
	)
	(via
		(at 34.16808 -155.179776)
		(size 0.4572)
		(drill 0.2032)
		(layers "F.Cu" "B.Cu")
		(net "MEMWEN")
	)
	(segment
		(start 38.27272 -153.416)
		(end 38.57752 -153.1112)
		(width 0.12065)
		(layer "B.Cu")
		(net "MEMWEN")
	)
	(segment
		(start 36.135818 -154.28595)
		(end 36.256468 -154.4066)
		(width 0.12065)
		(layer "B.Cu")
		(net "MEMWEN")
	)
	(segment
		(start 38.57752 -153.1112)
		(end 38.57752 -149.86508)
		(width 0.12065)
		(layer "B.Cu")
		(net "MEMWEN")
	)
	(segment
		(start 36.256468 -154.4066)
		(end 36.497768 -154.4066)
		(width 0.12065)
		(layer "B.Cu")
		(net "MEMWEN")
	)
	(segment
		(start 35.773868 -153.416)
		(end 36.015168 -153.416)
		(width 0.12065)
		(layer "B.Cu")
		(net "MEMWEN")
	)
	(segment
		(start 34.941256 -154.4066)
		(end 35.532568 -154.4066)
		(width 0.12065)
		(layer "B.Cu")
		(net "MEMWEN")
	)
	(segment
		(start 37.78758 -137.68578)
		(end 36.496244 -137.68578)
		(width 0.12065)
		(layer "B.Cu")
		(net "MEMWEN")
	)
	(segment
		(start 35.653218 -153.53665)
		(end 35.773868 -153.416)
		(width 0.12065)
		(layer "B.Cu")
		(net "MEMWEN")
	)
	(segment
		(start 39.6367 -148.8059)
		(end 39.6367 -143.235172)
		(width 0.12065)
		(layer "B.Cu")
		(net "MEMWEN")
	)
	(segment
		(start 36.497768 -154.4066)
		(end 36.618418 -154.28595)
		(width 0.12065)
		(layer "B.Cu")
		(net "MEMWEN")
	)
	(segment
		(start 36.015168 -153.416)
		(end 36.135818 -153.53665)
		(width 0.12065)
		(layer "B.Cu")
		(net "MEMWEN")
	)
	(segment
		(start 40.065198 -139.963398)
		(end 37.78758 -137.68578)
		(width 0.12065)
		(layer "B.Cu")
		(net "MEMWEN")
	)
	(segment
		(start 34.16808 -155.179776)
		(end 34.941256 -154.4066)
		(width 0.12065)
		(layer "B.Cu")
		(net "MEMWEN")
	)
	(segment
		(start 35.532568 -154.4066)
		(end 35.653218 -154.28595)
		(width 0.12065)
		(layer "B.Cu")
		(net "MEMWEN")
	)
	(segment
		(start 40.065198 -142.806674)
		(end 40.065198 -139.963398)
		(width 0.12065)
		(layer "B.Cu")
		(net "MEMWEN")
	)
	(segment
		(start 36.739068 -153.416)
		(end 38.27272 -153.416)
		(width 0.12065)
		(layer "B.Cu")
		(net "MEMWEN")
	)
	(segment
		(start 36.618418 -154.28595)
		(end 36.618418 -153.53665)
		(width 0.12065)
		(layer "B.Cu")
		(net "MEMWEN")
	)
	(segment
		(start 38.57752 -149.86508)
		(end 39.6367 -148.8059)
		(width 0.12065)
		(layer "B.Cu")
		(net "MEMWEN")
	)
	(segment
		(start 36.135818 -153.53665)
		(end 36.135818 -154.28595)
		(width 0.12065)
		(layer "B.Cu")
		(net "MEMWEN")
	)
	(segment
		(start 36.618418 -153.53665)
		(end 36.739068 -153.416)
		(width 0.12065)
		(layer "B.Cu")
		(net "MEMWEN")
	)
	(segment
		(start 39.6367 -143.235172)
		(end 40.065198 -142.806674)
		(width 0.12065)
		(layer "B.Cu")
		(net "MEMWEN")
	)
	(segment
		(start 35.653218 -154.28595)
		(end 35.653218 -153.53665)
		(width 0.12065)
		(layer "B.Cu")
		(net "MEMWEN")
	)
	(segment
		(start 35.367976 -155.579826)
		(end 35.767772 -155.18003)
		(width 0.12065)
		(layer "F.Cu")
		(net "MEMRASN")
	)
	(segment
		(start 36.90493 -136.484868)
		(end 36.90493 -136.493504)
		(width 0.12065)
		(layer "F.Cu")
		(net "MEMRASN")
	)
	(segment
		(start 36.90493 -136.493504)
		(end 36.504372 -136.894062)
		(width 0.12065)
		(layer "F.Cu")
		(net "MEMRASN")
	)
	(via
		(at 36.504372 -136.894062)
		(size 0.4572)
		(drill 0.2032)
		(layers "F.Cu" "B.Cu")
		(net "MEMRASN")
	)
	(via
		(at 35.767772 -155.18003)
		(size 0.4572)
		(drill 0.2032)
		(layers "F.Cu" "B.Cu")
		(net "MEMRASN")
	)
	(segment
		(start 37.93617 -137.27557)
		(end 37.933376 -137.27557)
		(width 0.12065)
		(layer "B.Cu")
		(net "MEMRASN")
	)
	(segment
		(start 36.778184 -135.687816)
		(end 36.504372 -135.961628)
		(width 0.12065)
		(layer "B.Cu")
		(net "MEMRASN")
	)
	(segment
		(start 39.5478 -149.6314)
		(end 39.99865 -149.18055)
		(width 0.12065)
		(layer "B.Cu")
		(net "MEMRASN")
	)
	(segment
		(start 37.704522 -135.928608)
		(end 37.46373 -135.687816)
		(width 0.12065)
		(layer "B.Cu")
		(net "MEMRASN")
	)
	(segment
		(start 37.933376 -137.27557)
		(end 37.704522 -137.046716)
		(width 0.12065)
		(layer "B.Cu")
		(net "MEMRASN")
	)
	(segment
		(start 39.99865 -143.385286)
		(end 40.427148 -142.956788)
		(width 0.12065)
		(layer "B.Cu")
		(net "MEMRASN")
	)
	(segment
		(start 35.767772 -155.18003)
		(end 36.158678 -154.789124)
		(width 0.12065)
		(layer "B.Cu")
		(net "MEMRASN")
	)
	(segment
		(start 37.46373 -135.687816)
		(end 36.778184 -135.687816)
		(width 0.12065)
		(layer "B.Cu")
		(net "MEMRASN")
	)
	(segment
		(start 36.158678 -154.789124)
		(end 38.225476 -154.789124)
		(width 0.12065)
		(layer "B.Cu")
		(net "MEMRASN")
	)
	(segment
		(start 40.427148 -139.766548)
		(end 37.93617 -137.27557)
		(width 0.12065)
		(layer "B.Cu")
		(net "MEMRASN")
	)
	(segment
		(start 39.99865 -149.18055)
		(end 39.99865 -143.385286)
		(width 0.12065)
		(layer "B.Cu")
		(net "MEMRASN")
	)
	(segment
		(start 40.427148 -142.956788)
		(end 40.427148 -139.766548)
		(width 0.12065)
		(layer "B.Cu")
		(net "MEMRASN")
	)
	(segment
		(start 37.704522 -137.046716)
		(end 37.704522 -135.928608)
		(width 0.12065)
		(layer "B.Cu")
		(net "MEMRASN")
	)
	(segment
		(start 39.5478 -153.4668)
		(end 39.5478 -149.6314)
		(width 0.12065)
		(layer "B.Cu")
		(net "MEMRASN")
	)
	(segment
		(start 36.504372 -135.961628)
		(end 36.504372 -136.894062)
		(width 0.12065)
		(layer "B.Cu")
		(net "MEMRASN")
	)
	(segment
		(start 38.225476 -154.789124)
		(end 39.5478 -153.4668)
		(width 0.12065)
		(layer "B.Cu")
		(net "MEMRASN")
	)
	(segment
		(start 36.10483 -135.684768)
		(end 35.705034 -135.284972)
		(width 0.12065)
		(layer "F.Cu")
		(net "MEMODT")
	)
	(segment
		(start 34.189162 -156.800804)
		(end 34.183574 -156.800804)
		(width 0.12065)
		(layer "F.Cu")
		(net "MEMODT")
	)
	(segment
		(start 34.183574 -156.800804)
		(end 34.168334 -156.785564)
		(width 0.12065)
		(layer "F.Cu")
		(net "MEMODT")
	)
	(segment
		(start 34.56813 -157.179772)
		(end 34.189162 -156.800804)
		(width 0.12065)
		(layer "F.Cu")
		(net "MEMODT")
	)
	(via
		(at 34.168334 -156.785564)
		(size 0.4572)
		(drill 0.2032)
		(layers "F.Cu" "B.Cu")
		(net "MEMODT")
	)
	(via
		(at 35.705034 -135.284972)
		(size 0.4572)
		(drill 0.2032)
		(layers "F.Cu" "B.Cu")
		(net "MEMODT")
	)
	(segment
		(start 38.058344 -144.177004)
		(end 38.058344 -141.944344)
		(width 0.12065)
		(layer "B.Cu")
		(net "MEMODT")
	)
	(segment
		(start 38.058344 -141.944344)
		(end 37.8968 -141.7828)
		(width 0.12065)
		(layer "B.Cu")
		(net "MEMODT")
	)
	(segment
		(start 37.3126 -141.7828)
		(end 37.0586 -141.5288)
		(width 0.12065)
		(layer "B.Cu")
		(net "MEMODT")
	)
	(segment
		(start 38.2016 -139.0142)
		(end 38.2016 -138.414252)
		(width 0.12065)
		(layer "B.Cu")
		(net "MEMODT")
	)
	(segment
		(start 37.0586 -139.319)
		(end 37.2364 -139.1412)
		(width 0.12065)
		(layer "B.Cu")
		(net "MEMODT")
	)
	(segment
		(start 34.153602 -152.546812)
		(end 35.129724 -151.57069)
		(width 0.12065)
		(layer "B.Cu")
		(net "MEMODT")
	)
	(segment
		(start 36.992052 -144.414748)
		(end 37.8206 -144.414748)
		(width 0.12065)
		(layer "B.Cu")
		(net "MEMODT")
	)
	(segment
		(start 35.129978 -151.57069)
		(end 35.372802 -151.327866)
		(width 0.12065)
		(layer "B.Cu")
		(net "MEMODT")
	)
	(segment
		(start 38.2016 -138.414252)
		(end 37.956998 -138.16965)
		(width 0.12065)
		(layer "B.Cu")
		(net "MEMODT")
	)
	(segment
		(start 34.168334 -156.785564)
		(end 34.168334 -156.533088)
		(width 0.12065)
		(layer "B.Cu")
		(net "MEMODT")
	)
	(segment
		(start 34.153602 -154.641804)
		(end 34.153602 -152.546812)
		(width 0.12065)
		(layer "B.Cu")
		(net "MEMODT")
	)
	(segment
		(start 33.777174 -155.1686)
		(end 33.777428 -155.168346)
		(width 0.12065)
		(layer "B.Cu")
		(net "MEMODT")
	)
	(segment
		(start 36.105592 -137.921746)
		(end 36.105592 -135.68553)
		(width 0.12065)
		(layer "B.Cu")
		(net "MEMODT")
	)
	(segment
		(start 37.2364 -139.1412)
		(end 38.0746 -139.1412)
		(width 0.12065)
		(layer "B.Cu")
		(net "MEMODT")
	)
	(segment
		(start 37.8968 -141.7828)
		(end 37.3126 -141.7828)
		(width 0.12065)
		(layer "B.Cu")
		(net "MEMODT")
	)
	(segment
		(start 35.372802 -151.327866)
		(end 35.372802 -149.02942)
		(width 0.12065)
		(layer "B.Cu")
		(net "MEMODT")
	)
	(segment
		(start 33.777174 -156.141928)
		(end 33.777174 -155.1686)
		(width 0.12065)
		(layer "B.Cu")
		(net "MEMODT")
	)
	(segment
		(start 38.0746 -139.1412)
		(end 38.2016 -139.0142)
		(width 0.12065)
		(layer "B.Cu")
		(net "MEMODT")
	)
	(segment
		(start 36.105592 -135.68553)
		(end 35.705034 -135.284972)
		(width 0.12065)
		(layer "B.Cu")
		(net "MEMODT")
	)
	(segment
		(start 37.8206 -144.414748)
		(end 38.058344 -144.177004)
		(width 0.12065)
		(layer "B.Cu")
		(net "MEMODT")
	)
	(segment
		(start 34.168334 -156.533088)
		(end 33.777174 -156.141928)
		(width 0.12065)
		(layer "B.Cu")
		(net "MEMODT")
	)
	(segment
		(start 36.353496 -138.16965)
		(end 36.105592 -137.921746)
		(width 0.12065)
		(layer "B.Cu")
		(net "MEMODT")
	)
	(segment
		(start 36.752022 -147.6502)
		(end 36.752022 -144.654778)
		(width 0.12065)
		(layer "B.Cu")
		(net "MEMODT")
	)
	(segment
		(start 35.372802 -149.02942)
		(end 36.752022 -147.6502)
		(width 0.12065)
		(layer "B.Cu")
		(net "MEMODT")
	)
	(segment
		(start 33.777428 -155.168346)
		(end 33.777428 -155.017978)
		(width 0.12065)
		(layer "B.Cu")
		(net "MEMODT")
	)
	(segment
		(start 37.956998 -138.16965)
		(end 36.353496 -138.16965)
		(width 0.12065)
		(layer "B.Cu")
		(net "MEMODT")
	)
	(segment
		(start 35.129724 -151.57069)
		(end 35.129978 -151.57069)
		(width 0.12065)
		(layer "B.Cu")
		(net "MEMODT")
	)
	(segment
		(start 36.752022 -144.654778)
		(end 36.992052 -144.414748)
		(width 0.12065)
		(layer "B.Cu")
		(net "MEMODT")
	)
	(segment
		(start 33.777428 -155.017978)
		(end 34.153602 -154.641804)
		(width 0.12065)
		(layer "B.Cu")
		(net "MEMODT")
	)
	(segment
		(start 37.0586 -141.5288)
		(end 37.0586 -139.319)
		(width 0.12065)
		(layer "B.Cu")
		(net "MEMODT")
	)
	(segment
		(start 43.14317 -140.851128)
		(end 43.14317 -145.287492)
		(width 0.136652)
		(layer "F.Cu")
		(net "MEMDQS_P1")
	)
	(segment
		(start 41.8338 -142.036292)
		(end 41.671748 -141.87424)
		(width 0.136652)
		(layer "F.Cu")
		(net "MEMDQS_P1")
	)
	(segment
		(start 41.118028 -141.8336)
		(end 40.96512 -141.8336)
		(width 0.136652)
		(layer "F.Cu")
		(net "MEMDQS_P1")
	)
	(segment
		(start 40.168068 -152.379934)
		(end 40.567864 -152.77973)
		(width 0.136652)
		(layer "F.Cu")
		(net "MEMDQS_P1")
	)
	(segment
		(start 42.837862 -145.5928)
		(end 42.139108 -145.5928)
		(width 0.136652)
		(layer "F.Cu")
		(net "MEMDQS_P1")
	)
	(segment
		(start 40.904922 -138.084814)
		(end 41.331642 -138.511534)
		(width 0.136652)
		(layer "F.Cu")
		(net "MEMDQS_P1")
	)
	(segment
		(start 43.14317 -145.287492)
		(end 42.837862 -145.5928)
		(width 0.136652)
		(layer "F.Cu")
		(net "MEMDQS_P1")
	)
	(segment
		(start 41.671748 -141.87424)
		(end 41.158668 -141.87424)
		(width 0.136652)
		(layer "F.Cu")
		(net "MEMDQS_P1")
	)
	(segment
		(start 41.8338 -145.287492)
		(end 41.8338 -142.036292)
		(width 0.136652)
		(layer "F.Cu")
		(net "MEMDQS_P1")
	)
	(segment
		(start 41.158668 -141.87424)
		(end 41.118028 -141.8336)
		(width 0.136652)
		(layer "F.Cu")
		(net "MEMDQS_P1")
	)
	(segment
		(start 42.139108 -145.5928)
		(end 41.8338 -145.287492)
		(width 0.136652)
		(layer "F.Cu")
		(net "MEMDQS_P1")
	)
	(segment
		(start 41.331642 -139.0396)
		(end 43.14317 -140.851128)
		(width 0.136652)
		(layer "F.Cu")
		(net "MEMDQS_P1")
	)
	(segment
		(start 41.331642 -138.511534)
		(end 41.331642 -139.0396)
		(width 0.136652)
		(layer "F.Cu")
		(net "MEMDQS_P1")
	)
	(via
		(at 40.96512 -141.8336)
		(size 0.4572)
		(drill 0.2032)
		(layers "F.Cu" "B.Cu")
		(net "MEMDQS_P1")
	)
	(via
		(at 40.567864 -152.77973)
		(size 0.4572)
		(drill 0.2032)
		(layers "F.Cu" "B.Cu")
		(net "MEMDQS_P1")
	)
	(segment
		(start 40.567864 -152.77973)
		(end 40.567864 -152.546558)
		(width 0.1397)
		(layer "In5.Cu")
		(net "MEMDQS_P1")
	)
	(segment
		(start 41.84777 -151.266652)
		(end 41.84777 -142.30604)
		(width 0.1397)
		(layer "In5.Cu")
		(net "MEMDQS_P1")
	)
	(segment
		(start 41.84777 -142.30604)
		(end 41.37533 -141.8336)
		(width 0.1397)
		(layer "In5.Cu")
		(net "MEMDQS_P1")
	)
	(segment
		(start 41.37533 -141.8336)
		(end 40.96512 -141.8336)
		(width 0.1397)
		(layer "In5.Cu")
		(net "MEMDQS_P1")
	)
	(segment
		(start 41.064434 -152.049734)
		(end 41.620948 -151.493474)
		(width 0.1397)
		(layer "In5.Cu")
		(net "MEMDQS_P1")
	)
	(segment
		(start 41.620948 -151.493474)
		(end 41.84777 -151.266652)
		(width 0.1397)
		(layer "In5.Cu")
		(net "MEMDQS_P1")
	)
	(segment
		(start 40.567864 -152.546558)
		(end 41.064434 -152.049734)
		(width 0.1397)
		(layer "In5.Cu")
		(net "MEMDQS_P1")
	)
	(segment
		(start 38.041072 -154.9908)
		(end 38.168072 -155.1178)
		(width 0.136652)
		(layer "F.Cu")
		(net "MEMDQS_P0")
	)
	(segment
		(start 38.758114 -140.928852)
		(end 38.605206 -140.928852)
		(width 0.136652)
		(layer "F.Cu")
		(net "MEMDQS_P0")
	)
	(segment
		(start 39.304722 -138.884914)
		(end 39.373048 -138.95324)
		(width 0.136652)
		(layer "F.Cu")
		(net "MEMDQS_P0")
	)
	(segment
		(start 39.373048 -139.4714)
		(end 39.081456 -139.762992)
		(width 0.136652)
		(layer "F.Cu")
		(net "MEMDQS_P0")
	)
	(segment
		(start 37.768022 -155.1178)
		(end 37.895022 -154.9908)
		(width 0.136652)
		(layer "F.Cu")
		(net "MEMDQS_P0")
	)
	(segment
		(start 37.895022 -154.9908)
		(end 38.041072 -154.9908)
		(width 0.136652)
		(layer "F.Cu")
		(net "MEMDQS_P0")
	)
	(segment
		(start 37.768022 -155.579826)
		(end 37.768022 -155.1178)
		(width 0.136652)
		(layer "F.Cu")
		(net "MEMDQS_P0")
	)
	(segment
		(start 39.081456 -140.60551)
		(end 38.758114 -140.928852)
		(width 0.136652)
		(layer "F.Cu")
		(net "MEMDQS_P0")
	)
	(segment
		(start 39.081456 -139.762992)
		(end 39.081456 -140.60551)
		(width 0.136652)
		(layer "F.Cu")
		(net "MEMDQS_P0")
	)
	(segment
		(start 39.373048 -138.95324)
		(end 39.373048 -139.4714)
		(width 0.136652)
		(layer "F.Cu")
		(net "MEMDQS_P0")
	)
	(segment
		(start 38.168072 -155.1178)
		(end 38.168072 -155.179776)
		(width 0.136652)
		(layer "F.Cu")
		(net "MEMDQS_P0")
	)
	(via
		(at 38.605206 -140.928852)
		(size 0.4572)
		(drill 0.2032)
		(layers "F.Cu" "B.Cu")
		(net "MEMDQS_P0")
	)
	(via
		(at 38.168072 -155.179776)
		(size 0.4572)
		(drill 0.2032)
		(layers "F.Cu" "B.Cu")
		(net "MEMDQS_P0")
	)
	(segment
		(start 37.767768 -155.067)
		(end 37.767768 -153.681938)
		(width 0.1397)
		(layer "In5.Cu")
		(net "MEMDQS_P0")
	)
	(segment
		(start 38.168072 -155.179776)
		(end 37.880544 -155.179776)
		(width 0.1397)
		(layer "In5.Cu")
		(net "MEMDQS_P0")
	)
	(segment
		(start 38.0492 -146.640042)
		(end 37.9222 -146.513042)
		(width 0.1397)
		(layer "In5.Cu")
		(net "MEMDQS_P0")
	)
	(segment
		(start 37.767768 -153.681938)
		(end 37.906706 -153.543)
		(width 0.1397)
		(layer "In5.Cu")
		(net "MEMDQS_P0")
	)
	(segment
		(start 37.880544 -155.179776)
		(end 37.767768 -155.067)
		(width 0.1397)
		(layer "In5.Cu")
		(net "MEMDQS_P0")
	)
	(segment
		(start 39.5224 -148.046694)
		(end 39.5224 -147.812506)
		(width 0.1397)
		(layer "In5.Cu")
		(net "MEMDQS_P0")
	)
	(segment
		(start 38.093904 -144.0688)
		(end 38.609016 -144.0688)
		(width 0.1397)
		(layer "In5.Cu")
		(net "MEMDQS_P0")
	)
	(segment
		(start 38.694106 -149.225)
		(end 39.506906 -149.225)
		(width 0.1397)
		(layer "In5.Cu")
		(net "MEMDQS_P0")
	)
	(segment
		(start 39.495476 -146.081242)
		(end 39.82847 -145.748248)
		(width 0.1397)
		(layer "In5.Cu")
		(net "MEMDQS_P0")
	)
	(segment
		(start 38.568122 -151.346916)
		(end 38.568122 -149.350984)
		(width 0.1397)
		(layer "In5.Cu")
		(net "MEMDQS_P0")
	)
	(segment
		(start 38.964616 -143.22171)
		(end 38.5826 -142.839694)
		(width 0.1397)
		(layer "In5.Cu")
		(net "MEMDQS_P0")
	)
	(segment
		(start 39.8272 -148.904706)
		(end 39.8272 -148.351494)
		(width 0.1397)
		(layer "In5.Cu")
		(net "MEMDQS_P0")
	)
	(segment
		(start 38.5826 -142.839694)
		(end 38.5826 -142.494762)
		(width 0.1397)
		(layer "In5.Cu")
		(net "MEMDQS_P0")
	)
	(segment
		(start 39.82847 -145.049494)
		(end 39.508176 -144.7292)
		(width 0.1397)
		(layer "In5.Cu")
		(net "MEMDQS_P0")
	)
	(segment
		(start 37.9222 -146.513042)
		(end 37.9222 -146.208242)
		(width 0.1397)
		(layer "In5.Cu")
		(net "MEMDQS_P0")
	)
	(segment
		(start 39.8272 -147.507706)
		(end 39.8272 -146.960336)
		(width 0.1397)
		(layer "In5.Cu")
		(net "MEMDQS_P0")
	)
	(segment
		(start 37.966904 -144.1958)
		(end 38.093904 -144.0688)
		(width 0.1397)
		(layer "In5.Cu")
		(net "MEMDQS_P0")
	)
	(segment
		(start 37.9222 -146.208242)
		(end 38.0492 -146.081242)
		(width 0.1397)
		(layer "In5.Cu")
		(net "MEMDQS_P0")
	)
	(segment
		(start 38.093904 -144.7292)
		(end 37.966904 -144.6022)
		(width 0.1397)
		(layer "In5.Cu")
		(net "MEMDQS_P0")
	)
	(segment
		(start 38.0492 -146.081242)
		(end 39.495476 -146.081242)
		(width 0.1397)
		(layer "In5.Cu")
		(net "MEMDQS_P0")
	)
	(segment
		(start 39.5224 -147.812506)
		(end 39.8272 -147.507706)
		(width 0.1397)
		(layer "In5.Cu")
		(net "MEMDQS_P0")
	)
	(segment
		(start 38.5826 -142.494762)
		(end 39.005256 -142.072106)
		(width 0.1397)
		(layer "In5.Cu")
		(net "MEMDQS_P0")
	)
	(segment
		(start 38.898576 -151.67737)
		(end 38.568122 -151.346916)
		(width 0.1397)
		(layer "In5.Cu")
		(net "MEMDQS_P0")
	)
	(segment
		(start 39.82847 -145.748248)
		(end 39.82847 -145.049494)
		(width 0.1397)
		(layer "In5.Cu")
		(net "MEMDQS_P0")
	)
	(segment
		(start 39.005256 -141.328902)
		(end 38.605206 -140.928852)
		(width 0.1397)
		(layer "In5.Cu")
		(net "MEMDQS_P0")
	)
	(segment
		(start 37.906706 -153.543)
		(end 38.527482 -153.543)
		(width 0.1397)
		(layer "In5.Cu")
		(net "MEMDQS_P0")
	)
	(segment
		(start 38.568122 -149.350984)
		(end 38.694106 -149.225)
		(width 0.1397)
		(layer "In5.Cu")
		(net "MEMDQS_P0")
	)
	(segment
		(start 38.609016 -144.0688)
		(end 38.964616 -143.7132)
		(width 0.1397)
		(layer "In5.Cu")
		(net "MEMDQS_P0")
	)
	(segment
		(start 39.506906 -149.225)
		(end 39.8272 -148.904706)
		(width 0.1397)
		(layer "In5.Cu")
		(net "MEMDQS_P0")
	)
	(segment
		(start 39.8272 -148.351494)
		(end 39.5224 -148.046694)
		(width 0.1397)
		(layer "In5.Cu")
		(net "MEMDQS_P0")
	)
	(segment
		(start 38.527482 -153.543)
		(end 38.898576 -153.171906)
		(width 0.1397)
		(layer "In5.Cu")
		(net "MEMDQS_P0")
	)
	(segment
		(start 37.966904 -144.6022)
		(end 37.966904 -144.1958)
		(width 0.1397)
		(layer "In5.Cu")
		(net "MEMDQS_P0")
	)
	(segment
		(start 38.898576 -153.171906)
		(end 38.898576 -151.67737)
		(width 0.1397)
		(layer "In5.Cu")
		(net "MEMDQS_P0")
	)
	(segment
		(start 39.8272 -146.960336)
		(end 39.506906 -146.640042)
		(width 0.1397)
		(layer "In5.Cu")
		(net "MEMDQS_P0")
	)
	(segment
		(start 39.005256 -142.072106)
		(end 39.005256 -141.328902)
		(width 0.1397)
		(layer "In5.Cu")
		(net "MEMDQS_P0")
	)
	(segment
		(start 39.508176 -144.7292)
		(end 38.093904 -144.7292)
		(width 0.1397)
		(layer "In5.Cu")
		(net "MEMDQS_P0")
	)
	(segment
		(start 39.506906 -146.640042)
		(end 38.0492 -146.640042)
		(width 0.1397)
		(layer "In5.Cu")
		(net "MEMDQS_P0")
	)
	(segment
		(start 38.964616 -143.7132)
		(end 38.964616 -143.22171)
		(width 0.1397)
		(layer "In5.Cu")
		(net "MEMDQS_P0")
	)
	(segment
		(start 42.1386 -141.9098)
		(end 41.79824 -141.56944)
		(width 0.136652)
		(layer "F.Cu")
		(net "MEMDQS_N1")
	)
	(segment
		(start 42.71137 -145.288)
		(end 42.2656 -145.288)
		(width 0.136652)
		(layer "F.Cu")
		(net "MEMDQS_N1")
	)
	(segment
		(start 41.36771 -152.908)
		(end 41.36771 -152.77973)
		(width 0.136652)
		(layer "F.Cu")
		(net "MEMDQS_N1")
	)
	(segment
		(start 41.79824 -141.56944)
		(end 41.28516 -141.56944)
		(width 0.136652)
		(layer "F.Cu")
		(net "MEMDQS_N1")
	)
	(segment
		(start 42.1386 -145.161)
		(end 42.1386 -141.9098)
		(width 0.136652)
		(layer "F.Cu")
		(net "MEMDQS_N1")
	)
	(segment
		(start 42.83837 -140.97762)
		(end 42.83837 -145.161)
		(width 0.136652)
		(layer "F.Cu")
		(net "MEMDQS_N1")
	)
	(segment
		(start 40.967914 -152.379934)
		(end 40.967914 -152.908)
		(width 0.136652)
		(layer "F.Cu")
		(net "MEMDQS_N1")
	)
	(segment
		(start 41.094914 -153.035)
		(end 41.24071 -153.035)
		(width 0.136652)
		(layer "F.Cu")
		(net "MEMDQS_N1")
	)
	(segment
		(start 42.83837 -145.161)
		(end 42.71137 -145.288)
		(width 0.136652)
		(layer "F.Cu")
		(net "MEMDQS_N1")
	)
	(segment
		(start 40.967914 -152.908)
		(end 41.094914 -153.035)
		(width 0.136652)
		(layer "F.Cu")
		(net "MEMDQS_N1")
	)
	(segment
		(start 41.026842 -139.166092)
		(end 42.83837 -140.97762)
		(width 0.136652)
		(layer "F.Cu")
		(net "MEMDQS_N1")
	)
	(segment
		(start 41.28516 -141.56944)
		(end 40.96512 -141.2494)
		(width 0.136652)
		(layer "F.Cu")
		(net "MEMDQS_N1")
	)
	(segment
		(start 40.904922 -138.884914)
		(end 41.026842 -139.006834)
		(width 0.136652)
		(layer "F.Cu")
		(net "MEMDQS_N1")
	)
	(segment
		(start 41.026842 -139.006834)
		(end 41.026842 -139.166092)
		(width 0.136652)
		(layer "F.Cu")
		(net "MEMDQS_N1")
	)
	(segment
		(start 42.2656 -145.288)
		(end 42.1386 -145.161)
		(width 0.136652)
		(layer "F.Cu")
		(net "MEMDQS_N1")
	)
	(segment
		(start 41.24071 -153.035)
		(end 41.36771 -152.908)
		(width 0.136652)
		(layer "F.Cu")
		(net "MEMDQS_N1")
	)
	(via
		(at 41.36771 -152.77973)
		(size 0.4572)
		(drill 0.2032)
		(layers "F.Cu" "B.Cu")
		(net "MEMDQS_N1")
	)
	(via
		(at 40.96512 -141.2494)
		(size 0.4572)
		(drill 0.2032)
		(layers "F.Cu" "B.Cu")
		(net "MEMDQS_N1")
	)
	(segment
		(start 42.17797 -142.169134)
		(end 41.512236 -141.5034)
		(width 0.1397)
		(layer "In5.Cu")
		(net "MEMDQS_N1")
	)
	(segment
		(start 41.21912 -141.5034)
		(end 40.96512 -141.2494)
		(width 0.1397)
		(layer "In5.Cu")
		(net "MEMDQS_N1")
	)
	(segment
		(start 41.290494 -152.77973)
		(end 41.139364 -152.6286)
		(width 0.1397)
		(layer "In5.Cu")
		(net "MEMDQS_N1")
	)
	(segment
		(start 41.139364 -152.442164)
		(end 42.17797 -151.403558)
		(width 0.1397)
		(layer "In5.Cu")
		(net "MEMDQS_N1")
	)
	(segment
		(start 41.139364 -152.6286)
		(end 41.139364 -152.442164)
		(width 0.1397)
		(layer "In5.Cu")
		(net "MEMDQS_N1")
	)
	(segment
		(start 42.17797 -151.403558)
		(end 42.17797 -142.169134)
		(width 0.1397)
		(layer "In5.Cu")
		(net "MEMDQS_N1")
	)
	(segment
		(start 41.36771 -152.77973)
		(end 41.290494 -152.77973)
		(width 0.1397)
		(layer "In5.Cu")
		(net "MEMDQS_N1")
	)
	(segment
		(start 41.512236 -141.5034)
		(end 41.21912 -141.5034)
		(width 0.1397)
		(layer "In5.Cu")
		(net "MEMDQS_N1")
	)
	(segment
		(start 39.304722 -138.084814)
		(end 39.304722 -138.357102)
		(width 0.136652)
		(layer "F.Cu")
		(net "MEMDQS_N0")
	)
	(segment
		(start 39.677848 -138.730228)
		(end 39.677848 -139.597892)
		(width 0.136652)
		(layer "F.Cu")
		(net "MEMDQS_N0")
	)
	(segment
		(start 39.386256 -139.889484)
		(end 39.386256 -140.732002)
		(width 0.136652)
		(layer "F.Cu")
		(net "MEMDQS_N0")
	)
	(segment
		(start 39.677848 -139.597892)
		(end 39.386256 -139.889484)
		(width 0.136652)
		(layer "F.Cu")
		(net "MEMDQS_N0")
	)
	(segment
		(start 39.386256 -140.732002)
		(end 38.605206 -141.513052)
		(width 0.136652)
		(layer "F.Cu")
		(net "MEMDQS_N0")
	)
	(segment
		(start 36.967922 -155.579826)
		(end 37.367718 -155.18003)
		(width 0.136652)
		(layer "F.Cu")
		(net "MEMDQS_N0")
	)
	(segment
		(start 39.304722 -138.357102)
		(end 39.677848 -138.730228)
		(width 0.136652)
		(layer "F.Cu")
		(net "MEMDQS_N0")
	)
	(via
		(at 37.367718 -155.18003)
		(size 0.4572)
		(drill 0.2032)
		(layers "F.Cu" "B.Cu")
		(net "MEMDQS_N0")
	)
	(via
		(at 38.605206 -141.513052)
		(size 0.4572)
		(drill 0.2032)
		(layers "F.Cu" "B.Cu")
		(net "MEMDQS_N0")
	)
	(segment
		(start 37.592 -146.071336)
		(end 37.912294 -145.751042)
		(width 0.1397)
		(layer "In5.Cu")
		(net "MEMDQS_N0")
	)
	(segment
		(start 38.634416 -143.576294)
		(end 38.634416 -143.358616)
		(width 0.1397)
		(layer "In5.Cu")
		(net "MEMDQS_N0")
	)
	(segment
		(start 39.497 -147.3708)
		(end 39.497 -147.097242)
		(width 0.1397)
		(layer "In5.Cu")
		(net "MEMDQS_N0")
	)
	(segment
		(start 37.636704 -144.058894)
		(end 37.956998 -143.7386)
		(width 0.1397)
		(layer "In5.Cu")
		(net "MEMDQS_N0")
	)
	(segment
		(start 39.1922 -147.6756)
		(end 39.497 -147.3708)
		(width 0.1397)
		(layer "In5.Cu")
		(net "MEMDQS_N0")
	)
	(segment
		(start 38.237922 -151.483822)
		(end 38.237922 -149.214078)
		(width 0.1397)
		(layer "In5.Cu")
		(net "MEMDQS_N0")
	)
	(segment
		(start 38.2524 -142.9766)
		(end 38.2524 -142.357856)
		(width 0.1397)
		(layer "In5.Cu")
		(net "MEMDQS_N0")
	)
	(segment
		(start 39.37 -146.970242)
		(end 37.912294 -146.970242)
		(width 0.1397)
		(layer "In5.Cu")
		(net "MEMDQS_N0")
	)
	(segment
		(start 39.497 -148.7678)
		(end 39.497 -148.4884)
		(width 0.1397)
		(layer "In5.Cu")
		(net "MEMDQS_N0")
	)
	(segment
		(start 37.956998 -145.0594)
		(end 37.636704 -144.739106)
		(width 0.1397)
		(layer "In5.Cu")
		(net "MEMDQS_N0")
	)
	(segment
		(start 38.5572 -148.8948)
		(end 39.37 -148.8948)
		(width 0.1397)
		(layer "In5.Cu")
		(net "MEMDQS_N0")
	)
	(segment
		(start 38.634416 -143.358616)
		(end 38.2524 -142.9766)
		(width 0.1397)
		(layer "In5.Cu")
		(net "MEMDQS_N0")
	)
	(segment
		(start 37.912294 -145.751042)
		(end 39.35857 -145.751042)
		(width 0.1397)
		(layer "In5.Cu")
		(net "MEMDQS_N0")
	)
	(segment
		(start 39.1922 -148.1836)
		(end 39.1922 -147.6756)
		(width 0.1397)
		(layer "In5.Cu")
		(net "MEMDQS_N0")
	)
	(segment
		(start 37.7698 -153.2128)
		(end 38.390576 -153.2128)
		(width 0.1397)
		(layer "In5.Cu")
		(net "MEMDQS_N0")
	)
	(segment
		(start 39.35857 -145.751042)
		(end 39.49827 -145.611342)
		(width 0.1397)
		(layer "In5.Cu")
		(net "MEMDQS_N0")
	)
	(segment
		(start 37.956998 -143.7386)
		(end 38.47211 -143.7386)
		(width 0.1397)
		(layer "In5.Cu")
		(net "MEMDQS_N0")
	)
	(segment
		(start 38.675056 -141.582902)
		(end 38.605206 -141.513052)
		(width 0.1397)
		(layer "In5.Cu")
		(net "MEMDQS_N0")
	)
	(segment
		(start 38.568376 -151.814276)
		(end 38.237922 -151.483822)
		(width 0.1397)
		(layer "In5.Cu")
		(net "MEMDQS_N0")
	)
	(segment
		(start 39.37 -148.8948)
		(end 39.497 -148.7678)
		(width 0.1397)
		(layer "In5.Cu")
		(net "MEMDQS_N0")
	)
	(segment
		(start 39.49827 -145.611342)
		(end 39.49827 -145.1864)
		(width 0.1397)
		(layer "In5.Cu")
		(net "MEMDQS_N0")
	)
	(segment
		(start 37.912294 -146.970242)
		(end 37.592 -146.649948)
		(width 0.1397)
		(layer "In5.Cu")
		(net "MEMDQS_N0")
	)
	(segment
		(start 37.367718 -155.18003)
		(end 37.437568 -155.11018)
		(width 0.1397)
		(layer "In5.Cu")
		(net "MEMDQS_N0")
	)
	(segment
		(start 37.437568 -153.545032)
		(end 37.7698 -153.2128)
		(width 0.1397)
		(layer "In5.Cu")
		(net "MEMDQS_N0")
	)
	(segment
		(start 38.390576 -153.2128)
		(end 38.568376 -153.035)
		(width 0.1397)
		(layer "In5.Cu")
		(net "MEMDQS_N0")
	)
	(segment
		(start 37.636704 -144.739106)
		(end 37.636704 -144.058894)
		(width 0.1397)
		(layer "In5.Cu")
		(net "MEMDQS_N0")
	)
	(segment
		(start 39.49827 -145.1864)
		(end 39.37127 -145.0594)
		(width 0.1397)
		(layer "In5.Cu")
		(net "MEMDQS_N0")
	)
	(segment
		(start 38.568376 -153.035)
		(end 38.568376 -151.814276)
		(width 0.1397)
		(layer "In5.Cu")
		(net "MEMDQS_N0")
	)
	(segment
		(start 39.37127 -145.0594)
		(end 37.956998 -145.0594)
		(width 0.1397)
		(layer "In5.Cu")
		(net "MEMDQS_N0")
	)
	(segment
		(start 39.497 -147.097242)
		(end 39.37 -146.970242)
		(width 0.1397)
		(layer "In5.Cu")
		(net "MEMDQS_N0")
	)
	(segment
		(start 37.437568 -155.11018)
		(end 37.437568 -153.545032)
		(width 0.1397)
		(layer "In5.Cu")
		(net "MEMDQS_N0")
	)
	(segment
		(start 39.497 -148.4884)
		(end 39.1922 -148.1836)
		(width 0.1397)
		(layer "In5.Cu")
		(net "MEMDQS_N0")
	)
	(segment
		(start 38.675056 -141.9352)
		(end 38.675056 -141.582902)
		(width 0.1397)
		(layer "In5.Cu")
		(net "MEMDQS_N0")
	)
	(segment
		(start 38.47211 -143.7386)
		(end 38.634416 -143.576294)
		(width 0.1397)
		(layer "In5.Cu")
		(net "MEMDQS_N0")
	)
	(segment
		(start 38.237922 -149.214078)
		(end 38.5572 -148.8948)
		(width 0.1397)
		(layer "In5.Cu")
		(net "MEMDQS_N0")
	)
	(segment
		(start 37.592 -146.649948)
		(end 37.592 -146.071336)
		(width 0.1397)
		(layer "In5.Cu")
		(net "MEMDQS_N0")
	)
	(segment
		(start 38.2524 -142.357856)
		(end 38.675056 -141.9352)
		(width 0.1397)
		(layer "In5.Cu")
		(net "MEMDQS_N0")
	)
	(segment
		(start 39.6748 -140.0302)
		(end 39.6748 -141.1478)
		(width 0.12065)
		(layer "F.Cu")
		(net "MEMDQ_9")
	)
	(segment
		(start 39.6748 -141.1478)
		(end 38.8112 -142.0114)
		(width 0.12065)
		(layer "F.Cu")
		(net "MEMDQ_9")
	)
	(segment
		(start 37.7698 -142.1384)
		(end 37.7698 -142.6972)
		(width 0.12065)
		(layer "F.Cu")
		(net "MEMDQ_9")
	)
	(segment
		(start 41.36771 -151.97963)
		(end 42.16781 -151.97963)
		(width 0.12065)
		(layer "F.Cu")
		(net "MEMDQ_9")
	)
	(segment
		(start 37.7698 -142.6972)
		(end 37.8968 -142.8242)
		(width 0.12065)
		(layer "F.Cu")
		(net "MEMDQ_9")
	)
	(segment
		(start 40.3352 -142.875)
		(end 40.4622 -142.748)
		(width 0.12065)
		(layer "F.Cu")
		(net "MEMDQ_9")
	)
	(segment
		(start 39.37 -142.2654)
		(end 39.497 -142.1384)
		(width 0.12065)
		(layer "F.Cu")
		(net "MEMDQ_9")
	)
	(segment
		(start 39.8526 -142.2654)
		(end 39.8526 -142.748)
		(width 0.12065)
		(layer "F.Cu")
		(net "MEMDQ_9")
	)
	(segment
		(start 39.7256 -142.1384)
		(end 39.8526 -142.2654)
		(width 0.12065)
		(layer "F.Cu")
		(net "MEMDQ_9")
	)
	(segment
		(start 39.8526 -142.748)
		(end 39.9796 -142.875)
		(width 0.12065)
		(layer "F.Cu")
		(net "MEMDQ_9")
	)
	(segment
		(start 39.37 -142.70355)
		(end 39.37 -142.2654)
		(width 0.12065)
		(layer "F.Cu")
		(net "MEMDQ_9")
	)
	(segment
		(start 40.4622 -142.748)
		(end 40.4622 -140.171424)
		(width 0.12065)
		(layer "F.Cu")
		(net "MEMDQ_9")
	)
	(segment
		(start 40.967914 -151.579834)
		(end 41.36771 -151.97963)
		(width 0.12065)
		(layer "F.Cu")
		(net "MEMDQ_9")
	)
	(segment
		(start 38.8112 -142.0114)
		(end 37.8968 -142.0114)
		(width 0.12065)
		(layer "F.Cu")
		(net "MEMDQ_9")
	)
	(segment
		(start 39.24935 -142.8242)
		(end 39.37 -142.70355)
		(width 0.12065)
		(layer "F.Cu")
		(net "MEMDQ_9")
	)
	(segment
		(start 37.8968 -142.8242)
		(end 39.24935 -142.8242)
		(width 0.12065)
		(layer "F.Cu")
		(net "MEMDQ_9")
	)
	(segment
		(start 40.4622 -140.171424)
		(end 40.5892 -140.044424)
		(width 0.12065)
		(layer "F.Cu")
		(net "MEMDQ_9")
	)
	(segment
		(start 39.9796 -142.875)
		(end 40.3352 -142.875)
		(width 0.12065)
		(layer "F.Cu")
		(net "MEMDQ_9")
	)
	(segment
		(start 40.104822 -139.600178)
		(end 39.6748 -140.0302)
		(width 0.12065)
		(layer "F.Cu")
		(net "MEMDQ_9")
	)
	(segment
		(start 37.8968 -142.0114)
		(end 37.7698 -142.1384)
		(width 0.12065)
		(layer "F.Cu")
		(net "MEMDQ_9")
	)
	(segment
		(start 40.104822 -138.884914)
		(end 40.104822 -139.600178)
		(width 0.12065)
		(layer "F.Cu")
		(net "MEMDQ_9")
	)
	(segment
		(start 40.5892 -140.044424)
		(end 40.8178 -140.044424)
		(width 0.12065)
		(layer "F.Cu")
		(net "MEMDQ_9")
	)
	(segment
		(start 39.497 -142.1384)
		(end 39.7256 -142.1384)
		(width 0.12065)
		(layer "F.Cu")
		(net "MEMDQ_9")
	)
	(via
		(at 42.16781 -151.97963)
		(size 0.4572)
		(drill 0.2032)
		(layers "F.Cu" "B.Cu")
		(net "MEMDQ_9")
	)
	(via
		(at 40.8178 -140.044424)
		(size 0.4572)
		(drill 0.2032)
		(layers "F.Cu" "B.Cu")
		(net "MEMDQ_9")
	)
	(segment
		(start 42.16781 -151.97963)
		(end 42.61612 -151.53132)
		(width 0.127)
		(layer "In5.Cu")
		(net "MEMDQ_9")
	)
	(segment
		(start 42.61612 -151.53132)
		(end 42.61612 -141.759178)
		(width 0.127)
		(layer "In5.Cu")
		(net "MEMDQ_9")
	)
	(segment
		(start 42.61612 -141.759178)
		(end 40.901366 -140.044424)
		(width 0.127)
		(layer "In5.Cu")
		(net "MEMDQ_9")
	)
	(segment
		(start 40.901366 -140.044424)
		(end 40.8178 -140.044424)
		(width 0.127)
		(layer "In5.Cu")
		(net "MEMDQ_9")
	)
	(segment
		(start 39.9288 -153.289)
		(end 40.0558 -153.162)
		(width 0.12065)
		(layer "F.Cu")
		(net "MEMDQ_8")
	)
	(segment
		(start 39.8018 -153.8224)
		(end 39.9288 -153.6954)
		(width 0.12065)
		(layer "F.Cu")
		(net "MEMDQ_8")
	)
	(segment
		(start 39.9288 -153.6954)
		(end 39.9288 -153.289)
		(width 0.12065)
		(layer "F.Cu")
		(net "MEMDQ_8")
	)
	(segment
		(start 39.494968 -153.8224)
		(end 39.8018 -153.8224)
		(width 0.12065)
		(layer "F.Cu")
		(net "MEMDQ_8")
	)
	(segment
		(start 39.367968 -152.379934)
		(end 39.367968 -153.6954)
		(width 0.12065)
		(layer "F.Cu")
		(net "MEMDQ_8")
	)
	(segment
		(start 39.367968 -153.6954)
		(end 39.494968 -153.8224)
		(width 0.12065)
		(layer "F.Cu")
		(net "MEMDQ_8")
	)
	(segment
		(start 40.567864 -153.289)
		(end 40.567864 -153.57983)
		(width 0.12065)
		(layer "F.Cu")
		(net "MEMDQ_8")
	)
	(segment
		(start 40.440864 -153.162)
		(end 40.567864 -153.289)
		(width 0.12065)
		(layer "F.Cu")
		(net "MEMDQ_8")
	)
	(segment
		(start 40.0558 -153.162)
		(end 40.440864 -153.162)
		(width 0.12065)
		(layer "F.Cu")
		(net "MEMDQ_8")
	)
	(segment
		(start 38.909498 -135.289544)
		(end 39.304722 -135.684768)
		(width 0.12065)
		(layer "F.Cu")
		(net "MEMDQ_8")
	)
	(via
		(at 38.909498 -135.289544)
		(size 0.4572)
		(drill 0.2032)
		(layers "F.Cu" "B.Cu")
		(net "MEMDQ_8")
	)
	(via
		(at 40.567864 -153.57983)
		(size 0.4572)
		(drill 0.2032)
		(layers "F.Cu" "B.Cu")
		(net "MEMDQ_8")
	)
	(segment
		(start 40.29329 -150.09749)
		(end 41.02862 -149.36216)
		(width 0.127)
		(layer "In5.Cu")
		(net "MEMDQ_8")
	)
	(segment
		(start 40.174164 -143.677894)
		(end 40.174164 -140.402564)
		(width 0.127)
		(layer "In5.Cu")
		(net "MEMDQ_8")
	)
	(segment
		(start 41.02862 -144.53235)
		(end 40.174164 -143.677894)
		(width 0.127)
		(layer "In5.Cu")
		(net "MEMDQ_8")
	)
	(segment
		(start 39.7002 -134.723632)
		(end 39.067994 -134.091426)
		(width 0.127)
		(layer "In5.Cu")
		(net "MEMDQ_8")
	)
	(segment
		(start 40.174164 -153.18613)
		(end 40.174164 -150.21687)
		(width 0.127)
		(layer "In5.Cu")
		(net "MEMDQ_8")
	)
	(segment
		(start 39.067994 -134.091426)
		(end 38.74135 -134.091426)
		(width 0.127)
		(layer "In5.Cu")
		(net "MEMDQ_8")
	)
	(segment
		(start 41.02862 -149.36216)
		(end 41.02862 -144.53235)
		(width 0.127)
		(layer "In5.Cu")
		(net "MEMDQ_8")
	)
	(segment
		(start 40.174164 -150.21687)
		(end 40.29329 -150.09749)
		(width 0.127)
		(layer "In5.Cu")
		(net "MEMDQ_8")
	)
	(segment
		(start 40.174164 -140.402564)
		(end 39.7002 -139.9286)
		(width 0.127)
		(layer "In5.Cu")
		(net "MEMDQ_8")
	)
	(segment
		(start 39.7002 -139.9286)
		(end 39.7002 -134.723632)
		(width 0.127)
		(layer "In5.Cu")
		(net "MEMDQ_8")
	)
	(segment
		(start 38.74135 -134.091426)
		(end 38.510972 -134.321804)
		(width 0.127)
		(layer "In5.Cu")
		(net "MEMDQ_8")
	)
	(segment
		(start 38.510972 -134.891018)
		(end 38.909498 -135.289544)
		(width 0.127)
		(layer "In5.Cu")
		(net "MEMDQ_8")
	)
	(segment
		(start 40.567864 -153.57983)
		(end 40.174164 -153.18613)
		(width 0.127)
		(layer "In5.Cu")
		(net "MEMDQ_8")
	)
	(segment
		(start 38.510972 -134.321804)
		(end 38.510972 -134.891018)
		(width 0.127)
		(layer "In5.Cu")
		(net "MEMDQ_8")
	)
	(segment
		(start 38.558724 -154.94)
		(end 38.379146 -154.760422)
		(width 0.12065)
		(layer "F.Cu")
		(net "MEMDQ_7")
	)
	(segment
		(start 39.304722 -137.284968)
		(end 38.925754 -137.663936)
		(width 0.12065)
		(layer "F.Cu")
		(net "MEMDQ_7")
	)
	(segment
		(start 38.379146 -154.760422)
		(end 37.310822 -154.760422)
		(width 0.12065)
		(layer "F.Cu")
		(net "MEMDQ_7")
	)
	(segment
		(start 38.568122 -155.382722)
		(end 38.558724 -155.373324)
		(width 0.12065)
		(layer "F.Cu")
		(net "MEMDQ_7")
	)
	(segment
		(start 38.967918 -154.910282)
		(end 38.967918 -155.18003)
		(width 0.12065)
		(layer "F.Cu")
		(net "MEMDQ_7")
	)
	(segment
		(start 37.1602 -154.6098)
		(end 37.1602 -154.17165)
		(width 0.12065)
		(layer "F.Cu")
		(net "MEMDQ_7")
	)
	(segment
		(start 39.9034 -154.17165)
		(end 39.9034 -154.6606)
		(width 0.12065)
		(layer "F.Cu")
		(net "MEMDQ_7")
	)
	(segment
		(start 38.925754 -137.663936)
		(end 38.925754 -137.673334)
		(width 0.12065)
		(layer "F.Cu")
		(net "MEMDQ_7")
	)
	(segment
		(start 39.0906 -154.7876)
		(end 38.967918 -154.910282)
		(width 0.12065)
		(layer "F.Cu")
		(net "MEMDQ_7")
	)
	(segment
		(start 38.558724 -155.373324)
		(end 38.558724 -154.94)
		(width 0.12065)
		(layer "F.Cu")
		(net "MEMDQ_7")
	)
	(segment
		(start 38.925754 -137.673334)
		(end 38.911276 -137.687812)
		(width 0.12065)
		(layer "F.Cu")
		(net "MEMDQ_7")
	)
	(segment
		(start 39.9034 -154.6606)
		(end 39.7764 -154.7876)
		(width 0.12065)
		(layer "F.Cu")
		(net "MEMDQ_7")
	)
	(segment
		(start 37.1602 -154.17165)
		(end 37.2872 -154.04465)
		(width 0.12065)
		(layer "F.Cu")
		(net "MEMDQ_7")
	)
	(segment
		(start 39.7764 -154.04465)
		(end 39.9034 -154.17165)
		(width 0.12065)
		(layer "F.Cu")
		(net "MEMDQ_7")
	)
	(segment
		(start 39.7764 -154.7876)
		(end 39.0906 -154.7876)
		(width 0.12065)
		(layer "F.Cu")
		(net "MEMDQ_7")
	)
	(segment
		(start 37.2872 -154.04465)
		(end 39.7764 -154.04465)
		(width 0.12065)
		(layer "F.Cu")
		(net "MEMDQ_7")
	)
	(segment
		(start 38.568122 -155.579826)
		(end 38.568122 -155.382722)
		(width 0.12065)
		(layer "F.Cu")
		(net "MEMDQ_7")
	)
	(segment
		(start 37.310822 -154.760422)
		(end 37.1602 -154.6098)
		(width 0.12065)
		(layer "F.Cu")
		(net "MEMDQ_7")
	)
	(via
		(at 38.967918 -155.18003)
		(size 0.4572)
		(drill 0.2032)
		(layers "F.Cu" "B.Cu")
		(net "MEMDQ_7")
	)
	(via
		(at 38.911276 -137.687812)
		(size 0.4572)
		(drill 0.2032)
		(layers "F.Cu" "B.Cu")
		(net "MEMDQ_7")
	)
	(segment
		(start 39.402766 -143.984472)
		(end 39.402766 -140.520166)
		(width 0.127)
		(layer "In5.Cu")
		(net "MEMDQ_7")
	)
	(segment
		(start 38.911276 -140.028676)
		(end 38.911276 -137.687812)
		(width 0.127)
		(layer "In5.Cu")
		(net "MEMDQ_7")
	)
	(segment
		(start 40.26662 -144.848326)
		(end 39.402766 -143.984472)
		(width 0.127)
		(layer "In5.Cu")
		(net "MEMDQ_7")
	)
	(segment
		(start 39.402766 -140.520166)
		(end 38.911276 -140.028676)
		(width 0.127)
		(layer "In5.Cu")
		(net "MEMDQ_7")
	)
	(segment
		(start 38.967918 -155.18003)
		(end 39.402766 -154.745182)
		(width 0.127)
		(layer "In5.Cu")
		(net "MEMDQ_7")
	)
	(segment
		(start 39.402766 -149.987)
		(end 40.26662 -149.123146)
		(width 0.127)
		(layer "In5.Cu")
		(net "MEMDQ_7")
	)
	(segment
		(start 40.26662 -149.123146)
		(end 40.26662 -144.848326)
		(width 0.127)
		(layer "In5.Cu")
		(net "MEMDQ_7")
	)
	(segment
		(start 39.402766 -154.745182)
		(end 39.402766 -149.987)
		(width 0.127)
		(layer "In5.Cu")
		(net "MEMDQ_7")
	)
	(segment
		(start 35.179 -148.11375)
		(end 35.179 -147.87245)
		(width 0.12065)
		(layer "F.Cu")
		(net "MEMDQ_6")
	)
	(segment
		(start 35.682174 -147.7518)
		(end 35.802824 -147.63115)
		(width 0.12065)
		(layer "F.Cu")
		(net "MEMDQ_6")
	)
	(segment
		(start 35.802824 -151.214582)
		(end 35.802824 -150.28545)
		(width 0.12065)
		(layer "F.Cu")
		(net "MEMDQ_6")
	)
	(segment
		(start 35.802824 -148.59635)
		(end 35.802824 -148.35505)
		(width 0.12065)
		(layer "F.Cu")
		(net "MEMDQ_6")
	)
	(segment
		(start 35.179 -149.07895)
		(end 35.179 -148.83765)
		(width 0.12065)
		(layer "F.Cu")
		(net "MEMDQ_6")
	)
	(segment
		(start 35.682174 -150.1648)
		(end 35.29965 -150.1648)
		(width 0.12065)
		(layer "F.Cu")
		(net "MEMDQ_6")
	)
	(segment
		(start 35.682174 -149.6822)
		(end 35.802824 -149.56155)
		(width 0.12065)
		(layer "F.Cu")
		(net "MEMDQ_6")
	)
	(segment
		(start 35.179 -150.04415)
		(end 35.179 -149.80285)
		(width 0.12065)
		(layer "F.Cu")
		(net "MEMDQ_6")
	)
	(segment
		(start 36.168076 -151.579834)
		(end 35.802824 -151.214582)
		(width 0.12065)
		(layer "F.Cu")
		(net "MEMDQ_6")
	)
	(segment
		(start 38.377876 -135.2804)
		(end 38.22319 -135.2804)
		(width 0.12065)
		(layer "F.Cu")
		(net "MEMDQ_6")
	)
	(segment
		(start 35.179 -147.87245)
		(end 35.29965 -147.7518)
		(width 0.12065)
		(layer "F.Cu")
		(net "MEMDQ_6")
	)
	(segment
		(start 38.504876 -135.684768)
		(end 38.504876 -135.4074)
		(width 0.12065)
		(layer "F.Cu")
		(net "MEMDQ_6")
	)
	(segment
		(start 35.29965 -148.717)
		(end 35.682174 -148.717)
		(width 0.12065)
		(layer "F.Cu")
		(net "MEMDQ_6")
	)
	(segment
		(start 35.802824 -147.2692)
		(end 35.929824 -147.1422)
		(width 0.12065)
		(layer "F.Cu")
		(net "MEMDQ_6")
	)
	(segment
		(start 35.682174 -149.1996)
		(end 35.29965 -149.1996)
		(width 0.12065)
		(layer "F.Cu")
		(net "MEMDQ_6")
	)
	(segment
		(start 36.440872 -147.1422)
		(end 36.567872 -147.2692)
		(width 0.12065)
		(layer "F.Cu")
		(net "MEMDQ_6")
	)
	(segment
		(start 38.504876 -135.4074)
		(end 38.377876 -135.2804)
		(width 0.12065)
		(layer "F.Cu")
		(net "MEMDQ_6")
	)
	(segment
		(start 35.802824 -149.56155)
		(end 35.802824 -149.32025)
		(width 0.12065)
		(layer "F.Cu")
		(net "MEMDQ_6")
	)
	(segment
		(start 35.29965 -149.6822)
		(end 35.682174 -149.6822)
		(width 0.12065)
		(layer "F.Cu")
		(net "MEMDQ_6")
	)
	(segment
		(start 35.802824 -148.35505)
		(end 35.682174 -148.2344)
		(width 0.12065)
		(layer "F.Cu")
		(net "MEMDQ_6")
	)
	(segment
		(start 35.802824 -150.28545)
		(end 35.682174 -150.1648)
		(width 0.12065)
		(layer "F.Cu")
		(net "MEMDQ_6")
	)
	(segment
		(start 35.29965 -147.7518)
		(end 35.682174 -147.7518)
		(width 0.12065)
		(layer "F.Cu")
		(net "MEMDQ_6")
	)
	(segment
		(start 35.29965 -149.1996)
		(end 35.179 -149.07895)
		(width 0.12065)
		(layer "F.Cu")
		(net "MEMDQ_6")
	)
	(segment
		(start 35.29965 -148.2344)
		(end 35.179 -148.11375)
		(width 0.12065)
		(layer "F.Cu")
		(net "MEMDQ_6")
	)
	(segment
		(start 35.682174 -148.717)
		(end 35.802824 -148.59635)
		(width 0.12065)
		(layer "F.Cu")
		(net "MEMDQ_6")
	)
	(segment
		(start 35.29965 -150.1648)
		(end 35.179 -150.04415)
		(width 0.12065)
		(layer "F.Cu")
		(net "MEMDQ_6")
	)
	(segment
		(start 35.682174 -148.2344)
		(end 35.29965 -148.2344)
		(width 0.12065)
		(layer "F.Cu")
		(net "MEMDQ_6")
	)
	(segment
		(start 35.179 -149.80285)
		(end 35.29965 -149.6822)
		(width 0.12065)
		(layer "F.Cu")
		(net "MEMDQ_6")
	)
	(segment
		(start 35.179 -148.83765)
		(end 35.29965 -148.717)
		(width 0.12065)
		(layer "F.Cu")
		(net "MEMDQ_6")
	)
	(segment
		(start 35.802824 -149.32025)
		(end 35.682174 -149.1996)
		(width 0.12065)
		(layer "F.Cu")
		(net "MEMDQ_6")
	)
	(segment
		(start 35.802824 -147.63115)
		(end 35.802824 -147.2692)
		(width 0.12065)
		(layer "F.Cu")
		(net "MEMDQ_6")
	)
	(segment
		(start 38.09619 -135.4074)
		(end 38.09619 -136.085834)
		(width 0.12065)
		(layer "F.Cu")
		(net "MEMDQ_6")
	)
	(segment
		(start 38.22319 -135.2804)
		(end 38.09619 -135.4074)
		(width 0.12065)
		(layer "F.Cu")
		(net "MEMDQ_6")
	)
	(segment
		(start 36.567872 -147.2692)
		(end 36.567872 -149.580092)
		(width 0.12065)
		(layer "F.Cu")
		(net "MEMDQ_6")
	)
	(segment
		(start 35.929824 -147.1422)
		(end 36.440872 -147.1422)
		(width 0.12065)
		(layer "F.Cu")
		(net "MEMDQ_6")
	)
	(via
		(at 36.567872 -149.580092)
		(size 0.4572)
		(drill 0.2032)
		(layers "F.Cu" "B.Cu")
		(net "MEMDQ_6")
	)
	(via
		(at 38.09619 -136.085834)
		(size 0.4572)
		(drill 0.2032)
		(layers "F.Cu" "B.Cu")
		(net "MEMDQ_6")
	)
	(segment
		(start 36.567872 -149.580092)
		(end 35.915854 -148.928074)
		(width 0.127)
		(layer "In5.Cu")
		(net "MEMDQ_6")
	)
	(segment
		(start 38.488874 -137.04824)
		(end 38.488874 -136.478518)
		(width 0.127)
		(layer "In5.Cu")
		(net "MEMDQ_6")
	)
	(segment
		(start 35.915854 -139.62126)
		(end 38.488874 -137.04824)
		(width 0.127)
		(layer "In5.Cu")
		(net "MEMDQ_6")
	)
	(segment
		(start 35.915854 -148.928074)
		(end 35.915854 -139.62126)
		(width 0.127)
		(layer "In5.Cu")
		(net "MEMDQ_6")
	)
	(segment
		(start 38.488874 -136.478518)
		(end 38.09619 -136.085834)
		(width 0.127)
		(layer "In5.Cu")
		(net "MEMDQ_6")
	)
	(segment
		(start 36.967922 -156.379926)
		(end 37.3634 -156.775404)
		(width 0.12065)
		(layer "F.Cu")
		(net "MEMDQ_5")
	)
	(segment
		(start 38.504876 -136.484868)
		(end 38.895274 -136.09447)
		(width 0.12065)
		(layer "F.Cu")
		(net "MEMDQ_5")
	)
	(segment
		(start 38.895274 -136.09447)
		(end 38.895274 -136.085072)
		(width 0.12065)
		(layer "F.Cu")
		(net "MEMDQ_5")
	)
	(segment
		(start 38.895274 -136.085072)
		(end 38.895528 -136.084818)
		(width 0.12065)
		(layer "F.Cu")
		(net "MEMDQ_5")
	)
	(segment
		(start 37.3634 -156.775404)
		(end 38.163754 -156.775404)
		(width 0.12065)
		(layer "F.Cu")
		(net "MEMDQ_5")
	)
	(via
		(at 38.895528 -136.084818)
		(size 0.4572)
		(drill 0.2032)
		(layers "F.Cu" "B.Cu")
		(net "MEMDQ_5")
	)
	(via
		(at 38.163754 -156.775404)
		(size 0.4572)
		(drill 0.2032)
		(layers "F.Cu" "B.Cu")
		(net "MEMDQ_5")
	)
	(segment
		(start 40.161464 -154.834336)
		(end 40.3352 -154.6606)
		(width 0.127)
		(layer "In5.Cu")
		(net "MEMDQ_5")
	)
	(segment
		(start 39.783766 -153.753566)
		(end 39.783766 -150.114)
		(width 0.127)
		(layer "In5.Cu")
		(net "MEMDQ_5")
	)
	(segment
		(start 40.6908 -153.97353)
		(end 40.00373 -153.97353)
		(width 0.127)
		(layer "In5.Cu")
		(net "MEMDQ_5")
	)
	(segment
		(start 39.304976 -136.494266)
		(end 38.895528 -136.084818)
		(width 0.127)
		(layer "In5.Cu")
		(net "MEMDQ_5")
	)
	(segment
		(start 40.64762 -144.690338)
		(end 39.783766 -143.826484)
		(width 0.127)
		(layer "In5.Cu")
		(net "MEMDQ_5")
	)
	(segment
		(start 40.3352 -154.6606)
		(end 40.6908 -154.6606)
		(width 0.127)
		(layer "In5.Cu")
		(net "MEMDQ_5")
	)
	(segment
		(start 40.6908 -154.6606)
		(end 40.8178 -154.5336)
		(width 0.127)
		(layer "In5.Cu")
		(net "MEMDQ_5")
	)
	(segment
		(start 39.783766 -140.436346)
		(end 39.304976 -139.957556)
		(width 0.127)
		(layer "In5.Cu")
		(net "MEMDQ_5")
	)
	(segment
		(start 40.64762 -149.250146)
		(end 40.64762 -144.690338)
		(width 0.127)
		(layer "In5.Cu")
		(net "MEMDQ_5")
	)
	(segment
		(start 39.783766 -143.826484)
		(end 39.783766 -140.436346)
		(width 0.127)
		(layer "In5.Cu")
		(net "MEMDQ_5")
	)
	(segment
		(start 40.8178 -154.5336)
		(end 40.8178 -154.10053)
		(width 0.127)
		(layer "In5.Cu")
		(net "MEMDQ_5")
	)
	(segment
		(start 38.565328 -155.825698)
		(end 38.817296 -155.57373)
		(width 0.127)
		(layer "In5.Cu")
		(net "MEMDQ_5")
	)
	(segment
		(start 40.00373 -153.97353)
		(end 39.783766 -153.753566)
		(width 0.127)
		(layer "In5.Cu")
		(net "MEMDQ_5")
	)
	(segment
		(start 39.931086 -155.57373)
		(end 40.161464 -155.343352)
		(width 0.127)
		(layer "In5.Cu")
		(net "MEMDQ_5")
	)
	(segment
		(start 38.817296 -155.57373)
		(end 39.931086 -155.57373)
		(width 0.127)
		(layer "In5.Cu")
		(net "MEMDQ_5")
	)
	(segment
		(start 38.565328 -156.37383)
		(end 38.565328 -155.825698)
		(width 0.127)
		(layer "In5.Cu")
		(net "MEMDQ_5")
	)
	(segment
		(start 39.304976 -139.957556)
		(end 39.304976 -136.494266)
		(width 0.127)
		(layer "In5.Cu")
		(net "MEMDQ_5")
	)
	(segment
		(start 40.8178 -154.10053)
		(end 40.6908 -153.97353)
		(width 0.127)
		(layer "In5.Cu")
		(net "MEMDQ_5")
	)
	(segment
		(start 39.783766 -150.114)
		(end 40.64762 -149.250146)
		(width 0.127)
		(layer "In5.Cu")
		(net "MEMDQ_5")
	)
	(segment
		(start 40.161464 -155.343352)
		(end 40.161464 -154.834336)
		(width 0.127)
		(layer "In5.Cu")
		(net "MEMDQ_5")
	)
	(segment
		(start 38.163754 -156.775404)
		(end 38.565328 -156.37383)
		(width 0.127)
		(layer "In5.Cu")
		(net "MEMDQ_5")
	)
	(segment
		(start 38.504876 -137.284968)
		(end 38.495224 -137.284968)
		(width 0.12065)
		(layer "F.Cu")
		(net "MEMDQ_4")
	)
	(segment
		(start 37.768022 -156.374592)
		(end 37.373814 -155.980384)
		(width 0.12065)
		(layer "F.Cu")
		(net "MEMDQ_4")
	)
	(segment
		(start 38.495224 -137.284968)
		(end 38.095174 -136.884918)
		(width 0.12065)
		(layer "F.Cu")
		(net "MEMDQ_4")
	)
	(segment
		(start 37.768022 -156.379926)
		(end 37.768022 -156.374592)
		(width 0.12065)
		(layer "F.Cu")
		(net "MEMDQ_4")
	)
	(via
		(at 37.373814 -155.980384)
		(size 0.4572)
		(drill 0.2032)
		(layers "F.Cu" "B.Cu")
		(net "MEMDQ_4")
	)
	(via
		(at 38.095174 -136.884918)
		(size 0.4572)
		(drill 0.2032)
		(layers "F.Cu" "B.Cu")
		(net "MEMDQ_4")
	)
	(segment
		(start 37.373814 -157.5562)
		(end 37.246814 -157.6832)
		(width 0.127)
		(layer "In5.Cu")
		(net "MEMDQ_4")
	)
	(segment
		(start 36.301172 -157.6832)
		(end 36.174172 -157.5562)
		(width 0.127)
		(layer "In5.Cu")
		(net "MEMDQ_4")
	)
	(segment
		(start 35.534854 -149.504654)
		(end 35.534854 -139.445238)
		(width 0.127)
		(layer "In5.Cu")
		(net "MEMDQ_4")
	)
	(segment
		(start 36.173918 -155.011882)
		(end 36.974018 -154.211782)
		(width 0.127)
		(layer "In5.Cu")
		(net "MEMDQ_4")
	)
	(segment
		(start 36.622482 -150.991824)
		(end 36.174172 -150.543514)
		(width 0.127)
		(layer "In5.Cu")
		(net "MEMDQ_4")
	)
	(segment
		(start 36.174172 -155.816808)
		(end 36.173918 -155.816554)
		(width 0.127)
		(layer "In5.Cu")
		(net "MEMDQ_4")
	)
	(segment
		(start 36.173918 -155.816554)
		(end 36.173918 -155.011882)
		(width 0.127)
		(layer "In5.Cu")
		(net "MEMDQ_4")
	)
	(segment
		(start 36.174172 -157.5562)
		(end 36.174172 -155.816808)
		(width 0.127)
		(layer "In5.Cu")
		(net "MEMDQ_4")
	)
	(segment
		(start 35.534854 -139.445238)
		(end 38.095174 -136.884918)
		(width 0.127)
		(layer "In5.Cu")
		(net "MEMDQ_4")
	)
	(segment
		(start 37.246814 -157.6832)
		(end 36.301172 -157.6832)
		(width 0.127)
		(layer "In5.Cu")
		(net "MEMDQ_4")
	)
	(segment
		(start 36.174172 -150.143972)
		(end 35.534854 -149.504654)
		(width 0.127)
		(layer "In5.Cu")
		(net "MEMDQ_4")
	)
	(segment
		(start 36.974018 -154.211782)
		(end 36.974018 -152.628854)
		(width 0.127)
		(layer "In5.Cu")
		(net "MEMDQ_4")
	)
	(segment
		(start 37.373814 -155.980384)
		(end 37.373814 -157.5562)
		(width 0.127)
		(layer "In5.Cu")
		(net "MEMDQ_4")
	)
	(segment
		(start 36.974018 -152.628854)
		(end 36.622482 -152.277318)
		(width 0.127)
		(layer "In5.Cu")
		(net "MEMDQ_4")
	)
	(segment
		(start 36.174172 -150.543514)
		(end 36.174172 -150.143972)
		(width 0.127)
		(layer "In5.Cu")
		(net "MEMDQ_4")
	)
	(segment
		(start 36.622482 -152.277318)
		(end 36.622482 -150.991824)
		(width 0.127)
		(layer "In5.Cu")
		(net "MEMDQ_4")
	)
	(segment
		(start 38.8874 -138.467338)
		(end 38.8874 -139.455652)
		(width 0.12065)
		(layer "F.Cu")
		(net "MEMDQ_3")
	)
	(segment
		(start 37.061902 -141.496542)
		(end 37.061902 -140.055346)
		(width 0.12065)
		(layer "F.Cu")
		(net "MEMDQ_3")
	)
	(segment
		(start 36.960556 -139.954)
		(end 36.817046 -139.954)
		(width 0.12065)
		(layer "F.Cu")
		(net "MEMDQ_3")
	)
	(segment
		(start 36.817046 -139.954)
		(end 36.7157 -140.055346)
		(width 0.12065)
		(layer "F.Cu")
		(net "MEMDQ_3")
	)
	(segment
		(start 36.436554 -141.3764)
		(end 36.309554 -141.2494)
		(width 0.12065)
		(layer "F.Cu")
		(net "MEMDQ_3")
	)
	(segment
		(start 37.290756 -141.725396)
		(end 37.061902 -141.496542)
		(width 0.12065)
		(layer "F.Cu")
		(net "MEMDQ_3")
	)
	(segment
		(start 37.061902 -140.055346)
		(end 36.960556 -139.954)
		(width 0.12065)
		(layer "F.Cu")
		(net "MEMDQ_3")
	)
	(segment
		(start 38.168072 -153.7462)
		(end 38.345872 -153.5684)
		(width 0.12065)
		(layer "F.Cu")
		(net "MEMDQ_3")
	)
	(segment
		(start 36.5887 -141.3764)
		(end 36.436554 -141.3764)
		(width 0.12065)
		(layer "F.Cu")
		(net "MEMDQ_3")
	)
	(segment
		(start 38.504876 -138.084814)
		(end 38.8874 -138.467338)
		(width 0.12065)
		(layer "F.Cu")
		(net "MEMDQ_3")
	)
	(segment
		(start 37.529516 -153.170382)
		(end 36.593018 -153.170382)
		(width 0.12065)
		(layer "F.Cu")
		(net "MEMDQ_3")
	)
	(segment
		(start 37.878004 -141.725396)
		(end 37.290756 -141.725396)
		(width 0.12065)
		(layer "F.Cu")
		(net "MEMDQ_3")
	)
	(segment
		(start 37.768022 -152.379934)
		(end 37.768022 -152.931876)
		(width 0.12065)
		(layer "F.Cu")
		(net "MEMDQ_3")
	)
	(segment
		(start 38.345872 -152.957784)
		(end 38.168072 -152.779984)
		(width 0.12065)
		(layer "F.Cu")
		(net "MEMDQ_3")
	)
	(segment
		(start 36.309554 -141.2494)
		(end 36.309554 -141.131544)
		(width 0.12065)
		(layer "F.Cu")
		(net "MEMDQ_3")
	)
	(segment
		(start 38.345872 -153.5684)
		(end 38.345872 -152.957784)
		(width 0.12065)
		(layer "F.Cu")
		(net "MEMDQ_3")
	)
	(segment
		(start 37.768022 -152.931876)
		(end 37.529516 -153.170382)
		(width 0.12065)
		(layer "F.Cu")
		(net "MEMDQ_3")
	)
	(segment
		(start 36.5252 -153.7462)
		(end 38.168072 -153.7462)
		(width 0.12065)
		(layer "F.Cu")
		(net "MEMDQ_3")
	)
	(segment
		(start 38.8874 -139.455652)
		(end 38.09365 -140.249402)
		(width 0.12065)
		(layer "F.Cu")
		(net "MEMDQ_3")
	)
	(segment
		(start 36.593018 -153.170382)
		(end 36.3982 -153.3652)
		(width 0.12065)
		(layer "F.Cu")
		(net "MEMDQ_3")
	)
	(segment
		(start 38.09365 -140.249402)
		(end 38.09365 -141.50975)
		(width 0.12065)
		(layer "F.Cu")
		(net "MEMDQ_3")
	)
	(segment
		(start 36.7157 -140.055346)
		(end 36.7157 -141.2494)
		(width 0.12065)
		(layer "F.Cu")
		(net "MEMDQ_3")
	)
	(segment
		(start 36.3982 -153.3652)
		(end 36.3982 -153.6192)
		(width 0.12065)
		(layer "F.Cu")
		(net "MEMDQ_3")
	)
	(segment
		(start 36.3982 -153.6192)
		(end 36.5252 -153.7462)
		(width 0.12065)
		(layer "F.Cu")
		(net "MEMDQ_3")
	)
	(segment
		(start 38.09365 -141.50975)
		(end 37.878004 -141.725396)
		(width 0.12065)
		(layer "F.Cu")
		(net "MEMDQ_3")
	)
	(segment
		(start 36.7157 -141.2494)
		(end 36.5887 -141.3764)
		(width 0.12065)
		(layer "F.Cu")
		(net "MEMDQ_3")
	)
	(via
		(at 38.168072 -152.779984)
		(size 0.4572)
		(drill 0.2032)
		(layers "F.Cu" "B.Cu")
		(net "MEMDQ_3")
	)
	(via
		(at 36.309554 -141.131544)
		(size 0.4572)
		(drill 0.2032)
		(layers "F.Cu" "B.Cu")
		(net "MEMDQ_3")
	)
	(segment
		(start 36.97351 -149.31771)
		(end 36.309554 -148.653754)
		(width 0.127)
		(layer "In5.Cu")
		(net "MEMDQ_3")
	)
	(segment
		(start 36.97351 -152.146762)
		(end 36.97351 -149.31771)
		(width 0.127)
		(layer "In5.Cu")
		(net "MEMDQ_3")
	)
	(segment
		(start 38.168072 -152.779984)
		(end 37.765228 -152.37714)
		(width 0.127)
		(layer "In5.Cu")
		(net "MEMDQ_3")
	)
	(segment
		(start 37.765228 -152.37714)
		(end 37.203888 -152.37714)
		(width 0.127)
		(layer "In5.Cu")
		(net "MEMDQ_3")
	)
	(segment
		(start 36.309554 -148.653754)
		(end 36.309554 -141.131544)
		(width 0.127)
		(layer "In5.Cu")
		(net "MEMDQ_3")
	)
	(segment
		(start 37.203888 -152.37714)
		(end 36.97351 -152.146762)
		(width 0.127)
		(layer "In5.Cu")
		(net "MEMDQ_3")
	)
	(segment
		(start 37.768022 -151.579834)
		(end 37.768022 -151.868378)
		(width 0.12065)
		(layer "F.Cu")
		(net "MEMDQ_2")
	)
	(segment
		(start 37.768022 -151.868378)
		(end 37.65296 -151.98344)
		(width 0.12065)
		(layer "F.Cu")
		(net "MEMDQ_2")
	)
	(segment
		(start 38.504876 -139.447524)
		(end 37.8714 -140.081)
		(width 0.12065)
		(layer "F.Cu")
		(net "MEMDQ_2")
	)
	(segment
		(start 37.8714 -140.081)
		(end 37.8714 -140.915898)
		(width 0.12065)
		(layer "F.Cu")
		(net "MEMDQ_2")
	)
	(segment
		(start 37.8714 -140.915898)
		(end 37.452554 -141.334744)
		(width 0.12065)
		(layer "F.Cu")
		(net "MEMDQ_2")
	)
	(segment
		(start 38.504876 -138.884914)
		(end 38.504876 -139.447524)
		(width 0.12065)
		(layer "F.Cu")
		(net "MEMDQ_2")
	)
	(segment
		(start 37.65296 -151.98344)
		(end 37.36721 -151.98344)
		(width 0.12065)
		(layer "F.Cu")
		(net "MEMDQ_2")
	)
	(via
		(at 37.452554 -141.334744)
		(size 0.4572)
		(drill 0.2032)
		(layers "F.Cu" "B.Cu")
		(net "MEMDQ_2")
	)
	(via
		(at 37.36721 -151.98344)
		(size 0.4572)
		(drill 0.2032)
		(layers "F.Cu" "B.Cu")
		(net "MEMDQ_2")
	)
	(segment
		(start 36.8808 -140.67536)
		(end 37.0078 -140.54836)
		(width 0.127)
		(layer "In5.Cu")
		(net "MEMDQ_2")
	)
	(segment
		(start 36.830254 -140.67536)
		(end 36.8808 -140.67536)
		(width 0.127)
		(layer "In5.Cu")
		(net "MEMDQ_2")
	)
	(segment
		(start 37.579554 -141.732)
		(end 37.452554 -141.605)
		(width 0.127)
		(layer "In5.Cu")
		(net "MEMDQ_2")
	)
	(segment
		(start 38.288976 -139.44219)
		(end 38.288976 -139.780518)
		(width 0.127)
		(layer "In5.Cu")
		(net "MEMDQ_2")
	)
	(segment
		(start 36.817554 -142.19936)
		(end 36.703254 -142.08506)
		(width 0.127)
		(layer "In5.Cu")
		(net "MEMDQ_2")
	)
	(segment
		(start 36.703254 -141.05636)
		(end 36.703254 -140.80236)
		(width 0.127)
		(layer "In5.Cu")
		(net "MEMDQ_2")
	)
	(segment
		(start 37.2618 -150.485602)
		(end 37.2618 -150.231602)
		(width 0.127)
		(layer "In5.Cu")
		(net "MEMDQ_2")
	)
	(segment
		(start 37.768022 -149.57425)
		(end 36.690554 -148.496782)
		(width 0.127)
		(layer "In5.Cu")
		(net "MEMDQ_2")
	)
	(segment
		(start 37.3888 -150.104602)
		(end 37.641022 -150.104602)
		(width 0.127)
		(layer "In5.Cu")
		(net "MEMDQ_2")
	)
	(segment
		(start 37.768022 -151.8412)
		(end 37.768022 -150.739602)
		(width 0.127)
		(layer "In5.Cu")
		(net "MEMDQ_2")
	)
	(segment
		(start 37.8206 -139.18819)
		(end 37.9476 -139.31519)
		(width 0.127)
		(layer "In5.Cu")
		(net "MEMDQ_2")
	)
	(segment
		(start 38.085776 -138.1506)
		(end 38.288976 -138.3538)
		(width 0.127)
		(layer "In5.Cu")
		(net "MEMDQ_2")
	)
	(segment
		(start 38.288976 -138.68019)
		(end 38.161976 -138.80719)
		(width 0.127)
		(layer "In5.Cu")
		(net "MEMDQ_2")
	)
	(segment
		(start 36.830254 -140.16736)
		(end 36.703254 -140.04036)
		(width 0.127)
		(layer "In5.Cu")
		(net "MEMDQ_2")
	)
	(segment
		(start 37.3888 -142.32636)
		(end 37.2618 -142.19936)
		(width 0.127)
		(layer "In5.Cu")
		(net "MEMDQ_2")
	)
	(segment
		(start 37.36721 -151.98344)
		(end 37.625782 -151.98344)
		(width 0.127)
		(layer "In5.Cu")
		(net "MEMDQ_2")
	)
	(segment
		(start 37.625782 -151.98344)
		(end 37.768022 -151.8412)
		(width 0.127)
		(layer "In5.Cu")
		(net "MEMDQ_2")
	)
	(segment
		(start 36.830254 -141.18336)
		(end 36.703254 -141.05636)
		(width 0.127)
		(layer "In5.Cu")
		(net "MEMDQ_2")
	)
	(segment
		(start 36.690554 -142.83436)
		(end 36.817554 -142.70736)
		(width 0.127)
		(layer "In5.Cu")
		(net "MEMDQ_2")
	)
	(segment
		(start 36.703254 -142.08506)
		(end 36.703254 -141.81836)
		(width 0.127)
		(layer "In5.Cu")
		(net "MEMDQ_2")
	)
	(segment
		(start 37.3888 -150.612602)
		(end 37.2618 -150.485602)
		(width 0.127)
		(layer "In5.Cu")
		(net "MEMDQ_2")
	)
	(segment
		(start 37.641022 -150.612602)
		(end 37.3888 -150.612602)
		(width 0.127)
		(layer "In5.Cu")
		(net "MEMDQ_2")
	)
	(segment
		(start 36.703254 -141.81836)
		(end 36.830254 -141.69136)
		(width 0.127)
		(layer "In5.Cu")
		(net "MEMDQ_2")
	)
	(segment
		(start 37.9476 -139.31519)
		(end 38.161976 -139.31519)
		(width 0.127)
		(layer "In5.Cu")
		(net "MEMDQ_2")
	)
	(segment
		(start 38.161976 -139.31519)
		(end 38.288976 -139.44219)
		(width 0.127)
		(layer "In5.Cu")
		(net "MEMDQ_2")
	)
	(segment
		(start 37.8206 -138.93419)
		(end 37.8206 -139.18819)
		(width 0.127)
		(layer "In5.Cu")
		(net "MEMDQ_2")
	)
	(segment
		(start 37.982906 -140.086588)
		(end 37.982906 -141.605)
		(width 0.127)
		(layer "In5.Cu")
		(net "MEMDQ_2")
	)
	(segment
		(start 37.8206 -138.1506)
		(end 38.085776 -138.1506)
		(width 0.127)
		(layer "In5.Cu")
		(net "MEMDQ_2")
	)
	(segment
		(start 37.982906 -141.605)
		(end 37.855906 -141.732)
		(width 0.127)
		(layer "In5.Cu")
		(net "MEMDQ_2")
	)
	(segment
		(start 36.703254 -140.80236)
		(end 36.830254 -140.67536)
		(width 0.127)
		(layer "In5.Cu")
		(net "MEMDQ_2")
	)
	(segment
		(start 36.8808 -141.69136)
		(end 37.0078 -141.56436)
		(width 0.127)
		(layer "In5.Cu")
		(net "MEMDQ_2")
	)
	(segment
		(start 37.2618 -142.19936)
		(end 36.817554 -142.19936)
		(width 0.127)
		(layer "In5.Cu")
		(net "MEMDQ_2")
	)
	(segment
		(start 37.0078 -140.29436)
		(end 36.8808 -140.16736)
		(width 0.127)
		(layer "In5.Cu")
		(net "MEMDQ_2")
	)
	(segment
		(start 37.0078 -141.56436)
		(end 37.0078 -141.31036)
		(width 0.127)
		(layer "In5.Cu")
		(net "MEMDQ_2")
	)
	(segment
		(start 36.8808 -141.18336)
		(end 36.830254 -141.18336)
		(width 0.127)
		(layer "In5.Cu")
		(net "MEMDQ_2")
	)
	(segment
		(start 37.0078 -140.54836)
		(end 37.0078 -140.29436)
		(width 0.127)
		(layer "In5.Cu")
		(net "MEMDQ_2")
	)
	(segment
		(start 36.830254 -141.69136)
		(end 36.8808 -141.69136)
		(width 0.127)
		(layer "In5.Cu")
		(net "MEMDQ_2")
	)
	(segment
		(start 37.3888 -142.58036)
		(end 37.3888 -142.32636)
		(width 0.127)
		(layer "In5.Cu")
		(net "MEMDQ_2")
	)
	(segment
		(start 38.288976 -138.3538)
		(end 38.288976 -138.68019)
		(width 0.127)
		(layer "In5.Cu")
		(net "MEMDQ_2")
	)
	(segment
		(start 37.768022 -150.739602)
		(end 37.641022 -150.612602)
		(width 0.127)
		(layer "In5.Cu")
		(net "MEMDQ_2")
	)
	(segment
		(start 37.0078 -141.31036)
		(end 36.8808 -141.18336)
		(width 0.127)
		(layer "In5.Cu")
		(net "MEMDQ_2")
	)
	(segment
		(start 37.641022 -150.104602)
		(end 37.768022 -149.977602)
		(width 0.127)
		(layer "In5.Cu")
		(net "MEMDQ_2")
	)
	(segment
		(start 36.817554 -142.70736)
		(end 37.2618 -142.70736)
		(width 0.127)
		(layer "In5.Cu")
		(net "MEMDQ_2")
	)
	(segment
		(start 36.703254 -140.04036)
		(end 36.703254 -139.267946)
		(width 0.127)
		(layer "In5.Cu")
		(net "MEMDQ_2")
	)
	(segment
		(start 36.8808 -140.16736)
		(end 36.830254 -140.16736)
		(width 0.127)
		(layer "In5.Cu")
		(net "MEMDQ_2")
	)
	(segment
		(start 38.288976 -139.780518)
		(end 37.982906 -140.086588)
		(width 0.127)
		(layer "In5.Cu")
		(net "MEMDQ_2")
	)
	(segment
		(start 36.690554 -148.496782)
		(end 36.690554 -142.83436)
		(width 0.127)
		(layer "In5.Cu")
		(net "MEMDQ_2")
	)
	(segment
		(start 37.452554 -141.605)
		(end 37.452554 -141.334744)
		(width 0.127)
		(layer "In5.Cu")
		(net "MEMDQ_2")
	)
	(segment
		(start 37.9476 -138.80719)
		(end 37.8206 -138.93419)
		(width 0.127)
		(layer "In5.Cu")
		(net "MEMDQ_2")
	)
	(segment
		(start 37.2618 -150.231602)
		(end 37.3888 -150.104602)
		(width 0.127)
		(layer "In5.Cu")
		(net "MEMDQ_2")
	)
	(segment
		(start 37.768022 -149.977602)
		(end 37.768022 -149.57425)
		(width 0.127)
		(layer "In5.Cu")
		(net "MEMDQ_2")
	)
	(segment
		(start 37.2618 -142.70736)
		(end 37.3888 -142.58036)
		(width 0.127)
		(layer "In5.Cu")
		(net "MEMDQ_2")
	)
	(segment
		(start 37.855906 -141.732)
		(end 37.579554 -141.732)
		(width 0.127)
		(layer "In5.Cu")
		(net "MEMDQ_2")
	)
	(segment
		(start 38.161976 -138.80719)
		(end 37.9476 -138.80719)
		(width 0.127)
		(layer "In5.Cu")
		(net "MEMDQ_2")
	)
	(segment
		(start 36.703254 -139.267946)
		(end 37.8206 -138.1506)
		(width 0.127)
		(layer "In5.Cu")
		(net "MEMDQ_2")
	)
	(segment
		(start 42.926 -156.10713)
		(end 42.799 -155.98013)
		(width 0.12065)
		(layer "F.Cu")
		(net "MEMDQ_15")
	)
	(segment
		(start 41.768014 -156.6926)
		(end 41.895014 -156.8196)
		(width 0.12065)
		(layer "F.Cu")
		(net "MEMDQ_15")
	)
	(segment
		(start 41.768014 -156.379926)
		(end 41.768014 -156.6926)
		(width 0.12065)
		(layer "F.Cu")
		(net "MEMDQ_15")
	)
	(segment
		(start 42.799 -155.98013)
		(end 41.368218 -155.98013)
		(width 0.12065)
		(layer "F.Cu")
		(net "MEMDQ_15")
	)
	(segment
		(start 42.926 -156.6926)
		(end 42.926 -156.10713)
		(width 0.12065)
		(layer "F.Cu")
		(net "MEMDQ_15")
	)
	(segment
		(start 42.799 -156.8196)
		(end 42.926 -156.6926)
		(width 0.12065)
		(layer "F.Cu")
		(net "MEMDQ_15")
	)
	(segment
		(start 41.895014 -156.8196)
		(end 42.799 -156.8196)
		(width 0.12065)
		(layer "F.Cu")
		(net "MEMDQ_15")
	)
	(segment
		(start 40.904922 -136.484868)
		(end 41.304718 -136.884664)
		(width 0.12065)
		(layer "F.Cu")
		(net "MEMDQ_15")
	)
	(via
		(at 41.304718 -136.884664)
		(size 0.4572)
		(drill 0.2032)
		(layers "F.Cu" "B.Cu")
		(net "MEMDQ_15")
	)
	(via
		(at 41.368218 -155.98013)
		(size 0.4572)
		(drill 0.2032)
		(layers "F.Cu" "B.Cu")
		(net "MEMDQ_15")
	)
	(segment
		(start 42.498264 -137.521442)
		(end 42.267886 -137.291064)
		(width 0.127)
		(layer "In5.Cu")
		(net "MEMDQ_15")
	)
	(segment
		(start 41.711118 -137.291064)
		(end 41.304718 -136.884664)
		(width 0.127)
		(layer "In5.Cu")
		(net "MEMDQ_15")
	)
	(segment
		(start 43.234864 -138.078464)
		(end 42.701464 -138.078464)
		(width 0.127)
		(layer "In5.Cu")
		(net "MEMDQ_15")
	)
	(segment
		(start 44.52112 -153.383742)
		(end 44.52112 -139.36472)
		(width 0.127)
		(layer "In5.Cu")
		(net "MEMDQ_15")
	)
	(segment
		(start 41.924732 -155.98013)
		(end 44.52112 -153.383742)
		(width 0.127)
		(layer "In5.Cu")
		(net "MEMDQ_15")
	)
	(segment
		(start 42.267886 -137.291064)
		(end 41.711118 -137.291064)
		(width 0.127)
		(layer "In5.Cu")
		(net "MEMDQ_15")
	)
	(segment
		(start 41.368218 -155.98013)
		(end 41.924732 -155.98013)
		(width 0.127)
		(layer "In5.Cu")
		(net "MEMDQ_15")
	)
	(segment
		(start 42.701464 -138.078464)
		(end 42.498264 -137.875264)
		(width 0.127)
		(layer "In5.Cu")
		(net "MEMDQ_15")
	)
	(segment
		(start 44.52112 -139.36472)
		(end 43.234864 -138.078464)
		(width 0.127)
		(layer "In5.Cu")
		(net "MEMDQ_15")
	)
	(segment
		(start 42.498264 -137.875264)
		(end 42.498264 -137.521442)
		(width 0.127)
		(layer "In5.Cu")
		(net "MEMDQ_15")
	)
	(segment
		(start 40.904922 -137.284968)
		(end 41.304718 -137.684764)
		(width 0.12065)
		(layer "F.Cu")
		(net "MEMDQ_14")
	)
	(segment
		(start 41.946068 -155.75788)
		(end 43.2308 -155.75788)
		(width 0.12065)
		(layer "F.Cu")
		(net "MEMDQ_14")
	)
	(segment
		(start 42.295064 -154.9146)
		(end 42.168064 -155.0416)
		(width 0.12065)
		(layer "F.Cu")
		(net "MEMDQ_14")
	)
	(segment
		(start 44.0182 -155.0416)
		(end 43.8912 -154.9146)
		(width 0.12065)
		(layer "F.Cu")
		(net "MEMDQ_14")
	)
	(segment
		(start 43.9166 -156.3624)
		(end 44.0182 -156.2608)
		(width 0.12065)
		(layer "F.Cu")
		(net "MEMDQ_14")
	)
	(segment
		(start 43.8912 -154.9146)
		(end 42.295064 -154.9146)
		(width 0.12065)
		(layer "F.Cu")
		(net "MEMDQ_14")
	)
	(segment
		(start 43.3324 -155.85948)
		(end 43.3324 -156.21)
		(width 0.12065)
		(layer "F.Cu")
		(net "MEMDQ_14")
	)
	(segment
		(start 44.0182 -156.2608)
		(end 44.0182 -155.0416)
		(width 0.12065)
		(layer "F.Cu")
		(net "MEMDQ_14")
	)
	(segment
		(start 42.168064 -155.0416)
		(end 42.168064 -155.179776)
		(width 0.12065)
		(layer "F.Cu")
		(net "MEMDQ_14")
	)
	(segment
		(start 41.768014 -155.579826)
		(end 41.946068 -155.75788)
		(width 0.12065)
		(layer "F.Cu")
		(net "MEMDQ_14")
	)
	(segment
		(start 43.3324 -156.21)
		(end 43.4848 -156.3624)
		(width 0.12065)
		(layer "F.Cu")
		(net "MEMDQ_14")
	)
	(segment
		(start 43.4848 -156.3624)
		(end 43.9166 -156.3624)
		(width 0.12065)
		(layer "F.Cu")
		(net "MEMDQ_14")
	)
	(segment
		(start 43.2308 -155.75788)
		(end 43.3324 -155.85948)
		(width 0.12065)
		(layer "F.Cu")
		(net "MEMDQ_14")
	)
	(via
		(at 42.168064 -155.179776)
		(size 0.4572)
		(drill 0.2032)
		(layers "F.Cu" "B.Cu")
		(net "MEMDQ_14")
	)
	(via
		(at 41.304718 -137.684764)
		(size 0.4572)
		(drill 0.2032)
		(layers "F.Cu" "B.Cu")
		(net "MEMDQ_14")
	)
	(segment
		(start 42.08145 -138.461496)
		(end 41.304718 -137.684764)
		(width 0.127)
		(layer "In5.Cu")
		(net "MEMDQ_14")
	)
	(segment
		(start 42.957496 -138.461496)
		(end 42.08145 -138.461496)
		(width 0.127)
		(layer "In5.Cu")
		(net "MEMDQ_14")
	)
	(segment
		(start 44.14012 -139.64412)
		(end 42.957496 -138.461496)
		(width 0.127)
		(layer "In5.Cu")
		(net "MEMDQ_14")
	)
	(segment
		(start 42.168064 -155.179776)
		(end 44.14012 -153.20772)
		(width 0.127)
		(layer "In5.Cu")
		(net "MEMDQ_14")
	)
	(segment
		(start 44.14012 -153.20772)
		(end 44.14012 -139.64412)
		(width 0.127)
		(layer "In5.Cu")
		(net "MEMDQ_14")
	)
	(segment
		(start 40.168068 -151.579834)
		(end 40.567864 -151.180038)
		(width 0.12065)
		(layer "F.Cu")
		(net "MEMDQ_13")
	)
	(segment
		(start 40.104822 -135.684768)
		(end 40.498522 -135.291068)
		(width 0.12065)
		(layer "F.Cu")
		(net "MEMDQ_13")
	)
	(segment
		(start 40.498522 -135.291068)
		(end 40.501824 -135.291068)
		(width 0.12065)
		(layer "F.Cu")
		(net "MEMDQ_13")
	)
	(via
		(at 40.501824 -135.291068)
		(size 0.4572)
		(drill 0.2032)
		(layers "F.Cu" "B.Cu")
		(net "MEMDQ_13")
	)
	(via
		(at 40.567864 -151.180038)
		(size 0.4572)
		(drill 0.2032)
		(layers "F.Cu" "B.Cu")
		(net "MEMDQ_13")
	)
	(segment
		(start 40.57142 -141.996922)
		(end 40.57142 -140.355066)
		(width 0.127)
		(layer "In5.Cu")
		(net "MEMDQ_13")
	)
	(segment
		(start 41.7322 -134.9756)
		(end 41.6052 -134.8486)
		(width 0.127)
		(layer "In5.Cu")
		(net "MEMDQ_13")
	)
	(segment
		(start 41.7322 -135.5344)
		(end 41.7322 -134.9756)
		(width 0.127)
		(layer "In5.Cu")
		(net "MEMDQ_13")
	)
	(segment
		(start 41.6052 -134.8486)
		(end 40.944292 -134.8486)
		(width 0.127)
		(layer "In5.Cu")
		(net "MEMDQ_13")
	)
	(segment
		(start 41.40962 -150.338282)
		(end 41.40962 -142.48765)
		(width 0.127)
		(layer "In5.Cu")
		(net "MEMDQ_13")
	)
	(segment
		(start 40.106346 -139.889992)
		(end 40.106346 -134.326376)
		(width 0.127)
		(layer "In5.Cu")
		(net "MEMDQ_13")
	)
	(segment
		(start 40.567864 -151.180038)
		(end 41.40962 -150.338282)
		(width 0.127)
		(layer "In5.Cu")
		(net "MEMDQ_13")
	)
	(segment
		(start 40.944292 -134.8486)
		(end 40.501824 -135.291068)
		(width 0.127)
		(layer "In5.Cu")
		(net "MEMDQ_13")
	)
	(segment
		(start 42.8752 -134.091426)
		(end 43.0022 -134.218426)
		(width 0.127)
		(layer "In5.Cu")
		(net "MEMDQ_13")
	)
	(segment
		(start 41.40962 -142.48765)
		(end 41.14927 -142.2273)
		(width 0.127)
		(layer "In5.Cu")
		(net "MEMDQ_13")
	)
	(segment
		(start 43.0022 -135.5344)
		(end 42.9006 -135.636)
		(width 0.127)
		(layer "In5.Cu")
		(net "MEMDQ_13")
	)
	(segment
		(start 42.9006 -135.636)
		(end 41.8338 -135.636)
		(width 0.127)
		(layer "In5.Cu")
		(net "MEMDQ_13")
	)
	(segment
		(start 40.341296 -134.091426)
		(end 42.8752 -134.091426)
		(width 0.127)
		(layer "In5.Cu")
		(net "MEMDQ_13")
	)
	(segment
		(start 41.8338 -135.636)
		(end 41.7322 -135.5344)
		(width 0.127)
		(layer "In5.Cu")
		(net "MEMDQ_13")
	)
	(segment
		(start 43.0022 -134.218426)
		(end 43.0022 -135.5344)
		(width 0.127)
		(layer "In5.Cu")
		(net "MEMDQ_13")
	)
	(segment
		(start 40.106346 -134.326376)
		(end 40.341296 -134.091426)
		(width 0.127)
		(layer "In5.Cu")
		(net "MEMDQ_13")
	)
	(segment
		(start 41.14927 -142.2273)
		(end 40.801798 -142.2273)
		(width 0.127)
		(layer "In5.Cu")
		(net "MEMDQ_13")
	)
	(segment
		(start 40.57142 -140.355066)
		(end 40.106346 -139.889992)
		(width 0.127)
		(layer "In5.Cu")
		(net "MEMDQ_13")
	)
	(segment
		(start 40.801798 -142.2273)
		(end 40.57142 -141.996922)
		(width 0.127)
		(layer "In5.Cu")
		(net "MEMDQ_13")
	)
	(segment
		(start 40.168068 -156.379926)
		(end 40.567864 -155.98013)
		(width 0.12065)
		(layer "F.Cu")
		(net "MEMDQ_12")
	)
	(segment
		(start 40.104822 -136.484868)
		(end 40.500046 -136.880092)
		(width 0.12065)
		(layer "F.Cu")
		(net "MEMDQ_12")
	)
	(via
		(at 40.500046 -136.880092)
		(size 0.4572)
		(drill 0.2032)
		(layers "F.Cu" "B.Cu")
		(net "MEMDQ_12")
	)
	(via
		(at 40.567864 -155.98013)
		(size 0.4572)
		(drill 0.2032)
		(layers "F.Cu" "B.Cu")
		(net "MEMDQ_12")
	)
	(segment
		(start 43.75912 -139.84732)
		(end 42.9006 -138.9888)
		(width 0.127)
		(layer "In5.Cu")
		(net "MEMDQ_12")
	)
	(segment
		(start 40.974264 -155.57373)
		(end 41.531032 -155.57373)
		(width 0.127)
		(layer "In5.Cu")
		(net "MEMDQ_12")
	)
	(segment
		(start 40.500046 -135.832596)
		(end 40.500046 -136.880092)
		(width 0.127)
		(layer "In5.Cu")
		(net "MEMDQ_12")
	)
	(segment
		(start 40.911018 -135.832596)
		(end 40.790622 -135.7122)
		(width 0.127)
		(layer "In5.Cu")
		(net "MEMDQ_12")
	)
	(segment
		(start 40.620442 -135.7122)
		(end 40.500046 -135.832596)
		(width 0.127)
		(layer "In5.Cu")
		(net "MEMDQ_12")
	)
	(segment
		(start 41.76141 -155.029408)
		(end 43.75912 -153.031698)
		(width 0.127)
		(layer "In5.Cu")
		(net "MEMDQ_12")
	)
	(segment
		(start 40.567864 -155.98013)
		(end 40.974264 -155.57373)
		(width 0.127)
		(layer "In5.Cu")
		(net "MEMDQ_12")
	)
	(segment
		(start 43.75912 -153.031698)
		(end 43.75912 -139.84732)
		(width 0.127)
		(layer "In5.Cu")
		(net "MEMDQ_12")
	)
	(segment
		(start 42.051732 -138.9888)
		(end 40.911018 -137.848086)
		(width 0.127)
		(layer "In5.Cu")
		(net "MEMDQ_12")
	)
	(segment
		(start 42.9006 -138.9888)
		(end 42.051732 -138.9888)
		(width 0.127)
		(layer "In5.Cu")
		(net "MEMDQ_12")
	)
	(segment
		(start 41.76141 -155.343352)
		(end 41.76141 -155.029408)
		(width 0.127)
		(layer "In5.Cu")
		(net "MEMDQ_12")
	)
	(segment
		(start 40.790622 -135.7122)
		(end 40.620442 -135.7122)
		(width 0.127)
		(layer "In5.Cu")
		(net "MEMDQ_12")
	)
	(segment
		(start 41.531032 -155.57373)
		(end 41.76141 -155.343352)
		(width 0.127)
		(layer "In5.Cu")
		(net "MEMDQ_12")
	)
	(segment
		(start 40.911018 -137.848086)
		(end 40.911018 -135.832596)
		(width 0.127)
		(layer "In5.Cu")
		(net "MEMDQ_12")
	)
	(segment
		(start 40.158416 -155.570174)
		(end 40.158416 -154.532584)
		(width 0.12065)
		(layer "F.Cu")
		(net "MEMDQ_11")
	)
	(segment
		(start 40.104822 -137.284968)
		(end 40.500046 -137.680192)
		(width 0.12065)
		(layer "F.Cu")
		(net "MEMDQ_11")
	)
	(segment
		(start 40.5384 -154.1526)
		(end 42.2656 -154.1526)
		(width 0.12065)
		(layer "F.Cu")
		(net "MEMDQ_11")
	)
	(segment
		(start 42.2656 -154.6352)
		(end 40.8686 -154.6352)
		(width 0.12065)
		(layer "F.Cu")
		(net "MEMDQ_11")
	)
	(segment
		(start 42.3926 -154.5082)
		(end 42.2656 -154.6352)
		(width 0.12065)
		(layer "F.Cu")
		(net "MEMDQ_11")
	)
	(segment
		(start 42.3926 -154.2796)
		(end 42.3926 -154.5082)
		(width 0.12065)
		(layer "F.Cu")
		(net "MEMDQ_11")
	)
	(segment
		(start 40.158416 -154.532584)
		(end 40.5384 -154.1526)
		(width 0.12065)
		(layer "F.Cu")
		(net "MEMDQ_11")
	)
	(segment
		(start 40.168068 -155.579826)
		(end 40.158416 -155.570174)
		(width 0.12065)
		(layer "F.Cu")
		(net "MEMDQ_11")
	)
	(segment
		(start 40.8686 -154.6352)
		(end 40.567864 -154.935936)
		(width 0.12065)
		(layer "F.Cu")
		(net "MEMDQ_11")
	)
	(segment
		(start 42.2656 -154.1526)
		(end 42.3926 -154.2796)
		(width 0.12065)
		(layer "F.Cu")
		(net "MEMDQ_11")
	)
	(segment
		(start 40.567864 -154.935936)
		(end 40.567864 -155.18003)
		(width 0.12065)
		(layer "F.Cu")
		(net "MEMDQ_11")
	)
	(via
		(at 40.500046 -137.680192)
		(size 0.4572)
		(drill 0.2032)
		(layers "F.Cu" "B.Cu")
		(net "MEMDQ_11")
	)
	(via
		(at 40.567864 -155.18003)
		(size 0.4572)
		(drill 0.2032)
		(layers "F.Cu" "B.Cu")
		(net "MEMDQ_11")
	)
	(segment
		(start 43.37812 -152.88768)
		(end 43.37812 -140.825474)
		(width 0.127)
		(layer "In5.Cu")
		(net "MEMDQ_11")
	)
	(segment
		(start 43.37812 -140.825474)
		(end 40.500046 -137.9474)
		(width 0.127)
		(layer "In5.Cu")
		(net "MEMDQ_11")
	)
	(segment
		(start 41.5798 -154.686)
		(end 43.37812 -152.88768)
		(width 0.127)
		(layer "In5.Cu")
		(net "MEMDQ_11")
	)
	(segment
		(start 40.500046 -137.9474)
		(end 40.500046 -137.680192)
		(width 0.127)
		(layer "In5.Cu")
		(net "MEMDQ_11")
	)
	(segment
		(start 40.567864 -155.18003)
		(end 41.061894 -154.686)
		(width 0.127)
		(layer "In5.Cu")
		(net "MEMDQ_11")
	)
	(segment
		(start 41.061894 -154.686)
		(end 41.5798 -154.686)
		(width 0.127)
		(layer "In5.Cu")
		(net "MEMDQ_11")
	)
	(segment
		(start 41.777666 -152.370282)
		(end 42.329608 -152.370282)
		(width 0.12065)
		(layer "F.Cu")
		(net "MEMDQ_10")
	)
	(segment
		(start 40.522398 -138.786108)
		(end 40.522398 -139.257024)
		(width 0.12065)
		(layer "F.Cu")
		(net "MEMDQ_10")
	)
	(segment
		(start 41.768014 -152.379934)
		(end 41.777666 -152.370282)
		(width 0.12065)
		(layer "F.Cu")
		(net "MEMDQ_10")
	)
	(segment
		(start 42.329608 -152.370282)
		(end 42.655744 -152.0444)
		(width 0.12065)
		(layer "F.Cu")
		(net "MEMDQ_10")
	)
	(segment
		(start 44.45 -154.0002)
		(end 44.323 -154.1272)
		(width 0.12065)
		(layer "F.Cu")
		(net "MEMDQ_10")
	)
	(segment
		(start 39.7002 -137.7696)
		(end 39.7002 -138.392662)
		(width 0.12065)
		(layer "F.Cu")
		(net "MEMDQ_10")
	)
	(segment
		(start 43.7896 -153.04897)
		(end 43.66133 -152.9207)
		(width 0.12065)
		(layer "F.Cu")
		(net "MEMDQ_10")
	)
	(segment
		(start 43.66133 -152.9207)
		(end 42.30878 -152.9207)
		(width 0.12065)
		(layer "F.Cu")
		(net "MEMDQ_10")
	)
	(segment
		(start 43.7896 -154.0002)
		(end 43.7896 -153.04897)
		(width 0.12065)
		(layer "F.Cu")
		(net "MEMDQ_10")
	)
	(segment
		(start 40.255952 -138.519662)
		(end 40.522398 -138.786108)
		(width 0.12065)
		(layer "F.Cu")
		(net "MEMDQ_10")
	)
	(segment
		(start 39.7002 -138.392662)
		(end 39.8272 -138.519662)
		(width 0.12065)
		(layer "F.Cu")
		(net "MEMDQ_10")
	)
	(segment
		(start 39.977822 -137.6426)
		(end 39.8272 -137.6426)
		(width 0.12065)
		(layer "F.Cu")
		(net "MEMDQ_10")
	)
	(segment
		(start 44.45 -152.1714)
		(end 44.45 -154.0002)
		(width 0.12065)
		(layer "F.Cu")
		(net "MEMDQ_10")
	)
	(segment
		(start 42.655744 -152.0444)
		(end 44.323 -152.0444)
		(width 0.12065)
		(layer "F.Cu")
		(net "MEMDQ_10")
	)
	(segment
		(start 39.8272 -137.6426)
		(end 39.7002 -137.7696)
		(width 0.12065)
		(layer "F.Cu")
		(net "MEMDQ_10")
	)
	(segment
		(start 40.104822 -137.7696)
		(end 39.977822 -137.6426)
		(width 0.12065)
		(layer "F.Cu")
		(net "MEMDQ_10")
	)
	(segment
		(start 44.323 -152.0444)
		(end 44.45 -152.1714)
		(width 0.12065)
		(layer "F.Cu")
		(net "MEMDQ_10")
	)
	(segment
		(start 42.30878 -152.9207)
		(end 42.168064 -152.779984)
		(width 0.12065)
		(layer "F.Cu")
		(net "MEMDQ_10")
	)
	(segment
		(start 43.9166 -154.1272)
		(end 43.7896 -154.0002)
		(width 0.12065)
		(layer "F.Cu")
		(net "MEMDQ_10")
	)
	(segment
		(start 44.323 -154.1272)
		(end 43.9166 -154.1272)
		(width 0.12065)
		(layer "F.Cu")
		(net "MEMDQ_10")
	)
	(segment
		(start 40.104822 -138.084814)
		(end 40.104822 -137.7696)
		(width 0.12065)
		(layer "F.Cu")
		(net "MEMDQ_10")
	)
	(segment
		(start 39.8272 -138.519662)
		(end 40.255952 -138.519662)
		(width 0.12065)
		(layer "F.Cu")
		(net "MEMDQ_10")
	)
	(via
		(at 40.522398 -139.257024)
		(size 0.4572)
		(drill 0.2032)
		(layers "F.Cu" "B.Cu")
		(net "MEMDQ_10")
	)
	(via
		(at 42.168064 -152.779984)
		(size 0.4572)
		(drill 0.2032)
		(layers "F.Cu" "B.Cu")
		(net "MEMDQ_10")
	)
	(segment
		(start 42.99712 -141.09192)
		(end 41.162224 -139.257024)
		(width 0.127)
		(layer "In5.Cu")
		(net "MEMDQ_10")
	)
	(segment
		(start 42.99712 -151.950928)
		(end 42.99712 -141.09192)
		(width 0.127)
		(layer "In5.Cu")
		(net "MEMDQ_10")
	)
	(segment
		(start 41.162224 -139.257024)
		(end 40.522398 -139.257024)
		(width 0.127)
		(layer "In5.Cu")
		(net "MEMDQ_10")
	)
	(segment
		(start 42.168064 -152.779984)
		(end 42.99712 -151.950928)
		(width 0.127)
		(layer "In5.Cu")
		(net "MEMDQ_10")
	)
	(segment
		(start 36.168076 -155.583382)
		(end 35.768534 -155.982924)
		(width 0.12065)
		(layer "F.Cu")
		(net "MEMDQ_1")
	)
	(segment
		(start 37.328856 -136.051544)
		(end 37.301932 -136.078468)
		(width 0.12065)
		(layer "F.Cu")
		(net "MEMDQ_1")
	)
	(segment
		(start 37.338 -136.051544)
		(end 37.328856 -136.051544)
		(width 0.12065)
		(layer "F.Cu")
		(net "MEMDQ_1")
	)
	(segment
		(start 36.168076 -155.579826)
		(end 36.168076 -155.583382)
		(width 0.12065)
		(layer "F.Cu")
		(net "MEMDQ_1")
	)
	(segment
		(start 37.704776 -135.684768)
		(end 37.338 -136.051544)
		(width 0.12065)
		(layer "F.Cu")
		(net "MEMDQ_1")
	)
	(via
		(at 35.768534 -155.982924)
		(size 0.4572)
		(drill 0.2032)
		(layers "F.Cu" "B.Cu")
		(net "MEMDQ_1")
	)
	(via
		(at 37.301932 -136.078468)
		(size 0.4572)
		(drill 0.2032)
		(layers "F.Cu" "B.Cu")
		(net "MEMDQ_1")
	)
	(segment
		(start 34.772854 -147.243546)
		(end 34.772854 -138.982196)
		(width 0.127)
		(layer "In5.Cu")
		(net "MEMDQ_1")
	)
	(segment
		(start 34.562034 -155.33116)
		(end 34.562034 -154.845766)
		(width 0.127)
		(layer "In5.Cu")
		(net "MEMDQ_1")
	)
	(segment
		(start 34.671 -154.7368)
		(end 35.9156 -154.7368)
		(width 0.127)
		(layer "In5.Cu")
		(net "MEMDQ_1")
	)
	(segment
		(start 36.762944 -136.078468)
		(end 37.301932 -136.078468)
		(width 0.127)
		(layer "In5.Cu")
		(net "MEMDQ_1")
	)
	(segment
		(start 35.768534 -155.982924)
		(end 35.361626 -155.576016)
		(width 0.127)
		(layer "In5.Cu")
		(net "MEMDQ_1")
	)
	(segment
		(start 36.0426 -154.6098)
		(end 36.0426 -154.178)
		(width 0.127)
		(layer "In5.Cu")
		(net "MEMDQ_1")
	)
	(segment
		(start 35.361626 -155.576016)
		(end 34.80689 -155.576016)
		(width 0.127)
		(layer "In5.Cu")
		(net "MEMDQ_1")
	)
	(segment
		(start 35.9156 -154.051)
		(end 34.714434 -154.051)
		(width 0.127)
		(layer "In5.Cu")
		(net "MEMDQ_1")
	)
	(segment
		(start 34.219134 -147.797266)
		(end 34.772854 -147.243546)
		(width 0.127)
		(layer "In5.Cu")
		(net "MEMDQ_1")
	)
	(segment
		(start 34.562034 -151.016462)
		(end 34.219134 -150.673562)
		(width 0.127)
		(layer "In5.Cu")
		(net "MEMDQ_1")
	)
	(segment
		(start 34.562034 -153.8986)
		(end 34.562034 -151.016462)
		(width 0.127)
		(layer "In5.Cu")
		(net "MEMDQ_1")
	)
	(segment
		(start 34.219134 -150.673562)
		(end 34.219134 -147.797266)
		(width 0.127)
		(layer "In5.Cu")
		(net "MEMDQ_1")
	)
	(segment
		(start 34.772854 -138.982196)
		(end 35.613086 -138.141964)
		(width 0.127)
		(layer "In5.Cu")
		(net "MEMDQ_1")
	)
	(segment
		(start 35.613086 -137.228326)
		(end 36.762944 -136.078468)
		(width 0.127)
		(layer "In5.Cu")
		(net "MEMDQ_1")
	)
	(segment
		(start 35.9156 -154.7368)
		(end 36.0426 -154.6098)
		(width 0.127)
		(layer "In5.Cu")
		(net "MEMDQ_1")
	)
	(segment
		(start 36.0426 -154.178)
		(end 35.9156 -154.051)
		(width 0.127)
		(layer "In5.Cu")
		(net "MEMDQ_1")
	)
	(segment
		(start 34.562034 -154.845766)
		(end 34.671 -154.7368)
		(width 0.127)
		(layer "In5.Cu")
		(net "MEMDQ_1")
	)
	(segment
		(start 34.714434 -154.051)
		(end 34.562034 -153.8986)
		(width 0.127)
		(layer "In5.Cu")
		(net "MEMDQ_1")
	)
	(segment
		(start 35.613086 -138.141964)
		(end 35.613086 -137.228326)
		(width 0.127)
		(layer "In5.Cu")
		(net "MEMDQ_1")
	)
	(segment
		(start 34.80689 -155.576016)
		(end 34.562034 -155.33116)
		(width 0.127)
		(layer "In5.Cu")
		(net "MEMDQ_1")
	)
	(segment
		(start 37.704776 -136.484868)
		(end 37.704776 -136.494266)
		(width 0.12065)
		(layer "F.Cu")
		(net "MEMDQ_0")
	)
	(segment
		(start 36.168076 -152.379934)
		(end 36.567872 -152.77973)
		(width 0.12065)
		(layer "F.Cu")
		(net "MEMDQ_0")
	)
	(segment
		(start 37.704776 -136.494266)
		(end 37.304726 -136.894316)
		(width 0.12065)
		(layer "F.Cu")
		(net "MEMDQ_0")
	)
	(via
		(at 36.567872 -152.77973)
		(size 0.4572)
		(drill 0.2032)
		(layers "F.Cu" "B.Cu")
		(net "MEMDQ_0")
	)
	(via
		(at 37.304726 -136.894316)
		(size 0.4572)
		(drill 0.2032)
		(layers "F.Cu" "B.Cu")
		(net "MEMDQ_0")
	)
	(segment
		(start 34.544 -148.265388)
		(end 34.544 -148.011388)
		(width 0.127)
		(layer "In5.Cu")
		(net "MEMDQ_0")
	)
	(segment
		(start 34.671 -147.884388)
		(end 35.026854 -147.884388)
		(width 0.127)
		(layer "In5.Cu")
		(net "MEMDQ_0")
	)
	(segment
		(start 36.068 -152.246838)
		(end 36.195 -152.119838)
		(width 0.127)
		(layer "In5.Cu")
		(net "MEMDQ_0")
	)
	(segment
		(start 35.814 -150.722838)
		(end 34.721038 -150.722838)
		(width 0.127)
		(layer "In5.Cu")
		(net "MEMDQ_0")
	)
	(segment
		(start 36.332922 -137.29208)
		(end 36.906962 -137.29208)
		(width 0.127)
		(layer "In5.Cu")
		(net "MEMDQ_0")
	)
	(segment
		(start 35.153854 -147.757388)
		(end 35.153854 -139.261596)
		(width 0.127)
		(layer "In5.Cu")
		(net "MEMDQ_0")
	)
	(segment
		(start 36.906962 -137.29208)
		(end 37.304726 -136.894316)
		(width 0.127)
		(layer "In5.Cu")
		(net "MEMDQ_0")
	)
	(segment
		(start 35.026854 -149.408388)
		(end 34.671 -149.408388)
		(width 0.127)
		(layer "In5.Cu")
		(net "MEMDQ_0")
	)
	(segment
		(start 35.153854 -149.535388)
		(end 35.026854 -149.408388)
		(width 0.127)
		(layer "In5.Cu")
		(net "MEMDQ_0")
	)
	(segment
		(start 36.068 -151.738838)
		(end 35.501072 -151.738838)
		(width 0.127)
		(layer "In5.Cu")
		(net "MEMDQ_0")
	)
	(segment
		(start 35.153854 -148.519388)
		(end 35.026854 -148.392388)
		(width 0.127)
		(layer "In5.Cu")
		(net "MEMDQ_0")
	)
	(segment
		(start 34.544 -150.5458)
		(end 34.544 -150.043388)
		(width 0.127)
		(layer "In5.Cu")
		(net "MEMDQ_0")
	)
	(segment
		(start 36.567872 -152.77973)
		(end 36.567872 -153.6192)
		(width 0.127)
		(layer "In5.Cu")
		(net "MEMDQ_0")
	)
	(segment
		(start 35.153854 -148.773388)
		(end 35.153854 -148.519388)
		(width 0.127)
		(layer "In5.Cu")
		(net "MEMDQ_0")
	)
	(segment
		(start 35.501072 -152.246838)
		(end 36.068 -152.246838)
		(width 0.127)
		(layer "In5.Cu")
		(net "MEMDQ_0")
	)
	(segment
		(start 35.026854 -147.884388)
		(end 35.153854 -147.757388)
		(width 0.127)
		(layer "In5.Cu")
		(net "MEMDQ_0")
	)
	(segment
		(start 36.088574 -137.536428)
		(end 36.332922 -137.29208)
		(width 0.127)
		(layer "In5.Cu")
		(net "MEMDQ_0")
	)
	(segment
		(start 36.195 -151.865838)
		(end 36.068 -151.738838)
		(width 0.127)
		(layer "In5.Cu")
		(net "MEMDQ_0")
	)
	(segment
		(start 34.544 -150.043388)
		(end 34.671 -149.916388)
		(width 0.127)
		(layer "In5.Cu")
		(net "MEMDQ_0")
	)
	(segment
		(start 35.941 -151.103838)
		(end 35.941 -150.849838)
		(width 0.127)
		(layer "In5.Cu")
		(net "MEMDQ_0")
	)
	(segment
		(start 34.671 -149.408388)
		(end 34.544 -149.281388)
		(width 0.127)
		(layer "In5.Cu")
		(net "MEMDQ_0")
	)
	(segment
		(start 35.501072 -151.738838)
		(end 35.374072 -151.611838)
		(width 0.127)
		(layer "In5.Cu")
		(net "MEMDQ_0")
	)
	(segment
		(start 34.671 -148.392388)
		(end 34.544 -148.265388)
		(width 0.127)
		(layer "In5.Cu")
		(net "MEMDQ_0")
	)
	(segment
		(start 35.501072 -153.7462)
		(end 35.374072 -153.6192)
		(width 0.127)
		(layer "In5.Cu")
		(net "MEMDQ_0")
	)
	(segment
		(start 35.374072 -151.357838)
		(end 35.501072 -151.230838)
		(width 0.127)
		(layer "In5.Cu")
		(net "MEMDQ_0")
	)
	(segment
		(start 34.721038 -150.722838)
		(end 34.544 -150.5458)
		(width 0.127)
		(layer "In5.Cu")
		(net "MEMDQ_0")
	)
	(segment
		(start 34.544 -149.027388)
		(end 34.671 -148.900388)
		(width 0.127)
		(layer "In5.Cu")
		(net "MEMDQ_0")
	)
	(segment
		(start 35.026854 -148.392388)
		(end 34.671 -148.392388)
		(width 0.127)
		(layer "In5.Cu")
		(net "MEMDQ_0")
	)
	(segment
		(start 36.195 -152.119838)
		(end 36.195 -151.865838)
		(width 0.127)
		(layer "In5.Cu")
		(net "MEMDQ_0")
	)
	(segment
		(start 34.671 -149.916388)
		(end 35.026854 -149.916388)
		(width 0.127)
		(layer "In5.Cu")
		(net "MEMDQ_0")
	)
	(segment
		(start 36.567872 -153.6192)
		(end 36.440872 -153.7462)
		(width 0.127)
		(layer "In5.Cu")
		(net "MEMDQ_0")
	)
	(segment
		(start 35.026854 -149.916388)
		(end 35.153854 -149.789388)
		(width 0.127)
		(layer "In5.Cu")
		(net "MEMDQ_0")
	)
	(segment
		(start 36.440872 -153.7462)
		(end 35.501072 -153.7462)
		(width 0.127)
		(layer "In5.Cu")
		(net "MEMDQ_0")
	)
	(segment
		(start 35.941 -150.849838)
		(end 35.814 -150.722838)
		(width 0.127)
		(layer "In5.Cu")
		(net "MEMDQ_0")
	)
	(segment
		(start 35.814 -151.230838)
		(end 35.941 -151.103838)
		(width 0.127)
		(layer "In5.Cu")
		(net "MEMDQ_0")
	)
	(segment
		(start 35.374072 -153.6192)
		(end 35.374072 -152.373838)
		(width 0.127)
		(layer "In5.Cu")
		(net "MEMDQ_0")
	)
	(segment
		(start 34.544 -148.011388)
		(end 34.671 -147.884388)
		(width 0.127)
		(layer "In5.Cu")
		(net "MEMDQ_0")
	)
	(segment
		(start 35.501072 -151.230838)
		(end 35.814 -151.230838)
		(width 0.127)
		(layer "In5.Cu")
		(net "MEMDQ_0")
	)
	(segment
		(start 35.153854 -139.261596)
		(end 36.088574 -138.326876)
		(width 0.127)
		(layer "In5.Cu")
		(net "MEMDQ_0")
	)
	(segment
		(start 36.088574 -138.326876)
		(end 36.088574 -137.536428)
		(width 0.127)
		(layer "In5.Cu")
		(net "MEMDQ_0")
	)
	(segment
		(start 34.544 -149.281388)
		(end 34.544 -149.027388)
		(width 0.127)
		(layer "In5.Cu")
		(net "MEMDQ_0")
	)
	(segment
		(start 35.153854 -149.789388)
		(end 35.153854 -149.535388)
		(width 0.127)
		(layer "In5.Cu")
		(net "MEMDQ_0")
	)
	(segment
		(start 34.671 -148.900388)
		(end 35.026854 -148.900388)
		(width 0.127)
		(layer "In5.Cu")
		(net "MEMDQ_0")
	)
	(segment
		(start 35.374072 -151.611838)
		(end 35.374072 -151.357838)
		(width 0.127)
		(layer "In5.Cu")
		(net "MEMDQ_0")
	)
	(segment
		(start 35.374072 -152.373838)
		(end 35.501072 -152.246838)
		(width 0.127)
		(layer "In5.Cu")
		(net "MEMDQ_0")
	)
	(segment
		(start 35.026854 -148.900388)
		(end 35.153854 -148.773388)
		(width 0.127)
		(layer "In5.Cu")
		(net "MEMDQ_0")
	)
	(segment
		(start 39.367968 -155.579826)
		(end 39.367968 -155.580334)
		(width 0.12065)
		(layer "F.Cu")
		(net "MEMDM_1")
	)
	(segment
		(start 39.367968 -155.580334)
		(end 39.767764 -155.98013)
		(width 0.12065)
		(layer "F.Cu")
		(net "MEMDM_1")
	)
	(segment
		(start 40.904922 -135.684768)
		(end 41.304718 -136.084564)
		(width 0.12065)
		(layer "F.Cu")
		(net "MEMDM_1")
	)
	(via
		(at 41.304718 -136.084564)
		(size 0.4572)
		(drill 0.2032)
		(layers "F.Cu" "B.Cu")
		(net "MEMDM_1")
	)
	(via
		(at 39.767764 -155.98013)
		(size 0.4572)
		(drill 0.2032)
		(layers "F.Cu" "B.Cu")
		(net "MEMDM_1")
	)
	(segment
		(start 42.07002 -156.37383)
		(end 44.90212 -153.54173)
		(width 0.127)
		(layer "In5.Cu")
		(net "MEMDM_1")
	)
	(segment
		(start 41.861486 -136.084564)
		(end 41.304718 -136.084564)
		(width 0.127)
		(layer "In5.Cu")
		(net "MEMDM_1")
	)
	(segment
		(start 42.498264 -137.035286)
		(end 42.498264 -136.721342)
		(width 0.127)
		(layer "In5.Cu")
		(net "MEMDM_1")
	)
	(segment
		(start 44.90212 -139.125198)
		(end 43.055286 -137.278364)
		(width 0.127)
		(layer "In5.Cu")
		(net "MEMDM_1")
	)
	(segment
		(start 40.161464 -156.37383)
		(end 42.07002 -156.37383)
		(width 0.127)
		(layer "In5.Cu")
		(net "MEMDM_1")
	)
	(segment
		(start 44.90212 -153.54173)
		(end 44.90212 -139.125198)
		(width 0.127)
		(layer "In5.Cu")
		(net "MEMDM_1")
	)
	(segment
		(start 42.498264 -136.721342)
		(end 41.861486 -136.084564)
		(width 0.127)
		(layer "In5.Cu")
		(net "MEMDM_1")
	)
	(segment
		(start 43.055286 -137.278364)
		(end 42.741342 -137.278364)
		(width 0.127)
		(layer "In5.Cu")
		(net "MEMDM_1")
	)
	(segment
		(start 42.741342 -137.278364)
		(end 42.498264 -137.035286)
		(width 0.127)
		(layer "In5.Cu")
		(net "MEMDM_1")
	)
	(segment
		(start 39.767764 -155.98013)
		(end 40.161464 -156.37383)
		(width 0.127)
		(layer "In5.Cu")
		(net "MEMDM_1")
	)
	(segment
		(start 38.887654 -151.980138)
		(end 38.168326 -151.980138)
		(width 0.12065)
		(layer "F.Cu")
		(net "MEMDM_0")
	)
	(segment
		(start 39.73957 -136.144)
		(end 39.73957 -136.829546)
		(width 0.12065)
		(layer "F.Cu")
		(net "MEMDM_0")
	)
	(segment
		(start 38.568122 -153.67)
		(end 38.695122 -153.797)
		(width 0.12065)
		(layer "F.Cu")
		(net "MEMDM_0")
	)
	(segment
		(start 39.304722 -136.144)
		(end 39.398702 -136.05002)
		(width 0.12065)
		(layer "F.Cu")
		(net "MEMDM_0")
	)
	(segment
		(start 39.002716 -152.0952)
		(end 38.887654 -151.980138)
		(width 0.12065)
		(layer "F.Cu")
		(net "MEMDM_0")
	)
	(segment
		(start 38.568122 -152.379934)
		(end 38.568122 -153.67)
		(width 0.12065)
		(layer "F.Cu")
		(net "MEMDM_0")
	)
	(segment
		(start 38.9128 -153.797)
		(end 39.002716 -153.707084)
		(width 0.12065)
		(layer "F.Cu")
		(net "MEMDM_0")
	)
	(segment
		(start 39.6494 -136.919716)
		(end 38.949122 -136.919716)
		(width 0.12065)
		(layer "F.Cu")
		(net "MEMDM_0")
	)
	(segment
		(start 39.398702 -136.05002)
		(end 39.64559 -136.05002)
		(width 0.12065)
		(layer "F.Cu")
		(net "MEMDM_0")
	)
	(segment
		(start 39.304722 -136.484868)
		(end 39.304722 -136.144)
		(width 0.12065)
		(layer "F.Cu")
		(net "MEMDM_0")
	)
	(segment
		(start 39.002716 -153.707084)
		(end 39.002716 -152.0952)
		(width 0.12065)
		(layer "F.Cu")
		(net "MEMDM_0")
	)
	(segment
		(start 39.73957 -136.829546)
		(end 39.6494 -136.919716)
		(width 0.12065)
		(layer "F.Cu")
		(net "MEMDM_0")
	)
	(segment
		(start 38.695122 -153.797)
		(end 38.9128 -153.797)
		(width 0.12065)
		(layer "F.Cu")
		(net "MEMDM_0")
	)
	(segment
		(start 39.64559 -136.05002)
		(end 39.73957 -136.144)
		(width 0.12065)
		(layer "F.Cu")
		(net "MEMDM_0")
	)
	(segment
		(start 38.949122 -136.919716)
		(end 38.909752 -136.880346)
		(width 0.12065)
		(layer "F.Cu")
		(net "MEMDM_0")
	)
	(via
		(at 38.168326 -151.980138)
		(size 0.4572)
		(drill 0.2032)
		(layers "F.Cu" "B.Cu")
		(net "MEMDM_0")
	)
	(via
		(at 38.909752 -136.880346)
		(size 0.4572)
		(drill 0.2032)
		(layers "F.Cu" "B.Cu")
		(net "MEMDM_0")
	)
	(segment
		(start 37.28085 -143.21536)
		(end 37.6428 -143.21536)
		(width 0.127)
		(layer "In5.Cu")
		(net "MEMDM_0")
	)
	(segment
		(start 37.15385 -148.477478)
		(end 37.15385 -148.248878)
		(width 0.127)
		(layer "In5.Cu")
		(net "MEMDM_0")
	)
	(segment
		(start 37.28085 -147.613878)
		(end 37.15385 -147.486878)
		(width 0.127)
		(layer "In5.Cu")
		(net "MEMDM_0")
	)
	(segment
		(start 38.211506 -141.77899)
		(end 38.211506 -140.18133)
		(width 0.127)
		(layer "In5.Cu")
		(net "MEMDM_0")
	)
	(segment
		(start 37.6428 -143.21536)
		(end 37.7698 -143.08836)
		(width 0.127)
		(layer "In5.Cu")
		(net "MEMDM_0")
	)
	(segment
		(start 37.81425 -142.19555)
		(end 37.81425 -142.176246)
		(width 0.127)
		(layer "In5.Cu")
		(net "MEMDM_0")
	)
	(segment
		(start 38.168326 -151.980138)
		(end 38.002972 -151.814784)
		(width 0.127)
		(layer "In5.Cu")
		(net "MEMDM_0")
	)
	(segment
		(start 37.15385 -148.248878)
		(end 37.28085 -148.121878)
		(width 0.127)
		(layer "In5.Cu")
		(net "MEMDM_0")
	)
	(segment
		(start 38.517576 -139.87526)
		(end 38.517576 -137.488676)
		(width 0.127)
		(layer "In5.Cu")
		(net "MEMDM_0")
	)
	(segment
		(start 37.15385 -143.34236)
		(end 37.28085 -143.21536)
		(width 0.127)
		(layer "In5.Cu")
		(net "MEMDM_0")
	)
	(segment
		(start 38.517576 -137.488676)
		(end 38.909752 -137.0965)
		(width 0.127)
		(layer "In5.Cu")
		(net "MEMDM_0")
	)
	(segment
		(start 37.81425 -142.176246)
		(end 38.211506 -141.77899)
		(width 0.127)
		(layer "In5.Cu")
		(net "MEMDM_0")
	)
	(segment
		(start 37.7698 -143.08836)
		(end 37.7698 -142.24)
		(width 0.127)
		(layer "In5.Cu")
		(net "MEMDM_0")
	)
	(segment
		(start 37.8206 -148.6408)
		(end 37.317172 -148.6408)
		(width 0.127)
		(layer "In5.Cu")
		(net "MEMDM_0")
	)
	(segment
		(start 37.7698 -142.24)
		(end 37.81425 -142.19555)
		(width 0.127)
		(layer "In5.Cu")
		(net "MEMDM_0")
	)
	(segment
		(start 38.62705 -147.613878)
		(end 37.28085 -147.613878)
		(width 0.127)
		(layer "In5.Cu")
		(net "MEMDM_0")
	)
	(segment
		(start 38.75405 -147.994878)
		(end 38.75405 -147.740878)
		(width 0.127)
		(layer "In5.Cu")
		(net "MEMDM_0")
	)
	(segment
		(start 37.317172 -148.6408)
		(end 37.15385 -148.477478)
		(width 0.127)
		(layer "In5.Cu")
		(net "MEMDM_0")
	)
	(segment
		(start 38.909752 -137.0965)
		(end 38.909752 -136.880346)
		(width 0.127)
		(layer "In5.Cu")
		(net "MEMDM_0")
	)
	(segment
		(start 38.75405 -147.740878)
		(end 38.62705 -147.613878)
		(width 0.127)
		(layer "In5.Cu")
		(net "MEMDM_0")
	)
	(segment
		(start 37.15385 -147.486878)
		(end 37.15385 -143.34236)
		(width 0.127)
		(layer "In5.Cu")
		(net "MEMDM_0")
	)
	(segment
		(start 37.28085 -148.121878)
		(end 38.62705 -148.121878)
		(width 0.127)
		(layer "In5.Cu")
		(net "MEMDM_0")
	)
	(segment
		(start 38.002972 -148.823172)
		(end 37.8206 -148.6408)
		(width 0.127)
		(layer "In5.Cu")
		(net "MEMDM_0")
	)
	(segment
		(start 38.211506 -140.18133)
		(end 38.517576 -139.87526)
		(width 0.127)
		(layer "In5.Cu")
		(net "MEMDM_0")
	)
	(segment
		(start 38.62705 -148.121878)
		(end 38.75405 -147.994878)
		(width 0.127)
		(layer "In5.Cu")
		(net "MEMDM_0")
	)
	(segment
		(start 38.002972 -151.814784)
		(end 38.002972 -148.823172)
		(width 0.127)
		(layer "In5.Cu")
		(net "MEMDM_0")
	)
	(segment
		(start 36.479226 -139.032234)
		(end 36.261294 -139.250166)
		(width 0.12065)
		(layer "F.Cu")
		(net "MEMCSN")
	)
	(segment
		(start 35.630104 -139.757658)
		(end 35.630104 -141.589506)
		(width 0.12065)
		(layer "F.Cu")
		(net "MEMCSN")
	)
	(segment
		(start 33.76803 -156.379926)
		(end 34.167826 -155.98013)
		(width 0.12065)
		(layer "F.Cu")
		(net "MEMCSN")
	)
	(segment
		(start 36.90493 -138.084814)
		(end 36.479226 -138.510518)
		(width 0.12065)
		(layer "F.Cu")
		(net "MEMCSN")
	)
	(segment
		(start 36.479226 -138.510518)
		(end 36.479226 -139.032234)
		(width 0.12065)
		(layer "F.Cu")
		(net "MEMCSN")
	)
	(segment
		(start 35.630104 -141.589506)
		(end 37.880798 -143.8402)
		(width 0.12065)
		(layer "F.Cu")
		(net "MEMCSN")
	)
	(segment
		(start 36.261294 -139.250166)
		(end 36.137596 -139.250166)
		(width 0.12065)
		(layer "F.Cu")
		(net "MEMCSN")
	)
	(segment
		(start 36.137596 -139.250166)
		(end 35.630104 -139.757658)
		(width 0.12065)
		(layer "F.Cu")
		(net "MEMCSN")
	)
	(segment
		(start 37.880798 -143.8402)
		(end 40.96512 -143.8402)
		(width 0.12065)
		(layer "F.Cu")
		(net "MEMCSN")
	)
	(via
		(at 40.96512 -143.8402)
		(size 0.4572)
		(drill 0.2032)
		(layers "F.Cu" "B.Cu")
		(net "MEMCSN")
	)
	(via
		(at 34.167826 -155.98013)
		(size 0.4572)
		(drill 0.2032)
		(layers "F.Cu" "B.Cu")
		(net "MEMCSN")
	)
	(segment
		(start 38.32733 -156.373576)
		(end 38.577266 -156.12364)
		(width 0.12065)
		(layer "B.Cu")
		(net "MEMCSN")
	)
	(segment
		(start 39.129716 -155.570682)
		(end 39.35857 -155.341828)
		(width 0.12065)
		(layer "B.Cu")
		(net "MEMCSN")
	)
	(segment
		(start 38.824916 -155.570682)
		(end 39.129716 -155.570682)
		(width 0.12065)
		(layer "B.Cu")
		(net "MEMCSN")
	)
	(segment
		(start 40.72255 -144.08277)
		(end 40.96512 -143.8402)
		(width 0.12065)
		(layer "B.Cu")
		(net "MEMCSN")
	)
	(segment
		(start 34.167826 -155.98013)
		(end 34.561272 -156.373576)
		(width 0.12065)
		(layer "B.Cu")
		(net "MEMCSN")
	)
	(segment
		(start 34.561272 -156.373576)
		(end 38.32733 -156.373576)
		(width 0.12065)
		(layer "B.Cu")
		(net "MEMCSN")
	)
	(segment
		(start 40.72255 -149.673056)
		(end 40.72255 -144.08277)
		(width 0.12065)
		(layer "B.Cu")
		(net "MEMCSN")
	)
	(segment
		(start 39.35857 -154.67203)
		(end 40.177212 -153.853388)
		(width 0.12065)
		(layer "B.Cu")
		(net "MEMCSN")
	)
	(segment
		(start 40.177212 -153.853388)
		(end 40.177212 -150.218394)
		(width 0.12065)
		(layer "B.Cu")
		(net "MEMCSN")
	)
	(segment
		(start 39.35857 -155.341828)
		(end 39.35857 -154.67203)
		(width 0.12065)
		(layer "B.Cu")
		(net "MEMCSN")
	)
	(segment
		(start 38.577266 -155.818332)
		(end 38.824916 -155.570682)
		(width 0.12065)
		(layer "B.Cu")
		(net "MEMCSN")
	)
	(segment
		(start 38.577266 -156.12364)
		(end 38.577266 -155.818332)
		(width 0.12065)
		(layer "B.Cu")
		(net "MEMCSN")
	)
	(segment
		(start 40.177212 -150.218394)
		(end 40.72255 -149.673056)
		(width 0.12065)
		(layer "B.Cu")
		(net "MEMCSN")
	)
	(segment
		(start 37.338 -139.010898)
		(end 36.385754 -139.963144)
		(width 0.12065)
		(layer "F.Cu")
		(net "MEMCKE")
	)
	(segment
		(start 34.743136 -148.0312)
		(end 34.295334 -148.0312)
		(width 0.12065)
		(layer "F.Cu")
		(net "MEMCKE")
	)
	(segment
		(start 37.704776 -137.284968)
		(end 37.704776 -137.297922)
		(width 0.12065)
		(layer "F.Cu")
		(net "MEMCKE")
	)
	(segment
		(start 37.704776 -137.297922)
		(end 37.338 -137.664698)
		(width 0.12065)
		(layer "F.Cu")
		(net "MEMCKE")
	)
	(segment
		(start 34.8742 -148.162264)
		(end 34.743136 -148.0312)
		(width 0.12065)
		(layer "F.Cu")
		(net "MEMCKE")
	)
	(segment
		(start 34.56813 -150.779988)
		(end 34.7472 -150.779988)
		(width 0.12065)
		(layer "F.Cu")
		(net "MEMCKE")
	)
	(segment
		(start 34.8742 -150.652988)
		(end 34.8742 -148.162264)
		(width 0.12065)
		(layer "F.Cu")
		(net "MEMCKE")
	)
	(segment
		(start 34.295334 -148.0312)
		(end 34.168334 -148.1582)
		(width 0.12065)
		(layer "F.Cu")
		(net "MEMCKE")
	)
	(segment
		(start 34.7472 -150.779988)
		(end 34.8742 -150.652988)
		(width 0.12065)
		(layer "F.Cu")
		(net "MEMCKE")
	)
	(segment
		(start 34.168334 -148.1582)
		(end 34.168334 -151.179784)
		(width 0.12065)
		(layer "F.Cu")
		(net "MEMCKE")
	)
	(segment
		(start 37.338 -137.664698)
		(end 37.338 -139.010898)
		(width 0.12065)
		(layer "F.Cu")
		(net "MEMCKE")
	)
	(segment
		(start 36.385754 -139.963144)
		(end 36.309554 -139.963144)
		(width 0.12065)
		(layer "F.Cu")
		(net "MEMCKE")
	)
	(via
		(at 36.309554 -139.963144)
		(size 0.4572)
		(drill 0.2032)
		(layers "F.Cu" "B.Cu")
		(net "MEMCKE")
	)
	(via
		(at 34.168334 -151.179784)
		(size 0.4572)
		(drill 0.2032)
		(layers "F.Cu" "B.Cu")
		(net "MEMCKE")
	)
	(segment
		(start 36.4109 -138.43)
		(end 36.2839 -138.557)
		(width 0.12065)
		(layer "B.Cu")
		(net "MEMCKE")
	)
	(segment
		(start 37.6936 -142.2654)
		(end 37.5666 -142.1384)
		(width 0.12065)
		(layer "B.Cu")
		(net "MEMCKE")
	)
	(segment
		(start 36.83635 -142.04315)
		(end 36.83635 -139.192)
		(width 0.12065)
		(layer "B.Cu")
		(net "MEMCKE")
	)
	(segment
		(start 37.214048 -138.534648)
		(end 37.1094 -138.43)
		(width 0.12065)
		(layer "B.Cu")
		(net "MEMCKE")
	)
	(segment
		(start 36.83635 -139.192)
		(end 37.214048 -138.814302)
		(width 0.12065)
		(layer "B.Cu")
		(net "MEMCKE")
	)
	(segment
		(start 36.2839 -139.93749)
		(end 36.309554 -139.963144)
		(width 0.12065)
		(layer "B.Cu")
		(net "MEMCKE")
	)
	(segment
		(start 37.5666 -142.1384)
		(end 36.9316 -142.1384)
		(width 0.12065)
		(layer "B.Cu")
		(net "MEMCKE")
	)
	(segment
		(start 34.168334 -151.179784)
		(end 35.010852 -150.337266)
		(width 0.12065)
		(layer "B.Cu")
		(net "MEMCKE")
	)
	(segment
		(start 36.2839 -138.557)
		(end 36.2839 -139.93749)
		(width 0.12065)
		(layer "B.Cu")
		(net "MEMCKE")
	)
	(segment
		(start 37.6936 -143.925798)
		(end 37.6936 -142.2654)
		(width 0.12065)
		(layer "B.Cu")
		(net "MEMCKE")
	)
	(segment
		(start 36.390072 -144.305528)
		(end 36.642802 -144.052798)
		(width 0.12065)
		(layer "B.Cu")
		(net "MEMCKE")
	)
	(segment
		(start 35.010852 -150.337266)
		(end 35.010852 -148.879306)
		(width 0.12065)
		(layer "B.Cu")
		(net "MEMCKE")
	)
	(segment
		(start 36.390072 -147.500086)
		(end 36.390072 -144.305528)
		(width 0.12065)
		(layer "B.Cu")
		(net "MEMCKE")
	)
	(segment
		(start 37.5666 -144.052798)
		(end 37.6936 -143.925798)
		(width 0.12065)
		(layer "B.Cu")
		(net "MEMCKE")
	)
	(segment
		(start 37.1094 -138.43)
		(end 36.4109 -138.43)
		(width 0.12065)
		(layer "B.Cu")
		(net "MEMCKE")
	)
	(segment
		(start 36.9316 -142.1384)
		(end 36.83635 -142.04315)
		(width 0.12065)
		(layer "B.Cu")
		(net "MEMCKE")
	)
	(segment
		(start 37.214048 -138.814302)
		(end 37.214048 -138.534648)
		(width 0.12065)
		(layer "B.Cu")
		(net "MEMCKE")
	)
	(segment
		(start 35.010852 -148.879306)
		(end 36.390072 -147.500086)
		(width 0.12065)
		(layer "B.Cu")
		(net "MEMCKE")
	)
	(segment
		(start 36.642802 -144.052798)
		(end 37.5666 -144.052798)
		(width 0.12065)
		(layer "B.Cu")
		(net "MEMCKE")
	)
	(segment
		(start 37.773102 -139.414504)
		(end 37.605462 -139.582144)
		(width 0.136652)
		(layer "F.Cu")
		(net "MEMCK_P")
	)
	(segment
		(start 35.367976 -152.379934)
		(end 35.367976 -152.917906)
		(width 0.136652)
		(layer "F.Cu")
		(net "MEMCK_P")
	)
	(segment
		(start 35.48507 -153.035)
		(end 35.650678 -153.035)
		(width 0.136652)
		(layer "F.Cu")
		(net "MEMCK_P")
	)
	(segment
		(start 35.367976 -152.917906)
		(end 35.48507 -153.035)
		(width 0.136652)
		(layer "F.Cu")
		(net "MEMCK_P")
	)
	(segment
		(start 37.773102 -138.95324)
		(end 37.773102 -139.414504)
		(width 0.136652)
		(layer "F.Cu")
		(net "MEMCK_P")
	)
	(segment
		(start 35.767772 -152.917906)
		(end 35.767772 -152.77973)
		(width 0.136652)
		(layer "F.Cu")
		(net "MEMCK_P")
	)
	(segment
		(start 37.605462 -139.582144)
		(end 37.452554 -139.582144)
		(width 0.136652)
		(layer "F.Cu")
		(net "MEMCK_P")
	)
	(segment
		(start 35.650678 -153.035)
		(end 35.767772 -152.917906)
		(width 0.136652)
		(layer "F.Cu")
		(net "MEMCK_P")
	)
	(segment
		(start 37.704776 -138.884914)
		(end 37.773102 -138.95324)
		(width 0.136652)
		(layer "F.Cu")
		(net "MEMCK_P")
	)
	(via
		(at 35.767772 -152.77973)
		(size 0.4572)
		(drill 0.2032)
		(layers "F.Cu" "B.Cu")
		(net "MEMCK_P")
	)
	(via
		(at 37.452554 -139.582144)
		(size 0.4572)
		(drill 0.2032)
		(layers "F.Cu" "B.Cu")
		(net "MEMCK_P")
	)
	(segment
		(start 36.169346 -149.225)
		(end 36.296346 -149.098)
		(width 0.136652)
		(layer "B.Cu")
		(net "MEMCK_P")
	)
	(segment
		(start 38.896798 -139.641326)
		(end 38.313614 -139.641326)
		(width 0.136652)
		(layer "B.Cu")
		(net "MEMCK_P")
	)
	(segment
		(start 38.3032 -150.418292)
		(end 38.3032 -149.479)
		(width 0.136652)
		(layer "B.Cu")
		(net "MEMCK_P")
	)
	(segment
		(start 37.830252 -146.026378)
		(end 37.6936 -145.889726)
		(width 0.136652)
		(layer "B.Cu")
		(net "MEMCK_P")
	)
	(segment
		(start 38.684962 -146.026378)
		(end 37.830252 -146.026378)
		(width 0.136652)
		(layer "B.Cu")
		(net "MEMCK_P")
	)
	(segment
		(start 37.271706 -150.7236)
		(end 37.997892 -150.7236)
		(width 0.136652)
		(layer "B.Cu")
		(net "MEMCK_P")
	)
	(segment
		(start 37.6936 -147.83943)
		(end 37.6936 -147.442682)
		(width 0.136652)
		(layer "B.Cu")
		(net "MEMCK_P")
	)
	(segment
		(start 38.093396 -139.861544)
		(end 37.731954 -139.861544)
		(width 0.136652)
		(layer "B.Cu")
		(net "MEMCK_P")
	)
	(segment
		(start 38.999922 -148.291042)
		(end 38.684962 -147.976082)
		(width 0.136652)
		(layer "B.Cu")
		(net "MEMCK_P")
	)
	(segment
		(start 38.999922 -145.041366)
		(end 38.999922 -142.971266)
		(width 0.136652)
		(layer "B.Cu")
		(net "MEMCK_P")
	)
	(segment
		(start 38.999922 -148.782278)
		(end 38.999922 -148.291042)
		(width 0.136652)
		(layer "B.Cu")
		(net "MEMCK_P")
	)
	(segment
		(start 35.366452 -152.237186)
		(end 36.169346 -151.434292)
		(width 0.136652)
		(layer "B.Cu")
		(net "MEMCK_P")
	)
	(segment
		(start 36.966398 -150.418292)
		(end 37.271706 -150.7236)
		(width 0.136652)
		(layer "B.Cu")
		(net "MEMCK_P")
	)
	(segment
		(start 37.6936 -145.889726)
		(end 37.6936 -145.492978)
		(width 0.136652)
		(layer "B.Cu")
		(net "MEMCK_P")
	)
	(segment
		(start 38.3032 -149.479)
		(end 38.999922 -148.782278)
		(width 0.136652)
		(layer "B.Cu")
		(net "MEMCK_P")
	)
	(segment
		(start 38.999922 -146.341338)
		(end 38.684962 -146.026378)
		(width 0.136652)
		(layer "B.Cu")
		(net "MEMCK_P")
	)
	(segment
		(start 38.313614 -139.641326)
		(end 38.093396 -139.861544)
		(width 0.136652)
		(layer "B.Cu")
		(net "MEMCK_P")
	)
	(segment
		(start 36.169346 -151.434292)
		(end 36.169346 -149.225)
		(width 0.136652)
		(layer "B.Cu")
		(net "MEMCK_P")
	)
	(segment
		(start 36.966398 -149.225)
		(end 36.966398 -150.418292)
		(width 0.136652)
		(layer "B.Cu")
		(net "MEMCK_P")
	)
	(segment
		(start 36.296346 -149.098)
		(end 36.839398 -149.098)
		(width 0.136652)
		(layer "B.Cu")
		(net "MEMCK_P")
	)
	(segment
		(start 35.366452 -152.654)
		(end 35.366452 -152.237186)
		(width 0.136652)
		(layer "B.Cu")
		(net "MEMCK_P")
	)
	(segment
		(start 35.767772 -152.77973)
		(end 35.492182 -152.77973)
		(width 0.136652)
		(layer "B.Cu")
		(net "MEMCK_P")
	)
	(segment
		(start 38.684962 -145.356326)
		(end 38.999922 -145.041366)
		(width 0.136652)
		(layer "B.Cu")
		(net "MEMCK_P")
	)
	(segment
		(start 38.999922 -142.971266)
		(end 39.42842 -142.542768)
		(width 0.136652)
		(layer "B.Cu")
		(net "MEMCK_P")
	)
	(segment
		(start 38.684962 -147.30603)
		(end 38.999922 -146.99107)
		(width 0.136652)
		(layer "B.Cu")
		(net "MEMCK_P")
	)
	(segment
		(start 37.997892 -150.7236)
		(end 38.3032 -150.418292)
		(width 0.136652)
		(layer "B.Cu")
		(net "MEMCK_P")
	)
	(segment
		(start 38.999922 -146.99107)
		(end 38.999922 -146.341338)
		(width 0.136652)
		(layer "B.Cu")
		(net "MEMCK_P")
	)
	(segment
		(start 37.830252 -145.356326)
		(end 38.684962 -145.356326)
		(width 0.136652)
		(layer "B.Cu")
		(net "MEMCK_P")
	)
	(segment
		(start 37.6936 -147.442682)
		(end 37.830252 -147.30603)
		(width 0.136652)
		(layer "B.Cu")
		(net "MEMCK_P")
	)
	(segment
		(start 37.731954 -139.861544)
		(end 37.452554 -139.582144)
		(width 0.136652)
		(layer "B.Cu")
		(net "MEMCK_P")
	)
	(segment
		(start 37.6936 -145.492978)
		(end 37.830252 -145.356326)
		(width 0.136652)
		(layer "B.Cu")
		(net "MEMCK_P")
	)
	(segment
		(start 39.42842 -140.172948)
		(end 38.896798 -139.641326)
		(width 0.136652)
		(layer "B.Cu")
		(net "MEMCK_P")
	)
	(segment
		(start 35.492182 -152.77973)
		(end 35.366452 -152.654)
		(width 0.136652)
		(layer "B.Cu")
		(net "MEMCK_P")
	)
	(segment
		(start 36.839398 -149.098)
		(end 36.966398 -149.225)
		(width 0.136652)
		(layer "B.Cu")
		(net "MEMCK_P")
	)
	(segment
		(start 37.830252 -147.30603)
		(end 38.684962 -147.30603)
		(width 0.136652)
		(layer "B.Cu")
		(net "MEMCK_P")
	)
	(segment
		(start 39.42842 -142.542768)
		(end 39.42842 -140.172948)
		(width 0.136652)
		(layer "B.Cu")
		(net "MEMCK_P")
	)
	(segment
		(start 37.830252 -147.976082)
		(end 37.6936 -147.83943)
		(width 0.136652)
		(layer "B.Cu")
		(net "MEMCK_P")
	)
	(segment
		(start 38.684962 -147.976082)
		(end 37.830252 -147.976082)
		(width 0.136652)
		(layer "B.Cu")
		(net "MEMCK_P")
	)
	(segment
		(start 38.077902 -138.45794)
		(end 38.077902 -139.540996)
		(width 0.136652)
		(layer "F.Cu")
		(net "MEMCK_N")
	)
	(segment
		(start 37.704776 -138.084814)
		(end 38.077902 -138.45794)
		(width 0.136652)
		(layer "F.Cu")
		(net "MEMCK_N")
	)
	(segment
		(start 34.56813 -152.379934)
		(end 34.967926 -152.77973)
		(width 0.136652)
		(layer "F.Cu")
		(net "MEMCK_N")
	)
	(segment
		(start 38.077902 -139.540996)
		(end 37.452554 -140.166344)
		(width 0.136652)
		(layer "F.Cu")
		(net "MEMCK_N")
	)
	(via
		(at 34.967926 -152.77973)
		(size 0.4572)
		(drill 0.2032)
		(layers "F.Cu" "B.Cu")
		(net "MEMCK_N")
	)
	(via
		(at 37.452554 -140.166344)
		(size 0.4572)
		(drill 0.2032)
		(layers "F.Cu" "B.Cu")
		(net "MEMCK_N")
	)
	(segment
		(start 38.695122 -142.844774)
		(end 39.12362 -142.416276)
		(width 0.136652)
		(layer "B.Cu")
		(net "MEMCK_N")
	)
	(segment
		(start 38.770306 -139.946126)
		(end 38.440106 -139.946126)
		(width 0.136652)
		(layer "B.Cu")
		(net "MEMCK_N")
	)
	(segment
		(start 38.55847 -148.280882)
		(end 37.70376 -148.280882)
		(width 0.136652)
		(layer "B.Cu")
		(net "MEMCK_N")
	)
	(segment
		(start 37.70376 -148.280882)
		(end 37.3888 -147.965922)
		(width 0.136652)
		(layer "B.Cu")
		(net "MEMCK_N")
	)
	(segment
		(start 35.864546 -151.3078)
		(end 35.864546 -149.098508)
		(width 0.136652)
		(layer "B.Cu")
		(net "MEMCK_N")
	)
	(segment
		(start 37.70376 -147.00123)
		(end 38.55847 -147.00123)
		(width 0.136652)
		(layer "B.Cu")
		(net "MEMCK_N")
	)
	(segment
		(start 37.3888 -145.366486)
		(end 37.70376 -145.051526)
		(width 0.136652)
		(layer "B.Cu")
		(net "MEMCK_N")
	)
	(segment
		(start 37.271198 -150.2918)
		(end 37.398198 -150.4188)
		(width 0.136652)
		(layer "B.Cu")
		(net "MEMCK_N")
	)
	(segment
		(start 37.9984 -150.2918)
		(end 37.9984 -149.352508)
		(width 0.136652)
		(layer "B.Cu")
		(net "MEMCK_N")
	)
	(segment
		(start 38.55847 -145.051526)
		(end 38.695122 -144.914874)
		(width 0.136652)
		(layer "B.Cu")
		(net "MEMCK_N")
	)
	(segment
		(start 35.864546 -149.098508)
		(end 36.169854 -148.7932)
		(width 0.136652)
		(layer "B.Cu")
		(net "MEMCK_N")
	)
	(segment
		(start 37.271198 -149.098508)
		(end 37.271198 -150.2918)
		(width 0.136652)
		(layer "B.Cu")
		(net "MEMCK_N")
	)
	(segment
		(start 36.96589 -148.7932)
		(end 37.271198 -149.098508)
		(width 0.136652)
		(layer "B.Cu")
		(net "MEMCK_N")
	)
	(segment
		(start 37.398198 -150.4188)
		(end 37.8714 -150.4188)
		(width 0.136652)
		(layer "B.Cu")
		(net "MEMCK_N")
	)
	(segment
		(start 39.12362 -140.29944)
		(end 38.770306 -139.946126)
		(width 0.136652)
		(layer "B.Cu")
		(net "MEMCK_N")
	)
	(segment
		(start 38.55847 -146.331178)
		(end 37.70376 -146.331178)
		(width 0.136652)
		(layer "B.Cu")
		(net "MEMCK_N")
	)
	(segment
		(start 38.219888 -140.166344)
		(end 37.452554 -140.166344)
		(width 0.136652)
		(layer "B.Cu")
		(net "MEMCK_N")
	)
	(segment
		(start 37.3888 -147.31619)
		(end 37.70376 -147.00123)
		(width 0.136652)
		(layer "B.Cu")
		(net "MEMCK_N")
	)
	(segment
		(start 38.55847 -147.00123)
		(end 38.695122 -146.864578)
		(width 0.136652)
		(layer "B.Cu")
		(net "MEMCK_N")
	)
	(segment
		(start 37.3888 -147.965922)
		(end 37.3888 -147.31619)
		(width 0.136652)
		(layer "B.Cu")
		(net "MEMCK_N")
	)
	(segment
		(start 39.12362 -142.416276)
		(end 39.12362 -140.29944)
		(width 0.136652)
		(layer "B.Cu")
		(net "MEMCK_N")
	)
	(segment
		(start 37.70376 -145.051526)
		(end 38.55847 -145.051526)
		(width 0.136652)
		(layer "B.Cu")
		(net "MEMCK_N")
	)
	(segment
		(start 37.3888 -146.016218)
		(end 37.3888 -145.366486)
		(width 0.136652)
		(layer "B.Cu")
		(net "MEMCK_N")
	)
	(segment
		(start 38.695122 -144.914874)
		(end 38.695122 -142.844774)
		(width 0.136652)
		(layer "B.Cu")
		(net "MEMCK_N")
	)
	(segment
		(start 38.695122 -148.417534)
		(end 38.55847 -148.280882)
		(width 0.136652)
		(layer "B.Cu")
		(net "MEMCK_N")
	)
	(segment
		(start 37.8714 -150.4188)
		(end 37.9984 -150.2918)
		(width 0.136652)
		(layer "B.Cu")
		(net "MEMCK_N")
	)
	(segment
		(start 36.169854 -148.7932)
		(end 36.96589 -148.7932)
		(width 0.136652)
		(layer "B.Cu")
		(net "MEMCK_N")
	)
	(segment
		(start 34.967926 -152.77973)
		(end 35.061652 -152.686004)
		(width 0.136652)
		(layer "B.Cu")
		(net "MEMCK_N")
	)
	(segment
		(start 35.061652 -152.686004)
		(end 35.061652 -152.110694)
		(width 0.136652)
		(layer "B.Cu")
		(net "MEMCK_N")
	)
	(segment
		(start 38.440106 -139.946126)
		(end 38.219888 -140.166344)
		(width 0.136652)
		(layer "B.Cu")
		(net "MEMCK_N")
	)
	(segment
		(start 38.695122 -146.46783)
		(end 38.55847 -146.331178)
		(width 0.136652)
		(layer "B.Cu")
		(net "MEMCK_N")
	)
	(segment
		(start 35.061652 -152.110694)
		(end 35.864546 -151.3078)
		(width 0.136652)
		(layer "B.Cu")
		(net "MEMCK_N")
	)
	(segment
		(start 38.695122 -148.655786)
		(end 38.695122 -148.417534)
		(width 0.136652)
		(layer "B.Cu")
		(net "MEMCK_N")
	)
	(segment
		(start 37.70376 -146.331178)
		(end 37.3888 -146.016218)
		(width 0.136652)
		(layer "B.Cu")
		(net "MEMCK_N")
	)
	(segment
		(start 37.9984 -149.352508)
		(end 38.695122 -148.655786)
		(width 0.136652)
		(layer "B.Cu")
		(net "MEMCK_N")
	)
	(segment
		(start 38.695122 -146.864578)
		(end 38.695122 -146.46783)
		(width 0.136652)
		(layer "B.Cu")
		(net "MEMCK_N")
	)
	(segment
		(start 36.90493 -138.920982)
		(end 36.353496 -139.472416)
		(width 0.12065)
		(layer "F.Cu")
		(net "MEMCASN")
	)
	(segment
		(start 35.871404 -141.318742)
		(end 37.808662 -143.256)
		(width 0.12065)
		(layer "F.Cu")
		(net "MEMCASN")
	)
	(segment
		(start 36.229798 -139.472416)
		(end 35.871404 -139.831064)
		(width 0.12065)
		(layer "F.Cu")
		(net "MEMCASN")
	)
	(segment
		(start 36.90493 -138.884914)
		(end 36.90493 -138.920982)
		(width 0.12065)
		(layer "F.Cu")
		(net "MEMCASN")
	)
	(segment
		(start 36.353496 -139.472416)
		(end 36.229798 -139.472416)
		(width 0.12065)
		(layer "F.Cu")
		(net "MEMCASN")
	)
	(segment
		(start 35.871404 -139.831064)
		(end 35.871404 -141.318742)
		(width 0.12065)
		(layer "F.Cu")
		(net "MEMCASN")
	)
	(segment
		(start 37.808662 -143.256)
		(end 40.96512 -143.256)
		(width 0.12065)
		(layer "F.Cu")
		(net "MEMCASN")
	)
	(segment
		(start 34.56813 -155.579826)
		(end 34.967926 -155.18003)
		(width 0.12065)
		(layer "F.Cu")
		(net "MEMCASN")
	)
	(via
		(at 34.967926 -155.18003)
		(size 0.4572)
		(drill 0.2032)
		(layers "F.Cu" "B.Cu")
		(net "MEMCASN")
	)
	(via
		(at 40.96512 -143.256)
		(size 0.4572)
		(drill 0.2032)
		(layers "F.Cu" "B.Cu")
		(net "MEMCASN")
	)
	(segment
		(start 38.329616 -155.570682)
		(end 38.577266 -155.323032)
		(width 0.12065)
		(layer "B.Cu")
		(net "MEMCASN")
	)
	(segment
		(start 39.878 -153.7208)
		(end 39.878 -149.86)
		(width 0.12065)
		(layer "B.Cu")
		(net "MEMCASN")
	)
	(segment
		(start 38.809422 -154.789378)
		(end 39.878 -153.7208)
		(width 0.12065)
		(layer "B.Cu")
		(net "MEMCASN")
	)
	(segment
		(start 38.577266 -155.323032)
		(end 38.577266 -155.018232)
		(width 0.12065)
		(layer "B.Cu")
		(net "MEMCASN")
	)
	(segment
		(start 40.3606 -143.5354)
		(end 40.64 -143.256)
		(width 0.12065)
		(layer "B.Cu")
		(net "MEMCASN")
	)
	(segment
		(start 35.358578 -155.570682)
		(end 38.329616 -155.570682)
		(width 0.12065)
		(layer "B.Cu")
		(net "MEMCASN")
	)
	(segment
		(start 39.878 -149.86)
		(end 40.3606 -149.3774)
		(width 0.12065)
		(layer "B.Cu")
		(net "MEMCASN")
	)
	(segment
		(start 40.3606 -149.3774)
		(end 40.3606 -143.5354)
		(width 0.12065)
		(layer "B.Cu")
		(net "MEMCASN")
	)
	(segment
		(start 34.967926 -155.18003)
		(end 35.358578 -155.570682)
		(width 0.12065)
		(layer "B.Cu")
		(net "MEMCASN")
	)
	(segment
		(start 40.64 -143.256)
		(end 40.96512 -143.256)
		(width 0.12065)
		(layer "B.Cu")
		(net "MEMCASN")
	)
	(segment
		(start 38.80612 -154.789378)
		(end 38.809422 -154.789378)
		(width 0.12065)
		(layer "B.Cu")
		(net "MEMCASN")
	)
	(segment
		(start 38.577266 -155.018232)
		(end 38.80612 -154.789378)
		(width 0.12065)
		(layer "B.Cu")
		(net "MEMCASN")
	)
	(segment
		(start 32.568134 -152.931368)
		(end 32.568134 -155.18003)
		(width 0.12065)
		(layer "F.Cu")
		(net "MEMBA_2")
	)
	(segment
		(start 36.10483 -137.284968)
		(end 35.705034 -136.885172)
		(width 0.12065)
		(layer "F.Cu")
		(net "MEMBA_2")
	)
	(segment
		(start 32.977074 -155.570682)
		(end 32.977074 -155.018232)
		(width 0.12065)
		(layer "F.Cu")
		(net "MEMBA_2")
	)
	(segment
		(start 32.977074 -155.018232)
		(end 32.9946 -155.000706)
		(width 0.12065)
		(layer "F.Cu")
		(net "MEMBA_2")
	)
	(segment
		(start 32.96793 -155.579826)
		(end 32.977074 -155.570682)
		(width 0.12065)
		(layer "F.Cu")
		(net "MEMBA_2")
	)
	(segment
		(start 32.9946 -152.931368)
		(end 32.869632 -152.8064)
		(width 0.12065)
		(layer "F.Cu")
		(net "MEMBA_2")
	)
	(segment
		(start 35.705034 -136.885172)
		(end 34.904934 -136.885172)
		(width 0.12065)
		(layer "F.Cu")
		(net "MEMBA_2")
	)
	(segment
		(start 32.693102 -152.8064)
		(end 32.568134 -152.931368)
		(width 0.12065)
		(layer "F.Cu")
		(net "MEMBA_2")
	)
	(segment
		(start 32.9946 -155.000706)
		(end 32.9946 -152.931368)
		(width 0.12065)
		(layer "F.Cu")
		(net "MEMBA_2")
	)
	(segment
		(start 32.869632 -152.8064)
		(end 32.693102 -152.8064)
		(width 0.12065)
		(layer "F.Cu")
		(net "MEMBA_2")
	)
	(via
		(at 34.904934 -136.885172)
		(size 0.4572)
		(drill 0.2032)
		(layers "F.Cu" "B.Cu")
		(net "MEMBA_2")
	)
	(via
		(at 32.568134 -155.18003)
		(size 0.4572)
		(drill 0.2032)
		(layers "F.Cu" "B.Cu")
		(net "MEMBA_2")
	)
	(segment
		(start 32.977328 -154.449272)
		(end 32.977328 -152.618186)
		(width 0.12065)
		(layer "B.Cu")
		(net "MEMBA_2")
	)
	(segment
		(start 34.514282 -137.8966)
		(end 34.514282 -137.275824)
		(width 0.12065)
		(layer "B.Cu")
		(net "MEMBA_2")
	)
	(segment
		(start 33.925002 -148.428964)
		(end 34.98088 -147.373086)
		(width 0.12065)
		(layer "B.Cu")
		(net "MEMBA_2")
	)
	(segment
		(start 34.98088 -147.373086)
		(end 34.98088 -138.363198)
		(width 0.12065)
		(layer "B.Cu")
		(net "MEMBA_2")
	)
	(segment
		(start 33.925002 -149.575266)
		(end 33.925002 -148.428964)
		(width 0.12065)
		(layer "B.Cu")
		(net "MEMBA_2")
	)
	(segment
		(start 33.1724 -150.327868)
		(end 33.925002 -149.575266)
		(width 0.12065)
		(layer "B.Cu")
		(net "MEMBA_2")
	)
	(segment
		(start 32.568134 -154.858466)
		(end 32.977328 -154.449272)
		(width 0.12065)
		(layer "B.Cu")
		(net "MEMBA_2")
	)
	(segment
		(start 32.977328 -152.618186)
		(end 33.1724 -152.423114)
		(width 0.12065)
		(layer "B.Cu")
		(net "MEMBA_2")
	)
	(segment
		(start 34.98088 -138.363198)
		(end 34.514282 -137.8966)
		(width 0.12065)
		(layer "B.Cu")
		(net "MEMBA_2")
	)
	(segment
		(start 34.514282 -137.275824)
		(end 34.904934 -136.885172)
		(width 0.12065)
		(layer "B.Cu")
		(net "MEMBA_2")
	)
	(segment
		(start 33.1724 -152.423114)
		(end 33.1724 -150.327868)
		(width 0.12065)
		(layer "B.Cu")
		(net "MEMBA_2")
	)
	(segment
		(start 32.568134 -155.18003)
		(end 32.568134 -154.858466)
		(width 0.12065)
		(layer "B.Cu")
		(net "MEMBA_2")
	)
	(segment
		(start 31.581598 -144.941798)
		(end 31.126938 -144.487138)
		(width 0.12065)
		(layer "F.Cu")
		(net "MEMBA_1")
	)
	(segment
		(start 30.761686 -149.227286)
		(end 30.761686 -148.8694)
		(width 0.12065)
		(layer "F.Cu")
		(net "MEMBA_1")
	)
	(segment
		(start 31.802832 -151.214582)
		(end 31.802832 -150.662386)
		(width 0.12065)
		(layer "F.Cu")
		(net "MEMBA_1")
	)
	(segment
		(start 30.1752 -148.7424)
		(end 30.0482 -148.8694)
		(width 0.12065)
		(layer "F.Cu")
		(net "MEMBA_1")
	)
	(segment
		(start 30.0482 -148.8694)
		(end 30.0482 -149.67585)
		(width 0.12065)
		(layer "F.Cu")
		(net "MEMBA_1")
	)
	(segment
		(start 30.761686 -148.8694)
		(end 30.634686 -148.7424)
		(width 0.12065)
		(layer "F.Cu")
		(net "MEMBA_1")
	)
	(segment
		(start 30.634686 -148.7424)
		(end 30.1752 -148.7424)
		(width 0.12065)
		(layer "F.Cu")
		(net "MEMBA_1")
	)
	(segment
		(start 31.126938 -144.487138)
		(end 31.126938 -144.177512)
		(width 0.12065)
		(layer "F.Cu")
		(net "MEMBA_1")
	)
	(segment
		(start 30.577536 -149.41169)
		(end 30.761686 -149.227286)
		(width 0.12065)
		(layer "F.Cu")
		(net "MEMBA_1")
	)
	(segment
		(start 31.129986 -149.98954)
		(end 30.83179 -149.98954)
		(width 0.12065)
		(layer "F.Cu")
		(net "MEMBA_1")
	)
	(segment
		(start 35.052 -142.122652)
		(end 37.515292 -144.585944)
		(width 0.12065)
		(layer "F.Cu")
		(net "MEMBA_1")
	)
	(segment
		(start 31.802832 -150.662386)
		(end 31.129986 -149.98954)
		(width 0.12065)
		(layer "F.Cu")
		(net "MEMBA_1")
	)
	(segment
		(start 30.83179 -149.98954)
		(end 30.577536 -149.735286)
		(width 0.12065)
		(layer "F.Cu")
		(net "MEMBA_1")
	)
	(segment
		(start 30.0482 -149.67585)
		(end 30.168342 -149.795992)
		(width 0.12065)
		(layer "F.Cu")
		(net "MEMBA_1")
	)
	(segment
		(start 36.10483 -138.084814)
		(end 35.7378 -138.451844)
		(width 0.12065)
		(layer "F.Cu")
		(net "MEMBA_1")
	)
	(segment
		(start 37.515292 -144.585944)
		(end 37.515292 -144.815306)
		(width 0.12065)
		(layer "F.Cu")
		(net "MEMBA_1")
	)
	(segment
		(start 37.3888 -144.941798)
		(end 31.581598 -144.941798)
		(width 0.12065)
		(layer "F.Cu")
		(net "MEMBA_1")
	)
	(segment
		(start 35.052 -139.671552)
		(end 35.052 -142.122652)
		(width 0.12065)
		(layer "F.Cu")
		(net "MEMBA_1")
	)
	(segment
		(start 35.7378 -138.985752)
		(end 35.052 -139.671552)
		(width 0.12065)
		(layer "F.Cu")
		(net "MEMBA_1")
	)
	(segment
		(start 30.577536 -149.735286)
		(end 30.577536 -149.41169)
		(width 0.12065)
		(layer "F.Cu")
		(net "MEMBA_1")
	)
	(segment
		(start 32.168084 -151.579834)
		(end 31.802832 -151.214582)
		(width 0.12065)
		(layer "F.Cu")
		(net "MEMBA_1")
	)
	(segment
		(start 37.515292 -144.815306)
		(end 37.3888 -144.941798)
		(width 0.12065)
		(layer "F.Cu")
		(net "MEMBA_1")
	)
	(segment
		(start 35.7378 -138.451844)
		(end 35.7378 -138.985752)
		(width 0.12065)
		(layer "F.Cu")
		(net "MEMBA_1")
	)
	(via
		(at 31.126938 -144.177512)
		(size 0.4572)
		(drill 0.2032)
		(layers "F.Cu" "B.Cu")
		(net "MEMBA_1")
	)
	(via
		(at 30.168342 -149.795992)
		(size 0.4572)
		(drill 0.2032)
		(layers "F.Cu" "B.Cu")
		(net "MEMBA_1")
	)
	(segment
		(start 31.098236 -144.576038)
		(end 31.098236 -144.206214)
		(width 0.12065)
		(layer "B.Cu")
		(net "MEMBA_1")
	)
	(segment
		(start 31.098236 -144.206214)
		(end 31.126938 -144.177512)
		(width 0.12065)
		(layer "B.Cu")
		(net "MEMBA_1")
	)
	(segment
		(start 30.168342 -149.795992)
		(end 29.895546 -149.523196)
		(width 0.12065)
		(layer "B.Cu")
		(net "MEMBA_1")
	)
	(segment
		(start 29.895546 -149.523196)
		(end 29.895546 -145.778728)
		(width 0.12065)
		(layer "B.Cu")
		(net "MEMBA_1")
	)
	(segment
		(start 29.895546 -145.778728)
		(end 31.098236 -144.576038)
		(width 0.12065)
		(layer "B.Cu")
		(net "MEMBA_1")
	)
	(segment
		(start 36.10483 -136.484868)
		(end 35.70478 -136.084818)
		(width 0.12065)
		(layer "F.Cu")
		(net "MEMBA_0")
	)
	(segment
		(start 32.96793 -156.379926)
		(end 33.367726 -155.98013)
		(width 0.12065)
		(layer "F.Cu")
		(net "MEMBA_0")
	)
	(via
		(at 33.367726 -155.98013)
		(size 0.4572)
		(drill 0.2032)
		(layers "F.Cu" "B.Cu")
		(net "MEMBA_0")
	)
	(via
		(at 35.70478 -136.084818)
		(size 0.4572)
		(drill 0.2032)
		(layers "F.Cu" "B.Cu")
		(net "MEMBA_0")
	)
	(segment
		(start 34.648902 -148.729192)
		(end 35.70478 -147.673314)
		(width 0.12065)
		(layer "B.Cu")
		(net "MEMBA_0")
	)
	(segment
		(start 35.82543 -141.723872)
		(end 35.70478 -141.603222)
		(width 0.12065)
		(layer "B.Cu")
		(net "MEMBA_0")
	)
	(segment
		(start 36.40455 -141.723872)
		(end 35.82543 -141.723872)
		(width 0.12065)
		(layer "B.Cu")
		(net "MEMBA_0")
	)
	(segment
		(start 36.5252 -141.844522)
		(end 36.40455 -141.723872)
		(width 0.12065)
		(layer "B.Cu")
		(net "MEMBA_0")
	)
	(segment
		(start 34.648902 -149.832314)
		(end 34.648902 -148.729192)
		(width 0.12065)
		(layer "B.Cu")
		(net "MEMBA_0")
	)
	(segment
		(start 37.1856 -143.044672)
		(end 37.1856 -142.816072)
		(width 0.12065)
		(layer "B.Cu")
		(net "MEMBA_0")
	)
	(segment
		(start 35.70478 -147.673314)
		(end 35.70478 -143.292322)
		(width 0.12065)
		(layer "B.Cu")
		(net "MEMBA_0")
	)
	(segment
		(start 33.777682 -154.217624)
		(end 33.777682 -150.703534)
		(width 0.12065)
		(layer "B.Cu")
		(net "MEMBA_0")
	)
	(segment
		(start 35.70478 -143.292322)
		(end 35.82543 -143.171672)
		(width 0.12065)
		(layer "B.Cu")
		(net "MEMBA_0")
	)
	(segment
		(start 33.777682 -150.703534)
		(end 34.648902 -149.832314)
		(width 0.12065)
		(layer "B.Cu")
		(net "MEMBA_0")
	)
	(segment
		(start 35.70478 -142.327122)
		(end 35.82543 -142.206472)
		(width 0.12065)
		(layer "B.Cu")
		(net "MEMBA_0")
	)
	(segment
		(start 36.40455 -142.206472)
		(end 36.5252 -142.085822)
		(width 0.12065)
		(layer "B.Cu")
		(net "MEMBA_0")
	)
	(segment
		(start 32.958786 -155.03652)
		(end 33.777682 -154.217624)
		(width 0.12065)
		(layer "B.Cu")
		(net "MEMBA_0")
	)
	(segment
		(start 37.0586 -142.689072)
		(end 35.82543 -142.689072)
		(width 0.12065)
		(layer "B.Cu")
		(net "MEMBA_0")
	)
	(segment
		(start 35.70478 -142.568422)
		(end 35.70478 -142.327122)
		(width 0.12065)
		(layer "B.Cu")
		(net "MEMBA_0")
	)
	(segment
		(start 37.0586 -143.171672)
		(end 37.1856 -143.044672)
		(width 0.12065)
		(layer "B.Cu")
		(net "MEMBA_0")
	)
	(segment
		(start 35.70478 -141.603222)
		(end 35.70478 -136.084818)
		(width 0.12065)
		(layer "B.Cu")
		(net "MEMBA_0")
	)
	(segment
		(start 37.1856 -142.816072)
		(end 37.0586 -142.689072)
		(width 0.12065)
		(layer "B.Cu")
		(net "MEMBA_0")
	)
	(segment
		(start 35.82543 -142.206472)
		(end 36.40455 -142.206472)
		(width 0.12065)
		(layer "B.Cu")
		(net "MEMBA_0")
	)
	(segment
		(start 35.82543 -142.689072)
		(end 35.70478 -142.568422)
		(width 0.12065)
		(layer "B.Cu")
		(net "MEMBA_0")
	)
	(segment
		(start 33.367726 -155.98013)
		(end 32.958786 -155.57119)
		(width 0.12065)
		(layer "B.Cu")
		(net "MEMBA_0")
	)
	(segment
		(start 35.82543 -143.171672)
		(end 37.0586 -143.171672)
		(width 0.12065)
		(layer "B.Cu")
		(net "MEMBA_0")
	)
	(segment
		(start 36.5252 -142.085822)
		(end 36.5252 -141.844522)
		(width 0.12065)
		(layer "B.Cu")
		(net "MEMBA_0")
	)
	(segment
		(start 32.958786 -155.57119)
		(end 32.958786 -155.03652)
		(width 0.12065)
		(layer "B.Cu")
		(net "MEMBA_0")
	)
	(segment
		(start 33.0454 -140.823696)
		(end 32.9184 -140.950696)
		(width 0.12065)
		(layer "F.Cu")
		(net "MEMA_9")
	)
	(segment
		(start 33.274 -139.664694)
		(end 33.0454 -139.893294)
		(width 0.12065)
		(layer "F.Cu")
		(net "MEMA_9")
	)
	(segment
		(start 33.704784 -138.184128)
		(end 33.274 -138.614912)
		(width 0.12065)
		(layer "F.Cu")
		(net "MEMA_9")
	)
	(segment
		(start 33.0454 -139.893294)
		(end 33.0454 -140.823696)
		(width 0.12065)
		(layer "F.Cu")
		(net "MEMA_9")
	)
	(segment
		(start 33.274 -138.614912)
		(end 33.274 -139.664694)
		(width 0.12065)
		(layer "F.Cu")
		(net "MEMA_9")
	)
	(segment
		(start 30.568138 -155.579826)
		(end 30.168342 -155.18003)
		(width 0.12065)
		(layer "F.Cu")
		(net "MEMA_9")
	)
	(segment
		(start 33.704784 -138.084814)
		(end 33.704784 -138.184128)
		(width 0.12065)
		(layer "F.Cu")
		(net "MEMA_9")
	)
	(segment
		(start 32.9184 -140.950696)
		(end 31.126938 -140.950696)
		(width 0.12065)
		(layer "F.Cu")
		(net "MEMA_9")
	)
	(via
		(at 31.126938 -140.950696)
		(size 0.4572)
		(drill 0.2032)
		(layers "F.Cu" "B.Cu")
		(net "MEMA_9")
	)
	(via
		(at 30.168342 -155.18003)
		(size 0.4572)
		(drill 0.2032)
		(layers "F.Cu" "B.Cu")
		(net "MEMA_9")
	)
	(segment
		(start 29.332428 -141.2748)
		(end 29.332428 -141.071346)
		(width 0.12065)
		(layer "B.Cu")
		(net "MEMA_9")
	)
	(segment
		(start 30.297628 -141.2748)
		(end 30.297628 -141.071346)
		(width 0.12065)
		(layer "B.Cu")
		(net "MEMA_9")
	)
	(segment
		(start 29.815028 -141.071346)
		(end 29.815028 -141.2748)
		(width 0.12065)
		(layer "B.Cu")
		(net "MEMA_9")
	)
	(segment
		(start 28.857956 -153.8478)
		(end 28.857956 -153.20391)
		(width 0.12065)
		(layer "B.Cu")
		(net "MEMA_9")
	)
	(segment
		(start 29.332428 -141.071346)
		(end 29.453078 -140.950696)
		(width 0.12065)
		(layer "B.Cu")
		(net "MEMA_9")
	)
	(segment
		(start 30.168342 -155.18003)
		(end 29.718 -155.18003)
		(width 0.12065)
		(layer "B.Cu")
		(net "MEMA_9")
	)
	(segment
		(start 30.297628 -141.071346)
		(end 30.418278 -140.950696)
		(width 0.12065)
		(layer "B.Cu")
		(net "MEMA_9")
	)
	(segment
		(start 30.418278 -140.950696)
		(end 31.126938 -140.950696)
		(width 0.12065)
		(layer "B.Cu")
		(net "MEMA_9")
	)
	(segment
		(start 29.205428 -141.4018)
		(end 29.332428 -141.2748)
		(width 0.12065)
		(layer "B.Cu")
		(net "MEMA_9")
	)
	(segment
		(start 29.942028 -141.4018)
		(end 30.170628 -141.4018)
		(width 0.12065)
		(layer "B.Cu")
		(net "MEMA_9")
	)
	(segment
		(start 30.48 -153.9748)
		(end 28.984956 -153.9748)
		(width 0.12065)
		(layer "B.Cu")
		(net "MEMA_9")
	)
	(segment
		(start 30.48 -154.559)
		(end 30.607 -154.432)
		(width 0.12065)
		(layer "B.Cu")
		(net "MEMA_9")
	)
	(segment
		(start 28.984956 -153.9748)
		(end 28.857956 -153.8478)
		(width 0.12065)
		(layer "B.Cu")
		(net "MEMA_9")
	)
	(segment
		(start 29.453078 -140.950696)
		(end 29.694378 -140.950696)
		(width 0.12065)
		(layer "B.Cu")
		(net "MEMA_9")
	)
	(segment
		(start 30.607 -154.432)
		(end 30.607 -154.1018)
		(width 0.12065)
		(layer "B.Cu")
		(net "MEMA_9")
	)
	(segment
		(start 29.591 -154.686)
		(end 29.718 -154.559)
		(width 0.12065)
		(layer "B.Cu")
		(net "MEMA_9")
	)
	(segment
		(start 29.815028 -141.2748)
		(end 29.942028 -141.4018)
		(width 0.12065)
		(layer "B.Cu")
		(net "MEMA_9")
	)
	(segment
		(start 29.694378 -140.950696)
		(end 29.815028 -141.071346)
		(width 0.12065)
		(layer "B.Cu")
		(net "MEMA_9")
	)
	(segment
		(start 30.170628 -141.4018)
		(end 30.297628 -141.2748)
		(width 0.12065)
		(layer "B.Cu")
		(net "MEMA_9")
	)
	(segment
		(start 29.718 -154.559)
		(end 30.48 -154.559)
		(width 0.12065)
		(layer "B.Cu")
		(net "MEMA_9")
	)
	(segment
		(start 27.723846 -141.87805)
		(end 28.200096 -141.4018)
		(width 0.12065)
		(layer "B.Cu")
		(net "MEMA_9")
	)
	(segment
		(start 27.723846 -152.0698)
		(end 27.723846 -141.87805)
		(width 0.12065)
		(layer "B.Cu")
		(net "MEMA_9")
	)
	(segment
		(start 28.200096 -141.4018)
		(end 29.205428 -141.4018)
		(width 0.12065)
		(layer "B.Cu")
		(net "MEMA_9")
	)
	(segment
		(start 29.591 -155.05303)
		(end 29.591 -154.686)
		(width 0.12065)
		(layer "B.Cu")
		(net "MEMA_9")
	)
	(segment
		(start 28.857956 -153.20391)
		(end 27.723846 -152.0698)
		(width 0.12065)
		(layer "B.Cu")
		(net "MEMA_9")
	)
	(segment
		(start 30.607 -154.1018)
		(end 30.48 -153.9748)
		(width 0.12065)
		(layer "B.Cu")
		(net "MEMA_9")
	)
	(segment
		(start 29.718 -155.18003)
		(end 29.591 -155.05303)
		(width 0.12065)
		(layer "B.Cu")
		(net "MEMA_9")
	)
	(segment
		(start 29.768038 -151.579834)
		(end 29.768038 -151.29637)
		(width 0.12065)
		(layer "F.Cu")
		(net "MEMA_8")
	)
	(segment
		(start 34.8234 -143.728948)
		(end 34.6964 -143.855948)
		(width 0.12065)
		(layer "F.Cu")
		(net "MEMA_8")
	)
	(segment
		(start 29.32049 -150.848822)
		(end 29.32049 -149.1234)
		(width 0.12065)
		(layer "F.Cu")
		(net "MEMA_8")
	)
	(segment
		(start 29.32049 -149.1234)
		(end 29.19349 -148.9964)
		(width 0.12065)
		(layer "F.Cu")
		(net "MEMA_8")
	)
	(segment
		(start 32.49295 -143.170656)
		(end 31.886398 -142.564104)
		(width 0.12065)
		(layer "F.Cu")
		(net "MEMA_8")
	)
	(segment
		(start 33.965896 -140.221208)
		(end 33.965896 -142.57274)
		(width 0.12065)
		(layer "F.Cu")
		(net "MEMA_8")
	)
	(segment
		(start 32.49295 -143.532098)
		(end 32.49295 -143.170656)
		(width 0.12065)
		(layer "F.Cu")
		(net "MEMA_8")
	)
	(segment
		(start 28.9306 -148.9964)
		(end 28.8036 -149.1234)
		(width 0.12065)
		(layer "F.Cu")
		(net "MEMA_8")
	)
	(segment
		(start 31.886398 -142.564104)
		(end 31.126938 -142.564104)
		(width 0.12065)
		(layer "F.Cu")
		(net "MEMA_8")
	)
	(segment
		(start 34.504884 -139.012422)
		(end 33.97885 -139.538456)
		(width 0.12065)
		(layer "F.Cu")
		(net "MEMA_8")
	)
	(segment
		(start 33.97885 -140.208254)
		(end 33.965896 -140.221208)
		(width 0.12065)
		(layer "F.Cu")
		(net "MEMA_8")
	)
	(segment
		(start 33.965896 -142.57274)
		(end 34.8234 -143.430244)
		(width 0.12065)
		(layer "F.Cu")
		(net "MEMA_8")
	)
	(segment
		(start 29.19349 -148.9964)
		(end 28.9306 -148.9964)
		(width 0.12065)
		(layer "F.Cu")
		(net "MEMA_8")
	)
	(segment
		(start 28.8036 -149.1234)
		(end 28.8036 -151.414988)
		(width 0.12065)
		(layer "F.Cu")
		(net "MEMA_8")
	)
	(segment
		(start 29.768038 -151.29637)
		(end 29.32049 -150.848822)
		(width 0.12065)
		(layer "F.Cu")
		(net "MEMA_8")
	)
	(segment
		(start 28.8036 -151.414988)
		(end 29.368242 -151.97963)
		(width 0.12065)
		(layer "F.Cu")
		(net "MEMA_8")
	)
	(segment
		(start 34.8234 -143.430244)
		(end 34.8234 -143.728948)
		(width 0.12065)
		(layer "F.Cu")
		(net "MEMA_8")
	)
	(segment
		(start 34.504884 -138.884914)
		(end 34.504884 -139.012422)
		(width 0.12065)
		(layer "F.Cu")
		(net "MEMA_8")
	)
	(segment
		(start 32.8168 -143.855948)
		(end 32.49295 -143.532098)
		(width 0.12065)
		(layer "F.Cu")
		(net "MEMA_8")
	)
	(segment
		(start 33.97885 -139.538456)
		(end 33.97885 -140.208254)
		(width 0.12065)
		(layer "F.Cu")
		(net "MEMA_8")
	)
	(segment
		(start 34.6964 -143.855948)
		(end 32.8168 -143.855948)
		(width 0.12065)
		(layer "F.Cu")
		(net "MEMA_8")
	)
	(via
		(at 31.126938 -142.564104)
		(size 0.4572)
		(drill 0.2032)
		(layers "F.Cu" "B.Cu")
		(net "MEMA_8")
	)
	(via
		(at 29.368242 -151.97963)
		(size 0.4572)
		(drill 0.2032)
		(layers "F.Cu" "B.Cu")
		(net "MEMA_8")
	)
	(segment
		(start 28.809696 -151.421084)
		(end 28.809696 -144.551654)
		(width 0.12065)
		(layer "B.Cu")
		(net "MEMA_8")
	)
	(segment
		(start 30.797246 -142.564104)
		(end 31.126938 -142.564104)
		(width 0.12065)
		(layer "B.Cu")
		(net "MEMA_8")
	)
	(segment
		(start 29.368242 -151.97963)
		(end 28.809696 -151.421084)
		(width 0.12065)
		(layer "B.Cu")
		(net "MEMA_8")
	)
	(segment
		(start 28.809696 -144.551654)
		(end 30.797246 -142.564104)
		(width 0.12065)
		(layer "B.Cu")
		(net "MEMA_8")
	)
	(segment
		(start 32.2326 -139.93495)
		(end 32.3596 -140.06195)
		(width 0.12065)
		(layer "F.Cu")
		(net "MEMA_7")
	)
	(segment
		(start 30.568138 -156.372814)
		(end 30.17647 -155.981146)
		(width 0.12065)
		(layer "F.Cu")
		(net "MEMA_7")
	)
	(segment
		(start 32.904938 -138.884914)
		(end 32.82315 -138.966702)
		(width 0.12065)
		(layer "F.Cu")
		(net "MEMA_7")
	)
	(segment
		(start 32.693356 -140.534644)
		(end 31.7246 -140.534644)
		(width 0.12065)
		(layer "F.Cu")
		(net "MEMA_7")
	)
	(segment
		(start 32.3596 -139.57935)
		(end 32.2326 -139.70635)
		(width 0.12065)
		(layer "F.Cu")
		(net "MEMA_7")
	)
	(segment
		(start 32.2326 -139.70635)
		(end 32.2326 -139.93495)
		(width 0.12065)
		(layer "F.Cu")
		(net "MEMA_7")
	)
	(segment
		(start 30.568138 -156.379926)
		(end 30.568138 -156.372814)
		(width 0.12065)
		(layer "F.Cu")
		(net "MEMA_7")
	)
	(segment
		(start 32.7025 -140.06195)
		(end 32.82315 -140.1826)
		(width 0.12065)
		(layer "F.Cu")
		(net "MEMA_7")
	)
	(segment
		(start 32.82315 -140.1826)
		(end 32.82315 -140.40485)
		(width 0.12065)
		(layer "F.Cu")
		(net "MEMA_7")
	)
	(segment
		(start 32.82315 -139.4587)
		(end 32.7025 -139.57935)
		(width 0.12065)
		(layer "F.Cu")
		(net "MEMA_7")
	)
	(segment
		(start 32.7025 -139.57935)
		(end 32.3596 -139.57935)
		(width 0.12065)
		(layer "F.Cu")
		(net "MEMA_7")
	)
	(segment
		(start 32.82315 -140.40485)
		(end 32.693356 -140.534644)
		(width 0.12065)
		(layer "F.Cu")
		(net "MEMA_7")
	)
	(segment
		(start 32.3596 -140.06195)
		(end 32.7025 -140.06195)
		(width 0.12065)
		(layer "F.Cu")
		(net "MEMA_7")
	)
	(segment
		(start 32.82315 -138.966702)
		(end 32.82315 -139.4587)
		(width 0.12065)
		(layer "F.Cu")
		(net "MEMA_7")
	)
	(via
		(at 31.7246 -140.534644)
		(size 0.4572)
		(drill 0.2032)
		(layers "F.Cu" "B.Cu")
		(net "MEMA_7")
	)
	(via
		(at 30.17647 -155.981146)
		(size 0.4572)
		(drill 0.2032)
		(layers "F.Cu" "B.Cu")
		(net "MEMA_7")
	)
	(segment
		(start 27.628596 -153.433272)
		(end 27.361896 -153.166572)
		(width 0.12065)
		(layer "B.Cu")
		(net "MEMA_7")
	)
	(segment
		(start 28.14066 -153.945336)
		(end 28.14066 -153.774648)
		(width 0.12065)
		(layer "B.Cu")
		(net "MEMA_7")
	)
	(segment
		(start 30.697424 -140.534644)
		(end 31.7246 -140.534644)
		(width 0.12065)
		(layer "B.Cu")
		(net "MEMA_7")
	)
	(segment
		(start 28.410916 -140.534644)
		(end 29.973524 -140.534644)
		(width 0.12065)
		(layer "B.Cu")
		(net "MEMA_7")
	)
	(segment
		(start 30.17647 -155.981146)
		(end 29.101034 -154.90571)
		(width 0.12065)
		(layer "B.Cu")
		(net "MEMA_7")
	)
	(segment
		(start 28.939236 -154.214068)
		(end 28.759658 -154.393646)
		(width 0.12065)
		(layer "B.Cu")
		(net "MEMA_7")
	)
	(segment
		(start 30.576774 -140.22705)
		(end 30.576774 -140.413994)
		(width 0.12065)
		(layer "B.Cu")
		(net "MEMA_7")
	)
	(segment
		(start 27.361896 -141.583664)
		(end 28.410916 -140.534644)
		(width 0.12065)
		(layer "B.Cu")
		(net "MEMA_7")
	)
	(segment
		(start 30.214824 -140.1064)
		(end 30.456124 -140.1064)
		(width 0.12065)
		(layer "B.Cu")
		(net "MEMA_7")
	)
	(segment
		(start 29.101034 -154.90571)
		(end 29.101034 -154.735022)
		(width 0.12065)
		(layer "B.Cu")
		(net "MEMA_7")
	)
	(segment
		(start 27.799284 -153.433272)
		(end 27.628596 -153.433272)
		(width 0.12065)
		(layer "B.Cu")
		(net "MEMA_7")
	)
	(segment
		(start 30.094174 -140.22705)
		(end 30.214824 -140.1064)
		(width 0.12065)
		(layer "B.Cu")
		(net "MEMA_7")
	)
	(segment
		(start 28.58897 -154.393646)
		(end 28.14066 -153.945336)
		(width 0.12065)
		(layer "B.Cu")
		(net "MEMA_7")
	)
	(segment
		(start 28.14066 -153.774648)
		(end 28.46451 -153.450798)
		(width 0.12065)
		(layer "B.Cu")
		(net "MEMA_7")
	)
	(segment
		(start 28.46451 -153.28011)
		(end 28.293822 -153.109422)
		(width 0.12065)
		(layer "B.Cu")
		(net "MEMA_7")
	)
	(segment
		(start 30.456124 -140.1064)
		(end 30.576774 -140.22705)
		(width 0.12065)
		(layer "B.Cu")
		(net "MEMA_7")
	)
	(segment
		(start 29.119068 -154.214068)
		(end 28.939236 -154.214068)
		(width 0.12065)
		(layer "B.Cu")
		(net "MEMA_7")
	)
	(segment
		(start 28.46451 -153.450798)
		(end 28.46451 -153.28011)
		(width 0.12065)
		(layer "B.Cu")
		(net "MEMA_7")
	)
	(segment
		(start 30.094174 -140.413994)
		(end 30.094174 -140.22705)
		(width 0.12065)
		(layer "B.Cu")
		(net "MEMA_7")
	)
	(segment
		(start 28.123134 -153.109422)
		(end 27.799284 -153.433272)
		(width 0.12065)
		(layer "B.Cu")
		(net "MEMA_7")
	)
	(segment
		(start 30.576774 -140.413994)
		(end 30.697424 -140.534644)
		(width 0.12065)
		(layer "B.Cu")
		(net "MEMA_7")
	)
	(segment
		(start 29.280612 -154.375612)
		(end 29.119068 -154.214068)
		(width 0.12065)
		(layer "B.Cu")
		(net "MEMA_7")
	)
	(segment
		(start 28.759658 -154.393646)
		(end 28.58897 -154.393646)
		(width 0.12065)
		(layer "B.Cu")
		(net "MEMA_7")
	)
	(segment
		(start 27.361896 -153.166572)
		(end 27.361896 -141.583664)
		(width 0.12065)
		(layer "B.Cu")
		(net "MEMA_7")
	)
	(segment
		(start 29.280612 -154.555444)
		(end 29.280612 -154.375612)
		(width 0.12065)
		(layer "B.Cu")
		(net "MEMA_7")
	)
	(segment
		(start 29.973524 -140.534644)
		(end 30.094174 -140.413994)
		(width 0.12065)
		(layer "B.Cu")
		(net "MEMA_7")
	)
	(segment
		(start 29.101034 -154.735022)
		(end 29.280612 -154.555444)
		(width 0.12065)
		(layer "B.Cu")
		(net "MEMA_7")
	)
	(segment
		(start 28.293822 -153.109422)
		(end 28.123134 -153.109422)
		(width 0.12065)
		(layer "B.Cu")
		(net "MEMA_7")
	)
	(segment
		(start 35.30473 -138.084814)
		(end 35.018726 -138.084814)
		(width 0.12065)
		(layer "F.Cu")
		(net "MEMA_6")
	)
	(segment
		(start 30.8864 -151.97963)
		(end 30.168342 -151.97963)
		(width 0.12065)
		(layer "F.Cu")
		(net "MEMA_6")
	)
	(segment
		(start 30.8864 -151.1808)
		(end 31.002732 -151.297132)
		(width 0.12065)
		(layer "F.Cu")
		(net "MEMA_6")
	)
	(segment
		(start 31.002732 -151.863298)
		(end 30.8864 -151.97963)
		(width 0.12065)
		(layer "F.Cu")
		(net "MEMA_6")
	)
	(segment
		(start 34.3281 -142.122652)
		(end 34.327846 -142.122906)
		(width 0.12065)
		(layer "F.Cu")
		(net "MEMA_6")
	)
	(segment
		(start 35.018726 -138.084814)
		(end 34.891726 -138.211814)
		(width 0.12065)
		(layer "F.Cu")
		(net "MEMA_6")
	)
	(segment
		(start 34.891726 -139.031726)
		(end 34.3281 -139.595352)
		(width 0.12065)
		(layer "F.Cu")
		(net "MEMA_6")
	)
	(segment
		(start 32.131 -144.090898)
		(end 32.131 -143.361156)
		(width 0.12065)
		(layer "F.Cu")
		(net "MEMA_6")
	)
	(segment
		(start 30.568138 -151.579834)
		(end 30.568138 -151.3078)
		(width 0.12065)
		(layer "F.Cu")
		(net "MEMA_6")
	)
	(segment
		(start 35.7886 -144.090898)
		(end 35.6616 -144.217898)
		(width 0.12065)
		(layer "F.Cu")
		(net "MEMA_6")
	)
	(segment
		(start 34.327846 -142.422626)
		(end 35.7886 -143.88338)
		(width 0.12065)
		(layer "F.Cu")
		(net "MEMA_6")
	)
	(segment
		(start 34.3281 -139.595352)
		(end 34.3281 -142.122652)
		(width 0.12065)
		(layer "F.Cu")
		(net "MEMA_6")
	)
	(segment
		(start 30.568138 -151.3078)
		(end 30.695138 -151.1808)
		(width 0.12065)
		(layer "F.Cu")
		(net "MEMA_6")
	)
	(segment
		(start 30.695138 -151.1808)
		(end 30.8864 -151.1808)
		(width 0.12065)
		(layer "F.Cu")
		(net "MEMA_6")
	)
	(segment
		(start 31.002732 -151.297132)
		(end 31.002732 -151.863298)
		(width 0.12065)
		(layer "F.Cu")
		(net "MEMA_6")
	)
	(segment
		(start 35.6616 -144.217898)
		(end 32.258 -144.217898)
		(width 0.12065)
		(layer "F.Cu")
		(net "MEMA_6")
	)
	(segment
		(start 34.891726 -138.211814)
		(end 34.891726 -139.031726)
		(width 0.12065)
		(layer "F.Cu")
		(net "MEMA_6")
	)
	(segment
		(start 32.258 -144.217898)
		(end 32.131 -144.090898)
		(width 0.12065)
		(layer "F.Cu")
		(net "MEMA_6")
	)
	(segment
		(start 35.7886 -143.88338)
		(end 35.7886 -144.090898)
		(width 0.12065)
		(layer "F.Cu")
		(net "MEMA_6")
	)
	(segment
		(start 34.327846 -142.122906)
		(end 34.327846 -142.422626)
		(width 0.12065)
		(layer "F.Cu")
		(net "MEMA_6")
	)
	(segment
		(start 32.131 -143.361156)
		(end 31.7246 -142.954756)
		(width 0.12065)
		(layer "F.Cu")
		(net "MEMA_6")
	)
	(via
		(at 30.168342 -151.97963)
		(size 0.4572)
		(drill 0.2032)
		(layers "F.Cu" "B.Cu")
		(net "MEMA_6")
	)
	(via
		(at 31.7246 -142.954756)
		(size 0.4572)
		(drill 0.2032)
		(layers "F.Cu" "B.Cu")
		(net "MEMA_6")
	)
	(segment
		(start 30.20314 -144.276318)
		(end 29.985462 -144.05864)
		(width 0.12065)
		(layer "B.Cu")
		(net "MEMA_6")
	)
	(segment
		(start 30.918658 -142.954756)
		(end 31.7246 -142.954756)
		(width 0.12065)
		(layer "B.Cu")
		(net "MEMA_6")
	)
	(segment
		(start 29.985462 -144.05864)
		(end 29.985462 -143.887952)
		(width 0.12065)
		(layer "B.Cu")
		(net "MEMA_6")
	)
	(segment
		(start 30.20314 -144.447006)
		(end 30.20314 -144.276318)
		(width 0.12065)
		(layer "B.Cu")
		(net "MEMA_6")
	)
	(segment
		(start 29.861764 -144.617694)
		(end 30.032452 -144.617694)
		(width 0.12065)
		(layer "B.Cu")
		(net "MEMA_6")
	)
	(segment
		(start 30.032452 -144.617694)
		(end 30.20314 -144.447006)
		(width 0.12065)
		(layer "B.Cu")
		(net "MEMA_6")
	)
	(segment
		(start 30.168342 -151.97963)
		(end 29.93263 -151.97963)
		(width 0.12065)
		(layer "B.Cu")
		(net "MEMA_6")
	)
	(segment
		(start 29.171646 -151.218646)
		(end 29.171646 -144.701768)
		(width 0.12065)
		(layer "B.Cu")
		(net "MEMA_6")
	)
	(segment
		(start 29.93263 -151.97963)
		(end 29.171646 -151.218646)
		(width 0.12065)
		(layer "B.Cu")
		(net "MEMA_6")
	)
	(segment
		(start 29.171646 -144.701768)
		(end 29.473398 -144.400016)
		(width 0.12065)
		(layer "B.Cu")
		(net "MEMA_6")
	)
	(segment
		(start 29.985462 -143.887952)
		(end 30.918658 -142.954756)
		(width 0.12065)
		(layer "B.Cu")
		(net "MEMA_6")
	)
	(segment
		(start 29.644086 -144.400016)
		(end 29.861764 -144.617694)
		(width 0.12065)
		(layer "B.Cu")
		(net "MEMA_6")
	)
	(segment
		(start 29.473398 -144.400016)
		(end 29.644086 -144.400016)
		(width 0.12065)
		(layer "B.Cu")
		(net "MEMA_6")
	)
	(segment
		(start 34.504884 -136.484868)
		(end 34.105088 -136.085072)
		(width 0.12065)
		(layer "F.Cu")
		(net "MEMA_5")
	)
	(segment
		(start 31.367984 -156.379926)
		(end 31.76778 -155.98013)
		(width 0.12065)
		(layer "F.Cu")
		(net "MEMA_5")
	)
	(via
		(at 31.76778 -155.98013)
		(size 0.4572)
		(drill 0.2032)
		(layers "F.Cu" "B.Cu")
		(net "MEMA_5")
	)
	(via
		(at 34.105088 -136.085072)
		(size 0.4572)
		(drill 0.2032)
		(layers "F.Cu" "B.Cu")
		(net "MEMA_5")
	)
	(segment
		(start 30.6832 -155.584652)
		(end 31.206948 -155.584652)
		(width 0.12065)
		(layer "B.Cu")
		(net "MEMA_5")
	)
	(segment
		(start 31.76778 -156.29382)
		(end 31.67253 -156.38907)
		(width 0.12065)
		(layer "B.Cu")
		(net "MEMA_5")
	)
	(segment
		(start 32.990536 -135.8138)
		(end 33.117536 -135.6868)
		(width 0.12065)
		(layer "B.Cu")
		(net "MEMA_5")
	)
	(segment
		(start 30.67685 -146.80438)
		(end 30.67685 -146.801078)
		(width 0.12065)
		(layer "B.Cu")
		(net "MEMA_5")
	)
	(segment
		(start 30.567122 -155.70073)
		(end 30.6832 -155.584652)
		(width 0.12065)
		(layer "B.Cu")
		(net "MEMA_5")
	)
	(segment
		(start 33.117536 -135.6868)
		(end 33.978088 -135.6868)
		(width 0.12065)
		(layer "B.Cu")
		(net "MEMA_5")
	)
	(segment
		(start 30.67685 -146.801078)
		(end 31.053278 -146.42465)
		(width 0.12065)
		(layer "B.Cu")
		(net "MEMA_5")
	)
	(segment
		(start 31.053278 -146.42465)
		(end 31.05658 -146.42465)
		(width 0.12065)
		(layer "B.Cu")
		(net "MEMA_5")
	)
	(segment
		(start 31.76778 -155.98013)
		(end 31.76778 -156.29382)
		(width 0.12065)
		(layer "B.Cu")
		(net "MEMA_5")
	)
	(segment
		(start 31.377128 -146.104102)
		(end 31.377128 -145.546064)
		(width 0.12065)
		(layer "B.Cu")
		(net "MEMA_5")
	)
	(segment
		(start 33.978088 -135.6868)
		(end 34.105088 -135.8138)
		(width 0.12065)
		(layer "B.Cu")
		(net "MEMA_5")
	)
	(segment
		(start 31.377128 -145.546064)
		(end 32.990536 -143.932656)
		(width 0.12065)
		(layer "B.Cu")
		(net "MEMA_5")
	)
	(segment
		(start 31.67253 -156.38907)
		(end 30.6832 -156.38907)
		(width 0.12065)
		(layer "B.Cu")
		(net "MEMA_5")
	)
	(segment
		(start 31.377128 -155.414472)
		(end 31.377128 -149.258528)
		(width 0.12065)
		(layer "B.Cu")
		(net "MEMA_5")
	)
	(segment
		(start 31.377128 -149.258528)
		(end 30.619446 -148.500846)
		(width 0.12065)
		(layer "B.Cu")
		(net "MEMA_5")
	)
	(segment
		(start 31.05658 -146.42465)
		(end 31.377128 -146.104102)
		(width 0.12065)
		(layer "B.Cu")
		(net "MEMA_5")
	)
	(segment
		(start 34.105088 -135.8138)
		(end 34.105088 -136.085072)
		(width 0.12065)
		(layer "B.Cu")
		(net "MEMA_5")
	)
	(segment
		(start 30.619446 -148.500846)
		(end 30.619446 -146.861784)
		(width 0.12065)
		(layer "B.Cu")
		(net "MEMA_5")
	)
	(segment
		(start 31.206948 -155.584652)
		(end 31.377128 -155.414472)
		(width 0.12065)
		(layer "B.Cu")
		(net "MEMA_5")
	)
	(segment
		(start 30.6832 -156.38907)
		(end 30.567122 -156.272992)
		(width 0.12065)
		(layer "B.Cu")
		(net "MEMA_5")
	)
	(segment
		(start 30.567122 -156.272992)
		(end 30.567122 -155.70073)
		(width 0.12065)
		(layer "B.Cu")
		(net "MEMA_5")
	)
	(segment
		(start 32.990536 -143.932656)
		(end 32.990536 -135.8138)
		(width 0.12065)
		(layer "B.Cu")
		(net "MEMA_5")
	)
	(segment
		(start 30.619446 -146.861784)
		(end 30.67685 -146.80438)
		(width 0.12065)
		(layer "B.Cu")
		(net "MEMA_5")
	)
	(segment
		(start 31.367984 -151.579834)
		(end 31.367984 -151.863552)
		(width 0.12065)
		(layer "F.Cu")
		(net "MEMA_4")
	)
	(segment
		(start 34.69005 -142.272766)
		(end 36.4236 -144.006316)
		(width 0.12065)
		(layer "F.Cu")
		(net "MEMA_4")
	)
	(segment
		(start 30.93339 -152.298146)
		(end 30.93339 -152.86101)
		(width 0.12065)
		(layer "F.Cu")
		(net "MEMA_4")
	)
	(segment
		(start 30.623764 -153.170636)
		(end 30.1752 -153.170636)
		(width 0.12065)
		(layer "F.Cu")
		(net "MEMA_4")
	)
	(segment
		(start 30.0482 -153.297636)
		(end 30.0482 -153.459688)
		(width 0.12065)
		(layer "F.Cu")
		(net "MEMA_4")
	)
	(segment
		(start 32.032448 -144.579848)
		(end 31.7246 -144.272)
		(width 0.12065)
		(layer "F.Cu")
		(net "MEMA_4")
	)
	(segment
		(start 30.93339 -152.86101)
		(end 30.623764 -153.170636)
		(width 0.12065)
		(layer "F.Cu")
		(net "MEMA_4")
	)
	(segment
		(start 31.367984 -151.863552)
		(end 30.93339 -152.298146)
		(width 0.12065)
		(layer "F.Cu")
		(net "MEMA_4")
	)
	(segment
		(start 35.133026 -139.056618)
		(end 35.133026 -139.19708)
		(width 0.12065)
		(layer "F.Cu")
		(net "MEMA_4")
	)
	(segment
		(start 35.133026 -139.19708)
		(end 34.69005 -139.640056)
		(width 0.12065)
		(layer "F.Cu")
		(net "MEMA_4")
	)
	(segment
		(start 36.4236 -144.427448)
		(end 36.2712 -144.579848)
		(width 0.12065)
		(layer "F.Cu")
		(net "MEMA_4")
	)
	(segment
		(start 34.69005 -139.640056)
		(end 34.69005 -142.272766)
		(width 0.12065)
		(layer "F.Cu")
		(net "MEMA_4")
	)
	(segment
		(start 36.2712 -144.579848)
		(end 32.032448 -144.579848)
		(width 0.12065)
		(layer "F.Cu")
		(net "MEMA_4")
	)
	(segment
		(start 35.30473 -138.884914)
		(end 35.133026 -139.056618)
		(width 0.12065)
		(layer "F.Cu")
		(net "MEMA_4")
	)
	(segment
		(start 30.1752 -153.170636)
		(end 30.0482 -153.297636)
		(width 0.12065)
		(layer "F.Cu")
		(net "MEMA_4")
	)
	(segment
		(start 30.0482 -153.459688)
		(end 30.168342 -153.57983)
		(width 0.12065)
		(layer "F.Cu")
		(net "MEMA_4")
	)
	(segment
		(start 31.7246 -144.272)
		(end 31.7246 -143.76146)
		(width 0.12065)
		(layer "F.Cu")
		(net "MEMA_4")
	)
	(segment
		(start 36.4236 -144.006316)
		(end 36.4236 -144.427448)
		(width 0.12065)
		(layer "F.Cu")
		(net "MEMA_4")
	)
	(via
		(at 30.168342 -153.57983)
		(size 0.4572)
		(drill 0.2032)
		(layers "F.Cu" "B.Cu")
		(net "MEMA_4")
	)
	(via
		(at 31.7246 -143.76146)
		(size 0.4572)
		(drill 0.2032)
		(layers "F.Cu" "B.Cu")
		(net "MEMA_4")
	)
	(segment
		(start 30.736286 -143.943832)
		(end 30.918658 -143.76146)
		(width 0.12065)
		(layer "B.Cu")
		(net "MEMA_4")
	)
	(segment
		(start 30.329632 -150.789132)
		(end 30.024832 -150.789132)
		(width 0.12065)
		(layer "B.Cu")
		(net "MEMA_4")
	)
	(segment
		(start 29.533596 -150.297896)
		(end 29.533596 -145.628614)
		(width 0.12065)
		(layer "B.Cu")
		(net "MEMA_4")
	)
	(segment
		(start 30.168342 -153.57983)
		(end 30.558994 -153.189178)
		(width 0.12065)
		(layer "B.Cu")
		(net "MEMA_4")
	)
	(segment
		(start 30.558994 -153.189178)
		(end 30.558994 -151.018494)
		(width 0.12065)
		(layer "B.Cu")
		(net "MEMA_4")
	)
	(segment
		(start 30.024832 -150.789132)
		(end 29.533596 -150.297896)
		(width 0.12065)
		(layer "B.Cu")
		(net "MEMA_4")
	)
	(segment
		(start 30.558994 -151.018494)
		(end 30.329632 -150.789132)
		(width 0.12065)
		(layer "B.Cu")
		(net "MEMA_4")
	)
	(segment
		(start 29.533596 -145.628614)
		(end 30.736286 -144.425924)
		(width 0.12065)
		(layer "B.Cu")
		(net "MEMA_4")
	)
	(segment
		(start 30.918658 -143.76146)
		(end 31.7246 -143.76146)
		(width 0.12065)
		(layer "B.Cu")
		(net "MEMA_4")
	)
	(segment
		(start 30.736286 -144.425924)
		(end 30.736286 -143.943832)
		(width 0.12065)
		(layer "B.Cu")
		(net "MEMA_4")
	)
	(segment
		(start 34.504884 -137.284968)
		(end 34.105088 -137.684764)
		(width 0.12065)
		(layer "F.Cu")
		(net "MEMA_3")
	)
	(segment
		(start 32.168084 -156.379926)
		(end 32.56788 -155.98013)
		(width 0.12065)
		(layer "F.Cu")
		(net "MEMA_3")
	)
	(via
		(at 34.105088 -137.684764)
		(size 0.4572)
		(drill 0.2032)
		(layers "F.Cu" "B.Cu")
		(net "MEMA_3")
	)
	(via
		(at 32.56788 -155.98013)
		(size 0.4572)
		(drill 0.2032)
		(layers "F.Cu" "B.Cu")
		(net "MEMA_3")
	)
	(segment
		(start 34.1376 -139.381738)
		(end 34.1376 -139.140438)
		(width 0.12065)
		(layer "B.Cu")
		(net "MEMA_3")
	)
	(segment
		(start 34.1376 -144.931638)
		(end 34.25825 -144.810988)
		(width 0.12065)
		(layer "B.Cu")
		(net "MEMA_3")
	)
	(segment
		(start 34.25825 -145.293588)
		(end 34.1376 -145.172938)
		(width 0.12065)
		(layer "B.Cu")
		(net "MEMA_3")
	)
	(segment
		(start 34.25825 -141.915388)
		(end 34.49828 -141.915388)
		(width 0.12065)
		(layer "B.Cu")
		(net "MEMA_3")
	)
	(segment
		(start 34.49828 -143.845788)
		(end 34.61893 -143.725138)
		(width 0.12065)
		(layer "B.Cu")
		(net "MEMA_3")
	)
	(segment
		(start 34.25825 -141.432788)
		(end 34.1376 -141.312138)
		(width 0.12065)
		(layer "B.Cu")
		(net "MEMA_3")
	)
	(segment
		(start 32.882332 -152.156668)
		(end 32.882332 -148.95957)
		(width 0.12065)
		(layer "B.Cu")
		(net "MEMA_3")
	)
	(segment
		(start 34.25825 -145.776188)
		(end 34.49828 -145.776188)
		(width 0.12065)
		(layer "B.Cu")
		(net "MEMA_3")
	)
	(segment
		(start 34.49828 -139.984988)
		(end 34.61893 -139.864338)
		(width 0.12065)
		(layer "B.Cu")
		(net "MEMA_3")
	)
	(segment
		(start 32.177482 -154.715718)
		(end 32.558736 -154.334464)
		(width 0.12065)
		(layer "B.Cu")
		(net "MEMA_3")
	)
	(segment
		(start 34.61893 -138.676888)
		(end 34.105088 -138.163046)
		(width 0.12065)
		(layer "B.Cu")
		(net "MEMA_3")
	)
	(segment
		(start 34.1376 -140.105638)
		(end 34.25825 -139.984988)
		(width 0.12065)
		(layer "B.Cu")
		(net "MEMA_3")
	)
	(segment
		(start 34.49828 -140.950188)
		(end 34.61893 -140.829538)
		(width 0.12065)
		(layer "B.Cu")
		(net "MEMA_3")
	)
	(segment
		(start 34.49828 -146.258788)
		(end 34.25825 -146.258788)
		(width 0.12065)
		(layer "B.Cu")
		(net "MEMA_3")
	)
	(segment
		(start 34.25825 -142.397988)
		(end 34.1376 -142.277338)
		(width 0.12065)
		(layer "B.Cu")
		(net "MEMA_3")
	)
	(segment
		(start 34.1376 -143.001238)
		(end 34.25825 -142.880588)
		(width 0.12065)
		(layer "B.Cu")
		(net "MEMA_3")
	)
	(segment
		(start 34.61893 -138.899138)
		(end 34.61893 -138.676888)
		(width 0.12065)
		(layer "B.Cu")
		(net "MEMA_3")
	)
	(segment
		(start 34.1376 -142.277338)
		(end 34.1376 -142.036038)
		(width 0.12065)
		(layer "B.Cu")
		(net "MEMA_3")
	)
	(segment
		(start 34.105088 -138.163046)
		(end 34.105088 -137.684764)
		(width 0.12065)
		(layer "B.Cu")
		(net "MEMA_3")
	)
	(segment
		(start 34.25825 -139.502388)
		(end 34.1376 -139.381738)
		(width 0.12065)
		(layer "B.Cu")
		(net "MEMA_3")
	)
	(segment
		(start 34.1376 -141.312138)
		(end 34.1376 -141.070838)
		(width 0.12065)
		(layer "B.Cu")
		(net "MEMA_3")
	)
	(segment
		(start 34.61893 -140.829538)
		(end 34.61893 -140.588238)
		(width 0.12065)
		(layer "B.Cu")
		(net "MEMA_3")
	)
	(segment
		(start 34.1376 -143.242538)
		(end 34.1376 -143.001238)
		(width 0.12065)
		(layer "B.Cu")
		(net "MEMA_3")
	)
	(segment
		(start 34.49828 -142.880588)
		(end 34.61893 -142.759938)
		(width 0.12065)
		(layer "B.Cu")
		(net "MEMA_3")
	)
	(segment
		(start 32.882332 -148.95957)
		(end 34.61893 -147.222972)
		(width 0.12065)
		(layer "B.Cu")
		(net "MEMA_3")
	)
	(segment
		(start 32.56788 -155.98013)
		(end 32.177482 -155.589732)
		(width 0.12065)
		(layer "B.Cu")
		(net "MEMA_3")
	)
	(segment
		(start 34.25825 -144.328388)
		(end 34.1376 -144.207738)
		(width 0.12065)
		(layer "B.Cu")
		(net "MEMA_3")
	)
	(segment
		(start 34.25825 -139.019788)
		(end 34.49828 -139.019788)
		(width 0.12065)
		(layer "B.Cu")
		(net "MEMA_3")
	)
	(segment
		(start 34.61893 -143.725138)
		(end 34.61893 -143.483838)
		(width 0.12065)
		(layer "B.Cu")
		(net "MEMA_3")
	)
	(segment
		(start 34.61893 -146.379438)
		(end 34.49828 -146.258788)
		(width 0.12065)
		(layer "B.Cu")
		(net "MEMA_3")
	)
	(segment
		(start 32.558736 -154.334464)
		(end 32.558736 -152.480264)
		(width 0.12065)
		(layer "B.Cu")
		(net "MEMA_3")
	)
	(segment
		(start 34.49828 -140.467588)
		(end 34.25825 -140.467588)
		(width 0.12065)
		(layer "B.Cu")
		(net "MEMA_3")
	)
	(segment
		(start 34.61893 -142.518638)
		(end 34.49828 -142.397988)
		(width 0.12065)
		(layer "B.Cu")
		(net "MEMA_3")
	)
	(segment
		(start 34.49828 -141.915388)
		(end 34.61893 -141.794738)
		(width 0.12065)
		(layer "B.Cu")
		(net "MEMA_3")
	)
	(segment
		(start 34.61893 -145.414238)
		(end 34.49828 -145.293588)
		(width 0.12065)
		(layer "B.Cu")
		(net "MEMA_3")
	)
	(segment
		(start 34.49828 -142.397988)
		(end 34.25825 -142.397988)
		(width 0.12065)
		(layer "B.Cu")
		(net "MEMA_3")
	)
	(segment
		(start 34.25825 -140.950188)
		(end 34.49828 -140.950188)
		(width 0.12065)
		(layer "B.Cu")
		(net "MEMA_3")
	)
	(segment
		(start 34.49828 -139.019788)
		(end 34.61893 -138.899138)
		(width 0.12065)
		(layer "B.Cu")
		(net "MEMA_3")
	)
	(segment
		(start 34.61893 -144.690338)
		(end 34.61893 -144.449038)
		(width 0.12065)
		(layer "B.Cu")
		(net "MEMA_3")
	)
	(segment
		(start 34.1376 -141.070838)
		(end 34.25825 -140.950188)
		(width 0.12065)
		(layer "B.Cu")
		(net "MEMA_3")
	)
	(segment
		(start 34.1376 -140.346938)
		(end 34.1376 -140.105638)
		(width 0.12065)
		(layer "B.Cu")
		(net "MEMA_3")
	)
	(segment
		(start 34.1376 -142.036038)
		(end 34.25825 -141.915388)
		(width 0.12065)
		(layer "B.Cu")
		(net "MEMA_3")
	)
	(segment
		(start 34.1376 -144.207738)
		(end 34.1376 -143.966438)
		(width 0.12065)
		(layer "B.Cu")
		(net "MEMA_3")
	)
	(segment
		(start 34.1376 -145.172938)
		(end 34.1376 -144.931638)
		(width 0.12065)
		(layer "B.Cu")
		(net "MEMA_3")
	)
	(segment
		(start 34.49828 -145.293588)
		(end 34.25825 -145.293588)
		(width 0.12065)
		(layer "B.Cu")
		(net "MEMA_3")
	)
	(segment
		(start 34.61893 -141.553438)
		(end 34.49828 -141.432788)
		(width 0.12065)
		(layer "B.Cu")
		(net "MEMA_3")
	)
	(segment
		(start 34.1376 -143.966438)
		(end 34.25825 -143.845788)
		(width 0.12065)
		(layer "B.Cu")
		(net "MEMA_3")
	)
	(segment
		(start 34.1376 -145.896838)
		(end 34.25825 -145.776188)
		(width 0.12065)
		(layer "B.Cu")
		(net "MEMA_3")
	)
	(segment
		(start 34.1376 -146.138138)
		(end 34.1376 -145.896838)
		(width 0.12065)
		(layer "B.Cu")
		(net "MEMA_3")
	)
	(segment
		(start 34.61893 -142.759938)
		(end 34.61893 -142.518638)
		(width 0.12065)
		(layer "B.Cu")
		(net "MEMA_3")
	)
	(segment
		(start 34.49828 -144.810988)
		(end 34.61893 -144.690338)
		(width 0.12065)
		(layer "B.Cu")
		(net "MEMA_3")
	)
	(segment
		(start 34.49828 -144.328388)
		(end 34.25825 -144.328388)
		(width 0.12065)
		(layer "B.Cu")
		(net "MEMA_3")
	)
	(segment
		(start 34.25825 -140.467588)
		(end 34.1376 -140.346938)
		(width 0.12065)
		(layer "B.Cu")
		(net "MEMA_3")
	)
	(segment
		(start 32.177482 -155.589732)
		(end 32.177482 -154.715718)
		(width 0.12065)
		(layer "B.Cu")
		(net "MEMA_3")
	)
	(segment
		(start 34.49828 -143.363188)
		(end 34.25825 -143.363188)
		(width 0.12065)
		(layer "B.Cu")
		(net "MEMA_3")
	)
	(segment
		(start 34.25825 -142.880588)
		(end 34.49828 -142.880588)
		(width 0.12065)
		(layer "B.Cu")
		(net "MEMA_3")
	)
	(segment
		(start 34.61893 -145.655538)
		(end 34.61893 -145.414238)
		(width 0.12065)
		(layer "B.Cu")
		(net "MEMA_3")
	)
	(segment
		(start 34.61893 -147.222972)
		(end 34.61893 -146.379438)
		(width 0.12065)
		(layer "B.Cu")
		(net "MEMA_3")
	)
	(segment
		(start 34.25825 -143.363188)
		(end 34.1376 -143.242538)
		(width 0.12065)
		(layer "B.Cu")
		(net "MEMA_3")
	)
	(segment
		(start 34.61893 -139.864338)
		(end 34.61893 -139.623038)
		(width 0.12065)
		(layer "B.Cu")
		(net "MEMA_3")
	)
	(segment
		(start 34.49828 -145.776188)
		(end 34.61893 -145.655538)
		(width 0.12065)
		(layer "B.Cu")
		(net "MEMA_3")
	)
	(segment
		(start 34.25825 -146.258788)
		(end 34.1376 -146.138138)
		(width 0.12065)
		(layer "B.Cu")
		(net "MEMA_3")
	)
	(segment
		(start 34.49828 -139.502388)
		(end 34.25825 -139.502388)
		(width 0.12065)
		(layer "B.Cu")
		(net "MEMA_3")
	)
	(segment
		(start 34.25825 -139.984988)
		(end 34.49828 -139.984988)
		(width 0.12065)
		(layer "B.Cu")
		(net "MEMA_3")
	)
	(segment
		(start 34.25825 -144.810988)
		(end 34.49828 -144.810988)
		(width 0.12065)
		(layer "B.Cu")
		(net "MEMA_3")
	)
	(segment
		(start 34.61893 -139.623038)
		(end 34.49828 -139.502388)
		(width 0.12065)
		(layer "B.Cu")
		(net "MEMA_3")
	)
	(segment
		(start 34.61893 -141.794738)
		(end 34.61893 -141.553438)
		(width 0.12065)
		(layer "B.Cu")
		(net "MEMA_3")
	)
	(segment
		(start 34.61893 -143.483838)
		(end 34.49828 -143.363188)
		(width 0.12065)
		(layer "B.Cu")
		(net "MEMA_3")
	)
	(segment
		(start 34.61893 -140.588238)
		(end 34.49828 -140.467588)
		(width 0.12065)
		(layer "B.Cu")
		(net "MEMA_3")
	)
	(segment
		(start 34.25825 -143.845788)
		(end 34.49828 -143.845788)
		(width 0.12065)
		(layer "B.Cu")
		(net "MEMA_3")
	)
	(segment
		(start 32.558736 -152.480264)
		(end 32.882332 -152.156668)
		(width 0.12065)
		(layer "B.Cu")
		(net "MEMA_3")
	)
	(segment
		(start 34.49828 -141.432788)
		(end 34.25825 -141.432788)
		(width 0.12065)
		(layer "B.Cu")
		(net "MEMA_3")
	)
	(segment
		(start 34.1376 -139.140438)
		(end 34.25825 -139.019788)
		(width 0.12065)
		(layer "B.Cu")
		(net "MEMA_3")
	)
	(segment
		(start 34.61893 -144.449038)
		(end 34.49828 -144.328388)
		(width 0.12065)
		(layer "B.Cu")
		(net "MEMA_3")
	)
	(segment
		(start 35.30473 -135.684768)
		(end 34.904934 -135.284972)
		(width 0.12065)
		(layer "F.Cu")
		(net "MEMA_2")
	)
	(segment
		(start 31.367984 -155.579826)
		(end 30.968188 -155.18003)
		(width 0.12065)
		(layer "F.Cu")
		(net "MEMA_2")
	)
	(via
		(at 30.968188 -155.18003)
		(size 0.4572)
		(drill 0.2032)
		(layers "F.Cu" "B.Cu")
		(net "MEMA_2")
	)
	(via
		(at 34.904934 -135.284972)
		(size 0.4572)
		(drill 0.2032)
		(layers "F.Cu" "B.Cu")
		(net "MEMA_2")
	)
	(segment
		(start 34.777934 -134.366)
		(end 34.904934 -134.493)
		(width 0.12065)
		(layer "B.Cu")
		(net "MEMA_2")
	)
	(segment
		(start 30.968188 -155.18003)
		(end 30.873446 -155.085288)
		(width 0.12065)
		(layer "B.Cu")
		(net "MEMA_2")
	)
	(segment
		(start 30.558994 -149.634194)
		(end 30.257496 -149.332696)
		(width 0.12065)
		(layer "B.Cu")
		(net "MEMA_2")
	)
	(segment
		(start 30.558994 -150.523448)
		(end 30.558994 -149.634194)
		(width 0.12065)
		(layer "B.Cu")
		(net "MEMA_2")
	)
	(segment
		(start 32.11449 -135.123174)
		(end 32.343344 -134.89432)
		(width 0.12065)
		(layer "B.Cu")
		(net "MEMA_2")
	)
	(segment
		(start 33.782 -134.493)
		(end 33.909 -134.366)
		(width 0.12065)
		(layer "B.Cu")
		(net "MEMA_2")
	)
	(segment
		(start 33.909 -134.366)
		(end 34.777934 -134.366)
		(width 0.12065)
		(layer "B.Cu")
		(net "MEMA_2")
	)
	(segment
		(start 30.257496 -149.332696)
		(end 30.257496 -145.928842)
		(width 0.12065)
		(layer "B.Cu")
		(net "MEMA_2")
	)
	(segment
		(start 34.904934 -134.493)
		(end 34.904934 -135.284972)
		(width 0.12065)
		(layer "B.Cu")
		(net "MEMA_2")
	)
	(segment
		(start 30.873446 -155.085288)
		(end 30.873446 -150.8379)
		(width 0.12065)
		(layer "B.Cu")
		(net "MEMA_2")
	)
	(segment
		(start 30.257496 -145.928842)
		(end 32.628586 -143.557752)
		(width 0.12065)
		(layer "B.Cu")
		(net "MEMA_2")
	)
	(segment
		(start 33.782 -134.76732)
		(end 33.782 -134.493)
		(width 0.12065)
		(layer "B.Cu")
		(net "MEMA_2")
	)
	(segment
		(start 32.628586 -143.557752)
		(end 32.628586 -138.360912)
		(width 0.12065)
		(layer "B.Cu")
		(net "MEMA_2")
	)
	(segment
		(start 32.343344 -134.89432)
		(end 33.655 -134.89432)
		(width 0.12065)
		(layer "B.Cu")
		(net "MEMA_2")
	)
	(segment
		(start 32.628586 -138.360912)
		(end 32.11449 -137.846816)
		(width 0.12065)
		(layer "B.Cu")
		(net "MEMA_2")
	)
	(segment
		(start 33.655 -134.89432)
		(end 33.782 -134.76732)
		(width 0.12065)
		(layer "B.Cu")
		(net "MEMA_2")
	)
	(segment
		(start 30.873446 -150.8379)
		(end 30.558994 -150.523448)
		(width 0.12065)
		(layer "B.Cu")
		(net "MEMA_2")
	)
	(segment
		(start 32.11449 -137.846816)
		(end 32.11449 -135.123174)
		(width 0.12065)
		(layer "B.Cu")
		(net "MEMA_2")
	)
	(segment
		(start 27.8638 -151.9174)
		(end 28.9306 -152.9842)
		(width 0.12065)
		(layer "F.Cu")
		(net "MEMA_14")
	)
	(segment
		(start 32.4358 -141.5288)
		(end 32.248348 -141.341348)
		(width 0.12065)
		(layer "F.Cu")
		(net "MEMA_14")
	)
	(segment
		(start 28.4734 -151.637238)
		(end 28.4734 -151.003)
		(width 0.12065)
		(layer "F.Cu")
		(net "MEMA_14")
	)
	(segment
		(start 33.5026 -139.087098)
		(end 33.5026 -139.8524)
		(width 0.12065)
		(layer "F.Cu")
		(net "MEMA_14")
	)
	(segment
		(start 32.5628 -142.1384)
		(end 32.4358 -142.0114)
		(width 0.12065)
		(layer "F.Cu")
		(net "MEMA_14")
	)
	(segment
		(start 28.3464 -150.876)
		(end 27.9908 -150.876)
		(width 0.12065)
		(layer "F.Cu")
		(net "MEMA_14")
	)
	(segment
		(start 32.4358 -142.0114)
		(end 32.4358 -141.5288)
		(width 0.12065)
		(layer "F.Cu")
		(net "MEMA_14")
	)
	(segment
		(start 28.4734 -151.003)
		(end 28.3464 -150.876)
		(width 0.12065)
		(layer "F.Cu")
		(net "MEMA_14")
	)
	(segment
		(start 28.9306 -152.9842)
		(end 29.163772 -152.9842)
		(width 0.12065)
		(layer "F.Cu")
		(net "MEMA_14")
	)
	(segment
		(start 32.248348 -141.341348)
		(end 31.7246 -141.341348)
		(width 0.12065)
		(layer "F.Cu")
		(net "MEMA_14")
	)
	(segment
		(start 33.2994 -142.0114)
		(end 33.1724 -142.1384)
		(width 0.12065)
		(layer "F.Cu")
		(net "MEMA_14")
	)
	(segment
		(start 29.768038 -152.379934)
		(end 29.216096 -152.379934)
		(width 0.12065)
		(layer "F.Cu")
		(net "MEMA_14")
	)
	(segment
		(start 33.2994 -140.0556)
		(end 33.2994 -142.0114)
		(width 0.12065)
		(layer "F.Cu")
		(net "MEMA_14")
	)
	(segment
		(start 27.8638 -151.003)
		(end 27.8638 -151.9174)
		(width 0.12065)
		(layer "F.Cu")
		(net "MEMA_14")
	)
	(segment
		(start 33.1724 -142.1384)
		(end 32.5628 -142.1384)
		(width 0.12065)
		(layer "F.Cu")
		(net "MEMA_14")
	)
	(segment
		(start 33.704784 -138.884914)
		(end 33.5026 -139.087098)
		(width 0.12065)
		(layer "F.Cu")
		(net "MEMA_14")
	)
	(segment
		(start 27.9908 -150.876)
		(end 27.8638 -151.003)
		(width 0.12065)
		(layer "F.Cu")
		(net "MEMA_14")
	)
	(segment
		(start 33.5026 -139.8524)
		(end 33.2994 -140.0556)
		(width 0.12065)
		(layer "F.Cu")
		(net "MEMA_14")
	)
	(segment
		(start 29.216096 -152.379934)
		(end 28.4734 -151.637238)
		(width 0.12065)
		(layer "F.Cu")
		(net "MEMA_14")
	)
	(segment
		(start 29.163772 -152.9842)
		(end 29.367988 -152.779984)
		(width 0.12065)
		(layer "F.Cu")
		(net "MEMA_14")
	)
	(via
		(at 31.7246 -141.341348)
		(size 0.4572)
		(drill 0.2032)
		(layers "F.Cu" "B.Cu")
		(net "MEMA_14")
	)
	(via
		(at 29.367988 -152.779984)
		(size 0.4572)
		(drill 0.2032)
		(layers "F.Cu" "B.Cu")
		(net "MEMA_14")
	)
	(segment
		(start 28.085796 -151.85898)
		(end 28.085796 -142.150592)
		(width 0.12065)
		(layer "B.Cu")
		(net "MEMA_14")
	)
	(segment
		(start 30.99054 -141.341348)
		(end 31.7246 -141.341348)
		(width 0.12065)
		(layer "B.Cu")
		(net "MEMA_14")
	)
	(segment
		(start 30.523688 -141.8082)
		(end 30.99054 -141.341348)
		(width 0.12065)
		(layer "B.Cu")
		(net "MEMA_14")
	)
	(segment
		(start 29.0068 -152.779984)
		(end 28.085796 -151.85898)
		(width 0.12065)
		(layer "B.Cu")
		(net "MEMA_14")
	)
	(segment
		(start 29.367988 -152.779984)
		(end 29.0068 -152.779984)
		(width 0.12065)
		(layer "B.Cu")
		(net "MEMA_14")
	)
	(segment
		(start 28.428188 -141.8082)
		(end 30.523688 -141.8082)
		(width 0.12065)
		(layer "B.Cu")
		(net "MEMA_14")
	)
	(segment
		(start 28.085796 -142.150592)
		(end 28.428188 -141.8082)
		(width 0.12065)
		(layer "B.Cu")
		(net "MEMA_14")
	)
	(segment
		(start 31.778194 -139.72794)
		(end 31.711138 -139.72794)
		(width 0.12065)
		(layer "F.Cu")
		(net "MEMA_13")
	)
	(segment
		(start 32.4866 -139.019534)
		(end 31.778194 -139.72794)
		(width 0.12065)
		(layer "F.Cu")
		(net "MEMA_13")
	)
	(segment
		(start 29.0068 -155.1686)
		(end 29.0068 -155.852876)
		(width 0.12065)
		(layer "F.Cu")
		(net "MEMA_13")
	)
	(segment
		(start 29.768038 -155.579826)
		(end 29.768038 -155.1686)
		(width 0.12065)
		(layer "F.Cu")
		(net "MEMA_13")
	)
	(segment
		(start 29.1338 -155.0416)
		(end 29.0068 -155.1686)
		(width 0.12065)
		(layer "F.Cu")
		(net "MEMA_13")
	)
	(segment
		(start 29.0068 -155.852876)
		(end 29.1338 -155.979876)
		(width 0.12065)
		(layer "F.Cu")
		(net "MEMA_13")
	)
	(segment
		(start 33.27019 -138.235944)
		(end 32.986472 -138.519662)
		(width 0.12065)
		(layer "F.Cu")
		(net "MEMA_13")
	)
	(segment
		(start 32.724344 -138.519662)
		(end 32.4866 -138.757406)
		(width 0.12065)
		(layer "F.Cu")
		(net "MEMA_13")
	)
	(segment
		(start 29.768038 -155.1686)
		(end 29.641038 -155.0416)
		(width 0.12065)
		(layer "F.Cu")
		(net "MEMA_13")
	)
	(segment
		(start 32.4866 -138.757406)
		(end 32.4866 -139.019534)
		(width 0.12065)
		(layer "F.Cu")
		(net "MEMA_13")
	)
	(segment
		(start 33.704784 -137.493248)
		(end 33.27019 -137.927588)
		(width 0.12065)
		(layer "F.Cu")
		(net "MEMA_13")
	)
	(segment
		(start 32.986472 -138.519662)
		(end 32.724344 -138.519662)
		(width 0.12065)
		(layer "F.Cu")
		(net "MEMA_13")
	)
	(segment
		(start 33.704784 -137.284968)
		(end 33.704784 -137.493248)
		(width 0.12065)
		(layer "F.Cu")
		(net "MEMA_13")
	)
	(segment
		(start 33.27019 -137.927588)
		(end 33.27019 -138.235944)
		(width 0.12065)
		(layer "F.Cu")
		(net "MEMA_13")
	)
	(segment
		(start 29.641038 -155.0416)
		(end 29.1338 -155.0416)
		(width 0.12065)
		(layer "F.Cu")
		(net "MEMA_13")
	)
	(segment
		(start 29.1338 -155.979876)
		(end 29.367988 -155.979876)
		(width 0.12065)
		(layer "F.Cu")
		(net "MEMA_13")
	)
	(via
		(at 29.367988 -155.979876)
		(size 0.4572)
		(drill 0.2032)
		(layers "F.Cu" "B.Cu")
		(net "MEMA_13")
	)
	(via
		(at 31.711138 -139.72794)
		(size 0.4572)
		(drill 0.2032)
		(layers "F.Cu" "B.Cu")
		(net "MEMA_13")
	)
	(segment
		(start 30.02026 -139.72794)
		(end 31.711138 -139.72794)
		(width 0.12065)
		(layer "B.Cu")
		(net "MEMA_13")
	)
	(segment
		(start 29.367988 -155.979876)
		(end 26.999946 -153.611834)
		(width 0.12065)
		(layer "B.Cu")
		(net "MEMA_13")
	)
	(segment
		(start 26.999946 -153.611834)
		(end 26.999946 -141.402054)
		(width 0.12065)
		(layer "B.Cu")
		(net "MEMA_13")
	)
	(segment
		(start 28.2702 -140.1318)
		(end 29.6164 -140.1318)
		(width 0.12065)
		(layer "B.Cu")
		(net "MEMA_13")
	)
	(segment
		(start 26.999946 -141.402054)
		(end 28.2702 -140.1318)
		(width 0.12065)
		(layer "B.Cu")
		(net "MEMA_13")
	)
	(segment
		(start 29.6164 -140.1318)
		(end 30.02026 -139.72794)
		(width 0.12065)
		(layer "B.Cu")
		(net "MEMA_13")
	)
	(segment
		(start 34.069528 -136.919716)
		(end 34.10458 -136.884664)
		(width 0.12065)
		(layer "F.Cu")
		(net "MEMA_12")
	)
	(segment
		(start 32.131 -153.3652)
		(end 30.8356 -153.3652)
		(width 0.12065)
		(layer "F.Cu")
		(net "MEMA_12")
	)
	(segment
		(start 33.27019 -136.22401)
		(end 33.27019 -136.814306)
		(width 0.12065)
		(layer "F.Cu")
		(net "MEMA_12")
	)
	(segment
		(start 30.8356 -153.3652)
		(end 30.7086 -153.4922)
		(width 0.12065)
		(layer "F.Cu")
		(net "MEMA_12")
	)
	(segment
		(start 32.168084 -152.379934)
		(end 32.216598 -152.428448)
		(width 0.12065)
		(layer "F.Cu")
		(net "MEMA_12")
	)
	(segment
		(start 30.7086 -153.4922)
		(end 30.7086 -153.9748)
		(width 0.12065)
		(layer "F.Cu")
		(net "MEMA_12")
	)
	(segment
		(start 33.577784 -136.1186)
		(end 33.3756 -136.1186)
		(width 0.12065)
		(layer "F.Cu")
		(net "MEMA_12")
	)
	(segment
		(start 32.216598 -152.428448)
		(end 32.216598 -153.279602)
		(width 0.12065)
		(layer "F.Cu")
		(net "MEMA_12")
	)
	(segment
		(start 33.27019 -136.814306)
		(end 33.3756 -136.919716)
		(width 0.12065)
		(layer "F.Cu")
		(net "MEMA_12")
	)
	(segment
		(start 32.041084 -154.686)
		(end 32.168084 -154.559)
		(width 0.12065)
		(layer "F.Cu")
		(net "MEMA_12")
	)
	(segment
		(start 29.8196 -154.686)
		(end 32.041084 -154.686)
		(width 0.12065)
		(layer "F.Cu")
		(net "MEMA_12")
	)
	(segment
		(start 30.5562 -154.1272)
		(end 29.845 -154.1272)
		(width 0.12065)
		(layer "F.Cu")
		(net "MEMA_12")
	)
	(segment
		(start 33.3756 -136.919716)
		(end 34.069528 -136.919716)
		(width 0.12065)
		(layer "F.Cu")
		(net "MEMA_12")
	)
	(segment
		(start 29.6672 -154.305)
		(end 29.6672 -154.5336)
		(width 0.12065)
		(layer "F.Cu")
		(net "MEMA_12")
	)
	(segment
		(start 32.168084 -154.559)
		(end 32.168084 -154.0256)
		(width 0.12065)
		(layer "F.Cu")
		(net "MEMA_12")
	)
	(segment
		(start 33.704784 -136.2456)
		(end 33.577784 -136.1186)
		(width 0.12065)
		(layer "F.Cu")
		(net "MEMA_12")
	)
	(segment
		(start 33.704784 -136.484868)
		(end 33.704784 -136.2456)
		(width 0.12065)
		(layer "F.Cu")
		(net "MEMA_12")
	)
	(segment
		(start 29.845 -154.1272)
		(end 29.6672 -154.305)
		(width 0.12065)
		(layer "F.Cu")
		(net "MEMA_12")
	)
	(segment
		(start 30.7086 -153.9748)
		(end 30.5562 -154.1272)
		(width 0.12065)
		(layer "F.Cu")
		(net "MEMA_12")
	)
	(segment
		(start 33.3756 -136.1186)
		(end 33.27019 -136.22401)
		(width 0.12065)
		(layer "F.Cu")
		(net "MEMA_12")
	)
	(segment
		(start 29.6672 -154.5336)
		(end 29.8196 -154.686)
		(width 0.12065)
		(layer "F.Cu")
		(net "MEMA_12")
	)
	(segment
		(start 32.216598 -153.279602)
		(end 32.131 -153.3652)
		(width 0.12065)
		(layer "F.Cu")
		(net "MEMA_12")
	)
	(via
		(at 34.10458 -136.884664)
		(size 0.4572)
		(drill 0.2032)
		(layers "F.Cu" "B.Cu")
		(net "MEMA_12")
	)
	(via
		(at 32.168084 -154.0256)
		(size 0.4572)
		(drill 0.2032)
		(layers "F.Cu" "B.Cu")
		(net "MEMA_12")
	)
	(segment
		(start 33.714436 -147.548346)
		(end 33.714436 -137.274808)
		(width 0.12065)
		(layer "B.Cu")
		(net "MEMA_12")
	)
	(segment
		(start 32.520382 -148.7424)
		(end 33.714436 -147.548346)
		(width 0.12065)
		(layer "B.Cu")
		(net "MEMA_12")
	)
	(segment
		(start 32.168084 -152.446736)
		(end 32.520382 -152.094438)
		(width 0.12065)
		(layer "B.Cu")
		(net "MEMA_12")
	)
	(segment
		(start 32.520382 -152.094438)
		(end 32.520382 -148.7424)
		(width 0.12065)
		(layer "B.Cu")
		(net "MEMA_12")
	)
	(segment
		(start 32.168084 -154.0256)
		(end 32.168084 -152.446736)
		(width 0.12065)
		(layer "B.Cu")
		(net "MEMA_12")
	)
	(segment
		(start 33.714436 -137.274808)
		(end 34.10458 -136.884664)
		(width 0.12065)
		(layer "B.Cu")
		(net "MEMA_12")
	)
	(segment
		(start 34.036 -143.366998)
		(end 33.909 -143.493998)
		(width 0.12065)
		(layer "F.Cu")
		(net "MEMA_11")
	)
	(segment
		(start 33.603946 -142.722854)
		(end 34.036 -143.154908)
		(width 0.12065)
		(layer "F.Cu")
		(net "MEMA_11")
	)
	(segment
		(start 34.091626 -138.49858)
		(end 34.091626 -139.009374)
		(width 0.12065)
		(layer "F.Cu")
		(net "MEMA_11")
	)
	(segment
		(start 33.909 -143.493998)
		(end 32.966914 -143.493998)
		(width 0.12065)
		(layer "F.Cu")
		(net "MEMA_11")
	)
	(segment
		(start 31.98241 -142.148052)
		(end 31.7246 -142.148052)
		(width 0.12065)
		(layer "F.Cu")
		(net "MEMA_11")
	)
	(segment
		(start 32.966914 -143.493998)
		(end 32.8549 -143.381984)
		(width 0.12065)
		(layer "F.Cu")
		(net "MEMA_11")
	)
	(segment
		(start 34.504884 -138.084814)
		(end 34.504884 -138.085322)
		(width 0.12065)
		(layer "F.Cu")
		(net "MEMA_11")
	)
	(segment
		(start 32.8549 -143.381984)
		(end 32.8549 -143.020542)
		(width 0.12065)
		(layer "F.Cu")
		(net "MEMA_11")
	)
	(segment
		(start 30.568138 -152.379934)
		(end 30.168342 -152.77973)
		(width 0.12065)
		(layer "F.Cu")
		(net "MEMA_11")
	)
	(segment
		(start 33.7566 -140.116052)
		(end 33.603946 -140.268706)
		(width 0.12065)
		(layer "F.Cu")
		(net "MEMA_11")
	)
	(segment
		(start 34.036 -143.154908)
		(end 34.036 -143.366998)
		(width 0.12065)
		(layer "F.Cu")
		(net "MEMA_11")
	)
	(segment
		(start 34.091626 -139.009374)
		(end 34.070036 -139.030964)
		(width 0.12065)
		(layer "F.Cu")
		(net "MEMA_11")
	)
	(segment
		(start 34.070036 -139.036044)
		(end 33.7566 -139.34948)
		(width 0.12065)
		(layer "F.Cu")
		(net "MEMA_11")
	)
	(segment
		(start 33.7566 -139.34948)
		(end 33.7566 -140.116052)
		(width 0.12065)
		(layer "F.Cu")
		(net "MEMA_11")
	)
	(segment
		(start 34.070036 -139.030964)
		(end 34.070036 -139.036044)
		(width 0.12065)
		(layer "F.Cu")
		(net "MEMA_11")
	)
	(segment
		(start 33.603946 -140.268706)
		(end 33.603946 -142.722854)
		(width 0.12065)
		(layer "F.Cu")
		(net "MEMA_11")
	)
	(segment
		(start 32.8549 -143.020542)
		(end 31.98241 -142.148052)
		(width 0.12065)
		(layer "F.Cu")
		(net "MEMA_11")
	)
	(segment
		(start 34.504884 -138.085322)
		(end 34.091626 -138.49858)
		(width 0.12065)
		(layer "F.Cu")
		(net "MEMA_11")
	)
	(via
		(at 31.7246 -142.148052)
		(size 0.4572)
		(drill 0.2032)
		(layers "F.Cu" "B.Cu")
		(net "MEMA_11")
	)
	(via
		(at 30.168342 -152.77973)
		(size 0.4572)
		(drill 0.2032)
		(layers "F.Cu" "B.Cu")
		(net "MEMA_11")
	)
	(segment
		(start 28.4734 -142.5448)
		(end 28.4734 -142.275052)
		(width 0.12065)
		(layer "B.Cu")
		(net "MEMA_11")
	)
	(segment
		(start 28.6004 -142.6718)
		(end 28.4734 -142.5448)
		(width 0.12065)
		(layer "B.Cu")
		(net "MEMA_11")
	)
	(segment
		(start 30.168342 -152.77973)
		(end 29.758894 -152.370282)
		(width 0.12065)
		(layer "B.Cu")
		(net "MEMA_11")
	)
	(segment
		(start 29.718 -143.129)
		(end 29.845 -143.002)
		(width 0.12065)
		(layer "B.Cu")
		(net "MEMA_11")
	)
	(segment
		(start 28.4734 -142.275052)
		(end 28.6004 -142.148052)
		(width 0.12065)
		(layer "B.Cu")
		(net "MEMA_11")
	)
	(segment
		(start 28.6004 -142.148052)
		(end 31.7246 -142.148052)
		(width 0.12065)
		(layer "B.Cu")
		(net "MEMA_11")
	)
	(segment
		(start 29.845 -142.7988)
		(end 29.718 -142.6718)
		(width 0.12065)
		(layer "B.Cu")
		(net "MEMA_11")
	)
	(segment
		(start 29.718 -142.6718)
		(end 28.6004 -142.6718)
		(width 0.12065)
		(layer "B.Cu")
		(net "MEMA_11")
	)
	(segment
		(start 29.845 -143.002)
		(end 29.845 -142.7988)
		(width 0.12065)
		(layer "B.Cu")
		(net "MEMA_11")
	)
	(segment
		(start 28.447746 -143.256)
		(end 28.574746 -143.129)
		(width 0.12065)
		(layer "B.Cu")
		(net "MEMA_11")
	)
	(segment
		(start 28.574746 -143.129)
		(end 29.718 -143.129)
		(width 0.12065)
		(layer "B.Cu")
		(net "MEMA_11")
	)
	(segment
		(start 29.154882 -152.370282)
		(end 28.447746 -151.663146)
		(width 0.12065)
		(layer "B.Cu")
		(net "MEMA_11")
	)
	(segment
		(start 28.447746 -151.663146)
		(end 28.447746 -143.256)
		(width 0.12065)
		(layer "B.Cu")
		(net "MEMA_11")
	)
	(segment
		(start 29.758894 -152.370282)
		(end 29.154882 -152.370282)
		(width 0.12065)
		(layer "B.Cu")
		(net "MEMA_11")
	)
	(segment
		(start 33.49498 -154.559)
		(end 33.36798 -154.432)
		(width 0.12065)
		(layer "F.Cu")
		(net "MEMA_10")
	)
	(segment
		(start 35.433 -153.4668)
		(end 35.5346 -153.3652)
		(width 0.12065)
		(layer "F.Cu")
		(net "MEMA_10")
	)
	(segment
		(start 34.163 -152.774904)
		(end 34.163 -153.8732)
		(width 0.12065)
		(layer "F.Cu")
		(net "MEMA_10")
	)
	(segment
		(start 34.163 -153.8732)
		(end 34.29 -154.0002)
		(width 0.12065)
		(layer "F.Cu")
		(net "MEMA_10")
	)
	(segment
		(start 35.5346 -153.3652)
		(end 35.8648 -153.3652)
		(width 0.12065)
		(layer "F.Cu")
		(net "MEMA_10")
	)
	(segment
		(start 33.36798 -154.432)
		(end 33.36798 -152.779984)
		(width 0.12065)
		(layer "F.Cu")
		(net "MEMA_10")
	)
	(segment
		(start 36.0172 -153.5176)
		(end 36.0172 -154.4574)
		(width 0.12065)
		(layer "F.Cu")
		(net "MEMA_10")
	)
	(segment
		(start 35.8648 -153.3652)
		(end 36.0172 -153.5176)
		(width 0.12065)
		(layer "F.Cu")
		(net "MEMA_10")
	)
	(segment
		(start 34.29 -154.0002)
		(end 35.306 -154.0002)
		(width 0.12065)
		(layer "F.Cu")
		(net "MEMA_10")
	)
	(segment
		(start 35.306 -154.0002)
		(end 35.433 -153.8732)
		(width 0.12065)
		(layer "F.Cu")
		(net "MEMA_10")
	)
	(segment
		(start 33.76803 -152.379934)
		(end 34.163 -152.774904)
		(width 0.12065)
		(layer "F.Cu")
		(net "MEMA_10")
	)
	(segment
		(start 35.9156 -154.559)
		(end 33.49498 -154.559)
		(width 0.12065)
		(layer "F.Cu")
		(net "MEMA_10")
	)
	(segment
		(start 36.0172 -154.4574)
		(end 35.9156 -154.559)
		(width 0.12065)
		(layer "F.Cu")
		(net "MEMA_10")
	)
	(segment
		(start 35.433 -153.8732)
		(end 35.433 -153.4668)
		(width 0.12065)
		(layer "F.Cu")
		(net "MEMA_10")
	)
	(segment
		(start 35.30473 -137.284968)
		(end 34.904934 -137.684764)
		(width 0.12065)
		(layer "F.Cu")
		(net "MEMA_10")
	)
	(via
		(at 34.904934 -137.684764)
		(size 0.4572)
		(drill 0.2032)
		(layers "F.Cu" "B.Cu")
		(net "MEMA_10")
	)
	(via
		(at 33.36798 -152.779984)
		(size 0.4572)
		(drill 0.2032)
		(layers "F.Cu" "B.Cu")
		(net "MEMA_10")
	)
	(segment
		(start 34.286952 -149.6822)
		(end 34.286952 -148.579078)
		(width 0.12065)
		(layer "B.Cu")
		(net "MEMA_10")
	)
	(segment
		(start 33.4518 -152.696164)
		(end 33.4518 -150.517352)
		(width 0.12065)
		(layer "B.Cu")
		(net "MEMA_10")
	)
	(segment
		(start 33.36798 -152.779984)
		(end 33.4518 -152.696164)
		(width 0.12065)
		(layer "B.Cu")
		(net "MEMA_10")
	)
	(segment
		(start 34.286952 -148.579078)
		(end 35.34283 -147.5232)
		(width 0.12065)
		(layer "B.Cu")
		(net "MEMA_10")
	)
	(segment
		(start 35.34283 -147.5232)
		(end 35.34283 -138.12266)
		(width 0.12065)
		(layer "B.Cu")
		(net "MEMA_10")
	)
	(segment
		(start 35.34283 -138.12266)
		(end 34.904934 -137.684764)
		(width 0.12065)
		(layer "B.Cu")
		(net "MEMA_10")
	)
	(segment
		(start 33.4518 -150.517352)
		(end 34.286952 -149.6822)
		(width 0.12065)
		(layer "B.Cu")
		(net "MEMA_10")
	)
	(segment
		(start 31.367984 -152.379934)
		(end 31.242 -152.505918)
		(width 0.12065)
		(layer "F.Cu")
		(net "MEMA_1")
	)
	(segment
		(start 31.369 -153.14295)
		(end 31.64078 -153.14295)
		(width 0.12065)
		(layer "F.Cu")
		(net "MEMA_1")
	)
	(segment
		(start 35.30473 -136.484868)
		(end 34.904934 -136.085072)
		(width 0.12065)
		(layer "F.Cu")
		(net "MEMA_1")
	)
	(segment
		(start 31.64078 -153.14295)
		(end 31.76778 -153.01595)
		(width 0.12065)
		(layer "F.Cu")
		(net "MEMA_1")
	)
	(segment
		(start 31.242 -152.505918)
		(end 31.242 -153.01595)
		(width 0.12065)
		(layer "F.Cu")
		(net "MEMA_1")
	)
	(segment
		(start 31.242 -153.01595)
		(end 31.369 -153.14295)
		(width 0.12065)
		(layer "F.Cu")
		(net "MEMA_1")
	)
	(segment
		(start 31.76778 -153.01595)
		(end 31.76778 -151.980138)
		(width 0.12065)
		(layer "F.Cu")
		(net "MEMA_1")
	)
	(via
		(at 34.904934 -136.085072)
		(size 0.4572)
		(drill 0.2032)
		(layers "F.Cu" "B.Cu")
		(net "MEMA_1")
	)
	(via
		(at 31.76778 -151.980138)
		(size 0.4572)
		(drill 0.2032)
		(layers "F.Cu" "B.Cu")
		(net "MEMA_1")
	)
	(segment
		(start 31.7754 -146.650202)
		(end 31.7754 -146.122136)
		(width 0.12065)
		(layer "B.Cu")
		(net "MEMA_1")
	)
	(segment
		(start 30.981396 -148.202396)
		(end 30.981396 -147.8788)
		(width 0.12065)
		(layer "B.Cu")
		(net "MEMA_1")
	)
	(segment
		(start 33.96107 -136.475724)
		(end 34.514282 -136.475724)
		(width 0.12065)
		(layer "B.Cu")
		(net "MEMA_1")
	)
	(segment
		(start 33.225486 -145.4404)
		(end 33.352486 -145.3134)
		(width 0.12065)
		(layer "B.Cu")
		(net "MEMA_1")
	)
	(segment
		(start 31.766002 -151.97836)
		(end 31.766002 -148.3868)
		(width 0.12065)
		(layer "B.Cu")
		(net "MEMA_1")
	)
	(segment
		(start 31.76778 -151.980138)
		(end 31.766002 -151.97836)
		(width 0.12065)
		(layer "B.Cu")
		(net "MEMA_1")
	)
	(segment
		(start 31.1658 -147.294346)
		(end 31.0388 -147.167346)
		(width 0.12065)
		(layer "B.Cu")
		(net "MEMA_1")
	)
	(segment
		(start 34.514282 -136.475724)
		(end 34.904934 -136.085072)
		(width 0.12065)
		(layer "B.Cu")
		(net "MEMA_1")
	)
	(segment
		(start 31.766002 -148.3868)
		(end 31.666942 -148.28774)
		(width 0.12065)
		(layer "B.Cu")
		(net "MEMA_1")
	)
	(segment
		(start 31.666942 -148.28774)
		(end 31.06674 -148.28774)
		(width 0.12065)
		(layer "B.Cu")
		(net "MEMA_1")
	)
	(segment
		(start 31.08325 -147.776946)
		(end 32.461708 -147.776946)
		(width 0.12065)
		(layer "B.Cu")
		(net "MEMA_1")
	)
	(segment
		(start 31.0388 -147.167346)
		(end 31.0388 -146.951192)
		(width 0.12065)
		(layer "B.Cu")
		(net "MEMA_1")
	)
	(segment
		(start 32.461708 -147.776946)
		(end 32.990536 -147.247864)
		(width 0.12065)
		(layer "B.Cu")
		(net "MEMA_1")
	)
	(segment
		(start 32.689038 -146.914362)
		(end 32.3088 -147.294346)
		(width 0.12065)
		(layer "B.Cu")
		(net "MEMA_1")
	)
	(segment
		(start 31.639002 -146.7866)
		(end 31.7754 -146.650202)
		(width 0.12065)
		(layer "B.Cu")
		(net "MEMA_1")
	)
	(segment
		(start 32.990536 -147.247864)
		(end 32.990536 -147.036536)
		(width 0.12065)
		(layer "B.Cu")
		(net "MEMA_1")
	)
	(segment
		(start 31.203392 -146.7866)
		(end 31.639002 -146.7866)
		(width 0.12065)
		(layer "B.Cu")
		(net "MEMA_1")
	)
	(segment
		(start 31.75 -146.096736)
		(end 31.75 -145.691352)
		(width 0.12065)
		(layer "B.Cu")
		(net "MEMA_1")
	)
	(segment
		(start 32.3088 -147.294346)
		(end 31.1658 -147.294346)
		(width 0.12065)
		(layer "B.Cu")
		(net "MEMA_1")
	)
	(segment
		(start 31.06674 -148.28774)
		(end 30.981396 -148.202396)
		(width 0.12065)
		(layer "B.Cu")
		(net "MEMA_1")
	)
	(segment
		(start 32.000952 -145.4404)
		(end 33.225486 -145.4404)
		(width 0.12065)
		(layer "B.Cu")
		(net "MEMA_1")
	)
	(segment
		(start 31.0388 -146.951192)
		(end 31.203392 -146.7866)
		(width 0.12065)
		(layer "B.Cu")
		(net "MEMA_1")
	)
	(segment
		(start 31.75 -145.691352)
		(end 32.000952 -145.4404)
		(width 0.12065)
		(layer "B.Cu")
		(net "MEMA_1")
	)
	(segment
		(start 33.352486 -137.084308)
		(end 33.96107 -136.475724)
		(width 0.12065)
		(layer "B.Cu")
		(net "MEMA_1")
	)
	(segment
		(start 32.868362 -146.914362)
		(end 32.689038 -146.914362)
		(width 0.12065)
		(layer "B.Cu")
		(net "MEMA_1")
	)
	(segment
		(start 32.990536 -147.036536)
		(end 32.868362 -146.914362)
		(width 0.12065)
		(layer "B.Cu")
		(net "MEMA_1")
	)
	(segment
		(start 33.352486 -145.3134)
		(end 33.352486 -137.084308)
		(width 0.12065)
		(layer "B.Cu")
		(net "MEMA_1")
	)
	(segment
		(start 31.7754 -146.122136)
		(end 31.75 -146.096736)
		(width 0.12065)
		(layer "B.Cu")
		(net "MEMA_1")
	)
	(segment
		(start 30.981396 -147.8788)
		(end 31.08325 -147.776946)
		(width 0.12065)
		(layer "B.Cu")
		(net "MEMA_1")
	)
	(segment
		(start 32.168084 -155.579826)
		(end 31.768288 -155.18003)
		(width 0.12065)
		(layer "F.Cu")
		(net "MEMA_0")
	)
	(segment
		(start 32.207454 -145.894044)
		(end 32.718756 -145.894044)
		(width 0.12065)
		(layer "F.Cu")
		(net "MEMA_0")
	)
	(segment
		(start 38.4048 -145.303748)
		(end 38.5318 -145.176748)
		(width 0.12065)
		(layer "F.Cu")
		(net "MEMA_0")
	)
	(segment
		(start 38.4048 -144.223994)
		(end 37.665406 -144.223994)
		(width 0.12065)
		(layer "F.Cu")
		(net "MEMA_0")
	)
	(segment
		(start 32.718756 -145.894044)
		(end 33.309052 -145.303748)
		(width 0.12065)
		(layer "F.Cu")
		(net "MEMA_0")
	)
	(segment
		(start 35.351212 -139.70254)
		(end 36.10483 -138.948922)
		(width 0.12065)
		(layer "F.Cu")
		(net "MEMA_0")
	)
	(segment
		(start 33.309052 -145.303748)
		(end 38.4048 -145.303748)
		(width 0.12065)
		(layer "F.Cu")
		(net "MEMA_0")
	)
	(segment
		(start 36.10483 -138.948922)
		(end 36.10483 -138.884914)
		(width 0.12065)
		(layer "F.Cu")
		(net "MEMA_0")
	)
	(segment
		(start 37.665406 -144.223994)
		(end 35.351212 -141.9098)
		(width 0.12065)
		(layer "F.Cu")
		(net "MEMA_0")
	)
	(segment
		(start 35.351212 -141.9098)
		(end 35.351212 -139.70254)
		(width 0.12065)
		(layer "F.Cu")
		(net "MEMA_0")
	)
	(segment
		(start 38.5318 -145.176748)
		(end 38.5318 -144.350994)
		(width 0.12065)
		(layer "F.Cu")
		(net "MEMA_0")
	)
	(segment
		(start 38.5318 -144.350994)
		(end 38.4048 -144.223994)
		(width 0.12065)
		(layer "F.Cu")
		(net "MEMA_0")
	)
	(via
		(at 31.768288 -155.18003)
		(size 0.4572)
		(drill 0.2032)
		(layers "F.Cu" "B.Cu")
		(net "MEMA_0")
	)
	(via
		(at 32.207454 -145.894044)
		(size 0.4572)
		(drill 0.2032)
		(layers "F.Cu" "B.Cu")
		(net "MEMA_0")
	)
	(segment
		(start 33.352486 -147.398232)
		(end 33.352486 -146.103086)
		(width 0.12065)
		(layer "B.Cu")
		(net "MEMA_0")
	)
	(segment
		(start 33.352486 -146.103086)
		(end 33.143444 -145.894044)
		(width 0.12065)
		(layer "B.Cu")
		(net "MEMA_0")
	)
	(segment
		(start 31.768288 -152.53208)
		(end 32.158432 -152.141936)
		(width 0.12065)
		(layer "B.Cu")
		(net "MEMA_0")
	)
	(segment
		(start 33.143444 -145.894044)
		(end 32.207454 -145.894044)
		(width 0.12065)
		(layer "B.Cu")
		(net "MEMA_0")
	)
	(segment
		(start 32.158432 -148.592286)
		(end 33.352486 -147.398232)
		(width 0.12065)
		(layer "B.Cu")
		(net "MEMA_0")
	)
	(segment
		(start 32.158432 -152.141936)
		(end 32.158432 -148.592286)
		(width 0.12065)
		(layer "B.Cu")
		(net "MEMA_0")
	)
	(segment
		(start 31.768288 -155.18003)
		(end 31.768288 -152.53208)
		(width 0.12065)
		(layer "B.Cu")
		(net "MEMA_0")
	)
	(segment
		(start 231.599994 -39.99992)
		(end 231.100122 -39.500048)
		(width 0.12065)
		(layer "F.Cu")
		(net "MDIO")
	)
	(via
		(at 220.6752 -21.6662)
		(size 0.508)
		(drill 0.254)
		(layers "F.Cu" "B.Cu")
		(net "MDIO")
	)
	(via
		(at 231.100122 -39.500048)
		(size 0.4572)
		(drill 0.2032)
		(layers "F.Cu" "B.Cu")
		(net "MDIO")
	)
	(segment
		(start 220.4974 -21.6662)
		(end 220.6752 -21.6662)
		(width 0.12065)
		(layer "B.Cu")
		(net "MDIO")
	)
	(segment
		(start 219.964 -21.1328)
		(end 220.4974 -21.6662)
		(width 0.12065)
		(layer "B.Cu")
		(net "MDIO")
	)
	(segment
		(start 220.324934 -20.594066)
		(end 219.964 -20.955)
		(width 0.12065)
		(layer "B.Cu")
		(net "MDIO")
	)
	(segment
		(start 220.936566 -20.594066)
		(end 220.324934 -20.594066)
		(width 0.12065)
		(layer "B.Cu")
		(net "MDIO")
	)
	(segment
		(start 219.964 -20.955)
		(end 219.964 -21.1328)
		(width 0.12065)
		(layer "B.Cu")
		(net "MDIO")
	)
	(segment
		(start 221.234 -20.8915)
		(end 220.936566 -20.594066)
		(width 0.12065)
		(layer "B.Cu")
		(net "MDIO")
	)
	(segment
		(start 231.100122 -39.500048)
		(end 231.100122 -38.085522)
		(width 0.127)
		(layer "In5.Cu")
		(net "MDIO")
	)
	(segment
		(start 231.100122 -38.085522)
		(end 230.693722 -37.679122)
		(width 0.127)
		(layer "In5.Cu")
		(net "MDIO")
	)
	(segment
		(start 225.777552 -22.346158)
		(end 225.54184 -22.346158)
		(width 0.127)
		(layer "In5.Cu")
		(net "MDIO")
	)
	(segment
		(start 228.3079 -24.8539)
		(end 228.3079 -24.366982)
		(width 0.127)
		(layer "In5.Cu")
		(net "MDIO")
	)
	(segment
		(start 228.3079 -24.366982)
		(end 227.816918 -23.876)
		(width 0.127)
		(layer "In5.Cu")
		(net "MDIO")
	)
	(segment
		(start 224.595182 -22.1869)
		(end 223.722438 -21.314156)
		(width 0.127)
		(layer "In5.Cu")
		(net "MDIO")
	)
	(segment
		(start 227.307394 -23.876)
		(end 225.777552 -22.346158)
		(width 0.127)
		(layer "In5.Cu")
		(net "MDIO")
	)
	(segment
		(start 223.722438 -21.314156)
		(end 221.027244 -21.314156)
		(width 0.127)
		(layer "In5.Cu")
		(net "MDIO")
	)
	(segment
		(start 221.027244 -21.314156)
		(end 220.6752 -21.6662)
		(width 0.127)
		(layer "In5.Cu")
		(net "MDIO")
	)
	(segment
		(start 230.693722 -37.679122)
		(end 230.693722 -27.239722)
		(width 0.127)
		(layer "In5.Cu")
		(net "MDIO")
	)
	(segment
		(start 225.382582 -22.1869)
		(end 224.595182 -22.1869)
		(width 0.127)
		(layer "In5.Cu")
		(net "MDIO")
	)
	(segment
		(start 227.816918 -23.876)
		(end 227.307394 -23.876)
		(width 0.127)
		(layer "In5.Cu")
		(net "MDIO")
	)
	(segment
		(start 225.54184 -22.346158)
		(end 225.382582 -22.1869)
		(width 0.127)
		(layer "In5.Cu")
		(net "MDIO")
	)
	(segment
		(start 230.693722 -27.239722)
		(end 228.3079 -24.8539)
		(width 0.127)
		(layer "In5.Cu")
		(net "MDIO")
	)
	(segment
		(start 231.599994 -36.999926)
		(end 231.100122 -36.500054)
		(width 0.12065)
		(layer "F.Cu")
		(net "MDC")
	)
	(via
		(at 231.100122 -36.500054)
		(size 0.4572)
		(drill 0.2032)
		(layers "F.Cu" "B.Cu")
		(net "MDC")
	)
	(segment
		(start 231.100122 -36.500054)
		(end 231.601518 -37.00145)
		(width 0.12065)
		(layer "B.Cu")
		(net "MDC")
	)
	(segment
		(start 231.601518 -37.00145)
		(end 231.601518 -38.002718)
		(width 0.12065)
		(layer "B.Cu")
		(net "MDC")
	)
	(segment
		(start 20.2057 -188.1886)
		(end 20.2057 -187.1091)
		(width 0.508)
		(layer "F.Cu")
		(net "MB0_VCC")
	)
	(segment
		(start 18.6182 -188.3664)
		(end 17.9324 -188.3664)
		(width 0.508)
		(layer "F.Cu")
		(net "MB0_VCC")
	)
	(segment
		(start 18.998184 -187.448952)
		(end 18.998184 -188.037216)
		(width 0.508)
		(layer "F.Cu")
		(net "MB0_VCC")
	)
	(segment
		(start 17.9324 -188.3664)
		(end 16.980662 -187.414662)
		(width 0.3048)
		(layer "F.Cu")
		(net "MB0_VCC")
	)
	(segment
		(start 18.6436 -188.3918)
		(end 18.6182 -188.3664)
		(width 0.508)
		(layer "F.Cu")
		(net "MB0_VCC")
	)
	(segment
		(start 20.2057 -187.1091)
		(end 20.2692 -187.0456)
		(width 0.508)
		(layer "F.Cu")
		(net "MB0_VCC")
	)
	(segment
		(start 18.998184 -188.037216)
		(end 18.6436 -188.3918)
		(width 0.508)
		(layer "F.Cu")
		(net "MB0_VCC")
	)
	(segment
		(start 20.2692 -187.0456)
		(end 19.401536 -187.0456)
		(width 0.508)
		(layer "F.Cu")
		(net "MB0_VCC")
	)
	(segment
		(start 16.980662 -187.414662)
		(end 16.2687 -187.414662)
		(width 0.3048)
		(layer "F.Cu")
		(net "MB0_VCC")
	)
	(segment
		(start 19.401536 -187.0456)
		(end 18.998184 -187.448952)
		(width 0.508)
		(layer "F.Cu")
		(net "MB0_VCC")
	)
	(via
		(at 18.6436 -188.3918)
		(size 0.7112)
		(drill 0.3556)
		(layers "F.Cu" "B.Cu")
		(net "MB0_VCC")
	)
	(segment
		(start 16.51 -195.7832)
		(end 16.51 -194.7037)
		(width 0.12065)
		(layer "F.Cu")
		(net "MB0_VCAP_R")
	)
	(segment
		(start 15.042134 -190.911734)
		(end 15.5702 -191.4398)
		(width 0.12065)
		(layer "F.Cu")
		(net "MB0_VCAP_R")
	)
	(segment
		(start 15.621 -193.8147)
		(end 16.51 -194.7037)
		(width 0.12065)
		(layer "F.Cu")
		(net "MB0_VCAP_R")
	)
	(segment
		(start 16.4846 -195.8086)
		(end 16.51 -195.7832)
		(width 0.12065)
		(layer "F.Cu")
		(net "MB0_VCAP_R")
	)
	(segment
		(start 15.5702 -191.4398)
		(end 15.5702 -192.0748)
		(width 0.12065)
		(layer "F.Cu")
		(net "MB0_VCAP_R")
	)
	(segment
		(start 14.4018 -193.8147)
		(end 15.4432 -193.8147)
		(width 0.12065)
		(layer "F.Cu")
		(net "MB0_VCAP_R")
	)
	(segment
		(start 15.5702 -192.0748)
		(end 15.5702 -192.2018)
		(width 0.12065)
		(layer "F.Cu")
		(net "MB0_VCAP_R")
	)
	(segment
		(start 15.042134 -189.1411)
		(end 15.042134 -190.911734)
		(width 0.12065)
		(layer "F.Cu")
		(net "MB0_VCAP_R")
	)
	(segment
		(start 14.4018 -193.3702)
		(end 14.4018 -193.8147)
		(width 0.12065)
		(layer "F.Cu")
		(net "MB0_VCAP_R")
	)
	(segment
		(start 15.5702 -192.2018)
		(end 14.4018 -193.3702)
		(width 0.12065)
		(layer "F.Cu")
		(net "MB0_VCAP_R")
	)
	(segment
		(start 15.4432 -193.8147)
		(end 15.621 -193.8147)
		(width 0.12065)
		(layer "F.Cu")
		(net "MB0_VCAP_R")
	)
	(via
		(at 15.5702 -192.0748)
		(size 0.7112)
		(drill 0.3556)
		(layers "F.Cu" "B.Cu")
		(net "MB0_VCAP_R")
	)
	(segment
		(start 13.542264 -190.064136)
		(end 13.542264 -189.1411)
		(width 0.12065)
		(layer "F.Cu")
		(net "MB0_TIME_R")
	)
	(segment
		(start 10.8966 -192.7098)
		(end 11.5316 -192.0748)
		(width 0.12065)
		(layer "F.Cu")
		(net "MB0_TIME_R")
	)
	(segment
		(start 10.8966 -193.8655)
		(end 10.8966 -192.7098)
		(width 0.12065)
		(layer "F.Cu")
		(net "MB0_TIME_R")
	)
	(segment
		(start 11.5316 -192.0748)
		(end 13.542264 -190.064136)
		(width 0.12065)
		(layer "F.Cu")
		(net "MB0_TIME_R")
	)
	(via
		(at 11.5316 -192.0748)
		(size 0.7112)
		(drill 0.3556)
		(layers "F.Cu" "B.Cu")
		(net "MB0_TIME_R")
	)
	(segment
		(start 22.016212 -183.4388)
		(end 23.0759 -183.4388)
		(width 0.12065)
		(layer "F.Cu")
		(net "MB0_TEMP_E")
	)
	(segment
		(start 23.0759 -183.4388)
		(end 23.3172 -183.6801)
		(width 0.12065)
		(layer "F.Cu")
		(net "MB0_TEMP_E")
	)
	(segment
		(start 22.7584 -184.8866)
		(end 22.7584 -184.3786)
		(width 0.12065)
		(layer "F.Cu")
		(net "MB0_TEMP_E")
	)
	(segment
		(start 22.7584 -184.3786)
		(end 23.3172 -183.8198)
		(width 0.12065)
		(layer "F.Cu")
		(net "MB0_TEMP_E")
	)
	(segment
		(start 23.3172 -183.8198)
		(end 23.3172 -183.6801)
		(width 0.12065)
		(layer "F.Cu")
		(net "MB0_TEMP_E")
	)
	(via
		(at 22.7584 -184.8866)
		(size 0.7112)
		(drill 0.3556)
		(layers "F.Cu" "B.Cu")
		(net "MB0_TEMP_E")
	)
	(segment
		(start 20.866354 -183.423814)
		(end 20.597368 -183.6928)
		(width 0.12065)
		(layer "F.Cu")
		(net "MB0_TEMP_C")
	)
	(segment
		(start 22.016212 -183.0324)
		(end 22.016212 -181.833012)
		(width 0.12065)
		(layer "F.Cu")
		(net "MB0_TEMP_C")
	)
	(segment
		(start 20.597368 -183.6928)
		(end 20.1295 -183.6928)
		(width 0.12065)
		(layer "F.Cu")
		(net "MB0_TEMP_C")
	)
	(segment
		(start 22.016212 -181.833012)
		(end 21.7678 -181.5846)
		(width 0.12065)
		(layer "F.Cu")
		(net "MB0_TEMP_C")
	)
	(segment
		(start 21.7678 -181.5846)
		(end 21.59 -181.5846)
		(width 0.12065)
		(layer "F.Cu")
		(net "MB0_TEMP_C")
	)
	(segment
		(start 22.016212 -183.0324)
		(end 21.71573 -183.0324)
		(width 0.12065)
		(layer "F.Cu")
		(net "MB0_TEMP_C")
	)
	(segment
		(start 21.209 -181.5846)
		(end 20.866354 -181.927246)
		(width 0.12065)
		(layer "F.Cu")
		(net "MB0_TEMP_C")
	)
	(segment
		(start 21.71573 -183.0324)
		(end 21.51253 -183.2356)
		(width 0.12065)
		(layer "F.Cu")
		(net "MB0_TEMP_C")
	)
	(segment
		(start 20.866354 -181.927246)
		(end 20.866354 -183.423814)
		(width 0.12065)
		(layer "F.Cu")
		(net "MB0_TEMP_C")
	)
	(segment
		(start 21.51253 -183.2356)
		(end 21.316188 -183.2356)
		(width 0.12065)
		(layer "F.Cu")
		(net "MB0_TEMP_C")
	)
	(segment
		(start 21.59 -181.5846)
		(end 21.209 -181.5846)
		(width 0.12065)
		(layer "F.Cu")
		(net "MB0_TEMP_C")
	)
	(via
		(at 21.59 -181.5846)
		(size 0.7112)
		(drill 0.3556)
		(layers "F.Cu" "B.Cu")
		(net "MB0_TEMP_C")
	)
	(segment
		(start 19.2405 -183.6928)
		(end 19.2405 -182.7022)
		(width 0.12065)
		(layer "F.Cu")
		(net "MB0_TEMP")
	)
	(segment
		(start 19.2405 -182.7022)
		(end 19.2151 -182.6768)
		(width 0.12065)
		(layer "F.Cu")
		(net "MB0_TEMP")
	)
	(segment
		(start 18.034 -182.6768)
		(end 16.3449 -184.3659)
		(width 0.12065)
		(layer "F.Cu")
		(net "MB0_TEMP")
	)
	(segment
		(start 16.3449 -184.3659)
		(end 16.3449 -184.91454)
		(width 0.12065)
		(layer "F.Cu")
		(net "MB0_TEMP")
	)
	(segment
		(start 19.2151 -182.6768)
		(end 18.034 -182.6768)
		(width 0.12065)
		(layer "F.Cu")
		(net "MB0_TEMP")
	)
	(via
		(at 18.034 -182.6768)
		(size 0.7112)
		(drill 0.3556)
		(layers "F.Cu" "B.Cu")
		(net "MB0_TEMP")
	)
	(segment
		(start 9.6012 -189.3316)
		(end 9.2202 -189.7126)
		(width 0.12065)
		(layer "F.Cu")
		(net "MB0_SPISS_PD")
	)
	(segment
		(start 9.6012 -189.3316)
		(end 10.51814 -188.41466)
		(width 0.12065)
		(layer "F.Cu")
		(net "MB0_SPISS_PD")
	)
	(segment
		(start 10.51814 -188.41466)
		(end 11.2395 -188.41466)
		(width 0.12065)
		(layer "F.Cu")
		(net "MB0_SPISS_PD")
	)
	(segment
		(start 9.2202 -189.7126)
		(end 7.2517 -189.7126)
		(width 0.12065)
		(layer "F.Cu")
		(net "MB0_SPISS_PD")
	)
	(via
		(at 9.6012 -189.3316)
		(size 0.7112)
		(drill 0.3556)
		(layers "F.Cu" "B.Cu")
		(net "MB0_SPISS_PD")
	)
	(segment
		(start 8.8392 -183.3626)
		(end 8.4582 -182.9816)
		(width 0.12065)
		(layer "F.Cu")
		(net "MB0_RETRY_R")
	)
	(segment
		(start 12.04214 -184.1119)
		(end 9.5885 -184.1119)
		(width 0.12065)
		(layer "F.Cu")
		(net "MB0_RETRY_R")
	)
	(segment
		(start 8.4582 -182.9816)
		(end 7.2517 -182.9816)
		(width 0.12065)
		(layer "F.Cu")
		(net "MB0_RETRY_R")
	)
	(segment
		(start 9.5885 -184.1119)
		(end 8.8392 -183.3626)
		(width 0.12065)
		(layer "F.Cu")
		(net "MB0_RETRY_R")
	)
	(via
		(at 8.8392 -183.3626)
		(size 0.7112)
		(drill 0.3556)
		(layers "F.Cu" "B.Cu")
		(net "MB0_RETRY_R")
	)
	(segment
		(start 16.51 -193.8147)
		(end 17.6911 -193.8147)
		(width 0.12065)
		(layer "F.Cu")
		(net "MB0_PSET_R")
	)
	(segment
		(start 15.54226 -190.14186)
		(end 15.54226 -189.2173)
		(width 0.12065)
		(layer "F.Cu")
		(net "MB0_PSET_R")
	)
	(segment
		(start 17.7292 -193.7766)
		(end 18.8087 -193.7766)
		(width 0.12065)
		(layer "F.Cu")
		(net "MB0_PSET_R")
	)
	(segment
		(start 16.51 -191.1096)
		(end 16.3576 -190.9572)
		(width 0.12065)
		(layer "F.Cu")
		(net "MB0_PSET_R")
	)
	(segment
		(start 16.51 -193.8147)
		(end 16.51 -191.1096)
		(width 0.12065)
		(layer "F.Cu")
		(net "MB0_PSET_R")
	)
	(segment
		(start 17.6911 -193.8147)
		(end 17.7292 -193.7766)
		(width 0.12065)
		(layer "F.Cu")
		(net "MB0_PSET_R")
	)
	(segment
		(start 18.8087 -193.7766)
		(end 18.8722 -193.7131)
		(width 0.12065)
		(layer "F.Cu")
		(net "MB0_PSET_R")
	)
	(segment
		(start 16.3576 -190.9572)
		(end 15.54226 -190.14186)
		(width 0.12065)
		(layer "F.Cu")
		(net "MB0_PSET_R")
	)
	(via
		(at 16.3576 -190.9572)
		(size 0.7112)
		(drill 0.3556)
		(layers "F.Cu" "B.Cu")
		(net "MB0_PSET_R")
	)
	(segment
		(start 30.1244 -193.675)
		(end 30.1244 -194.9704)
		(width 0.254)
		(layer "F.Cu")
		(net "MB0_P12V_R")
	)
	(segment
		(start 30.9245 -196.85)
		(end 30.9245 -195.7705)
		(width 0.508)
		(layer "F.Cu")
		(net "MB0_P12V_R")
	)
	(segment
		(start 30.9245 -195.7705)
		(end 30.353 -195.199)
		(width 0.508)
		(layer "F.Cu")
		(net "MB0_P12V_R")
	)
	(segment
		(start 30.1244 -194.9704)
		(end 30.353 -195.199)
		(width 0.254)
		(layer "F.Cu")
		(net "MB0_P12V_R")
	)
	(via
		(at 30.1244 -193.675)
		(size 0.7112)
		(drill 0.3556)
		(layers "F.Cu" "B.Cu")
		(net "MB0_P12V_R")
	)
	(segment
		(start 34.5694 -83.3882)
		(end 35.122866 -83.3882)
		(width 0.12065)
		(layer "F.Cu")
		(net "MB0_P12V_PWRGOOD")
	)
	(segment
		(start 7.9248 -181.0131)
		(end 8.6487 -181.0131)
		(width 0.12065)
		(layer "F.Cu")
		(net "MB0_P12V_PWRGOOD")
	)
	(segment
		(start 11.9126 -182.9054)
		(end 12.542266 -183.535066)
		(width 0.12065)
		(layer "F.Cu")
		(net "MB0_P12V_PWRGOOD")
	)
	(segment
		(start 12.542266 -183.535066)
		(end 12.542266 -184.1881)
		(width 0.12065)
		(layer "F.Cu")
		(net "MB0_P12V_PWRGOOD")
	)
	(segment
		(start 10.9982 -181.1401)
		(end 9.7155 -181.1401)
		(width 0.12065)
		(layer "F.Cu")
		(net "MB0_P12V_PWRGOOD")
	)
	(segment
		(start 38.206934 -83.295744)
		(end 40.62349 -83.295744)
		(width 0.12065)
		(layer "F.Cu")
		(net "MB0_P12V_PWRGOOD")
	)
	(segment
		(start 9.7155 -181.1401)
		(end 9.4742 -180.8988)
		(width 0.12065)
		(layer "F.Cu")
		(net "MB0_P12V_PWRGOOD")
	)
	(segment
		(start 38.206934 -83.302094)
		(end 38.206934 -83.295744)
		(width 0.12065)
		(layer "F.Cu")
		(net "MB0_P12V_PWRGOOD")
	)
	(segment
		(start 10.8204 -182.372)
		(end 10.8204 -181.3179)
		(width 0.12065)
		(layer "F.Cu")
		(net "MB0_P12V_PWRGOOD")
	)
	(segment
		(start 8.6487 -181.0131)
		(end 8.763 -180.8988)
		(width 0.12065)
		(layer "F.Cu")
		(net "MB0_P12V_PWRGOOD")
	)
	(segment
		(start 35.968178 -84.233512)
		(end 37.275516 -84.233512)
		(width 0.12065)
		(layer "F.Cu")
		(net "MB0_P12V_PWRGOOD")
	)
	(segment
		(start 10.8204 -182.372)
		(end 11.3538 -182.9054)
		(width 0.12065)
		(layer "F.Cu")
		(net "MB0_P12V_PWRGOOD")
	)
	(segment
		(start 8.763 -180.8988)
		(end 9.4742 -180.8988)
		(width 0.12065)
		(layer "F.Cu")
		(net "MB0_P12V_PWRGOOD")
	)
	(segment
		(start 10.8204 -181.3179)
		(end 10.9982 -181.1401)
		(width 0.12065)
		(layer "F.Cu")
		(net "MB0_P12V_PWRGOOD")
	)
	(segment
		(start 11.3538 -182.9054)
		(end 11.9126 -182.9054)
		(width 0.12065)
		(layer "F.Cu")
		(net "MB0_P12V_PWRGOOD")
	)
	(segment
		(start 37.275516 -84.233512)
		(end 38.206934 -83.302094)
		(width 0.12065)
		(layer "F.Cu")
		(net "MB0_P12V_PWRGOOD")
	)
	(segment
		(start 34.2392 -83.7184)
		(end 34.5694 -83.3882)
		(width 0.12065)
		(layer "F.Cu")
		(net "MB0_P12V_PWRGOOD")
	)
	(segment
		(start 35.122866 -83.3882)
		(end 35.968178 -84.233512)
		(width 0.12065)
		(layer "F.Cu")
		(net "MB0_P12V_PWRGOOD")
	)
	(segment
		(start 7.9248 -181.0131)
		(end 6.4008 -181.0131)
		(width 0.12065)
		(layer "F.Cu")
		(net "MB0_P12V_PWRGOOD")
	)
	(via
		(at 10.8204 -182.372)
		(size 0.7112)
		(drill 0.3556)
		(layers "F.Cu" "B.Cu")
		(net "MB0_P12V_PWRGOOD")
	)
	(via
		(at 6.4389 -98.806)
		(size 0.508)
		(drill 0.254)
		(layers "F.Cu" "B.Cu")
		(net "MB0_P12V_PWRGOOD")
	)
	(via
		(at 34.2392 -83.7184)
		(size 0.508)
		(drill 0.254)
		(layers "F.Cu" "B.Cu")
		(net "MB0_P12V_PWRGOOD")
	)
	(via
		(at 6.4008 -181.0131)
		(size 0.508)
		(drill 0.254)
		(layers "F.Cu" "B.Cu")
		(net "MB0_P12V_PWRGOOD")
	)
	(segment
		(start 34.2392 -83.46821)
		(end 33.333944 -82.562954)
		(width 0.12065)
		(layer "B.Cu")
		(net "MB0_P12V_PWRGOOD")
	)
	(segment
		(start 33.333944 -79.942944)
		(end 29.678884 -76.287884)
		(width 0.12065)
		(layer "B.Cu")
		(net "MB0_P12V_PWRGOOD")
	)
	(segment
		(start 34.2392 -83.7184)
		(end 34.2392 -83.46821)
		(width 0.12065)
		(layer "B.Cu")
		(net "MB0_P12V_PWRGOOD")
	)
	(segment
		(start 33.333944 -82.562954)
		(end 33.333944 -79.942944)
		(width 0.12065)
		(layer "B.Cu")
		(net "MB0_P12V_PWRGOOD")
	)
	(segment
		(start 26.797 -74.791062)
		(end 26.797 -73.9775)
		(width 0.12065)
		(layer "B.Cu")
		(net "MB0_P12V_PWRGOOD")
	)
	(segment
		(start 29.678884 -76.287884)
		(end 28.293822 -76.287884)
		(width 0.12065)
		(layer "B.Cu")
		(net "MB0_P12V_PWRGOOD")
	)
	(segment
		(start 28.293822 -76.287884)
		(end 26.797 -74.791062)
		(width 0.12065)
		(layer "B.Cu")
		(net "MB0_P12V_PWRGOOD")
	)
	(segment
		(start 34.2392 -83.7184)
		(end 25.654254 -83.7184)
		(width 0.127)
		(layer "In2.Cu")
		(net "MB0_P12V_PWRGOOD")
	)
	(segment
		(start 25.654254 -83.7184)
		(end 24.5237 -84.848954)
		(width 0.127)
		(layer "In2.Cu")
		(net "MB0_P12V_PWRGOOD")
	)
	(segment
		(start 21.1328 -88.5698)
		(end 18.218404 -88.5698)
		(width 0.127)
		(layer "In2.Cu")
		(net "MB0_P12V_PWRGOOD")
	)
	(segment
		(start 10.253472 -95.931482)
		(end 7.378954 -98.806)
		(width 0.127)
		(layer "In2.Cu")
		(net "MB0_P12V_PWRGOOD")
	)
	(segment
		(start 9.656064 -94.521782)
		(end 10.253472 -95.11919)
		(width 0.127)
		(layer "In2.Cu")
		(net "MB0_P12V_PWRGOOD")
	)
	(segment
		(start 10.508234 -93.279976)
		(end 9.656064 -94.132146)
		(width 0.127)
		(layer "In2.Cu")
		(net "MB0_P12V_PWRGOOD")
	)
	(segment
		(start 22.117812 -87.9475)
		(end 21.7551 -87.9475)
		(width 0.127)
		(layer "In2.Cu")
		(net "MB0_P12V_PWRGOOD")
	)
	(segment
		(start 24.5237 -84.848954)
		(end 24.5237 -85.541612)
		(width 0.127)
		(layer "In2.Cu")
		(net "MB0_P12V_PWRGOOD")
	)
	(segment
		(start 24.5237 -85.541612)
		(end 22.117812 -87.9475)
		(width 0.127)
		(layer "In2.Cu")
		(net "MB0_P12V_PWRGOOD")
	)
	(segment
		(start 10.253472 -95.11919)
		(end 10.253472 -95.931482)
		(width 0.127)
		(layer "In2.Cu")
		(net "MB0_P12V_PWRGOOD")
	)
	(segment
		(start 7.378954 -98.806)
		(end 6.4389 -98.806)
		(width 0.127)
		(layer "In2.Cu")
		(net "MB0_P12V_PWRGOOD")
	)
	(segment
		(start 9.656064 -94.132146)
		(end 9.656064 -94.521782)
		(width 0.127)
		(layer "In2.Cu")
		(net "MB0_P12V_PWRGOOD")
	)
	(segment
		(start 21.7551 -87.9475)
		(end 21.1328 -88.5698)
		(width 0.127)
		(layer "In2.Cu")
		(net "MB0_P12V_PWRGOOD")
	)
	(segment
		(start 13.508228 -93.279976)
		(end 10.508234 -93.279976)
		(width 0.127)
		(layer "In2.Cu")
		(net "MB0_P12V_PWRGOOD")
	)
	(segment
		(start 18.218404 -88.5698)
		(end 13.508228 -93.279976)
		(width 0.127)
		(layer "In2.Cu")
		(net "MB0_P12V_PWRGOOD")
	)
	(segment
		(start 6.4389 -98.806)
		(end 6.4516 -98.806)
		(width 0.127)
		(layer "In5.Cu")
		(net "MB0_P12V_PWRGOOD")
	)
	(segment
		(start 6.4516 -98.806)
		(end 6.4008 -98.8568)
		(width 0.127)
		(layer "In5.Cu")
		(net "MB0_P12V_PWRGOOD")
	)
	(segment
		(start 6.4008 -111.33709)
		(end 5.2578 -112.48009)
		(width 0.127)
		(layer "In5.Cu")
		(net "MB0_P12V_PWRGOOD")
	)
	(segment
		(start 5.2578 -112.48009)
		(end 5.2578 -179.8701)
		(width 0.127)
		(layer "In5.Cu")
		(net "MB0_P12V_PWRGOOD")
	)
	(segment
		(start 5.2578 -179.8701)
		(end 6.4008 -181.0131)
		(width 0.127)
		(layer "In5.Cu")
		(net "MB0_P12V_PWRGOOD")
	)
	(segment
		(start 6.4008 -98.8568)
		(end 6.4008 -111.33709)
		(width 0.127)
		(layer "In5.Cu")
		(net "MB0_P12V_PWRGOOD")
	)
	(segment
		(start 14.0716 -180.0733)
		(end 14.0589 -180.0606)
		(width 0.12065)
		(layer "F.Cu")
		(net "MB0_P12V_PWGIN_R")
	)
	(segment
		(start 13.6398 -183.064912)
		(end 14.042136 -183.467248)
		(width 0.12065)
		(layer "F.Cu")
		(net "MB0_P12V_PWGIN_R")
	)
	(segment
		(start 14.042136 -183.467248)
		(end 14.042136 -184.1881)
		(width 0.12065)
		(layer "F.Cu")
		(net "MB0_P12V_PWGIN_R")
	)
	(segment
		(start 14.0589 -181.102)
		(end 14.0716 -181.0893)
		(width 0.12065)
		(layer "F.Cu")
		(net "MB0_P12V_PWGIN_R")
	)
	(segment
		(start 13.8938 -181.9275)
		(end 13.6398 -182.1815)
		(width 0.12065)
		(layer "F.Cu")
		(net "MB0_P12V_PWGIN_R")
	)
	(segment
		(start 13.6398 -182.1815)
		(end 13.6398 -183.064912)
		(width 0.12065)
		(layer "F.Cu")
		(net "MB0_P12V_PWGIN_R")
	)
	(segment
		(start 13.8938 -181.2671)
		(end 13.8938 -181.9275)
		(width 0.12065)
		(layer "F.Cu")
		(net "MB0_P12V_PWGIN_R")
	)
	(segment
		(start 14.0716 -181.0893)
		(end 14.0716 -180.0733)
		(width 0.12065)
		(layer "F.Cu")
		(net "MB0_P12V_PWGIN_R")
	)
	(segment
		(start 14.0589 -181.102)
		(end 13.8938 -181.2671)
		(width 0.12065)
		(layer "F.Cu")
		(net "MB0_P12V_PWGIN_R")
	)
	(via
		(at 13.6398 -182.1815)
		(size 0.7112)
		(drill 0.3556)
		(layers "F.Cu" "B.Cu")
		(net "MB0_P12V_PWGIN_R")
	)
	(via
		(at 30.4292 -206.6798)
		(size 0.7112)
		(drill 0.3556)
		(layers "F.Cu" "B.Cu")
		(net "MB0_P12V_MAIN_R")
	)
	(segment
		(start 12.2047 -193.8401)
		(end 12.1412 -193.9036)
		(width 0.12065)
		(layer "F.Cu")
		(net "MB0_ISTART_R")
	)
	(segment
		(start 12.1412 -193.9036)
		(end 11.4554 -194.5894)
		(width 0.12065)
		(layer "F.Cu")
		(net "MB0_ISTART_R")
	)
	(segment
		(start 13.2842 -193.8401)
		(end 12.2047 -193.8401)
		(width 0.12065)
		(layer "F.Cu")
		(net "MB0_ISTART_R")
	)
	(segment
		(start 13.2842 -193.3956)
		(end 13.2842 -193.8401)
		(width 0.12065)
		(layer "F.Cu")
		(net "MB0_ISTART_R")
	)
	(segment
		(start 11.4554 -197.8152)
		(end 12.2682 -198.628)
		(width 0.12065)
		(layer "F.Cu")
		(net "MB0_ISTART_R")
	)
	(segment
		(start 12.9286 -192.024)
		(end 12.9286 -193.04)
		(width 0.12065)
		(layer "F.Cu")
		(net "MB0_ISTART_R")
	)
	(segment
		(start 11.4554 -194.5894)
		(end 11.4554 -197.8152)
		(width 0.12065)
		(layer "F.Cu")
		(net "MB0_ISTART_R")
	)
	(segment
		(start 12.2682 -198.628)
		(end 14.6304 -198.628)
		(width 0.12065)
		(layer "F.Cu")
		(net "MB0_ISTART_R")
	)
	(segment
		(start 14.042136 -190.529464)
		(end 14.042136 -189.1411)
		(width 0.12065)
		(layer "F.Cu")
		(net "MB0_ISTART_R")
	)
	(segment
		(start 12.9286 -193.04)
		(end 13.2842 -193.3956)
		(width 0.12065)
		(layer "F.Cu")
		(net "MB0_ISTART_R")
	)
	(segment
		(start 12.9286 -191.643)
		(end 14.042136 -190.529464)
		(width 0.12065)
		(layer "F.Cu")
		(net "MB0_ISTART_R")
	)
	(segment
		(start 14.6304 -198.628)
		(end 15.4432 -197.8152)
		(width 0.12065)
		(layer "F.Cu")
		(net "MB0_ISTART_R")
	)
	(segment
		(start 12.9286 -192.024)
		(end 12.9286 -191.643)
		(width 0.12065)
		(layer "F.Cu")
		(net "MB0_ISTART_R")
	)
	(segment
		(start 15.4432 -197.8152)
		(end 15.4432 -194.7037)
		(width 0.12065)
		(layer "F.Cu")
		(net "MB0_ISTART_R")
	)
	(via
		(at 12.9286 -192.024)
		(size 0.7112)
		(drill 0.3556)
		(layers "F.Cu" "B.Cu")
		(net "MB0_ISTART_R")
	)
	(segment
		(start 14.2494 -191.9986)
		(end 13.843 -192.405)
		(width 0.12065)
		(layer "F.Cu")
		(net "MB0_ISET_R")
	)
	(segment
		(start 14.542262 -191.705738)
		(end 14.542262 -189.1411)
		(width 0.12065)
		(layer "F.Cu")
		(net "MB0_ISET_R")
	)
	(segment
		(start 14.2494 -191.9986)
		(end 14.542262 -191.705738)
		(width 0.12065)
		(layer "F.Cu")
		(net "MB0_ISET_R")
	)
	(segment
		(start 14.4018 -195.7705)
		(end 14.3891 -195.7832)
		(width 0.12065)
		(layer "F.Cu")
		(net "MB0_ISET_R")
	)
	(segment
		(start 14.3891 -195.7832)
		(end 14.3891 -196.4563)
		(width 0.12065)
		(layer "F.Cu")
		(net "MB0_ISET_R")
	)
	(segment
		(start 14.4018 -194.7037)
		(end 14.4018 -195.7705)
		(width 0.12065)
		(layer "F.Cu")
		(net "MB0_ISET_R")
	)
	(segment
		(start 13.843 -194.1449)
		(end 14.4018 -194.7037)
		(width 0.12065)
		(layer "F.Cu")
		(net "MB0_ISET_R")
	)
	(segment
		(start 14.3891 -196.4563)
		(end 14.859 -196.9262)
		(width 0.12065)
		(layer "F.Cu")
		(net "MB0_ISET_R")
	)
	(segment
		(start 13.843 -192.405)
		(end 13.843 -194.1449)
		(width 0.12065)
		(layer "F.Cu")
		(net "MB0_ISET_R")
	)
	(via
		(at 14.2494 -191.9986)
		(size 0.7112)
		(drill 0.3556)
		(layers "F.Cu" "B.Cu")
		(net "MB0_ISET_R")
	)
	(segment
		(start 6.4262 -188.6331)
		(end 5.3975 -188.6331)
		(width 0.12065)
		(layer "F.Cu")
		(net "MB0_HS_ENABLE")
	)
	(segment
		(start 20.4978 -179.1081)
		(end 19.4183 -179.1081)
		(width 0.12065)
		(layer "F.Cu")
		(net "MB0_HS_ENABLE")
	)
	(segment
		(start 20.5613 -179.1716)
		(end 20.4978 -179.1081)
		(width 0.12065)
		(layer "F.Cu")
		(net "MB0_HS_ENABLE")
	)
	(segment
		(start 17.9705 -179.1081)
		(end 17.7038 -179.3748)
		(width 0.12065)
		(layer "F.Cu")
		(net "MB0_HS_ENABLE")
	)
	(segment
		(start 16.7894 -179.3748)
		(end 17.7038 -179.3748)
		(width 0.12065)
		(layer "F.Cu")
		(net "MB0_HS_ENABLE")
	)
	(segment
		(start 8.9662 -187.5536)
		(end 7.8867 -188.6331)
		(width 0.12065)
		(layer "F.Cu")
		(net "MB0_HS_ENABLE")
	)
	(segment
		(start 16.0782 -177.0888)
		(end 16.0782 -178.6636)
		(width 0.12065)
		(layer "F.Cu")
		(net "MB0_HS_ENABLE")
	)
	(segment
		(start 19.4183 -179.1081)
		(end 17.9705 -179.1081)
		(width 0.12065)
		(layer "F.Cu")
		(net "MB0_HS_ENABLE")
	)
	(segment
		(start 9.605264 -186.914536)
		(end 11.3157 -186.914536)
		(width 0.12065)
		(layer "F.Cu")
		(net "MB0_HS_ENABLE")
	)
	(segment
		(start 8.9662 -187.5536)
		(end 9.605264 -186.914536)
		(width 0.12065)
		(layer "F.Cu")
		(net "MB0_HS_ENABLE")
	)
	(segment
		(start 7.8867 -188.6331)
		(end 6.4262 -188.6331)
		(width 0.12065)
		(layer "F.Cu")
		(net "MB0_HS_ENABLE")
	)
	(segment
		(start 16.0782 -178.6636)
		(end 16.7894 -179.3748)
		(width 0.12065)
		(layer "F.Cu")
		(net "MB0_HS_ENABLE")
	)
	(via
		(at 8.9662 -187.5536)
		(size 0.7112)
		(drill 0.3556)
		(layers "F.Cu" "B.Cu")
		(net "MB0_HS_ENABLE")
	)
	(via
		(at 16.0782 -177.0888)
		(size 0.508)
		(drill 0.254)
		(layers "F.Cu" "B.Cu")
		(net "MB0_HS_ENABLE")
	)
	(via
		(at 5.3975 -188.6331)
		(size 0.508)
		(drill 0.254)
		(layers "F.Cu" "B.Cu")
		(net "MB0_HS_ENABLE")
	)
	(segment
		(start 6.1595 -187.8711)
		(end 6.1595 -183.5277)
		(width 0.127)
		(layer "In2.Cu")
		(net "MB0_HS_ENABLE")
	)
	(segment
		(start 6.1595 -183.5277)
		(end 5.79374 -183.16194)
		(width 0.127)
		(layer "In2.Cu")
		(net "MB0_HS_ENABLE")
	)
	(segment
		(start 8.0137 -177.90668)
		(end 10.08126 -177.90668)
		(width 0.127)
		(layer "In2.Cu")
		(net "MB0_HS_ENABLE")
	)
	(segment
		(start 10.89914 -177.0888)
		(end 16.0782 -177.0888)
		(width 0.127)
		(layer "In2.Cu")
		(net "MB0_HS_ENABLE")
	)
	(segment
		(start 5.79374 -183.16194)
		(end 5.79374 -180.12664)
		(width 0.127)
		(layer "In2.Cu")
		(net "MB0_HS_ENABLE")
	)
	(segment
		(start 5.79374 -180.12664)
		(end 8.0137 -177.90668)
		(width 0.127)
		(layer "In2.Cu")
		(net "MB0_HS_ENABLE")
	)
	(segment
		(start 10.08126 -177.90668)
		(end 10.89914 -177.0888)
		(width 0.127)
		(layer "In2.Cu")
		(net "MB0_HS_ENABLE")
	)
	(segment
		(start 5.3975 -188.6331)
		(end 6.1595 -187.8711)
		(width 0.127)
		(layer "In2.Cu")
		(net "MB0_HS_ENABLE")
	)
	(segment
		(start 13.0302 -181.1401)
		(end 12.0142 -181.1401)
		(width 0.12065)
		(layer "F.Cu")
		(net "MB0_CM_VOUT_R")
	)
	(segment
		(start 13.542264 -183.593994)
		(end 13.542264 -184.1881)
		(width 0.12065)
		(layer "F.Cu")
		(net "MB0_CM_VOUT_R")
	)
	(segment
		(start 12.0142 -182.06593)
		(end 12.0142 -181.1401)
		(width 0.12065)
		(layer "F.Cu")
		(net "MB0_CM_VOUT_R")
	)
	(segment
		(start 12.3698 -182.42153)
		(end 12.0142 -182.06593)
		(width 0.12065)
		(layer "F.Cu")
		(net "MB0_CM_VOUT_R")
	)
	(segment
		(start 12.3698 -182.42153)
		(end 13.542264 -183.593994)
		(width 0.12065)
		(layer "F.Cu")
		(net "MB0_CM_VOUT_R")
	)
	(via
		(at 12.3698 -182.42153)
		(size 0.7112)
		(drill 0.3556)
		(layers "F.Cu" "B.Cu")
		(net "MB0_CM_VOUT_R")
	)
	(segment
		(start 18.7452 -190.3984)
		(end 17.046448 -188.699648)
		(width 0.12065)
		(layer "F.Cu")
		(net "MB0_CM_UV_R")
	)
	(segment
		(start 16.838168 -187.914534)
		(end 16.2687 -187.914534)
		(width 0.12065)
		(layer "F.Cu")
		(net "MB0_CM_UV_R")
	)
	(segment
		(start 19.7866 -191.4398)
		(end 18.7452 -190.3984)
		(width 0.12065)
		(layer "F.Cu")
		(net "MB0_CM_UV_R")
	)
	(segment
		(start 20.2946 -189.2935)
		(end 20.2057 -189.2046)
		(width 0.12065)
		(layer "F.Cu")
		(net "MB0_CM_UV_R")
	)
	(segment
		(start 20.2057 -191.4398)
		(end 19.7866 -191.4398)
		(width 0.12065)
		(layer "F.Cu")
		(net "MB0_CM_UV_R")
	)
	(segment
		(start 17.046448 -188.699648)
		(end 17.046448 -188.122814)
		(width 0.12065)
		(layer "F.Cu")
		(net "MB0_CM_UV_R")
	)
	(segment
		(start 20.2057 -190.4111)
		(end 20.2946 -190.3222)
		(width 0.12065)
		(layer "F.Cu")
		(net "MB0_CM_UV_R")
	)
	(segment
		(start 17.046448 -188.122814)
		(end 16.838168 -187.914534)
		(width 0.12065)
		(layer "F.Cu")
		(net "MB0_CM_UV_R")
	)
	(segment
		(start 20.2057 -191.4398)
		(end 20.2057 -190.4111)
		(width 0.12065)
		(layer "F.Cu")
		(net "MB0_CM_UV_R")
	)
	(segment
		(start 20.2946 -190.3222)
		(end 20.2946 -189.2935)
		(width 0.12065)
		(layer "F.Cu")
		(net "MB0_CM_UV_R")
	)
	(via
		(at 18.7452 -190.3984)
		(size 0.7112)
		(drill 0.3556)
		(layers "F.Cu" "B.Cu")
		(net "MB0_CM_UV_R")
	)
	(segment
		(start 24.700992 -208.331562)
		(end 24.029162 -208.331562)
		(width 0.12065)
		(layer "F.Cu")
		(net "MB0_CM_SENSE_R1_P")
	)
	(segment
		(start 20.7899 -185.7502)
		(end 21.717 -185.7502)
		(width 0.12065)
		(layer "F.Cu")
		(net "MB0_CM_SENSE_R1_P")
	)
	(segment
		(start 21.717 -185.7502)
		(end 21.7932 -185.674)
		(width 0.12065)
		(layer "F.Cu")
		(net "MB0_CM_SENSE_R1_P")
	)
	(segment
		(start 24.029162 -208.331562)
		(end 23.6982 -208.0006)
		(width 0.12065)
		(layer "F.Cu")
		(net "MB0_CM_SENSE_R1_P")
	)
	(via
		(at 21.7932 -185.674)
		(size 0.508)
		(drill 0.254)
		(layers "F.Cu" "B.Cu")
		(net "MB0_CM_SENSE_R1_P")
	)
	(via
		(at 23.6982 -208.0006)
		(size 0.508)
		(drill 0.254)
		(layers "F.Cu" "B.Cu")
		(net "MB0_CM_SENSE_R1_P")
	)
	(segment
		(start 20.3581 -186.2582)
		(end 21.209 -186.2582)
		(width 0.12065)
		(layer "B.Cu")
		(net "MB0_CM_SENSE_R1_P")
	)
	(segment
		(start 21.209 -186.2582)
		(end 21.7932 -185.674)
		(width 0.12065)
		(layer "B.Cu")
		(net "MB0_CM_SENSE_R1_P")
	)
	(segment
		(start 23.9395 -187.524136)
		(end 22.089364 -185.674)
		(width 0.127)
		(layer "In5.Cu")
		(net "MB0_CM_SENSE_R1_P")
	)
	(segment
		(start 23.1775 -207.4799)
		(end 23.1775 -204.908912)
		(width 0.127)
		(layer "In5.Cu")
		(net "MB0_CM_SENSE_R1_P")
	)
	(segment
		(start 23.1775 -204.908912)
		(end 23.9395 -204.146912)
		(width 0.127)
		(layer "In5.Cu")
		(net "MB0_CM_SENSE_R1_P")
	)
	(segment
		(start 22.089364 -185.674)
		(end 21.7932 -185.674)
		(width 0.127)
		(layer "In5.Cu")
		(net "MB0_CM_SENSE_R1_P")
	)
	(segment
		(start 23.9395 -204.146912)
		(end 23.9395 -187.524136)
		(width 0.127)
		(layer "In5.Cu")
		(net "MB0_CM_SENSE_R1_P")
	)
	(segment
		(start 23.6982 -208.0006)
		(end 23.1775 -207.4799)
		(width 0.127)
		(layer "In5.Cu")
		(net "MB0_CM_SENSE_R1_P")
	)
	(segment
		(start 23.799038 -206.704438)
		(end 23.6474 -206.5528)
		(width 0.12065)
		(layer "F.Cu")
		(net "MB0_CM_SENSE_R1_N")
	)
	(segment
		(start 20.7899 -184.7342)
		(end 21.7424 -184.7342)
		(width 0.12065)
		(layer "F.Cu")
		(net "MB0_CM_SENSE_R1_N")
	)
	(segment
		(start 21.7424 -184.7342)
		(end 21.7932 -184.785)
		(width 0.12065)
		(layer "F.Cu")
		(net "MB0_CM_SENSE_R1_N")
	)
	(segment
		(start 24.700992 -206.704438)
		(end 23.799038 -206.704438)
		(width 0.12065)
		(layer "F.Cu")
		(net "MB0_CM_SENSE_R1_N")
	)
	(via
		(at 23.6474 -206.5528)
		(size 0.508)
		(drill 0.254)
		(layers "F.Cu" "B.Cu")
		(net "MB0_CM_SENSE_R1_N")
	)
	(via
		(at 21.7932 -184.785)
		(size 0.508)
		(drill 0.254)
		(layers "F.Cu" "B.Cu")
		(net "MB0_CM_SENSE_R1_N")
	)
	(segment
		(start 21.7932 -184.785)
		(end 20.8153 -184.785)
		(width 0.12065)
		(layer "B.Cu")
		(net "MB0_CM_SENSE_R1_N")
	)
	(segment
		(start 20.8153 -184.785)
		(end 20.3581 -185.2422)
		(width 0.12065)
		(layer "B.Cu")
		(net "MB0_CM_SENSE_R1_N")
	)
	(segment
		(start 24.3586 -204.3684)
		(end 24.3586 -187.3504)
		(width 0.127)
		(layer "In5.Cu")
		(net "MB0_CM_SENSE_R1_N")
	)
	(segment
		(start 23.6474 -206.5528)
		(end 23.6474 -205.0796)
		(width 0.127)
		(layer "In5.Cu")
		(net "MB0_CM_SENSE_R1_N")
	)
	(segment
		(start 23.6474 -205.0796)
		(end 24.3586 -204.3684)
		(width 0.127)
		(layer "In5.Cu")
		(net "MB0_CM_SENSE_R1_N")
	)
	(segment
		(start 24.3586 -187.3504)
		(end 21.7932 -184.785)
		(width 0.127)
		(layer "In5.Cu")
		(net "MB0_CM_SENSE_R1_N")
	)
	(segment
		(start 17.30248 -186.914536)
		(end 17.39011 -187.002166)
		(width 0.12065)
		(layer "F.Cu")
		(net "MB0_CM_SENSE_P")
	)
	(segment
		(start 16.2687 -186.914536)
		(end 17.30248 -186.914536)
		(width 0.12065)
		(layer "F.Cu")
		(net "MB0_CM_SENSE_P")
	)
	(via
		(at 17.39011 -187.002166)
		(size 0.508)
		(drill 0.254)
		(layers "F.Cu" "B.Cu")
		(net "MB0_CM_SENSE_P")
	)
	(segment
		(start 18.5166 -186.1947)
		(end 18.197576 -186.1947)
		(width 0.12065)
		(layer "B.Cu")
		(net "MB0_CM_SENSE_P")
	)
	(segment
		(start 18.197576 -186.1947)
		(end 17.39011 -187.002166)
		(width 0.12065)
		(layer "B.Cu")
		(net "MB0_CM_SENSE_P")
	)
	(segment
		(start 19.4691 -186.2582)
		(end 18.5801 -186.2582)
		(width 0.12065)
		(layer "B.Cu")
		(net "MB0_CM_SENSE_P")
	)
	(segment
		(start 18.5801 -186.2582)
		(end 18.5166 -186.1947)
		(width 0.12065)
		(layer "B.Cu")
		(net "MB0_CM_SENSE_P")
	)
	(segment
		(start 17.5006 -185.42)
		(end 17.4498 -185.42)
		(width 0.12065)
		(layer "F.Cu")
		(net "MB0_CM_SENSE_N")
	)
	(segment
		(start 17.444466 -185.414666)
		(end 16.2687 -185.414666)
		(width 0.12065)
		(layer "F.Cu")
		(net "MB0_CM_SENSE_N")
	)
	(segment
		(start 17.4498 -185.42)
		(end 17.444466 -185.414666)
		(width 0.12065)
		(layer "F.Cu")
		(net "MB0_CM_SENSE_N")
	)
	(via
		(at 17.5006 -185.42)
		(size 0.508)
		(drill 0.254)
		(layers "F.Cu" "B.Cu")
		(net "MB0_CM_SENSE_N")
	)
	(segment
		(start 17.6149 -185.3057)
		(end 17.5006 -185.42)
		(width 0.12065)
		(layer "B.Cu")
		(net "MB0_CM_SENSE_N")
	)
	(segment
		(start 18.5166 -185.3057)
		(end 19.4056 -185.3057)
		(width 0.12065)
		(layer "B.Cu")
		(net "MB0_CM_SENSE_N")
	)
	(segment
		(start 18.5166 -185.3057)
		(end 17.6149 -185.3057)
		(width 0.12065)
		(layer "B.Cu")
		(net "MB0_CM_SENSE_N")
	)
	(segment
		(start 19.4056 -185.3057)
		(end 19.4691 -185.2422)
		(width 0.12065)
		(layer "B.Cu")
		(net "MB0_CM_SENSE_N")
	)
	(segment
		(start 20.2057 -192.5066)
		(end 19.4564 -192.5066)
		(width 0.12065)
		(layer "F.Cu")
		(net "MB0_CM_OV_R")
	)
	(segment
		(start 20.2692 -193.6496)
		(end 20.2692 -194.7291)
		(width 0.12065)
		(layer "F.Cu")
		(net "MB0_CM_OV_R")
	)
	(segment
		(start 19.4564 -192.5066)
		(end 18.7706 -191.8208)
		(width 0.12065)
		(layer "F.Cu")
		(net "MB0_CM_OV_R")
	)
	(segment
		(start 16.3449 -188.8363)
		(end 16.3449 -188.41466)
		(width 0.12065)
		(layer "F.Cu")
		(net "MB0_CM_OV_R")
	)
	(segment
		(start 20.2057 -193.5861)
		(end 20.2692 -193.6496)
		(width 0.12065)
		(layer "F.Cu")
		(net "MB0_CM_OV_R")
	)
	(segment
		(start 17.2212 -189.7126)
		(end 16.3449 -188.8363)
		(width 0.12065)
		(layer "F.Cu")
		(net "MB0_CM_OV_R")
	)
	(segment
		(start 20.2057 -192.5066)
		(end 20.2057 -193.5861)
		(width 0.12065)
		(layer "F.Cu")
		(net "MB0_CM_OV_R")
	)
	(segment
		(start 18.7706 -191.8208)
		(end 17.2212 -190.2714)
		(width 0.12065)
		(layer "F.Cu")
		(net "MB0_CM_OV_R")
	)
	(segment
		(start 17.2212 -190.2714)
		(end 17.2212 -189.7126)
		(width 0.12065)
		(layer "F.Cu")
		(net "MB0_CM_OV_R")
	)
	(segment
		(start 20.2692 -194.7291)
		(end 20.2057 -194.7926)
		(width 0.12065)
		(layer "F.Cu")
		(net "MB0_CM_OV_R")
	)
	(via
		(at 18.7706 -191.8208)
		(size 0.7112)
		(drill 0.3556)
		(layers "F.Cu" "B.Cu")
		(net "MB0_CM_OV_R")
	)
	(segment
		(start 30.48 -191.0334)
		(end 30.607 -191.0334)
		(width 0.12065)
		(layer "F.Cu")
		(net "MB0_CM_GATE_R")
	)
	(segment
		(start 31.1658 -192.1002)
		(end 31.1658 -191.4398)
		(width 0.12065)
		(layer "F.Cu")
		(net "MB0_CM_GATE_R")
	)
	(segment
		(start 30.0355 -191.4779)
		(end 30.48 -191.0334)
		(width 0.12065)
		(layer "F.Cu")
		(net "MB0_CM_GATE_R")
	)
	(segment
		(start 30.0355 -192.024)
		(end 30.0355 -191.4779)
		(width 0.12065)
		(layer "F.Cu")
		(net "MB0_CM_GATE_R")
	)
	(segment
		(start 30.7594 -191.0334)
		(end 30.607 -191.0334)
		(width 0.12065)
		(layer "F.Cu")
		(net "MB0_CM_GATE_R")
	)
	(segment
		(start 32.639 -196.7865)
		(end 32.639 -195.199)
		(width 0.12065)
		(layer "F.Cu")
		(net "MB0_CM_GATE_R")
	)
	(segment
		(start 31.1658 -193.3702)
		(end 31.1658 -193.7258)
		(width 0.12065)
		(layer "F.Cu")
		(net "MB0_CM_GATE_R")
	)
	(segment
		(start 31.1658 -193.3702)
		(end 31.1658 -192.1002)
		(width 0.12065)
		(layer "F.Cu")
		(net "MB0_CM_GATE_R")
	)
	(segment
		(start 31.1658 -191.4398)
		(end 30.7594 -191.0334)
		(width 0.12065)
		(layer "F.Cu")
		(net "MB0_CM_GATE_R")
	)
	(segment
		(start 31.1658 -193.7258)
		(end 32.639 -195.199)
		(width 0.12065)
		(layer "F.Cu")
		(net "MB0_CM_GATE_R")
	)
	(segment
		(start 32.004 -197.4215)
		(end 32.639 -196.7865)
		(width 0.12065)
		(layer "F.Cu")
		(net "MB0_CM_GATE_R")
	)
	(via
		(at 30.607 -191.0334)
		(size 0.7112)
		(drill 0.3556)
		(layers "F.Cu" "B.Cu")
		(net "MB0_CM_GATE_R")
	)
	(segment
		(start 29.1465 -192.024)
		(end 28.2702 -192.024)
		(width 0.12065)
		(layer "F.Cu")
		(net "MB0_CM_GATE")
	)
	(segment
		(start 17.9578 -181.356)
		(end 17.3736 -181.9402)
		(width 0.12065)
		(layer "F.Cu")
		(net "MB0_CM_GATE")
	)
	(segment
		(start 18.1102 -181.2036)
		(end 17.9578 -181.356)
		(width 0.12065)
		(layer "F.Cu")
		(net "MB0_CM_GATE")
	)
	(segment
		(start 17.3736 -182.6768)
		(end 15.9385 -184.1119)
		(width 0.12065)
		(layer "F.Cu")
		(net "MB0_CM_GATE")
	)
	(segment
		(start 17.3736 -181.9402)
		(end 17.3736 -182.6768)
		(width 0.12065)
		(layer "F.Cu")
		(net "MB0_CM_GATE")
	)
	(segment
		(start 15.9385 -184.1119)
		(end 15.54226 -184.1119)
		(width 0.12065)
		(layer "F.Cu")
		(net "MB0_CM_GATE")
	)
	(segment
		(start 18.923 -181.2036)
		(end 18.1102 -181.2036)
		(width 0.12065)
		(layer "F.Cu")
		(net "MB0_CM_GATE")
	)
	(via
		(at 17.9578 -181.356)
		(size 0.7112)
		(drill 0.3556)
		(layers "F.Cu" "B.Cu")
		(net "MB0_CM_GATE")
	)
	(via
		(at 28.2702 -192.024)
		(size 0.508)
		(drill 0.254)
		(layers "F.Cu" "B.Cu")
		(net "MB0_CM_GATE")
	)
	(via
		(at 18.923 -181.2036)
		(size 0.508)
		(drill 0.254)
		(layers "F.Cu" "B.Cu")
		(net "MB0_CM_GATE")
	)
	(segment
		(start 24.7904 -187.049918)
		(end 20.645882 -182.9054)
		(width 0.127)
		(layer "In5.Cu")
		(net "MB0_CM_GATE")
	)
	(segment
		(start 24.7904 -188.5442)
		(end 24.7904 -187.049918)
		(width 0.127)
		(layer "In5.Cu")
		(net "MB0_CM_GATE")
	)
	(segment
		(start 20.645882 -182.9054)
		(end 19.6596 -182.9054)
		(width 0.127)
		(layer "In5.Cu")
		(net "MB0_CM_GATE")
	)
	(segment
		(start 18.923 -182.1688)
		(end 18.923 -181.2036)
		(width 0.127)
		(layer "In5.Cu")
		(net "MB0_CM_GATE")
	)
	(segment
		(start 28.2702 -192.024)
		(end 24.7904 -188.5442)
		(width 0.127)
		(layer "In5.Cu")
		(net "MB0_CM_GATE")
	)
	(segment
		(start 19.6596 -182.9054)
		(end 18.923 -182.1688)
		(width 0.127)
		(layer "In5.Cu")
		(net "MB0_CM_GATE")
	)
	(segment
		(start 12.04214 -190.11646)
		(end 11.6332 -190.5254)
		(width 0.12065)
		(layer "F.Cu")
		(net "MB0_CM_ADR2_R")
	)
	(segment
		(start 11.6332 -190.5254)
		(end 10.4902 -190.5254)
		(width 0.12065)
		(layer "F.Cu")
		(net "MB0_CM_ADR2_R")
	)
	(segment
		(start 10.4902 -190.5254)
		(end 8.89 -192.1256)
		(width 0.12065)
		(layer "F.Cu")
		(net "MB0_CM_ADR2_R")
	)
	(segment
		(start 8.89 -193.8909)
		(end 8.89 -192.1256)
		(width 0.12065)
		(layer "F.Cu")
		(net "MB0_CM_ADR2_R")
	)
	(segment
		(start 12.04214 -189.2173)
		(end 12.04214 -190.11646)
		(width 0.12065)
		(layer "F.Cu")
		(net "MB0_CM_ADR2_R")
	)
	(via
		(at 8.89 -192.1256)
		(size 0.7112)
		(drill 0.3556)
		(layers "F.Cu" "B.Cu")
		(net "MB0_CM_ADR2_R")
	)
	(segment
		(start 12.542266 -189.1411)
		(end 12.542266 -190.302134)
		(width 0.12065)
		(layer "F.Cu")
		(net "MB0_CM_ADR1_R")
	)
	(segment
		(start 11.0998 -191.1858)
		(end 10.2108 -192.0748)
		(width 0.12065)
		(layer "F.Cu")
		(net "MB0_CM_ADR1_R")
	)
	(segment
		(start 9.906 -193.8909)
		(end 9.906 -192.3796)
		(width 0.12065)
		(layer "F.Cu")
		(net "MB0_CM_ADR1_R")
	)
	(segment
		(start 11.6586 -191.1858)
		(end 11.0998 -191.1858)
		(width 0.12065)
		(layer "F.Cu")
		(net "MB0_CM_ADR1_R")
	)
	(segment
		(start 12.542266 -190.302134)
		(end 11.6586 -191.1858)
		(width 0.12065)
		(layer "F.Cu")
		(net "MB0_CM_ADR1_R")
	)
	(segment
		(start 9.906 -192.3796)
		(end 10.2108 -192.0748)
		(width 0.12065)
		(layer "F.Cu")
		(net "MB0_CM_ADR1_R")
	)
	(via
		(at 10.2108 -192.0748)
		(size 0.7112)
		(drill 0.3556)
		(layers "F.Cu" "B.Cu")
		(net "MB0_CM_ADR1_R")
	)
	(segment
		(start 32.004 -198.3105)
		(end 32.004 -199.3646)
		(width 0.12065)
		(layer "F.Cu")
		(net "MB0_12V_CTRL_GATE1")
	)
	(segment
		(start 32.004 -199.3646)
		(end 31.9786 -199.39)
		(width 0.12065)
		(layer "F.Cu")
		(net "MB0_12V_CTRL_GATE1")
	)
	(segment
		(start 30.0228 -198.7042)
		(end 30.7086 -199.39)
		(width 0.12065)
		(layer "F.Cu")
		(net "MB0_12V_CTRL_GATE1")
	)
	(segment
		(start 30.7086 -199.39)
		(end 31.9786 -199.39)
		(width 0.12065)
		(layer "F.Cu")
		(net "MB0_12V_CTRL_GATE1")
	)
	(via
		(at 31.9786 -199.39)
		(size 0.7112)
		(drill 0.3556)
		(layers "F.Cu" "B.Cu")
		(net "MB0_12V_CTRL_GATE1")
	)
	(segment
		(start 250.994418 -4.721098)
		(end 252.082808 -4.721098)
		(width 0.12065)
		(layer "F.Cu")
		(net "MAX6654_ALERT#")
	)
	(segment
		(start 252.082808 -4.721098)
		(end 252.10516 -4.74345)
		(width 0.12065)
		(layer "F.Cu")
		(net "MAX6654_ALERT#")
	)
	(segment
		(start 254.572262 -4.79933)
		(end 254.169418 -5.202174)
		(width 0.12065)
		(layer "F.Cu")
		(net "MAX6654_ALERT#")
	)
	(segment
		(start 252.53569 -5.202174)
		(end 252.10516 -4.771644)
		(width 0.12065)
		(layer "F.Cu")
		(net "MAX6654_ALERT#")
	)
	(segment
		(start 254.572262 -3.481578)
		(end 254.572262 -4.79933)
		(width 0.12065)
		(layer "F.Cu")
		(net "MAX6654_ALERT#")
	)
	(segment
		(start 252.10516 -4.771644)
		(end 252.10516 -4.74345)
		(width 0.12065)
		(layer "F.Cu")
		(net "MAX6654_ALERT#")
	)
	(segment
		(start 254.169418 -5.202174)
		(end 252.53569 -5.202174)
		(width 0.12065)
		(layer "F.Cu")
		(net "MAX6654_ALERT#")
	)
	(segment
		(start 254.572262 -9.543034)
		(end 254.572262 -8.713978)
		(width 0.12065)
		(layer "F.Cu")
		(net "MAX6654_ADD1")
	)
	(segment
		(start 252.777244 -9.412224)
		(end 253.272036 -9.907016)
		(width 0.12065)
		(layer "F.Cu")
		(net "MAX6654_ADD1")
	)
	(segment
		(start 252.102874 -10.814304)
		(end 252.936248 -10.814304)
		(width 0.12065)
		(layer "F.Cu")
		(net "MAX6654_ADD1")
	)
	(segment
		(start 253.272036 -9.907016)
		(end 254.20828 -9.907016)
		(width 0.12065)
		(layer "F.Cu")
		(net "MAX6654_ADD1")
	)
	(segment
		(start 254.20828 -9.907016)
		(end 254.572262 -9.543034)
		(width 0.12065)
		(layer "F.Cu")
		(net "MAX6654_ADD1")
	)
	(segment
		(start 251.671836 -9.708896)
		(end 251.671836 -10.383266)
		(width 0.12065)
		(layer "F.Cu")
		(net "MAX6654_ADD1")
	)
	(segment
		(start 251.968508 -9.412224)
		(end 252.777244 -9.412224)
		(width 0.12065)
		(layer "F.Cu")
		(net "MAX6654_ADD1")
	)
	(segment
		(start 252.936248 -10.814304)
		(end 253.04242 -10.920476)
		(width 0.12065)
		(layer "F.Cu")
		(net "MAX6654_ADD1")
	)
	(segment
		(start 251.968508 -9.412224)
		(end 251.671836 -9.708896)
		(width 0.12065)
		(layer "F.Cu")
		(net "MAX6654_ADD1")
	)
	(segment
		(start 251.671836 -10.383266)
		(end 252.102874 -10.814304)
		(width 0.12065)
		(layer "F.Cu")
		(net "MAX6654_ADD1")
	)
	(via
		(at 251.968508 -9.412224)
		(size 0.7112)
		(drill 0.3556)
		(layers "F.Cu" "B.Cu")
		(net "MAX6654_ADD1")
	)
	(segment
		(start 253.788926 -4.502912)
		(end 253.016766 -4.502912)
		(width 0.12065)
		(layer "F.Cu")
		(net "MAX6654_ADD0")
	)
	(segment
		(start 253.016766 -4.502912)
		(end 252.110494 -3.59664)
		(width 0.12065)
		(layer "F.Cu")
		(net "MAX6654_ADD0")
	)
	(segment
		(start 253.937262 -4.354576)
		(end 253.788926 -4.502912)
		(width 0.12065)
		(layer "F.Cu")
		(net "MAX6654_ADD0")
	)
	(segment
		(start 252.110494 -3.59664)
		(end 252.085094 -3.59664)
		(width 0.12065)
		(layer "F.Cu")
		(net "MAX6654_ADD0")
	)
	(segment
		(start 253.937262 -3.481578)
		(end 253.937262 -4.354576)
		(width 0.12065)
		(layer "F.Cu")
		(net "MAX6654_ADD0")
	)
	(segment
		(start 21.844 -178.4858)
		(end 21.7043 -178.3461)
		(width 0.12065)
		(layer "F.Cu")
		(net "MATED_P12V_EN")
	)
	(segment
		(start 21.717 -179.5272)
		(end 21.844 -179.4002)
		(width 0.12065)
		(layer "F.Cu")
		(net "MATED_P12V_EN")
	)
	(segment
		(start 21.7043 -176.7586)
		(end 21.7043 -178.3461)
		(width 0.12065)
		(layer "F.Cu")
		(net "MATED_P12V_EN")
	)
	(segment
		(start 21.082 -178.8033)
		(end 20.5613 -178.2826)
		(width 0.12065)
		(layer "F.Cu")
		(net "MATED_P12V_EN")
	)
	(segment
		(start 21.8313 -176.6316)
		(end 21.7043 -176.7586)
		(width 0.12065)
		(layer "F.Cu")
		(net "MATED_P12V_EN")
	)
	(segment
		(start 21.082 -179.197)
		(end 21.082 -178.8033)
		(width 0.12065)
		(layer "F.Cu")
		(net "MATED_P12V_EN")
	)
	(segment
		(start 25.3873 -176.6316)
		(end 21.8313 -176.6316)
		(width 0.12065)
		(layer "F.Cu")
		(net "MATED_P12V_EN")
	)
	(segment
		(start 21.844 -179.4002)
		(end 21.844 -178.4858)
		(width 0.12065)
		(layer "F.Cu")
		(net "MATED_P12V_EN")
	)
	(segment
		(start 21.4122 -179.5272)
		(end 21.082 -179.197)
		(width 0.12065)
		(layer "F.Cu")
		(net "MATED_P12V_EN")
	)
	(segment
		(start 21.717 -179.5272)
		(end 21.4122 -179.5272)
		(width 0.12065)
		(layer "F.Cu")
		(net "MATED_P12V_EN")
	)
	(via
		(at 21.717 -179.5272)
		(size 0.7112)
		(drill 0.3556)
		(layers "F.Cu" "B.Cu")
		(net "MATED_P12V_EN")
	)
	(segment
		(start 44.904914 -128.484884)
		(end 45.30471 -128.085088)
		(width 0.12065)
		(layer "F.Cu")
		(net "LOW_HEX_3")
	)
	(via
		(at 81.797144 -117.652292)
		(size 0.508)
		(drill 0.254)
		(layers "F.Cu" "B.Cu")
		(net "LOW_HEX_3")
	)
	(via
		(at 45.30471 -128.085088)
		(size 0.4572)
		(drill 0.2032)
		(layers "F.Cu" "B.Cu")
		(net "LOW_HEX_3")
	)
	(via
		(at 91.023948 -91.858846)
		(size 0.508)
		(drill 0.254)
		(layers "F.Cu" "B.Cu")
		(net "LOW_HEX_3")
	)
	(segment
		(start 82.513424 -116.936012)
		(end 81.797144 -117.652292)
		(width 0.12065)
		(layer "B.Cu")
		(net "LOW_HEX_3")
	)
	(segment
		(start 91.023948 -96.929956)
		(end 82.513424 -105.44048)
		(width 0.12065)
		(layer "B.Cu")
		(net "LOW_HEX_3")
	)
	(segment
		(start 91.023948 -91.858846)
		(end 91.023948 -96.929956)
		(width 0.12065)
		(layer "B.Cu")
		(net "LOW_HEX_3")
	)
	(segment
		(start 82.513424 -105.44048)
		(end 82.513424 -116.936012)
		(width 0.12065)
		(layer "B.Cu")
		(net "LOW_HEX_3")
	)
	(segment
		(start 178.07559 -5.82041)
		(end 133.971792 -5.82041)
		(width 0.127)
		(layer "In2.Cu")
		(net "LOW_HEX_3")
	)
	(segment
		(start 193.691764 -8.6868)
		(end 192.675764 -7.6708)
		(width 0.127)
		(layer "In2.Cu")
		(net "LOW_HEX_3")
	)
	(segment
		(start 60.925456 -129.83972)
		(end 57.668414 -129.83972)
		(width 0.127)
		(layer "In2.Cu")
		(net "LOW_HEX_3")
	)
	(segment
		(start 48.938688 -128.262888)
		(end 45.48251 -128.262888)
		(width 0.127)
		(layer "In2.Cu")
		(net "LOW_HEX_3")
	)
	(segment
		(start 81.797144 -117.652292)
		(end 75.862942 -123.586494)
		(width 0.127)
		(layer "In2.Cu")
		(net "LOW_HEX_3")
	)
	(segment
		(start 233.673904 -6.611112)
		(end 225.83267 -6.611112)
		(width 0.127)
		(layer "In2.Cu")
		(net "LOW_HEX_3")
	)
	(segment
		(start 186.165998 -6.410198)
		(end 185.572654 -5.816854)
		(width 0.127)
		(layer "In2.Cu")
		(net "LOW_HEX_3")
	)
	(segment
		(start 102.209346 -74.703432)
		(end 102.209346 -76.431648)
		(width 0.127)
		(layer "In2.Cu")
		(net "LOW_HEX_3")
	)
	(segment
		(start 225.83267 -6.611112)
		(end 223.425258 -4.2037)
		(width 0.127)
		(layer "In2.Cu")
		(net "LOW_HEX_3")
	)
	(segment
		(start 75.504294 -123.586494)
		(end 73.311004 -125.779784)
		(width 0.127)
		(layer "In2.Cu")
		(net "LOW_HEX_3")
	)
	(segment
		(start 119.786654 -20.000976)
		(end 119.096028 -20.000976)
		(width 0.127)
		(layer "In2.Cu")
		(net "LOW_HEX_3")
	)
	(segment
		(start 102.209346 -76.431648)
		(end 99.5934 -79.04861)
		(width 0.127)
		(layer "In2.Cu")
		(net "LOW_HEX_3")
	)
	(segment
		(start 178.312826 -6.057646)
		(end 178.07559 -5.82041)
		(width 0.127)
		(layer "In2.Cu")
		(net "LOW_HEX_3")
	)
	(segment
		(start 55.626 -128.6002)
		(end 54.61 -129.6162)
		(width 0.127)
		(layer "In2.Cu")
		(net "LOW_HEX_3")
	)
	(segment
		(start 223.425258 -4.2037)
		(end 209.2452 -4.2037)
		(width 0.127)
		(layer "In2.Cu")
		(net "LOW_HEX_3")
	)
	(segment
		(start 241.550444 -1.500632)
		(end 242.375944 -2.326132)
		(width 0.127)
		(layer "In2.Cu")
		(net "LOW_HEX_3")
	)
	(segment
		(start 233.921046 -6.36397)
		(end 233.673904 -6.611112)
		(width 0.127)
		(layer "In2.Cu")
		(net "LOW_HEX_3")
	)
	(segment
		(start 119.096028 -20.000976)
		(end 119.09552 -20.000722)
		(width 0.127)
		(layer "In2.Cu")
		(net "LOW_HEX_3")
	)
	(segment
		(start 188.638942 -6.410198)
		(end 186.165998 -6.410198)
		(width 0.127)
		(layer "In2.Cu")
		(net "LOW_HEX_3")
	)
	(segment
		(start 115.521486 -20.000722)
		(end 99.56419 -35.958018)
		(width 0.127)
		(layer "In2.Cu")
		(net "LOW_HEX_3")
	)
	(segment
		(start 71.59371 -125.779784)
		(end 68.220082 -129.153412)
		(width 0.127)
		(layer "In2.Cu")
		(net "LOW_HEX_3")
	)
	(segment
		(start 45.48251 -128.262888)
		(end 45.30471 -128.085088)
		(width 0.127)
		(layer "In2.Cu")
		(net "LOW_HEX_3")
	)
	(segment
		(start 191.240918 -7.670292)
		(end 189.89929 -7.670292)
		(width 0.127)
		(layer "In2.Cu")
		(net "LOW_HEX_3")
	)
	(segment
		(start 204.7621 -8.6868)
		(end 193.691764 -8.6868)
		(width 0.127)
		(layer "In2.Cu")
		(net "LOW_HEX_3")
	)
	(segment
		(start 133.966966 -5.825236)
		(end 119.786654 -20.000976)
		(width 0.127)
		(layer "In2.Cu")
		(net "LOW_HEX_3")
	)
	(segment
		(start 68.220082 -129.350516)
		(end 68.219828 -130.214624)
		(width 0.127)
		(layer "In2.Cu")
		(net "LOW_HEX_3")
	)
	(segment
		(start 99.56419 -46.834044)
		(end 102.2096 -49.479454)
		(width 0.127)
		(layer "In2.Cu")
		(net "LOW_HEX_3")
	)
	(segment
		(start 242.375944 -3.84175)
		(end 239.853724 -6.36397)
		(width 0.127)
		(layer "In2.Cu")
		(net "LOW_HEX_3")
	)
	(segment
		(start 56.428894 -128.6002)
		(end 55.626 -128.6002)
		(width 0.127)
		(layer "In2.Cu")
		(net "LOW_HEX_3")
	)
	(segment
		(start 73.311004 -125.779784)
		(end 71.59371 -125.779784)
		(width 0.127)
		(layer "In2.Cu")
		(net "LOW_HEX_3")
	)
	(segment
		(start 68.219828 -130.214624)
		(end 67.356228 -131.078224)
		(width 0.127)
		(layer "In2.Cu")
		(net "LOW_HEX_3")
	)
	(segment
		(start 119.09552 -20.000722)
		(end 115.521486 -20.000722)
		(width 0.127)
		(layer "In2.Cu")
		(net "LOW_HEX_3")
	)
	(segment
		(start 182.82285 -6.057646)
		(end 178.312826 -6.057646)
		(width 0.127)
		(layer "In2.Cu")
		(net "LOW_HEX_3")
	)
	(segment
		(start 54.61 -129.6162)
		(end 50.292 -129.6162)
		(width 0.127)
		(layer "In2.Cu")
		(net "LOW_HEX_3")
	)
	(segment
		(start 102.2096 -71.785226)
		(end 102.209346 -74.703432)
		(width 0.127)
		(layer "In2.Cu")
		(net "LOW_HEX_3")
	)
	(segment
		(start 68.220082 -129.153412)
		(end 68.220082 -129.350516)
		(width 0.127)
		(layer "In2.Cu")
		(net "LOW_HEX_3")
	)
	(segment
		(start 67.356228 -131.078224)
		(end 62.16396 -131.078224)
		(width 0.127)
		(layer "In2.Cu")
		(net "LOW_HEX_3")
	)
	(segment
		(start 189.89929 -7.670292)
		(end 188.638942 -6.410198)
		(width 0.127)
		(layer "In2.Cu")
		(net "LOW_HEX_3")
	)
	(segment
		(start 91.023948 -90.705686)
		(end 91.023948 -91.858846)
		(width 0.127)
		(layer "In2.Cu")
		(net "LOW_HEX_3")
	)
	(segment
		(start 50.292 -129.6162)
		(end 48.938688 -128.262888)
		(width 0.127)
		(layer "In2.Cu")
		(net "LOW_HEX_3")
	)
	(segment
		(start 57.668414 -129.83972)
		(end 56.428894 -128.6002)
		(width 0.127)
		(layer "In2.Cu")
		(net "LOW_HEX_3")
	)
	(segment
		(start 62.16396 -131.078224)
		(end 60.925456 -129.83972)
		(width 0.127)
		(layer "In2.Cu")
		(net "LOW_HEX_3")
	)
	(segment
		(start 183.063642 -5.816854)
		(end 182.82285 -6.057646)
		(width 0.127)
		(layer "In2.Cu")
		(net "LOW_HEX_3")
	)
	(segment
		(start 102.2096 -49.479454)
		(end 102.2096 -71.785226)
		(width 0.127)
		(layer "In2.Cu")
		(net "LOW_HEX_3")
	)
	(segment
		(start 75.862942 -123.586494)
		(end 75.504294 -123.586494)
		(width 0.127)
		(layer "In2.Cu")
		(net "LOW_HEX_3")
	)
	(segment
		(start 192.675764 -7.6708)
		(end 191.241426 -7.6708)
		(width 0.127)
		(layer "In2.Cu")
		(net "LOW_HEX_3")
	)
	(segment
		(start 239.853724 -6.36397)
		(end 233.921046 -6.36397)
		(width 0.127)
		(layer "In2.Cu")
		(net "LOW_HEX_3")
	)
	(segment
		(start 185.572654 -5.816854)
		(end 183.063642 -5.816854)
		(width 0.127)
		(layer "In2.Cu")
		(net "LOW_HEX_3")
	)
	(segment
		(start 99.5934 -82.136234)
		(end 91.023948 -90.705686)
		(width 0.127)
		(layer "In2.Cu")
		(net "LOW_HEX_3")
	)
	(segment
		(start 242.375944 -2.326132)
		(end 242.375944 -3.84175)
		(width 0.127)
		(layer "In2.Cu")
		(net "LOW_HEX_3")
	)
	(segment
		(start 133.971792 -5.82041)
		(end 133.966966 -5.825236)
		(width 0.127)
		(layer "In2.Cu")
		(net "LOW_HEX_3")
	)
	(segment
		(start 99.56419 -35.958018)
		(end 99.56419 -46.834044)
		(width 0.127)
		(layer "In2.Cu")
		(net "LOW_HEX_3")
	)
	(segment
		(start 99.5934 -79.04861)
		(end 99.5934 -82.136234)
		(width 0.127)
		(layer "In2.Cu")
		(net "LOW_HEX_3")
	)
	(segment
		(start 209.2452 -4.2037)
		(end 204.7621 -8.6868)
		(width 0.127)
		(layer "In2.Cu")
		(net "LOW_HEX_3")
	)
	(segment
		(start 191.241426 -7.6708)
		(end 191.240918 -7.670292)
		(width 0.127)
		(layer "In2.Cu")
		(net "LOW_HEX_3")
	)
	(segment
		(start 43.304714 -129.284984)
		(end 43.70451 -128.885188)
		(width 0.12065)
		(layer "F.Cu")
		(net "LOW_HEX_2")
	)
	(via
		(at 90.391488 -92.44711)
		(size 0.508)
		(drill 0.254)
		(layers "F.Cu" "B.Cu")
		(net "LOW_HEX_2")
	)
	(via
		(at 81.7626 -116.7892)
		(size 0.508)
		(drill 0.254)
		(layers "F.Cu" "B.Cu")
		(net "LOW_HEX_2")
	)
	(via
		(at 43.70451 -128.885188)
		(size 0.4572)
		(drill 0.2032)
		(layers "F.Cu" "B.Cu")
		(net "LOW_HEX_2")
	)
	(segment
		(start 82.151474 -105.290366)
		(end 82.151474 -116.400326)
		(width 0.12065)
		(layer "B.Cu")
		(net "LOW_HEX_2")
	)
	(segment
		(start 90.391488 -97.050352)
		(end 82.151474 -105.290366)
		(width 0.12065)
		(layer "B.Cu")
		(net "LOW_HEX_2")
	)
	(segment
		(start 90.391488 -92.44711)
		(end 90.391488 -97.050352)
		(width 0.12065)
		(layer "B.Cu")
		(net "LOW_HEX_2")
	)
	(segment
		(start 82.151474 -116.400326)
		(end 81.7626 -116.7892)
		(width 0.12065)
		(layer "B.Cu")
		(net "LOW_HEX_2")
	)
	(segment
		(start 90.391488 -90.799158)
		(end 90.391488 -92.44711)
		(width 0.127)
		(layer "In2.Cu")
		(net "LOW_HEX_2")
	)
	(segment
		(start 67.838828 -129.192782)
		(end 67.839082 -129.192528)
		(width 0.127)
		(layer "In2.Cu")
		(net "LOW_HEX_2")
	)
	(segment
		(start 43.70451 -128.885188)
		(end 43.70451 -128.87071)
		(width 0.127)
		(layer "In2.Cu")
		(net "LOW_HEX_2")
	)
	(segment
		(start 67.839082 -129.192528)
		(end 67.839082 -128.455928)
		(width 0.127)
		(layer "In2.Cu")
		(net "LOW_HEX_2")
	)
	(segment
		(start 55.5752 -128.0922)
		(end 56.459882 -128.0922)
		(width 0.127)
		(layer "In2.Cu")
		(net "LOW_HEX_2")
	)
	(segment
		(start 99.18319 -46.992032)
		(end 101.8286 -49.637442)
		(width 0.127)
		(layer "In2.Cu")
		(net "LOW_HEX_2")
	)
	(segment
		(start 76.624688 -122.2629)
		(end 79.8322 -119.055388)
		(width 0.127)
		(layer "In2.Cu")
		(net "LOW_HEX_2")
	)
	(segment
		(start 44.11091 -127.43561)
		(end 44.11091 -127.121666)
		(width 0.127)
		(layer "In2.Cu")
		(net "LOW_HEX_2")
	)
	(segment
		(start 223.583246 -3.8227)
		(end 209.087212 -3.8227)
		(width 0.127)
		(layer "In2.Cu")
		(net "LOW_HEX_2")
	)
	(segment
		(start 193.849752 -8.3058)
		(end 192.833752 -7.2898)
		(width 0.127)
		(layer "In2.Cu")
		(net "LOW_HEX_2")
	)
	(segment
		(start 67.839082 -128.455928)
		(end 67.838828 -128.455674)
		(width 0.127)
		(layer "In2.Cu")
		(net "LOW_HEX_2")
	)
	(segment
		(start 192.833752 -7.2898)
		(end 191.445896 -7.2898)
		(width 0.127)
		(layer "In2.Cu")
		(net "LOW_HEX_2")
	)
	(segment
		(start 70.57263 -125.349)
		(end 73.2028 -125.349)
		(width 0.127)
		(layer "In2.Cu")
		(net "LOW_HEX_2")
	)
	(segment
		(start 133.81355 -5.439664)
		(end 119.628666 -19.619722)
		(width 0.127)
		(layer "In2.Cu")
		(net "LOW_HEX_2")
	)
	(segment
		(start 133.814058 -5.439156)
		(end 133.81355 -5.439664)
		(width 0.127)
		(layer "In2.Cu")
		(net "LOW_HEX_2")
	)
	(segment
		(start 182.0799 -5.43941)
		(end 135.019034 -5.43941)
		(width 0.127)
		(layer "In2.Cu")
		(net "LOW_HEX_2")
	)
	(segment
		(start 99.2124 -81.978246)
		(end 90.391488 -90.799158)
		(width 0.127)
		(layer "In2.Cu")
		(net "LOW_HEX_2")
	)
	(segment
		(start 48.5394 -126.891288)
		(end 50.883312 -129.2352)
		(width 0.127)
		(layer "In2.Cu")
		(net "LOW_HEX_2")
	)
	(segment
		(start 44.341288 -126.891288)
		(end 48.5394 -126.891288)
		(width 0.127)
		(layer "In2.Cu")
		(net "LOW_HEX_2")
	)
	(segment
		(start 101.828346 -76.27366)
		(end 99.2124 -78.890622)
		(width 0.127)
		(layer "In2.Cu")
		(net "LOW_HEX_2")
	)
	(segment
		(start 79.8322 -119.055388)
		(end 79.8322 -118.7196)
		(width 0.127)
		(layer "In2.Cu")
		(net "LOW_HEX_2")
	)
	(segment
		(start 190.057024 -7.289038)
		(end 188.79693 -6.029198)
		(width 0.127)
		(layer "In2.Cu")
		(net "LOW_HEX_2")
	)
	(segment
		(start 101.8286 -71.784972)
		(end 101.828346 -74.545444)
		(width 0.127)
		(layer "In2.Cu")
		(net "LOW_HEX_2")
	)
	(segment
		(start 191.445134 -7.289038)
		(end 190.057024 -7.289038)
		(width 0.127)
		(layer "In2.Cu")
		(net "LOW_HEX_2")
	)
	(segment
		(start 115.363498 -19.619722)
		(end 99.18319 -35.80003)
		(width 0.127)
		(layer "In2.Cu")
		(net "LOW_HEX_2")
	)
	(segment
		(start 225.990658 -6.230112)
		(end 223.583246 -3.8227)
		(width 0.127)
		(layer "In2.Cu")
		(net "LOW_HEX_2")
	)
	(segment
		(start 73.2028 -125.349)
		(end 76.2889 -122.2629)
		(width 0.127)
		(layer "In2.Cu")
		(net "LOW_HEX_2")
	)
	(segment
		(start 43.31081 -128.47701)
		(end 43.31081 -127.921766)
		(width 0.127)
		(layer "In2.Cu")
		(net "LOW_HEX_2")
	)
	(segment
		(start 62.321948 -130.697224)
		(end 67.19824 -130.697224)
		(width 0.127)
		(layer "In2.Cu")
		(net "LOW_HEX_2")
	)
	(segment
		(start 233.515916 -6.230112)
		(end 225.990658 -6.230112)
		(width 0.127)
		(layer "In2.Cu")
		(net "LOW_HEX_2")
	)
	(segment
		(start 241.550444 -3.499612)
		(end 239.067086 -5.98297)
		(width 0.127)
		(layer "In2.Cu")
		(net "LOW_HEX_2")
	)
	(segment
		(start 56.459882 -128.0922)
		(end 57.826148 -129.458466)
		(width 0.127)
		(layer "In2.Cu")
		(net "LOW_HEX_2")
	)
	(segment
		(start 188.79693 -6.029198)
		(end 186.800744 -6.029198)
		(width 0.127)
		(layer "In2.Cu")
		(net "LOW_HEX_2")
	)
	(segment
		(start 233.763058 -5.98297)
		(end 233.515916 -6.230112)
		(width 0.127)
		(layer "In2.Cu")
		(net "LOW_HEX_2")
	)
	(segment
		(start 67.838828 -128.455674)
		(end 67.838828 -128.082802)
		(width 0.127)
		(layer "In2.Cu")
		(net "LOW_HEX_2")
	)
	(segment
		(start 101.8286 -49.637442)
		(end 101.8286 -71.784972)
		(width 0.127)
		(layer "In2.Cu")
		(net "LOW_HEX_2")
	)
	(segment
		(start 67.838828 -128.082802)
		(end 70.57263 -125.349)
		(width 0.127)
		(layer "In2.Cu")
		(net "LOW_HEX_2")
	)
	(segment
		(start 79.8322 -118.7196)
		(end 81.7626 -116.7892)
		(width 0.127)
		(layer "In2.Cu")
		(net "LOW_HEX_2")
	)
	(segment
		(start 186.800744 -6.029198)
		(end 185.889392 -5.117846)
		(width 0.127)
		(layer "In2.Cu")
		(net "LOW_HEX_2")
	)
	(segment
		(start 61.08319 -129.458466)
		(end 62.321948 -130.697224)
		(width 0.127)
		(layer "In2.Cu")
		(net "LOW_HEX_2")
	)
	(segment
		(start 44.11091 -127.121666)
		(end 44.341288 -126.891288)
		(width 0.127)
		(layer "In2.Cu")
		(net "LOW_HEX_2")
	)
	(segment
		(start 67.838828 -130.056636)
		(end 67.838828 -129.192782)
		(width 0.127)
		(layer "In2.Cu")
		(net "LOW_HEX_2")
	)
	(segment
		(start 101.828346 -74.545444)
		(end 101.828346 -76.27366)
		(width 0.127)
		(layer "In2.Cu")
		(net "LOW_HEX_2")
	)
	(segment
		(start 209.087212 -3.8227)
		(end 204.604112 -8.3058)
		(width 0.127)
		(layer "In2.Cu")
		(net "LOW_HEX_2")
	)
	(segment
		(start 135.019034 -5.43941)
		(end 135.01878 -5.439156)
		(width 0.127)
		(layer "In2.Cu")
		(net "LOW_HEX_2")
	)
	(segment
		(start 239.067086 -5.98297)
		(end 233.763058 -5.98297)
		(width 0.127)
		(layer "In2.Cu")
		(net "LOW_HEX_2")
	)
	(segment
		(start 119.628666 -19.619722)
		(end 115.363498 -19.619722)
		(width 0.127)
		(layer "In2.Cu")
		(net "LOW_HEX_2")
	)
	(segment
		(start 99.2124 -78.890622)
		(end 99.2124 -81.978246)
		(width 0.127)
		(layer "In2.Cu")
		(net "LOW_HEX_2")
	)
	(segment
		(start 43.855132 -127.691388)
		(end 44.11091 -127.43561)
		(width 0.127)
		(layer "In2.Cu")
		(net "LOW_HEX_2")
	)
	(segment
		(start 185.889392 -5.117846)
		(end 182.401464 -5.117846)
		(width 0.127)
		(layer "In2.Cu")
		(net "LOW_HEX_2")
	)
	(segment
		(start 43.541188 -127.691388)
		(end 43.855132 -127.691388)
		(width 0.127)
		(layer "In2.Cu")
		(net "LOW_HEX_2")
	)
	(segment
		(start 182.401464 -5.117846)
		(end 182.0799 -5.43941)
		(width 0.127)
		(layer "In2.Cu")
		(net "LOW_HEX_2")
	)
	(segment
		(start 191.445896 -7.2898)
		(end 191.445134 -7.289038)
		(width 0.127)
		(layer "In2.Cu")
		(net "LOW_HEX_2")
	)
	(segment
		(start 43.70451 -128.87071)
		(end 43.31081 -128.47701)
		(width 0.127)
		(layer "In2.Cu")
		(net "LOW_HEX_2")
	)
	(segment
		(start 57.826148 -129.458466)
		(end 61.08319 -129.458466)
		(width 0.127)
		(layer "In2.Cu")
		(net "LOW_HEX_2")
	)
	(segment
		(start 43.31081 -127.921766)
		(end 43.541188 -127.691388)
		(width 0.127)
		(layer "In2.Cu")
		(net "LOW_HEX_2")
	)
	(segment
		(start 135.01878 -5.439156)
		(end 133.814058 -5.439156)
		(width 0.127)
		(layer "In2.Cu")
		(net "LOW_HEX_2")
	)
	(segment
		(start 67.19824 -130.697224)
		(end 67.838828 -130.056636)
		(width 0.127)
		(layer "In2.Cu")
		(net "LOW_HEX_2")
	)
	(segment
		(start 99.18319 -35.80003)
		(end 99.18319 -46.992032)
		(width 0.127)
		(layer "In2.Cu")
		(net "LOW_HEX_2")
	)
	(segment
		(start 54.4322 -129.2352)
		(end 55.5752 -128.0922)
		(width 0.127)
		(layer "In2.Cu")
		(net "LOW_HEX_2")
	)
	(segment
		(start 204.604112 -8.3058)
		(end 193.849752 -8.3058)
		(width 0.127)
		(layer "In2.Cu")
		(net "LOW_HEX_2")
	)
	(segment
		(start 50.883312 -129.2352)
		(end 54.4322 -129.2352)
		(width 0.127)
		(layer "In2.Cu")
		(net "LOW_HEX_2")
	)
	(segment
		(start 76.2889 -122.2629)
		(end 76.624688 -122.2629)
		(width 0.127)
		(layer "In2.Cu")
		(net "LOW_HEX_2")
	)
	(segment
		(start 44.104814 -128.484884)
		(end 44.504864 -128.084834)
		(width 0.12065)
		(layer "F.Cu")
		(net "LOW_HEX_1")
	)
	(via
		(at 92.27058 -90.66276)
		(size 0.508)
		(drill 0.254)
		(layers "F.Cu" "B.Cu")
		(net "LOW_HEX_1")
	)
	(via
		(at 81.86547 -119.377714)
		(size 0.508)
		(drill 0.254)
		(layers "F.Cu" "B.Cu")
		(net "LOW_HEX_1")
	)
	(via
		(at 44.504864 -128.084834)
		(size 0.4572)
		(drill 0.2032)
		(layers "F.Cu" "B.Cu")
		(net "LOW_HEX_1")
	)
	(segment
		(start 83.237324 -118.00586)
		(end 81.86547 -119.377714)
		(width 0.12065)
		(layer "B.Cu")
		(net "LOW_HEX_1")
	)
	(segment
		(start 92.27058 -90.66276)
		(end 92.27058 -96.707452)
		(width 0.12065)
		(layer "B.Cu")
		(net "LOW_HEX_1")
	)
	(segment
		(start 92.27058 -96.707452)
		(end 83.237324 -105.740708)
		(width 0.12065)
		(layer "B.Cu")
		(net "LOW_HEX_1")
	)
	(segment
		(start 83.237324 -105.740708)
		(end 83.237324 -118.00586)
		(width 0.12065)
		(layer "B.Cu")
		(net "LOW_HEX_1")
	)
	(segment
		(start 217.449908 -5.278374)
		(end 217.762582 -4.9657)
		(width 0.127)
		(layer "In2.Cu")
		(net "LOW_HEX_1")
	)
	(segment
		(start 102.9716 -71.943468)
		(end 102.9716 -47.376588)
		(width 0.127)
		(layer "In2.Cu")
		(net "LOW_HEX_1")
	)
	(segment
		(start 177.759614 -6.58241)
		(end 178.349402 -7.172198)
		(width 0.127)
		(layer "In2.Cu")
		(net "LOW_HEX_1")
	)
	(segment
		(start 220.779594 -5.65531)
		(end 222.414846 -5.65531)
		(width 0.127)
		(layer "In2.Cu")
		(net "LOW_HEX_1")
	)
	(segment
		(start 100.3554 -82.643472)
		(end 100.3554 -79.364586)
		(width 0.127)
		(layer "In2.Cu")
		(net "LOW_HEX_1")
	)
	(segment
		(start 178.349402 -7.172198)
		(end 188.322966 -7.172198)
		(width 0.127)
		(layer "In2.Cu")
		(net "LOW_HEX_1")
	)
	(segment
		(start 118.780306 -20.762976)
		(end 120.102884 -20.762976)
		(width 0.127)
		(layer "In2.Cu")
		(net "LOW_HEX_1")
	)
	(segment
		(start 74.439272 -128.028446)
		(end 71.558404 -128.028446)
		(width 0.127)
		(layer "In2.Cu")
		(net "LOW_HEX_1")
	)
	(segment
		(start 115.837462 -20.762722)
		(end 118.780052 -20.762722)
		(width 0.127)
		(layer "In2.Cu")
		(net "LOW_HEX_1")
	)
	(segment
		(start 100.32619 -44.731178)
		(end 100.32619 -36.273994)
		(width 0.127)
		(layer "In2.Cu")
		(net "LOW_HEX_1")
	)
	(segment
		(start 120.102884 -20.762976)
		(end 120.170194 -20.695666)
		(width 0.127)
		(layer "In2.Cu")
		(net "LOW_HEX_1")
	)
	(segment
		(start 120.170194 -20.695666)
		(end 120.170702 -20.695412)
		(width 0.127)
		(layer "In2.Cu")
		(net "LOW_HEX_1")
	)
	(segment
		(start 102.971346 -74.70394)
		(end 102.9716 -71.943468)
		(width 0.127)
		(layer "In2.Cu")
		(net "LOW_HEX_1")
	)
	(segment
		(start 217.762582 -4.9657)
		(end 220.089984 -4.9657)
		(width 0.127)
		(layer "In2.Cu")
		(net "LOW_HEX_1")
	)
	(segment
		(start 92.27058 -90.66276)
		(end 92.336112 -90.66276)
		(width 0.127)
		(layer "In2.Cu")
		(net "LOW_HEX_1")
	)
	(segment
		(start 57.281318 -130.6576)
		(end 48.818546 -130.6576)
		(width 0.127)
		(layer "In2.Cu")
		(net "LOW_HEX_1")
	)
	(segment
		(start 233.98988 -7.373112)
		(end 234.237022 -7.12597)
		(width 0.127)
		(layer "In2.Cu")
		(net "LOW_HEX_1")
	)
	(segment
		(start 241.090704 -7.12597)
		(end 244.374924 -3.84175)
		(width 0.127)
		(layer "In2.Cu")
		(net "LOW_HEX_1")
	)
	(segment
		(start 222.414846 -5.65531)
		(end 222.545656 -5.5245)
		(width 0.127)
		(layer "In2.Cu")
		(net "LOW_HEX_1")
	)
	(segment
		(start 134.287514 -6.582664)
		(end 134.287768 -6.58241)
		(width 0.127)
		(layer "In2.Cu")
		(net "LOW_HEX_1")
	)
	(segment
		(start 193.410078 -9.48309)
		(end 205.043786 -9.48309)
		(width 0.127)
		(layer "In2.Cu")
		(net "LOW_HEX_1")
	)
	(segment
		(start 225.516694 -7.373112)
		(end 233.98988 -7.373112)
		(width 0.127)
		(layer "In2.Cu")
		(net "LOW_HEX_1")
	)
	(segment
		(start 222.545656 -5.5245)
		(end 223.668082 -5.5245)
		(width 0.127)
		(layer "In2.Cu")
		(net "LOW_HEX_1")
	)
	(segment
		(start 100.32619 -36.273994)
		(end 115.837462 -20.762722)
		(width 0.127)
		(layer "In2.Cu")
		(net "LOW_HEX_1")
	)
	(segment
		(start 47.45228 -129.291334)
		(end 44.353734 -129.291334)
		(width 0.127)
		(layer "In2.Cu")
		(net "LOW_HEX_1")
	)
	(segment
		(start 118.780052 -20.762722)
		(end 118.780306 -20.762976)
		(width 0.127)
		(layer "In2.Cu")
		(net "LOW_HEX_1")
	)
	(segment
		(start 102.9716 -47.376588)
		(end 100.32619 -44.731178)
		(width 0.127)
		(layer "In2.Cu")
		(net "LOW_HEX_1")
	)
	(segment
		(start 188.322966 -7.172198)
		(end 189.583822 -8.4328)
		(width 0.127)
		(layer "In2.Cu")
		(net "LOW_HEX_1")
	)
	(segment
		(start 134.287768 -6.58241)
		(end 177.759614 -6.58241)
		(width 0.127)
		(layer "In2.Cu")
		(net "LOW_HEX_1")
	)
	(segment
		(start 71.558404 -128.028446)
		(end 67.746626 -131.840224)
		(width 0.127)
		(layer "In2.Cu")
		(net "LOW_HEX_1")
	)
	(segment
		(start 44.353734 -129.291334)
		(end 44.11091 -129.04851)
		(width 0.127)
		(layer "In2.Cu")
		(net "LOW_HEX_1")
	)
	(segment
		(start 58.463942 -131.840224)
		(end 57.281318 -130.6576)
		(width 0.127)
		(layer "In2.Cu")
		(net "LOW_HEX_1")
	)
	(segment
		(start 223.668082 -5.5245)
		(end 225.516694 -7.373112)
		(width 0.127)
		(layer "In2.Cu")
		(net "LOW_HEX_1")
	)
	(segment
		(start 100.3554 -79.364586)
		(end 102.971346 -76.747624)
		(width 0.127)
		(layer "In2.Cu")
		(net "LOW_HEX_1")
	)
	(segment
		(start 205.043786 -9.48309)
		(end 207.511396 -7.01548)
		(width 0.127)
		(layer "In2.Cu")
		(net "LOW_HEX_1")
	)
	(segment
		(start 44.11091 -128.478788)
		(end 44.504864 -128.084834)
		(width 0.127)
		(layer "In2.Cu")
		(net "LOW_HEX_1")
	)
	(segment
		(start 81.86547 -119.377714)
		(end 81.86547 -120.602248)
		(width 0.127)
		(layer "In2.Cu")
		(net "LOW_HEX_1")
	)
	(segment
		(start 215.912446 -7.01548)
		(end 217.449908 -5.478018)
		(width 0.127)
		(layer "In2.Cu")
		(net "LOW_HEX_1")
	)
	(segment
		(start 92.336112 -90.66276)
		(end 100.3554 -82.643472)
		(width 0.127)
		(layer "In2.Cu")
		(net "LOW_HEX_1")
	)
	(segment
		(start 44.11091 -129.04851)
		(end 44.11091 -128.478788)
		(width 0.127)
		(layer "In2.Cu")
		(net "LOW_HEX_1")
	)
	(segment
		(start 217.449908 -5.478018)
		(end 217.449908 -5.278374)
		(width 0.127)
		(layer "In2.Cu")
		(net "LOW_HEX_1")
	)
	(segment
		(start 207.511396 -7.01548)
		(end 215.912446 -7.01548)
		(width 0.127)
		(layer "In2.Cu")
		(net "LOW_HEX_1")
	)
	(segment
		(start 81.86547 -120.602248)
		(end 74.439272 -128.028446)
		(width 0.127)
		(layer "In2.Cu")
		(net "LOW_HEX_1")
	)
	(segment
		(start 244.374924 -3.84175)
		(end 244.374924 -2.326132)
		(width 0.127)
		(layer "In2.Cu")
		(net "LOW_HEX_1")
	)
	(segment
		(start 102.971346 -76.747624)
		(end 102.971346 -74.70394)
		(width 0.127)
		(layer "In2.Cu")
		(net "LOW_HEX_1")
	)
	(segment
		(start 220.089984 -4.9657)
		(end 220.779594 -5.65531)
		(width 0.127)
		(layer "In2.Cu")
		(net "LOW_HEX_1")
	)
	(segment
		(start 48.818546 -130.6576)
		(end 47.45228 -129.291334)
		(width 0.127)
		(layer "In2.Cu")
		(net "LOW_HEX_1")
	)
	(segment
		(start 67.746626 -131.840224)
		(end 58.463942 -131.840224)
		(width 0.127)
		(layer "In2.Cu")
		(net "LOW_HEX_1")
	)
	(segment
		(start 192.359788 -8.4328)
		(end 193.410078 -9.48309)
		(width 0.127)
		(layer "In2.Cu")
		(net "LOW_HEX_1")
	)
	(segment
		(start 244.374924 -2.326132)
		(end 243.549424 -1.500632)
		(width 0.127)
		(layer "In2.Cu")
		(net "LOW_HEX_1")
	)
	(segment
		(start 189.583822 -8.4328)
		(end 192.359788 -8.4328)
		(width 0.127)
		(layer "In2.Cu")
		(net "LOW_HEX_1")
	)
	(segment
		(start 120.170702 -20.695412)
		(end 134.287514 -6.582664)
		(width 0.127)
		(layer "In2.Cu")
		(net "LOW_HEX_1")
	)
	(segment
		(start 234.237022 -7.12597)
		(end 241.090704 -7.12597)
		(width 0.127)
		(layer "In2.Cu")
		(net "LOW_HEX_1")
	)
	(segment
		(start 43.304714 -128.484884)
		(end 43.70451 -128.085088)
		(width 0.12065)
		(layer "F.Cu")
		(net "LOW_HEX_0")
	)
	(via
		(at 81.856072 -118.514114)
		(size 0.508)
		(drill 0.254)
		(layers "F.Cu" "B.Cu")
		(net "LOW_HEX_0")
	)
	(via
		(at 91.64828 -91.261946)
		(size 0.508)
		(drill 0.254)
		(layers "F.Cu" "B.Cu")
		(net "LOW_HEX_0")
	)
	(via
		(at 43.70451 -128.085088)
		(size 0.4572)
		(drill 0.2032)
		(layers "F.Cu" "B.Cu")
		(net "LOW_HEX_0")
	)
	(segment
		(start 91.64828 -96.817688)
		(end 82.875374 -105.590594)
		(width 0.12065)
		(layer "B.Cu")
		(net "LOW_HEX_0")
	)
	(segment
		(start 82.875374 -117.494812)
		(end 81.856072 -118.514114)
		(width 0.12065)
		(layer "B.Cu")
		(net "LOW_HEX_0")
	)
	(segment
		(start 82.875374 -105.590594)
		(end 82.875374 -117.494812)
		(width 0.12065)
		(layer "B.Cu")
		(net "LOW_HEX_0")
	)
	(segment
		(start 91.64828 -91.261946)
		(end 91.64828 -96.817688)
		(width 0.12065)
		(layer "B.Cu")
		(net "LOW_HEX_0")
	)
	(segment
		(start 99.9744 -79.206598)
		(end 99.9744 -82.294222)
		(width 0.127)
		(layer "In2.Cu")
		(net "LOW_HEX_0")
	)
	(segment
		(start 204.920088 -9.0678)
		(end 193.533776 -9.0678)
		(width 0.127)
		(layer "In2.Cu")
		(net "LOW_HEX_0")
	)
	(segment
		(start 225.674682 -6.992112)
		(end 223.82607 -5.1435)
		(width 0.127)
		(layer "In2.Cu")
		(net "LOW_HEX_0")
	)
	(segment
		(start 222.387668 -5.1435)
		(end 222.256858 -5.27431)
		(width 0.127)
		(layer "In2.Cu")
		(net "LOW_HEX_0")
	)
	(segment
		(start 55.126382 -129.7051)
		(end 55.516018 -129.7051)
		(width 0.127)
		(layer "In2.Cu")
		(net "LOW_HEX_0")
	)
	(segment
		(start 220.937582 -5.27431)
		(end 220.247972 -4.5847)
		(width 0.127)
		(layer "In2.Cu")
		(net "LOW_HEX_0")
	)
	(segment
		(start 216.510108 -5.124196)
		(end 215.853772 -5.780532)
		(width 0.127)
		(layer "In2.Cu")
		(net "LOW_HEX_0")
	)
	(segment
		(start 56.794654 -129.8194)
		(end 57.196228 -130.220974)
		(width 0.127)
		(layer "In2.Cu")
		(net "LOW_HEX_0")
	)
	(segment
		(start 220.247972 -4.5847)
		(end 217.01379 -4.5847)
		(width 0.127)
		(layer "In2.Cu")
		(net "LOW_HEX_0")
	)
	(segment
		(start 188.480954 -6.791198)
		(end 178.50739 -6.791198)
		(width 0.127)
		(layer "In2.Cu")
		(net "LOW_HEX_0")
	)
	(segment
		(start 134.125208 -6.205982)
		(end 119.944896 -20.381976)
		(width 0.127)
		(layer "In2.Cu")
		(net "LOW_HEX_0")
	)
	(segment
		(start 91.64828 -90.620342)
		(end 91.64828 -91.261946)
		(width 0.127)
		(layer "In2.Cu")
		(net "LOW_HEX_0")
	)
	(segment
		(start 134.12978 -6.20141)
		(end 134.125208 -6.205982)
		(width 0.127)
		(layer "In2.Cu")
		(net "LOW_HEX_0")
	)
	(segment
		(start 44.668186 -127.691134)
		(end 44.898564 -127.921512)
		(width 0.127)
		(layer "In2.Cu")
		(net "LOW_HEX_0")
	)
	(segment
		(start 222.256858 -5.27431)
		(end 220.937582 -5.27431)
		(width 0.127)
		(layer "In2.Cu")
		(net "LOW_HEX_0")
	)
	(segment
		(start 102.590346 -76.589636)
		(end 99.9744 -79.206598)
		(width 0.127)
		(layer "In2.Cu")
		(net "LOW_HEX_0")
	)
	(segment
		(start 102.5906 -47.534576)
		(end 102.5906 -71.78548)
		(width 0.127)
		(layer "In2.Cu")
		(net "LOW_HEX_0")
	)
	(segment
		(start 118.93804 -20.381722)
		(end 115.679474 -20.381722)
		(width 0.127)
		(layer "In2.Cu")
		(net "LOW_HEX_0")
	)
	(segment
		(start 80.5688 -119.801386)
		(end 81.856072 -118.514114)
		(width 0.127)
		(layer "In2.Cu")
		(net "LOW_HEX_0")
	)
	(segment
		(start 73.468992 -126.160784)
		(end 75.532488 -124.097288)
		(width 0.127)
		(layer "In2.Cu")
		(net "LOW_HEX_0")
	)
	(segment
		(start 75.532488 -124.097288)
		(end 76.98613 -124.097288)
		(width 0.127)
		(layer "In2.Cu")
		(net "LOW_HEX_0")
	)
	(segment
		(start 43.70451 -128.085088)
		(end 43.947588 -128.085088)
		(width 0.127)
		(layer "In2.Cu")
		(net "LOW_HEX_0")
	)
	(segment
		(start 49.511458 -130.175)
		(end 54.656482 -130.175)
		(width 0.127)
		(layer "In2.Cu")
		(net "LOW_HEX_0")
	)
	(segment
		(start 208.951576 -5.82676)
		(end 208.161128 -5.82676)
		(width 0.127)
		(layer "In2.Cu")
		(net "LOW_HEX_0")
	)
	(segment
		(start 45.154088 -128.491488)
		(end 47.827946 -128.491488)
		(width 0.127)
		(layer "In2.Cu")
		(net "LOW_HEX_0")
	)
	(segment
		(start 193.533776 -9.0678)
		(end 192.517776 -8.0518)
		(width 0.127)
		(layer "In2.Cu")
		(net "LOW_HEX_0")
	)
	(segment
		(start 240.304066 -6.74497)
		(end 234.079034 -6.74497)
		(width 0.127)
		(layer "In2.Cu")
		(net "LOW_HEX_0")
	)
	(segment
		(start 99.94519 -44.889166)
		(end 102.5906 -47.534576)
		(width 0.127)
		(layer "In2.Cu")
		(net "LOW_HEX_0")
	)
	(segment
		(start 223.82607 -5.1435)
		(end 222.387668 -5.1435)
		(width 0.127)
		(layer "In2.Cu")
		(net "LOW_HEX_0")
	)
	(segment
		(start 60.767722 -130.220974)
		(end 62.005972 -131.459224)
		(width 0.127)
		(layer "In2.Cu")
		(net "LOW_HEX_0")
	)
	(segment
		(start 118.938294 -20.381976)
		(end 118.93804 -20.381722)
		(width 0.127)
		(layer "In2.Cu")
		(net "LOW_HEX_0")
	)
	(segment
		(start 72.220074 -126.435866)
		(end 72.495156 -126.160784)
		(width 0.127)
		(layer "In2.Cu")
		(net "LOW_HEX_0")
	)
	(segment
		(start 55.630318 -129.8194)
		(end 56.794654 -129.8194)
		(width 0.127)
		(layer "In2.Cu")
		(net "LOW_HEX_0")
	)
	(segment
		(start 178.50739 -6.791198)
		(end 177.917602 -6.20141)
		(width 0.127)
		(layer "In2.Cu")
		(net "LOW_HEX_0")
	)
	(segment
		(start 177.917602 -6.20141)
		(end 134.12978 -6.20141)
		(width 0.127)
		(layer "In2.Cu")
		(net "LOW_HEX_0")
	)
	(segment
		(start 44.898564 -127.921512)
		(end 44.898564 -128.235964)
		(width 0.127)
		(layer "In2.Cu")
		(net "LOW_HEX_0")
	)
	(segment
		(start 57.196228 -130.220974)
		(end 60.767722 -130.220974)
		(width 0.127)
		(layer "In2.Cu")
		(net "LOW_HEX_0")
	)
	(segment
		(start 192.517776 -8.0518)
		(end 191.005968 -8.0518)
		(width 0.127)
		(layer "In2.Cu")
		(net "LOW_HEX_0")
	)
	(segment
		(start 43.947588 -128.085088)
		(end 44.341542 -127.691134)
		(width 0.127)
		(layer "In2.Cu")
		(net "LOW_HEX_0")
	)
	(segment
		(start 217.01379 -4.5847)
		(end 216.510108 -5.088382)
		(width 0.127)
		(layer "In2.Cu")
		(net "LOW_HEX_0")
	)
	(segment
		(start 44.898564 -128.235964)
		(end 45.154088 -128.491488)
		(width 0.127)
		(layer "In2.Cu")
		(net "LOW_HEX_0")
	)
	(segment
		(start 191.005714 -8.051546)
		(end 189.741556 -8.051546)
		(width 0.127)
		(layer "In2.Cu")
		(net "LOW_HEX_0")
	)
	(segment
		(start 44.341542 -127.691134)
		(end 44.668186 -127.691134)
		(width 0.127)
		(layer "In2.Cu")
		(net "LOW_HEX_0")
	)
	(segment
		(start 55.516018 -129.7051)
		(end 55.630318 -129.8194)
		(width 0.127)
		(layer "In2.Cu")
		(net "LOW_HEX_0")
	)
	(segment
		(start 191.005968 -8.0518)
		(end 191.005714 -8.051546)
		(width 0.127)
		(layer "In2.Cu")
		(net "LOW_HEX_0")
	)
	(segment
		(start 76.98613 -124.097288)
		(end 80.5688 -120.514618)
		(width 0.127)
		(layer "In2.Cu")
		(net "LOW_HEX_0")
	)
	(segment
		(start 243.549424 -3.499612)
		(end 240.304066 -6.74497)
		(width 0.127)
		(layer "In2.Cu")
		(net "LOW_HEX_0")
	)
	(segment
		(start 233.831892 -6.992112)
		(end 225.674682 -6.992112)
		(width 0.127)
		(layer "In2.Cu")
		(net "LOW_HEX_0")
	)
	(segment
		(start 102.5906 -71.78548)
		(end 102.590346 -74.703686)
		(width 0.127)
		(layer "In2.Cu")
		(net "LOW_HEX_0")
	)
	(segment
		(start 234.079034 -6.74497)
		(end 233.831892 -6.992112)
		(width 0.127)
		(layer "In2.Cu")
		(net "LOW_HEX_0")
	)
	(segment
		(start 54.656482 -130.175)
		(end 55.126382 -129.7051)
		(width 0.127)
		(layer "In2.Cu")
		(net "LOW_HEX_0")
	)
	(segment
		(start 99.9744 -82.294222)
		(end 91.64828 -90.620342)
		(width 0.127)
		(layer "In2.Cu")
		(net "LOW_HEX_0")
	)
	(segment
		(start 67.514216 -131.459224)
		(end 72.220074 -126.753366)
		(width 0.127)
		(layer "In2.Cu")
		(net "LOW_HEX_0")
	)
	(segment
		(start 62.005972 -131.459224)
		(end 67.514216 -131.459224)
		(width 0.127)
		(layer "In2.Cu")
		(net "LOW_HEX_0")
	)
	(segment
		(start 102.590346 -74.703686)
		(end 102.590346 -76.589636)
		(width 0.127)
		(layer "In2.Cu")
		(net "LOW_HEX_0")
	)
	(segment
		(start 215.853772 -5.780532)
		(end 208.997804 -5.780532)
		(width 0.127)
		(layer "In2.Cu")
		(net "LOW_HEX_0")
	)
	(segment
		(start 119.944896 -20.381976)
		(end 118.938294 -20.381976)
		(width 0.127)
		(layer "In2.Cu")
		(net "LOW_HEX_0")
	)
	(segment
		(start 72.495156 -126.160784)
		(end 73.468992 -126.160784)
		(width 0.127)
		(layer "In2.Cu")
		(net "LOW_HEX_0")
	)
	(segment
		(start 208.161128 -5.82676)
		(end 204.920088 -9.0678)
		(width 0.127)
		(layer "In2.Cu")
		(net "LOW_HEX_0")
	)
	(segment
		(start 115.679474 -20.381722)
		(end 99.94519 -36.116006)
		(width 0.127)
		(layer "In2.Cu")
		(net "LOW_HEX_0")
	)
	(segment
		(start 99.94519 -36.116006)
		(end 99.94519 -44.889166)
		(width 0.127)
		(layer "In2.Cu")
		(net "LOW_HEX_0")
	)
	(segment
		(start 216.510108 -5.088382)
		(end 216.510108 -5.124196)
		(width 0.127)
		(layer "In2.Cu")
		(net "LOW_HEX_0")
	)
	(segment
		(start 80.5688 -120.514618)
		(end 80.5688 -119.801386)
		(width 0.127)
		(layer "In2.Cu")
		(net "LOW_HEX_0")
	)
	(segment
		(start 47.827946 -128.491488)
		(end 49.511458 -130.175)
		(width 0.127)
		(layer "In2.Cu")
		(net "LOW_HEX_0")
	)
	(segment
		(start 208.997804 -5.780532)
		(end 208.951576 -5.82676)
		(width 0.127)
		(layer "In2.Cu")
		(net "LOW_HEX_0")
	)
	(segment
		(start 189.741556 -8.051546)
		(end 188.480954 -6.791198)
		(width 0.127)
		(layer "In2.Cu")
		(net "LOW_HEX_0")
	)
	(segment
		(start 72.220074 -126.753366)
		(end 72.220074 -126.435866)
		(width 0.127)
		(layer "In2.Cu")
		(net "LOW_HEX_0")
	)
	(segment
		(start 231.599994 -40.999918)
		(end 231.100122 -40.500046)
		(width 0.12065)
		(layer "F.Cu")
		(net "LINK")
	)
	(via
		(at 231.100122 -40.500046)
		(size 0.4572)
		(drill 0.2032)
		(layers "F.Cu" "B.Cu")
		(net "LINK")
	)
	(segment
		(start 231.595168 -40.005)
		(end 231.100122 -40.500046)
		(width 0.12065)
		(layer "B.Cu")
		(net "LINK")
	)
	(segment
		(start 231.60228 -40.005)
		(end 231.595168 -40.005)
		(width 0.12065)
		(layer "B.Cu")
		(net "LINK")
	)
	(segment
		(start 182.499 -17.3355)
		(end 182.499 -17.399)
		(width 0.12065)
		(layer "F.Cu")
		(net "LED_R_9")
	)
	(segment
		(start 181.4195 -16.256)
		(end 182.499 -17.3355)
		(width 0.12065)
		(layer "F.Cu")
		(net "LED_R_9")
	)
	(segment
		(start 182.499 -17.399)
		(end 182.397908 -17.500092)
		(width 0.12065)
		(layer "F.Cu")
		(net "LED_R_9")
	)
	(segment
		(start 182.397908 -17.500092)
		(end 181.362096 -17.500092)
		(width 0.12065)
		(layer "F.Cu")
		(net "LED_R_9")
	)
	(via
		(at 182.499 -17.399)
		(size 0.7112)
		(drill 0.3556)
		(layers "F.Cu" "B.Cu")
		(net "LED_R_9")
	)
	(segment
		(start 330.861924 -1.999996)
		(end 331.216 -2.354072)
		(width 0.12065)
		(layer "F.Cu")
		(net "LED_R_8")
	)
	(segment
		(start 331.216 -2.354072)
		(end 331.216 -3.2385)
		(width 0.12065)
		(layer "F.Cu")
		(net "LED_R_8")
	)
	(segment
		(start 331.216 -8.35406)
		(end 331.216 -9.2075)
		(width 0.12065)
		(layer "F.Cu")
		(net "LED_R_7")
	)
	(segment
		(start 330.861924 -7.999984)
		(end 331.216 -8.35406)
		(width 0.12065)
		(layer "F.Cu")
		(net "LED_R_7")
	)
	(segment
		(start 330.861924 -13.999972)
		(end 331.216 -14.354048)
		(width 0.12065)
		(layer "F.Cu")
		(net "LED_R_6")
	)
	(segment
		(start 331.216 -14.354048)
		(end 331.216 -15.1765)
		(width 0.12065)
		(layer "F.Cu")
		(net "LED_R_6")
	)
	(segment
		(start 330.861924 -20.448524)
		(end 331.216 -20.8026)
		(width 0.12065)
		(layer "F.Cu")
		(net "LED_R_5")
	)
	(segment
		(start 330.861924 -19.99996)
		(end 330.861924 -20.448524)
		(width 0.12065)
		(layer "F.Cu")
		(net "LED_R_5")
	)
	(segment
		(start 331.216 -20.8026)
		(end 331.216 -21.1455)
		(width 0.12065)
		(layer "F.Cu")
		(net "LED_R_5")
	)
	(segment
		(start 123.692666 -2.244598)
		(end 123.937268 -1.999996)
		(width 0.12065)
		(layer "F.Cu")
		(net "LED_R_4")
	)
	(segment
		(start 123.62434 -2.312924)
		(end 123.692666 -2.244598)
		(width 0.12065)
		(layer "F.Cu")
		(net "LED_R_4")
	)
	(segment
		(start 123.62434 -3.34772)
		(end 123.62434 -2.312924)
		(width 0.12065)
		(layer "F.Cu")
		(net "LED_R_4")
	)
	(segment
		(start 123.937268 -1.999996)
		(end 124.837952 -1.999996)
		(width 0.12065)
		(layer "F.Cu")
		(net "LED_R_4")
	)
	(via
		(at 123.692666 -2.244598)
		(size 0.7112)
		(drill 0.3556)
		(layers "F.Cu" "B.Cu")
		(net "LED_R_4")
	)
	(segment
		(start 123.755404 -7.999984)
		(end 123.6345 -7.87908)
		(width 0.12065)
		(layer "F.Cu")
		(net "LED_R_3")
	)
	(segment
		(start 123.62688 -7.87146)
		(end 123.6345 -7.87908)
		(width 0.12065)
		(layer "F.Cu")
		(net "LED_R_3")
	)
	(segment
		(start 124.837952 -7.999984)
		(end 123.755404 -7.999984)
		(width 0.12065)
		(layer "F.Cu")
		(net "LED_R_3")
	)
	(segment
		(start 123.62688 -6.78688)
		(end 123.62688 -7.87146)
		(width 0.12065)
		(layer "F.Cu")
		(net "LED_R_3")
	)
	(via
		(at 123.6345 -7.87908)
		(size 0.7112)
		(drill 0.3556)
		(layers "F.Cu" "B.Cu")
		(net "LED_R_3")
	)
	(segment
		(start 123.6345 -12.66952)
		(end 123.6345 -13.86078)
		(width 0.12065)
		(layer "F.Cu")
		(net "LED_R_2")
	)
	(segment
		(start 123.773692 -13.999972)
		(end 123.63704 -13.86332)
		(width 0.12065)
		(layer "F.Cu")
		(net "LED_R_2")
	)
	(segment
		(start 123.6345 -13.86078)
		(end 123.63704 -13.86332)
		(width 0.12065)
		(layer "F.Cu")
		(net "LED_R_2")
	)
	(segment
		(start 124.837952 -13.999972)
		(end 123.773692 -13.999972)
		(width 0.12065)
		(layer "F.Cu")
		(net "LED_R_2")
	)
	(via
		(at 123.63704 -13.86332)
		(size 0.7112)
		(drill 0.3556)
		(layers "F.Cu" "B.Cu")
		(net "LED_R_2")
	)
	(segment
		(start 274.837906 -17.500092)
		(end 273.922998 -18.415)
		(width 0.12065)
		(layer "F.Cu")
		(net "LED_R_14")
	)
	(segment
		(start 273.922998 -18.415)
		(end 273.812 -18.415)
		(width 0.12065)
		(layer "F.Cu")
		(net "LED_R_14")
	)
	(segment
		(start 273.7485 -18.3515)
		(end 273.812 -18.415)
		(width 0.12065)
		(layer "F.Cu")
		(net "LED_R_14")
	)
	(segment
		(start 273.7485 -17.399)
		(end 273.7485 -18.3515)
		(width 0.12065)
		(layer "F.Cu")
		(net "LED_R_14")
	)
	(via
		(at 273.812 -18.415)
		(size 0.7112)
		(drill 0.3556)
		(layers "F.Cu" "B.Cu")
		(net "LED_R_14")
	)
	(segment
		(start 269.837916 -18.198084)
		(end 269.24 -18.796)
		(width 0.12065)
		(layer "F.Cu")
		(net "LED_R_13")
	)
	(segment
		(start 269.837916 -17.500092)
		(end 269.837916 -18.198084)
		(width 0.12065)
		(layer "F.Cu")
		(net "LED_R_13")
	)
	(segment
		(start 268.75994 -17.61617)
		(end 268.75994 -18.31594)
		(width 0.12065)
		(layer "F.Cu")
		(net "LED_R_13")
	)
	(segment
		(start 268.75994 -18.31594)
		(end 269.24 -18.796)
		(width 0.12065)
		(layer "F.Cu")
		(net "LED_R_13")
	)
	(via
		(at 269.24 -18.796)
		(size 0.7112)
		(drill 0.3556)
		(layers "F.Cu" "B.Cu")
		(net "LED_R_13")
	)
	(segment
		(start 266.5349 -16.2814)
		(end 265.5316 -16.2814)
		(width 0.12065)
		(layer "F.Cu")
		(net "LED_R_12")
	)
	(segment
		(start 264.837926 -17.500092)
		(end 264.837926 -16.975074)
		(width 0.12065)
		(layer "F.Cu")
		(net "LED_R_12")
	)
	(segment
		(start 264.837926 -16.975074)
		(end 265.43 -16.383)
		(width 0.12065)
		(layer "F.Cu")
		(net "LED_R_12")
	)
	(segment
		(start 265.5316 -16.2814)
		(end 265.43 -16.383)
		(width 0.12065)
		(layer "F.Cu")
		(net "LED_R_12")
	)
	(via
		(at 265.43 -16.383)
		(size 0.7112)
		(drill 0.3556)
		(layers "F.Cu" "B.Cu")
		(net "LED_R_12")
	)
	(segment
		(start 192.532 -16.4465)
		(end 192.532 -17.399)
		(width 0.12065)
		(layer "F.Cu")
		(net "LED_R_11")
	)
	(segment
		(start 192.430908 -17.500092)
		(end 191.362076 -17.500092)
		(width 0.12065)
		(layer "F.Cu")
		(net "LED_R_11")
	)
	(segment
		(start 192.3415 -16.256)
		(end 192.532 -16.4465)
		(width 0.12065)
		(layer "F.Cu")
		(net "LED_R_11")
	)
	(segment
		(start 192.532 -17.399)
		(end 192.430908 -17.500092)
		(width 0.12065)
		(layer "F.Cu")
		(net "LED_R_11")
	)
	(via
		(at 192.532 -17.399)
		(size 0.7112)
		(drill 0.3556)
		(layers "F.Cu" "B.Cu")
		(net "LED_R_11")
	)
	(segment
		(start 186.65952 -16.23314)
		(end 186.65952 -16.3703)
		(width 0.12065)
		(layer "F.Cu")
		(net "LED_R_10")
	)
	(segment
		(start 186.65952 -16.3703)
		(end 187.50788 -17.21866)
		(width 0.12065)
		(layer "F.Cu")
		(net "LED_R_10")
	)
	(segment
		(start 187.50788 -17.21866)
		(end 187.50788 -17.3609)
		(width 0.12065)
		(layer "F.Cu")
		(net "LED_R_10")
	)
	(segment
		(start 186.535314 -17.67332)
		(end 186.362086 -17.500092)
		(width 0.12065)
		(layer "F.Cu")
		(net "LED_R_10")
	)
	(segment
		(start 187.50788 -17.3609)
		(end 187.19546 -17.67332)
		(width 0.12065)
		(layer "F.Cu")
		(net "LED_R_10")
	)
	(segment
		(start 187.19546 -17.67332)
		(end 186.535314 -17.67332)
		(width 0.12065)
		(layer "F.Cu")
		(net "LED_R_10")
	)
	(via
		(at 187.50788 -17.3609)
		(size 0.7112)
		(drill 0.3556)
		(layers "F.Cu" "B.Cu")
		(net "LED_R_10")
	)
	(segment
		(start 123.630436 -19.823938)
		(end 123.630436 -18.642584)
		(width 0.12065)
		(layer "F.Cu")
		(net "LED_R_1")
	)
	(segment
		(start 123.638056 -19.831558)
		(end 123.630436 -19.823938)
		(width 0.12065)
		(layer "F.Cu")
		(net "LED_R_1")
	)
	(segment
		(start 124.837952 -19.99996)
		(end 123.806458 -19.99996)
		(width 0.12065)
		(layer "F.Cu")
		(net "LED_R_1")
	)
	(segment
		(start 123.630436 -18.642584)
		(end 123.6345 -18.63852)
		(width 0.12065)
		(layer "F.Cu")
		(net "LED_R_1")
	)
	(segment
		(start 123.806458 -19.99996)
		(end 123.638056 -19.831558)
		(width 0.12065)
		(layer "F.Cu")
		(net "LED_R_1")
	)
	(via
		(at 123.638056 -19.831558)
		(size 0.7112)
		(drill 0.3556)
		(layers "F.Cu" "B.Cu")
		(net "LED_R_1")
	)
	(segment
		(start 180.704744 -18.36674)
		(end 179.838096 -17.500092)
		(width 0.12065)
		(layer "F.Cu")
		(net "LED_Q_9")
	)
	(segment
		(start 188.976 -27.287728)
		(end 188.976 -23.921466)
		(width 0.12065)
		(layer "F.Cu")
		(net "LED_Q_9")
	)
	(segment
		(start 185.837322 -31.662878)
		(end 187.349892 -31.662878)
		(width 0.12065)
		(layer "F.Cu")
		(net "LED_Q_9")
	)
	(segment
		(start 189.313312 -27.62504)
		(end 188.976 -27.287728)
		(width 0.12065)
		(layer "F.Cu")
		(net "LED_Q_9")
	)
	(segment
		(start 188.976 -23.921466)
		(end 183.421274 -18.36674)
		(width 0.12065)
		(layer "F.Cu")
		(net "LED_Q_9")
	)
	(segment
		(start 183.421274 -18.36674)
		(end 180.704744 -18.36674)
		(width 0.12065)
		(layer "F.Cu")
		(net "LED_Q_9")
	)
	(segment
		(start 187.349892 -31.662878)
		(end 189.313312 -29.699458)
		(width 0.12065)
		(layer "F.Cu")
		(net "LED_Q_9")
	)
	(segment
		(start 189.313312 -29.699458)
		(end 189.313312 -27.62504)
		(width 0.12065)
		(layer "F.Cu")
		(net "LED_Q_9")
	)
	(segment
		(start 167.609774 -50.150268)
		(end 167.609774 -49.890426)
		(width 0.12065)
		(layer "F.Cu")
		(net "LED_Q_9")
	)
	(segment
		(start 167.609774 -49.890426)
		(end 173.228 -44.2722)
		(width 0.12065)
		(layer "F.Cu")
		(net "LED_Q_9")
	)
	(segment
		(start 173.228 -44.2722)
		(end 185.837322 -31.662878)
		(width 0.12065)
		(layer "F.Cu")
		(net "LED_Q_9")
	)
	(via
		(at 173.228 -44.2722)
		(size 0.7112)
		(drill 0.3556)
		(layers "F.Cu" "B.Cu")
		(net "LED_Q_9")
	)
	(segment
		(start 332.495652 -13.340588)
		(end 332.232 -13.076936)
		(width 0.12065)
		(layer "F.Cu")
		(net "LED_Q_8")
	)
	(segment
		(start 332.232 -8.128)
		(end 329.337924 -5.233924)
		(width 0.12065)
		(layer "F.Cu")
		(net "LED_Q_8")
	)
	(segment
		(start 333.772256 -30.68955)
		(end 332.495652 -29.41828)
		(width 0.12065)
		(layer "F.Cu")
		(net "LED_Q_8")
	)
	(segment
		(start 332.232 -13.076936)
		(end 332.232 -8.128)
		(width 0.12065)
		(layer "F.Cu")
		(net "LED_Q_8")
	)
	(segment
		(start 336.03692 -30.38602)
		(end 336.60588 -30.95498)
		(width 0.12065)
		(layer "F.Cu")
		(net "LED_Q_8")
	)
	(segment
		(start 332.495652 -29.41828)
		(end 332.495652 -13.340588)
		(width 0.12065)
		(layer "F.Cu")
		(net "LED_Q_8")
	)
	(segment
		(start 329.337924 -5.233924)
		(end 329.337924 -1.999996)
		(width 0.12065)
		(layer "F.Cu")
		(net "LED_Q_8")
	)
	(segment
		(start 334.276446 -30.688534)
		(end 333.772256 -30.68955)
		(width 0.12065)
		(layer "F.Cu")
		(net "LED_Q_8")
	)
	(segment
		(start 334.57896 -30.38602)
		(end 336.03692 -30.38602)
		(width 0.12065)
		(layer "F.Cu")
		(net "LED_Q_8")
	)
	(segment
		(start 334.276446 -30.688534)
		(end 334.57896 -30.38602)
		(width 0.12065)
		(layer "F.Cu")
		(net "LED_Q_8")
	)
	(via
		(at 334.276446 -30.688534)
		(size 0.7112)
		(drill 0.3556)
		(layers "F.Cu" "B.Cu")
		(net "LED_Q_8")
	)
	(segment
		(start 332.133702 -13.490702)
		(end 329.337924 -10.694924)
		(width 0.12065)
		(layer "F.Cu")
		(net "LED_Q_7")
	)
	(segment
		(start 335.24825 -34.316416)
		(end 334.77962 -33.847786)
		(width 0.12065)
		(layer "F.Cu")
		(net "LED_Q_7")
	)
	(segment
		(start 334.77962 -33.847786)
		(end 334.77962 -32.02686)
		(width 0.12065)
		(layer "F.Cu")
		(net "LED_Q_7")
	)
	(segment
		(start 334.007968 -31.600648)
		(end 332.133702 -29.726382)
		(width 0.12065)
		(layer "F.Cu")
		(net "LED_Q_7")
	)
	(segment
		(start 332.133702 -29.726382)
		(end 332.133702 -13.490702)
		(width 0.12065)
		(layer "F.Cu")
		(net "LED_Q_7")
	)
	(segment
		(start 336.68462 -35.752786)
		(end 335.24825 -34.316416)
		(width 0.12065)
		(layer "F.Cu")
		(net "LED_Q_7")
	)
	(segment
		(start 329.337924 -10.694924)
		(end 329.337924 -7.999984)
		(width 0.12065)
		(layer "F.Cu")
		(net "LED_Q_7")
	)
	(segment
		(start 334.353408 -31.600648)
		(end 334.007968 -31.600648)
		(width 0.12065)
		(layer "F.Cu")
		(net "LED_Q_7")
	)
	(segment
		(start 334.77962 -32.02686)
		(end 334.353408 -31.600648)
		(width 0.12065)
		(layer "F.Cu")
		(net "LED_Q_7")
	)
	(via
		(at 335.24825 -34.316416)
		(size 0.7112)
		(drill 0.3556)
		(layers "F.Cu" "B.Cu")
		(net "LED_Q_7")
	)
	(segment
		(start 333.99222 -34.2519)
		(end 333.87538 -34.36874)
		(width 0.12065)
		(layer "F.Cu")
		(net "LED_Q_6")
	)
	(segment
		(start 329.337924 -16.409924)
		(end 329.337924 -13.999972)
		(width 0.12065)
		(layer "F.Cu")
		(net "LED_Q_6")
	)
	(segment
		(start 333.99222 -32.1691)
		(end 333.99222 -34.2519)
		(width 0.12065)
		(layer "F.Cu")
		(net "LED_Q_6")
	)
	(segment
		(start 331.771752 -29.948632)
		(end 331.771752 -18.843752)
		(width 0.12065)
		(layer "F.Cu")
		(net "LED_Q_6")
	)
	(segment
		(start 331.771752 -18.843752)
		(end 329.337924 -16.409924)
		(width 0.12065)
		(layer "F.Cu")
		(net "LED_Q_6")
	)
	(segment
		(start 333.99222 -32.1691)
		(end 331.771752 -29.948632)
		(width 0.12065)
		(layer "F.Cu")
		(net "LED_Q_6")
	)
	(via
		(at 333.99222 -32.1691)
		(size 0.7112)
		(drill 0.3556)
		(layers "F.Cu" "B.Cu")
		(net "LED_Q_6")
	)
	(segment
		(start 330.12888 -31.600902)
		(end 330.12888 -32.14243)
		(width 0.12065)
		(layer "F.Cu")
		(net "LED_Q_5")
	)
	(segment
		(start 330.12888 -32.14243)
		(end 330.182982 -32.196532)
		(width 0.12065)
		(layer "F.Cu")
		(net "LED_Q_5")
	)
	(segment
		(start 330.182982 -31.5468)
		(end 330.12888 -31.600902)
		(width 0.12065)
		(layer "F.Cu")
		(net "LED_Q_5")
	)
	(segment
		(start 329.337924 -19.99996)
		(end 329.26274 -20.075144)
		(width 0.12065)
		(layer "F.Cu")
		(net "LED_Q_5")
	)
	(segment
		(start 330.182982 -32.196532)
		(end 330.182982 -32.905192)
		(width 0.12065)
		(layer "F.Cu")
		(net "LED_Q_5")
	)
	(segment
		(start 329.26274 -20.075144)
		(end 329.26274 -23.61057)
		(width 0.12065)
		(layer "F.Cu")
		(net "LED_Q_5")
	)
	(segment
		(start 330.591922 -33.314132)
		(end 330.591922 -38.69309)
		(width 0.12065)
		(layer "F.Cu")
		(net "LED_Q_5")
	)
	(segment
		(start 330.182982 -24.530812)
		(end 330.182982 -31.5468)
		(width 0.12065)
		(layer "F.Cu")
		(net "LED_Q_5")
	)
	(segment
		(start 330.182982 -32.905192)
		(end 330.591922 -33.314132)
		(width 0.12065)
		(layer "F.Cu")
		(net "LED_Q_5")
	)
	(segment
		(start 329.26274 -23.61057)
		(end 330.182982 -24.530812)
		(width 0.12065)
		(layer "F.Cu")
		(net "LED_Q_5")
	)
	(via
		(at 330.182982 -32.905192)
		(size 0.7112)
		(drill 0.3556)
		(layers "F.Cu" "B.Cu")
		(net "LED_Q_5")
	)
	(segment
		(start 126.361952 -4.441952)
		(end 126.361952 -1.999996)
		(width 0.12065)
		(layer "F.Cu")
		(net "LED_Q_4")
	)
	(segment
		(start 125.349 -30.47492)
		(end 128.397 -27.42692)
		(width 0.12065)
		(layer "F.Cu")
		(net "LED_Q_4")
	)
	(segment
		(start 125.349 -35.76828)
		(end 125.349 -30.47492)
		(width 0.12065)
		(layer "F.Cu")
		(net "LED_Q_4")
	)
	(segment
		(start 128.397 -27.42692)
		(end 128.397 -6.477)
		(width 0.12065)
		(layer "F.Cu")
		(net "LED_Q_4")
	)
	(segment
		(start 129.36093 -38.5445)
		(end 129.388362 -38.517068)
		(width 0.12065)
		(layer "F.Cu")
		(net "LED_Q_4")
	)
	(segment
		(start 128.12522 -38.5445)
		(end 129.36093 -38.5445)
		(width 0.12065)
		(layer "F.Cu")
		(net "LED_Q_4")
	)
	(segment
		(start 128.397 -6.477)
		(end 126.361952 -4.441952)
		(width 0.12065)
		(layer "F.Cu")
		(net "LED_Q_4")
	)
	(segment
		(start 126.37262 -36.7919)
		(end 128.12522 -38.5445)
		(width 0.12065)
		(layer "F.Cu")
		(net "LED_Q_4")
	)
	(segment
		(start 126.37262 -36.7919)
		(end 125.349 -35.76828)
		(width 0.12065)
		(layer "F.Cu")
		(net "LED_Q_4")
	)
	(via
		(at 126.37262 -36.7919)
		(size 0.7112)
		(drill 0.3556)
		(layers "F.Cu" "B.Cu")
		(net "LED_Q_4")
	)
	(segment
		(start 125.832362 -38.517068)
		(end 124.164852 -36.849558)
		(width 0.12065)
		(layer "F.Cu")
		(net "LED_Q_3")
	)
	(segment
		(start 124.164852 -35.7378)
		(end 124.164852 -30.828488)
		(width 0.12065)
		(layer "F.Cu")
		(net "LED_Q_3")
	)
	(segment
		(start 126.361952 -10.791952)
		(end 126.361952 -7.999984)
		(width 0.12065)
		(layer "F.Cu")
		(net "LED_Q_3")
	)
	(segment
		(start 127.61595 -12.04595)
		(end 126.361952 -10.791952)
		(width 0.12065)
		(layer "F.Cu")
		(net "LED_Q_3")
	)
	(segment
		(start 124.164852 -36.849558)
		(end 124.164852 -35.7378)
		(width 0.12065)
		(layer "F.Cu")
		(net "LED_Q_3")
	)
	(segment
		(start 124.164852 -30.828488)
		(end 127.61595 -27.37739)
		(width 0.12065)
		(layer "F.Cu")
		(net "LED_Q_3")
	)
	(segment
		(start 127.61595 -27.37739)
		(end 127.61595 -12.04595)
		(width 0.12065)
		(layer "F.Cu")
		(net "LED_Q_3")
	)
	(via
		(at 124.164852 -35.7378)
		(size 0.7112)
		(drill 0.3556)
		(layers "F.Cu" "B.Cu")
		(net "LED_Q_3")
	)
	(segment
		(start 127.254 -27.022552)
		(end 127.254 -14.89202)
		(width 0.12065)
		(layer "F.Cu")
		(net "LED_Q_2")
	)
	(segment
		(start 122.3772 -33.456626)
		(end 122.881898 -32.951928)
		(width 0.12065)
		(layer "F.Cu")
		(net "LED_Q_2")
	)
	(segment
		(start 122.881898 -31.394654)
		(end 127.254 -27.022552)
		(width 0.12065)
		(layer "F.Cu")
		(net "LED_Q_2")
	)
	(segment
		(start 121.785888 -34.047938)
		(end 118.576852 -34.047938)
		(width 0.12065)
		(layer "F.Cu")
		(net "LED_Q_2")
	)
	(segment
		(start 117.987572 -36.1315)
		(end 117.096286 -37.022786)
		(width 0.12065)
		(layer "F.Cu")
		(net "LED_Q_2")
	)
	(segment
		(start 118.576852 -34.047938)
		(end 117.987572 -34.637218)
		(width 0.12065)
		(layer "F.Cu")
		(net "LED_Q_2")
	)
	(segment
		(start 117.987572 -34.637218)
		(end 117.987572 -36.1315)
		(width 0.12065)
		(layer "F.Cu")
		(net "LED_Q_2")
	)
	(segment
		(start 117.096286 -37.022786)
		(end 117.03939 -37.022786)
		(width 0.12065)
		(layer "F.Cu")
		(net "LED_Q_2")
	)
	(segment
		(start 122.3772 -33.456626)
		(end 121.785888 -34.047938)
		(width 0.12065)
		(layer "F.Cu")
		(net "LED_Q_2")
	)
	(segment
		(start 122.881898 -32.951928)
		(end 122.881898 -31.394654)
		(width 0.12065)
		(layer "F.Cu")
		(net "LED_Q_2")
	)
	(segment
		(start 127.254 -14.89202)
		(end 126.361952 -13.999972)
		(width 0.12065)
		(layer "F.Cu")
		(net "LED_Q_2")
	)
	(via
		(at 122.3772 -33.456626)
		(size 0.7112)
		(drill 0.3556)
		(layers "F.Cu" "B.Cu")
		(net "LED_Q_2")
	)
	(segment
		(start 271.145 -22.716998)
		(end 271.145 -32.7025)
		(width 0.12065)
		(layer "F.Cu")
		(net "LED_Q_14")
	)
	(segment
		(start 292.227 -56.1975)
		(end 292.227 -53.7845)
		(width 0.12065)
		(layer "F.Cu")
		(net "LED_Q_14")
	)
	(segment
		(start 276.361906 -17.500092)
		(end 271.145 -22.716998)
		(width 0.12065)
		(layer "F.Cu")
		(net "LED_Q_14")
	)
	(segment
		(start 292.227 -53.7845)
		(end 272.11782 -33.67532)
		(width 0.12065)
		(layer "F.Cu")
		(net "LED_Q_14")
	)
	(segment
		(start 271.145 -32.7025)
		(end 272.11782 -33.67532)
		(width 0.12065)
		(layer "F.Cu")
		(net "LED_Q_14")
	)
	(via
		(at 272.11782 -33.67532)
		(size 0.7112)
		(drill 0.3556)
		(layers "F.Cu" "B.Cu")
		(net "LED_Q_14")
	)
	(segment
		(start 271.361916 -17.500092)
		(end 271.361916 -19.061938)
		(width 0.12065)
		(layer "F.Cu")
		(net "LED_Q_13")
	)
	(segment
		(start 268.587474 -21.83638)
		(end 268.587474 -22.652228)
		(width 0.12065)
		(layer "F.Cu")
		(net "LED_Q_13")
	)
	(segment
		(start 270.637 -24.701754)
		(end 268.587474 -22.652228)
		(width 0.12065)
		(layer "F.Cu")
		(net "LED_Q_13")
	)
	(segment
		(start 270.637 -32.99841)
		(end 270.637 -24.701754)
		(width 0.12065)
		(layer "F.Cu")
		(net "LED_Q_13")
	)
	(segment
		(start 288.544 -56.1975)
		(end 288.544 -50.90541)
		(width 0.12065)
		(layer "F.Cu")
		(net "LED_Q_13")
	)
	(segment
		(start 271.361916 -19.061938)
		(end 268.587474 -21.83638)
		(width 0.12065)
		(layer "F.Cu")
		(net "LED_Q_13")
	)
	(segment
		(start 288.544 -50.90541)
		(end 270.637 -32.99841)
		(width 0.12065)
		(layer "F.Cu")
		(net "LED_Q_13")
	)
	(via
		(at 268.587474 -22.652228)
		(size 0.7112)
		(drill 0.3556)
		(layers "F.Cu" "B.Cu")
		(net "LED_Q_13")
	)
	(segment
		(start 270.176752 -33.050226)
		(end 284.861 -47.734474)
		(width 0.12065)
		(layer "F.Cu")
		(net "LED_Q_12")
	)
	(segment
		(start 284.861 -47.734474)
		(end 284.861 -56.1975)
		(width 0.12065)
		(layer "F.Cu")
		(net "LED_Q_12")
	)
	(segment
		(start 270.176752 -25.045416)
		(end 270.176752 -33.050226)
		(width 0.12065)
		(layer "F.Cu")
		(net "LED_Q_12")
	)
	(segment
		(start 267.1699 -19.1897)
		(end 267.875258 -19.895058)
		(width 0.12065)
		(layer "F.Cu")
		(net "LED_Q_12")
	)
	(segment
		(start 267.875258 -22.743922)
		(end 270.176752 -25.045416)
		(width 0.12065)
		(layer "F.Cu")
		(net "LED_Q_12")
	)
	(segment
		(start 266.361926 -17.500092)
		(end 266.361926 -18.381726)
		(width 0.12065)
		(layer "F.Cu")
		(net "LED_Q_12")
	)
	(segment
		(start 267.875258 -19.895058)
		(end 267.875258 -22.743922)
		(width 0.12065)
		(layer "F.Cu")
		(net "LED_Q_12")
	)
	(segment
		(start 266.361926 -18.381726)
		(end 267.1699 -19.1897)
		(width 0.12065)
		(layer "F.Cu")
		(net "LED_Q_12")
	)
	(via
		(at 267.1699 -19.1897)
		(size 0.7112)
		(drill 0.3556)
		(layers "F.Cu" "B.Cu")
		(net "LED_Q_12")
	)
	(segment
		(start 174.721774 -50.150268)
		(end 174.721774 -48.645826)
		(width 0.12065)
		(layer "F.Cu")
		(net "LED_Q_11")
	)
	(segment
		(start 190.26251 -29.44622)
		(end 190.26251 -31.073344)
		(width 0.12065)
		(layer "F.Cu")
		(net "LED_Q_11")
	)
	(segment
		(start 190.26251 -27.55011)
		(end 190.26251 -28.97378)
		(width 0.12065)
		(layer "F.Cu")
		(net "LED_Q_11")
	)
	(segment
		(start 190.26251 -31.073344)
		(end 174.8028 -46.533054)
		(width 0.12065)
		(layer "F.Cu")
		(net "LED_Q_11")
	)
	(segment
		(start 190.261748 -28.974542)
		(end 190.261748 -29.445458)
		(width 0.12065)
		(layer "F.Cu")
		(net "LED_Q_11")
	)
	(segment
		(start 174.8028 -46.533054)
		(end 174.8028 -48.5648)
		(width 0.12065)
		(layer "F.Cu")
		(net "LED_Q_11")
	)
	(segment
		(start 190.261748 -29.445458)
		(end 190.26251 -29.44622)
		(width 0.12065)
		(layer "F.Cu")
		(net "LED_Q_11")
	)
	(segment
		(start 174.721774 -48.645826)
		(end 174.8028 -48.5648)
		(width 0.12065)
		(layer "F.Cu")
		(net "LED_Q_11")
	)
	(segment
		(start 190.26251 -28.97378)
		(end 190.261748 -28.974542)
		(width 0.12065)
		(layer "F.Cu")
		(net "LED_Q_11")
	)
	(segment
		(start 189.838076 -17.500092)
		(end 189.838076 -27.125676)
		(width 0.12065)
		(layer "F.Cu")
		(net "LED_Q_11")
	)
	(segment
		(start 189.838076 -27.125676)
		(end 190.26251 -27.55011)
		(width 0.12065)
		(layer "F.Cu")
		(net "LED_Q_11")
	)
	(via
		(at 174.8028 -48.5648)
		(size 0.7112)
		(drill 0.3556)
		(layers "F.Cu" "B.Cu")
		(net "LED_Q_11")
	)
	(segment
		(start 189.90056 -27.700224)
		(end 189.90056 -28.823666)
		(width 0.12065)
		(layer "F.Cu")
		(net "LED_Q_10")
	)
	(segment
		(start 171.165774 -50.150268)
		(end 171.165774 -48.696626)
		(width 0.12065)
		(layer "F.Cu")
		(net "LED_Q_10")
	)
	(segment
		(start 189.899798 -29.595572)
		(end 189.90056 -29.596334)
		(width 0.12065)
		(layer "F.Cu")
		(net "LED_Q_10")
	)
	(segment
		(start 171.165774 -48.696626)
		(end 171.2214 -48.641)
		(width 0.12065)
		(layer "F.Cu")
		(net "LED_Q_10")
	)
	(segment
		(start 189.90056 -29.596334)
		(end 189.90056 -29.96184)
		(width 0.12065)
		(layer "F.Cu")
		(net "LED_Q_10")
	)
	(segment
		(start 184.838086 -17.500092)
		(end 189.357 -22.019006)
		(width 0.12065)
		(layer "F.Cu")
		(net "LED_Q_10")
	)
	(segment
		(start 189.357 -27.156664)
		(end 189.90056 -27.700224)
		(width 0.12065)
		(layer "F.Cu")
		(net "LED_Q_10")
	)
	(segment
		(start 189.90056 -29.96184)
		(end 171.2214 -48.641)
		(width 0.12065)
		(layer "F.Cu")
		(net "LED_Q_10")
	)
	(segment
		(start 189.899798 -28.824428)
		(end 189.899798 -29.595572)
		(width 0.12065)
		(layer "F.Cu")
		(net "LED_Q_10")
	)
	(segment
		(start 189.357 -22.019006)
		(end 189.357 -27.156664)
		(width 0.12065)
		(layer "F.Cu")
		(net "LED_Q_10")
	)
	(segment
		(start 189.90056 -28.823666)
		(end 189.899798 -28.824428)
		(width 0.12065)
		(layer "F.Cu")
		(net "LED_Q_10")
	)
	(via
		(at 171.2214 -48.641)
		(size 0.7112)
		(drill 0.3556)
		(layers "F.Cu" "B.Cu")
		(net "LED_Q_10")
	)
	(segment
		(start 126.361952 -27.402536)
		(end 126.361952 -19.99996)
		(width 0.12065)
		(layer "F.Cu")
		(net "LED_Q_1")
	)
	(segment
		(start 120.553988 -33.2105)
		(end 126.361952 -27.402536)
		(width 0.12065)
		(layer "F.Cu")
		(net "LED_Q_1")
	)
	(segment
		(start 120.487948 -33.2105)
		(end 120.553988 -33.2105)
		(width 0.12065)
		(layer "F.Cu")
		(net "LED_Q_1")
	)
	(segment
		(start 120.487948 -33.2105)
		(end 118.411752 -33.2105)
		(width 0.12065)
		(layer "F.Cu")
		(net "LED_Q_1")
	)
	(segment
		(start 118.411752 -33.2105)
		(end 118.17858 -32.977328)
		(width 0.12065)
		(layer "F.Cu")
		(net "LED_Q_1")
	)
	(via
		(at 120.487948 -33.2105)
		(size 0.7112)
		(drill 0.3556)
		(layers "F.Cu" "B.Cu")
		(net "LED_Q_1")
	)
	(segment
		(start 209.9818 -0.508)
		(end 208.050638 -0.508)
		(width 0.12065)
		(layer "F.Cu")
		(net "LED_PWR_N_R")
	)
	(segment
		(start 208.050638 -0.52832)
		(end 207.645 -0.933958)
		(width 0.12065)
		(layer "F.Cu")
		(net "LED_PWR_N_R")
	)
	(segment
		(start 207.0354 -1.8796)
		(end 205.222602 -1.8796)
		(width 0.12065)
		(layer "F.Cu")
		(net "LED_PWR_N_R")
	)
	(segment
		(start 207.645 -0.933958)
		(end 207.645 -1.3208)
		(width 0.12065)
		(layer "F.Cu")
		(net "LED_PWR_N_R")
	)
	(segment
		(start 204.029056 -0.686054)
		(end 204.029056 0)
		(width 0.12065)
		(layer "F.Cu")
		(net "LED_PWR_N_R")
	)
	(segment
		(start 205.222602 -1.8796)
		(end 204.029056 -0.686054)
		(width 0.12065)
		(layer "F.Cu")
		(net "LED_PWR_N_R")
	)
	(segment
		(start 207.0608 -1.905)
		(end 207.0354 -1.8796)
		(width 0.12065)
		(layer "F.Cu")
		(net "LED_PWR_N_R")
	)
	(segment
		(start 208.050638 -0.508)
		(end 208.050638 -0.52832)
		(width 0.12065)
		(layer "F.Cu")
		(net "LED_PWR_N_R")
	)
	(segment
		(start 207.645 -1.3208)
		(end 207.0608 -1.905)
		(width 0.12065)
		(layer "F.Cu")
		(net "LED_PWR_N_R")
	)
	(via
		(at 207.0608 -1.905)
		(size 0.7112)
		(drill 0.3556)
		(layers "F.Cu" "B.Cu")
		(net "LED_PWR_N_R")
	)
	(segment
		(start 207.171036 0)
		(end 205.667102 0)
		(width 0.12065)
		(layer "F.Cu")
		(net "LED_PWR_N_ON")
	)
	(segment
		(start 210.36915 -16.2306)
		(end 210.4898 -16.10995)
		(width 0.12065)
		(layer "F.Cu")
		(net "LED_PWR_N_ON")
	)
	(segment
		(start 205.667102 0)
		(end 205.108556 -0.558546)
		(width 0.12065)
		(layer "F.Cu")
		(net "LED_PWR_N_ON")
	)
	(segment
		(start 207.5053 -16.2306)
		(end 210.36915 -16.2306)
		(width 0.12065)
		(layer "F.Cu")
		(net "LED_PWR_N_ON")
	)
	(segment
		(start 210.4898 -16.10995)
		(end 210.4898 -12.3952)
		(width 0.12065)
		(layer "F.Cu")
		(net "LED_PWR_N_ON")
	)
	(via
		(at 205.108556 -0.558546)
		(size 0.508)
		(drill 0.254)
		(layers "F.Cu" "B.Cu")
		(net "LED_PWR_N_ON")
	)
	(via
		(at 210.242658 -11.062716)
		(size 0.7112)
		(drill 0.3556)
		(layers "F.Cu" "B.Cu")
		(net "LED_PWR_N_ON")
	)
	(via
		(at 210.4898 -12.3952)
		(size 0.508)
		(drill 0.254)
		(layers "F.Cu" "B.Cu")
		(net "LED_PWR_N_ON")
	)
	(segment
		(start 205.108556 -0.558546)
		(end 205.108556 -3.38074)
		(width 0.12065)
		(layer "B.Cu")
		(net "LED_PWR_N_ON")
	)
	(segment
		(start 210.242658 -12.148058)
		(end 210.4898 -12.3952)
		(width 0.12065)
		(layer "B.Cu")
		(net "LED_PWR_N_ON")
	)
	(segment
		(start 210.242658 -11.062716)
		(end 210.242658 -12.148058)
		(width 0.12065)
		(layer "B.Cu")
		(net "LED_PWR_N_ON")
	)
	(segment
		(start 210.242658 -10.317988)
		(end 210.242658 -11.062716)
		(width 0.12065)
		(layer "B.Cu")
		(net "LED_PWR_N_ON")
	)
	(segment
		(start 205.444852 -5.520182)
		(end 210.242658 -10.317988)
		(width 0.12065)
		(layer "B.Cu")
		(net "LED_PWR_N_ON")
	)
	(segment
		(start 205.108556 -3.38074)
		(end 205.444852 -3.717036)
		(width 0.12065)
		(layer "B.Cu")
		(net "LED_PWR_N_ON")
	)
	(segment
		(start 205.444852 -3.717036)
		(end 205.444852 -5.520182)
		(width 0.12065)
		(layer "B.Cu")
		(net "LED_PWR_N_ON")
	)
	(segment
		(start 5.8674 -53.3527)
		(end 2.9718 -50.4571)
		(width 0.12065)
		(layer "F.Cu")
		(net "LED_MDI0_ACT")
	)
	(segment
		(start 6.8707 -55.1053)
		(end 6.9342 -55.1688)
		(width 0.12065)
		(layer "F.Cu")
		(net "LED_MDI0_ACT")
	)
	(segment
		(start 8.122158 -30.333442)
		(end 8.122158 -29.619956)
		(width 0.12065)
		(layer "F.Cu")
		(net "LED_MDI0_ACT")
	)
	(segment
		(start 5.8674 -55.1053)
		(end 5.8674 -53.3527)
		(width 0.12065)
		(layer "F.Cu")
		(net "LED_MDI0_ACT")
	)
	(segment
		(start 2.9718 -50.4571)
		(end 2.9718 -35.4838)
		(width 0.12065)
		(layer "F.Cu")
		(net "LED_MDI0_ACT")
	)
	(segment
		(start 2.9718 -35.4838)
		(end 8.122158 -30.333442)
		(width 0.12065)
		(layer "F.Cu")
		(net "LED_MDI0_ACT")
	)
	(segment
		(start 5.8674 -55.1053)
		(end 6.8707 -55.1053)
		(width 0.12065)
		(layer "F.Cu")
		(net "LED_MDI0_ACT")
	)
	(segment
		(start 49.912016 -141.62278)
		(end 46.764702 -138.475466)
		(width 0.12065)
		(layer "F.Cu")
		(net "LED_DR_LED1")
	)
	(segment
		(start 51.3842 -142.179802)
		(end 50.469038 -142.179802)
		(width 0.12065)
		(layer "F.Cu")
		(net "LED_DR_LED1")
	)
	(segment
		(start 50.469038 -142.179802)
		(end 50.195988 -141.906752)
		(width 0.12065)
		(layer "F.Cu")
		(net "LED_DR_LED1")
	)
	(segment
		(start 51.3842 -142.179802)
		(end 51.501802 -142.179802)
		(width 0.12065)
		(layer "F.Cu")
		(net "LED_DR_LED1")
	)
	(segment
		(start 51.968654 -142.646654)
		(end 52.441094 -142.646654)
		(width 0.12065)
		(layer "F.Cu")
		(net "LED_DR_LED1")
	)
	(segment
		(start 53.18379 -142.585948)
		(end 53.609748 -143.011906)
		(width 0.12065)
		(layer "F.Cu")
		(net "LED_DR_LED1")
	)
	(segment
		(start 53.609748 -144.573752)
		(end 53.2765 -144.907)
		(width 0.12065)
		(layer "F.Cu")
		(net "LED_DR_LED1")
	)
	(segment
		(start 46.343062 -138.475466)
		(end 45.95241 -138.084814)
		(width 0.12065)
		(layer "F.Cu")
		(net "LED_DR_LED1")
	)
	(segment
		(start 50.195988 -141.884908)
		(end 49.93386 -141.62278)
		(width 0.12065)
		(layer "F.Cu")
		(net "LED_DR_LED1")
	)
	(segment
		(start 45.95241 -138.084814)
		(end 45.70476 -138.084814)
		(width 0.12065)
		(layer "F.Cu")
		(net "LED_DR_LED1")
	)
	(segment
		(start 53.609748 -143.011906)
		(end 53.609748 -144.573752)
		(width 0.12065)
		(layer "F.Cu")
		(net "LED_DR_LED1")
	)
	(segment
		(start 208.284572 -12.097766)
		(end 208.284572 -11.238992)
		(width 0.12065)
		(layer "F.Cu")
		(net "LED_DR_LED1")
	)
	(segment
		(start 52.441094 -142.646654)
		(end 52.5018 -142.585948)
		(width 0.12065)
		(layer "F.Cu")
		(net "LED_DR_LED1")
	)
	(segment
		(start 50.195988 -141.906752)
		(end 50.195988 -141.884908)
		(width 0.12065)
		(layer "F.Cu")
		(net "LED_DR_LED1")
	)
	(segment
		(start 208.284572 -11.238992)
		(end 208.281016 -11.235436)
		(width 0.12065)
		(layer "F.Cu")
		(net "LED_DR_LED1")
	)
	(segment
		(start 51.501802 -142.179802)
		(end 51.968654 -142.646654)
		(width 0.12065)
		(layer "F.Cu")
		(net "LED_DR_LED1")
	)
	(segment
		(start 52.5018 -142.585948)
		(end 53.18379 -142.585948)
		(width 0.12065)
		(layer "F.Cu")
		(net "LED_DR_LED1")
	)
	(segment
		(start 46.764702 -138.475466)
		(end 46.343062 -138.475466)
		(width 0.12065)
		(layer "F.Cu")
		(net "LED_DR_LED1")
	)
	(segment
		(start 49.93386 -141.62278)
		(end 49.912016 -141.62278)
		(width 0.12065)
		(layer "F.Cu")
		(net "LED_DR_LED1")
	)
	(via
		(at 51.3842 -142.179802)
		(size 0.508)
		(drill 0.254)
		(layers "F.Cu" "B.Cu")
		(net "LED_DR_LED1")
	)
	(via
		(at 206.231998 -10.510774)
		(size 0.7112)
		(drill 0.3556)
		(layers "F.Cu" "B.Cu")
		(net "LED_DR_LED1")
	)
	(via
		(at 200.255632 1.097534)
		(size 0.508)
		(drill 0.254)
		(layers "F.Cu" "B.Cu")
		(net "LED_DR_LED1")
	)
	(via
		(at 208.281016 -11.235436)
		(size 0.508)
		(drill 0.254)
		(layers "F.Cu" "B.Cu")
		(net "LED_DR_LED1")
	)
	(via
		(at 77.093318 -78.683358)
		(size 0.508)
		(drill 0.254)
		(layers "F.Cu" "B.Cu")
		(net "LED_DR_LED1")
	)
	(via
		(at 72.0344 -140.0556)
		(size 0.508)
		(drill 0.254)
		(layers "F.Cu" "B.Cu")
		(net "LED_DR_LED1")
	)
	(segment
		(start 200.0504 0.892302)
		(end 200.255632 1.097534)
		(width 0.12065)
		(layer "B.Cu")
		(net "LED_DR_LED1")
	)
	(segment
		(start 200.0504 -0.7366)
		(end 200.0504 0.892302)
		(width 0.12065)
		(layer "B.Cu")
		(net "LED_DR_LED1")
	)
	(segment
		(start 206.849218 -11.127994)
		(end 206.231998 -10.510774)
		(width 0.12065)
		(layer "B.Cu")
		(net "LED_DR_LED1")
	)
	(segment
		(start 203.11745 -7.396226)
		(end 203.11745 -3.80365)
		(width 0.12065)
		(layer "B.Cu")
		(net "LED_DR_LED1")
	)
	(segment
		(start 208.281016 -11.235436)
		(end 208.173574 -11.127994)
		(width 0.12065)
		(layer "B.Cu")
		(net "LED_DR_LED1")
	)
	(segment
		(start 208.173574 -11.127994)
		(end 206.849218 -11.127994)
		(width 0.12065)
		(layer "B.Cu")
		(net "LED_DR_LED1")
	)
	(segment
		(start 203.11745 -3.80365)
		(end 200.0504 -0.7366)
		(width 0.12065)
		(layer "B.Cu")
		(net "LED_DR_LED1")
	)
	(segment
		(start 206.231998 -10.510774)
		(end 203.11745 -7.396226)
		(width 0.12065)
		(layer "B.Cu")
		(net "LED_DR_LED1")
	)
	(segment
		(start 78.407514 -77.369162)
		(end 77.093318 -78.683358)
		(width 0.127)
		(layer "In2.Cu")
		(net "LED_DR_LED1")
	)
	(segment
		(start 120.924066 -5.501386)
		(end 120.007634 -5.501386)
		(width 0.127)
		(layer "In2.Cu")
		(net "LED_DR_LED1")
	)
	(segment
		(start 69.577204 -140.734796)
		(end 70.7263 -139.5857)
		(width 0.127)
		(layer "In2.Cu")
		(net "LED_DR_LED1")
	)
	(segment
		(start 84.90204 -72.492616)
		(end 80.025494 -77.369162)
		(width 0.127)
		(layer "In2.Cu")
		(net "LED_DR_LED1")
	)
	(segment
		(start 198.575676 2.77749)
		(end 129.202942 2.77749)
		(width 0.127)
		(layer "In2.Cu")
		(net "LED_DR_LED1")
	)
	(segment
		(start 92.57919 -32.92983)
		(end 92.57919 -59.46521)
		(width 0.127)
		(layer "In2.Cu")
		(net "LED_DR_LED1")
	)
	(segment
		(start 92.57919 -59.46521)
		(end 84.90204 -67.14236)
		(width 0.127)
		(layer "In2.Cu")
		(net "LED_DR_LED1")
	)
	(segment
		(start 70.7263 -139.5857)
		(end 71.5645 -139.5857)
		(width 0.127)
		(layer "In2.Cu")
		(net "LED_DR_LED1")
	)
	(segment
		(start 51.89347 -141.670532)
		(end 55.27675 -141.670532)
		(width 0.127)
		(layer "In2.Cu")
		(net "LED_DR_LED1")
	)
	(segment
		(start 55.27675 -141.670532)
		(end 56.212486 -140.734796)
		(width 0.127)
		(layer "In2.Cu")
		(net "LED_DR_LED1")
	)
	(segment
		(start 120.007634 -5.501386)
		(end 92.57919 -32.92983)
		(width 0.127)
		(layer "In2.Cu")
		(net "LED_DR_LED1")
	)
	(segment
		(start 56.212486 -140.734796)
		(end 69.577204 -140.734796)
		(width 0.127)
		(layer "In2.Cu")
		(net "LED_DR_LED1")
	)
	(segment
		(start 129.202942 2.77749)
		(end 120.924066 -5.501386)
		(width 0.127)
		(layer "In2.Cu")
		(net "LED_DR_LED1")
	)
	(segment
		(start 200.255632 1.097534)
		(end 198.575676 2.77749)
		(width 0.127)
		(layer "In2.Cu")
		(net "LED_DR_LED1")
	)
	(segment
		(start 71.5645 -139.5857)
		(end 72.0344 -140.0556)
		(width 0.127)
		(layer "In2.Cu")
		(net "LED_DR_LED1")
	)
	(segment
		(start 80.025494 -77.369162)
		(end 78.407514 -77.369162)
		(width 0.127)
		(layer "In2.Cu")
		(net "LED_DR_LED1")
	)
	(segment
		(start 51.3842 -142.179802)
		(end 51.89347 -141.670532)
		(width 0.127)
		(layer "In2.Cu")
		(net "LED_DR_LED1")
	)
	(segment
		(start 84.90204 -67.14236)
		(end 84.90204 -72.492616)
		(width 0.127)
		(layer "In2.Cu")
		(net "LED_DR_LED1")
	)
	(segment
		(start 75.590908 -95.19285)
		(end 77.48778 -93.295978)
		(width 0.127)
		(layer "In5.Cu")
		(net "LED_DR_LED1")
	)
	(segment
		(start 77.48778 -84.29498)
		(end 77.093318 -83.900518)
		(width 0.127)
		(layer "In5.Cu")
		(net "LED_DR_LED1")
	)
	(segment
		(start 73.15962 -131.48818)
		(end 73.15962 -129.741168)
		(width 0.127)
		(layer "In5.Cu")
		(net "LED_DR_LED1")
	)
	(segment
		(start 72.0344 -140.0556)
		(end 72.0344 -132.6134)
		(width 0.127)
		(layer "In5.Cu")
		(net "LED_DR_LED1")
	)
	(segment
		(start 74.564748 -128.051052)
		(end 74.986134 -127.629666)
		(width 0.127)
		(layer "In5.Cu")
		(net "LED_DR_LED1")
	)
	(segment
		(start 73.15962 -129.741168)
		(end 73.159366 -129.740914)
		(width 0.127)
		(layer "In5.Cu")
		(net "LED_DR_LED1")
	)
	(segment
		(start 75.565 -123.836176)
		(end 75.565 -104.538526)
		(width 0.127)
		(layer "In5.Cu")
		(net "LED_DR_LED1")
	)
	(segment
		(start 74.53376 -128.051052)
		(end 74.564748 -128.051052)
		(width 0.127)
		(layer "In5.Cu")
		(net "LED_DR_LED1")
	)
	(segment
		(start 75.565 -104.538526)
		(end 75.590908 -104.512618)
		(width 0.127)
		(layer "In5.Cu")
		(net "LED_DR_LED1")
	)
	(segment
		(start 74.986134 -127.629666)
		(end 74.986134 -124.415042)
		(width 0.127)
		(layer "In5.Cu")
		(net "LED_DR_LED1")
	)
	(segment
		(start 74.986134 -124.415042)
		(end 75.565 -123.836176)
		(width 0.127)
		(layer "In5.Cu")
		(net "LED_DR_LED1")
	)
	(segment
		(start 73.159366 -129.740914)
		(end 73.159366 -129.425446)
		(width 0.127)
		(layer "In5.Cu")
		(net "LED_DR_LED1")
	)
	(segment
		(start 77.48778 -93.295978)
		(end 77.48778 -84.29498)
		(width 0.127)
		(layer "In5.Cu")
		(net "LED_DR_LED1")
	)
	(segment
		(start 75.590908 -104.512618)
		(end 75.590908 -95.19285)
		(width 0.127)
		(layer "In5.Cu")
		(net "LED_DR_LED1")
	)
	(segment
		(start 77.093318 -83.900518)
		(end 77.093318 -78.683358)
		(width 0.127)
		(layer "In5.Cu")
		(net "LED_DR_LED1")
	)
	(segment
		(start 73.159366 -129.425446)
		(end 74.53376 -128.051052)
		(width 0.127)
		(layer "In5.Cu")
		(net "LED_DR_LED1")
	)
	(segment
		(start 72.0344 -132.6134)
		(end 73.15962 -131.48818)
		(width 0.127)
		(layer "In5.Cu")
		(net "LED_DR_LED1")
	)
	(segment
		(start 52.197 -145.8595)
		(end 52.663852 -145.392648)
		(width 0.12065)
		(layer "F.Cu")
		(net "LED_DR_LED0")
	)
	(segment
		(start 52.663852 -145.392648)
		(end 52.663852 -143.424148)
		(width 0.12065)
		(layer "F.Cu")
		(net "LED_DR_LED0")
	)
	(segment
		(start 52.663852 -143.424148)
		(end 52.959 -143.129)
		(width 0.12065)
		(layer "F.Cu")
		(net "LED_DR_LED0")
	)
	(segment
		(start 241.599974 -39.99992)
		(end 242.099846 -39.500048)
		(width 0.12065)
		(layer "F.Cu")
		(net "LBI_WE#")
	)
	(via
		(at 242.099846 -39.500048)
		(size 0.4572)
		(drill 0.2032)
		(layers "F.Cu" "B.Cu")
		(net "LBI_WE#")
	)
	(segment
		(start 241.599974 -38.999922)
		(end 241.599974 -39.000176)
		(width 0.12065)
		(layer "B.Cu")
		(net "LBI_WE#")
	)
	(segment
		(start 241.599974 -39.000176)
		(end 242.099846 -39.500048)
		(width 0.12065)
		(layer "B.Cu")
		(net "LBI_WE#")
	)
	(segment
		(start 242.599972 -34.99993)
		(end 243.099844 -34.500058)
		(width 0.12065)
		(layer "F.Cu")
		(net "LBI_OE#")
	)
	(via
		(at 243.099844 -34.500058)
		(size 0.4572)
		(drill 0.2032)
		(layers "F.Cu" "B.Cu")
		(net "LBI_OE#")
	)
	(segment
		(start 243.423948 -28.161996)
		(end 242.502944 -29.083)
		(width 0.12065)
		(layer "B.Cu")
		(net "LBI_OE#")
	)
	(segment
		(start 243.423948 -25.943052)
		(end 243.423948 -28.161996)
		(width 0.12065)
		(layer "B.Cu")
		(net "LBI_OE#")
	)
	(segment
		(start 242.502944 -29.083)
		(end 242.502944 -33.903158)
		(width 0.1016)
		(layer "B.Cu")
		(net "LBI_OE#")
	)
	(segment
		(start 243.967 -25.4)
		(end 243.423948 -25.943052)
		(width 0.12065)
		(layer "B.Cu")
		(net "LBI_OE#")
	)
	(segment
		(start 242.502944 -33.903158)
		(end 243.099844 -34.500058)
		(width 0.1016)
		(layer "B.Cu")
		(net "LBI_OE#")
	)
	(segment
		(start 241.599974 -36.999926)
		(end 242.099846 -36.500054)
		(width 0.12065)
		(layer "F.Cu")
		(net "LBI_DATA15")
	)
	(via
		(at 242.099846 -36.500054)
		(size 0.4572)
		(drill 0.2032)
		(layers "F.Cu" "B.Cu")
		(net "LBI_DATA15")
	)
	(segment
		(start 242.099846 -36.436046)
		(end 242.099846 -36.500054)
		(width 0.12065)
		(layer "B.Cu")
		(net "LBI_DATA15")
	)
	(segment
		(start 239.86871 -27.566112)
		(end 239.86871 -29.069284)
		(width 0.12065)
		(layer "B.Cu")
		(net "LBI_DATA15")
	)
	(segment
		(start 240.132108 -32.062928)
		(end 240.132108 -35.408108)
		(width 0.12065)
		(layer "B.Cu")
		(net "LBI_DATA15")
	)
	(segment
		(start 238.4044 -25.273)
		(end 239.258348 -26.126948)
		(width 0.12065)
		(layer "B.Cu")
		(net "LBI_DATA15")
	)
	(segment
		(start 241.5794 -35.9156)
		(end 242.099846 -36.436046)
		(width 0.12065)
		(layer "B.Cu")
		(net "LBI_DATA15")
	)
	(segment
		(start 240.416588 -31.778448)
		(end 240.132108 -32.062928)
		(width 0.12065)
		(layer "B.Cu")
		(net "LBI_DATA15")
	)
	(segment
		(start 239.258348 -26.126948)
		(end 239.258348 -26.95575)
		(width 0.12065)
		(layer "B.Cu")
		(net "LBI_DATA15")
	)
	(segment
		(start 240.416588 -29.617162)
		(end 240.416588 -31.778448)
		(width 0.12065)
		(layer "B.Cu")
		(net "LBI_DATA15")
	)
	(segment
		(start 240.132108 -35.408108)
		(end 240.6396 -35.9156)
		(width 0.12065)
		(layer "B.Cu")
		(net "LBI_DATA15")
	)
	(segment
		(start 239.258348 -26.95575)
		(end 239.86871 -27.566112)
		(width 0.12065)
		(layer "B.Cu")
		(net "LBI_DATA15")
	)
	(segment
		(start 240.6396 -35.9156)
		(end 241.5794 -35.9156)
		(width 0.12065)
		(layer "B.Cu")
		(net "LBI_DATA15")
	)
	(segment
		(start 239.86871 -29.069284)
		(end 240.416588 -29.617162)
		(width 0.12065)
		(layer "B.Cu")
		(net "LBI_DATA15")
	)
	(segment
		(start 229.599998 -33.999932)
		(end 229.100126 -33.50006)
		(width 0.12065)
		(layer "F.Cu")
		(net "LBI_DATA14_R")
	)
	(segment
		(start 217.0176 -31.12262)
		(end 217.0176 -29.845)
		(width 0.12065)
		(layer "F.Cu")
		(net "LBI_DATA14_R")
	)
	(segment
		(start 217.04554 -31.15056)
		(end 217.0176 -31.12262)
		(width 0.12065)
		(layer "F.Cu")
		(net "LBI_DATA14_R")
	)
	(via
		(at 217.0176 -29.845)
		(size 0.508)
		(drill 0.254)
		(layers "F.Cu" "B.Cu")
		(net "LBI_DATA14_R")
	)
	(via
		(at 229.100126 -33.50006)
		(size 0.4572)
		(drill 0.2032)
		(layers "F.Cu" "B.Cu")
		(net "LBI_DATA14_R")
	)
	(segment
		(start 227.49383 -32.33674)
		(end 227.49383 -32.59201)
		(width 0.1016)
		(layer "In2.Cu")
		(net "LBI_DATA14_R")
	)
	(segment
		(start 227.263452 -32.106362)
		(end 227.49383 -32.33674)
		(width 0.1016)
		(layer "In2.Cu")
		(net "LBI_DATA14_R")
	)
	(segment
		(start 217.0176 -29.845)
		(end 217.17 -29.845)
		(width 0.127)
		(layer "In2.Cu")
		(net "LBI_DATA14_R")
	)
	(segment
		(start 226.263454 -31.106364)
		(end 226.493832 -31.336742)
		(width 0.1016)
		(layer "In2.Cu")
		(net "LBI_DATA14_R")
	)
	(segment
		(start 228.65715 -33.50006)
		(end 229.100126 -33.50006)
		(width 0.1016)
		(layer "In2.Cu")
		(net "LBI_DATA14_R")
	)
	(segment
		(start 217.17 -29.845)
		(end 218.43238 -31.10738)
		(width 0.127)
		(layer "In2.Cu")
		(net "LBI_DATA14_R")
	)
	(segment
		(start 221.511368 -31.10738)
		(end 221.512384 -31.106364)
		(width 0.1016)
		(layer "In2.Cu")
		(net "LBI_DATA14_R")
	)
	(segment
		(start 227.051362 -32.106362)
		(end 227.263452 -32.106362)
		(width 0.1016)
		(layer "In2.Cu")
		(net "LBI_DATA14_R")
	)
	(segment
		(start 218.43238 -31.10738)
		(end 221.511368 -31.10738)
		(width 0.127)
		(layer "In2.Cu")
		(net "LBI_DATA14_R")
	)
	(segment
		(start 228.00818 -33.10636)
		(end 228.26345 -33.10636)
		(width 0.1016)
		(layer "In2.Cu")
		(net "LBI_DATA14_R")
	)
	(segment
		(start 226.493832 -31.548832)
		(end 227.051362 -32.106362)
		(width 0.1016)
		(layer "In2.Cu")
		(net "LBI_DATA14_R")
	)
	(segment
		(start 228.26345 -33.10636)
		(end 228.65715 -33.50006)
		(width 0.1016)
		(layer "In2.Cu")
		(net "LBI_DATA14_R")
	)
	(segment
		(start 226.493832 -31.336742)
		(end 226.493832 -31.548832)
		(width 0.1016)
		(layer "In2.Cu")
		(net "LBI_DATA14_R")
	)
	(segment
		(start 227.49383 -32.59201)
		(end 228.00818 -33.10636)
		(width 0.1016)
		(layer "In2.Cu")
		(net "LBI_DATA14_R")
	)
	(segment
		(start 221.512384 -31.106364)
		(end 226.263454 -31.106364)
		(width 0.1016)
		(layer "In2.Cu")
		(net "LBI_DATA14_R")
	)
	(segment
		(start 229.599998 -34.99993)
		(end 229.100126 -34.500058)
		(width 0.12065)
		(layer "F.Cu")
		(net "LBI_DATA13_R")
	)
	(via
		(at 229.100126 -34.500058)
		(size 0.4572)
		(drill 0.2032)
		(layers "F.Cu" "B.Cu")
		(net "LBI_DATA13_R")
	)
	(segment
		(start 229.493826 -31.175706)
		(end 229.493826 -33.663382)
		(width 0.1016)
		(layer "B.Cu")
		(net "LBI_DATA13_R")
	)
	(segment
		(start 227.2919 -28.46324)
		(end 227.5332 -28.70454)
		(width 0.1016)
		(layer "B.Cu")
		(net "LBI_DATA13_R")
	)
	(segment
		(start 229.493826 -33.663382)
		(end 229.100126 -34.057082)
		(width 0.1016)
		(layer "B.Cu")
		(net "LBI_DATA13_R")
	)
	(segment
		(start 228.04882 -31.00578)
		(end 229.3239 -31.00578)
		(width 0.1016)
		(layer "B.Cu")
		(net "LBI_DATA13_R")
	)
	(segment
		(start 227.5332 -28.70454)
		(end 227.5332 -30.49016)
		(width 0.1016)
		(layer "B.Cu")
		(net "LBI_DATA13_R")
	)
	(segment
		(start 227.5332 -30.49016)
		(end 228.04882 -31.00578)
		(width 0.1016)
		(layer "B.Cu")
		(net "LBI_DATA13_R")
	)
	(segment
		(start 229.100126 -34.057082)
		(end 229.100126 -34.500058)
		(width 0.1016)
		(layer "B.Cu")
		(net "LBI_DATA13_R")
	)
	(segment
		(start 229.3239 -31.00578)
		(end 229.493826 -31.175706)
		(width 0.1016)
		(layer "B.Cu")
		(net "LBI_DATA13_R")
	)
	(segment
		(start 215.062308 -31.2674)
		(end 215.062308 -29.812234)
		(width 0.12065)
		(layer "F.Cu")
		(net "LBI_DATA12_R")
	)
	(segment
		(start 229.599998 -35.999928)
		(end 229.100126 -35.500056)
		(width 0.12065)
		(layer "F.Cu")
		(net "LBI_DATA12_R")
	)
	(segment
		(start 215.06942 -31.274512)
		(end 215.062308 -31.2674)
		(width 0.12065)
		(layer "F.Cu")
		(net "LBI_DATA12_R")
	)
	(via
		(at 229.100126 -35.500056)
		(size 0.4572)
		(drill 0.2032)
		(layers "F.Cu" "B.Cu")
		(net "LBI_DATA12_R")
	)
	(via
		(at 215.062308 -29.812234)
		(size 0.508)
		(drill 0.254)
		(layers "F.Cu" "B.Cu")
		(net "LBI_DATA12_R")
	)
	(segment
		(start 226.263454 -32.106362)
		(end 226.493832 -32.33674)
		(width 0.1016)
		(layer "In2.Cu")
		(net "LBI_DATA12_R")
	)
	(segment
		(start 215.062308 -29.812234)
		(end 215.156034 -29.812234)
		(width 0.127)
		(layer "In2.Cu")
		(net "LBI_DATA12_R")
	)
	(segment
		(start 215.156034 -29.812234)
		(end 217.105484 -31.761684)
		(width 0.127)
		(layer "In2.Cu")
		(net "LBI_DATA12_R")
	)
	(segment
		(start 227.49383 -33.336738)
		(end 227.49383 -33.450784)
		(width 0.1016)
		(layer "In2.Cu")
		(net "LBI_DATA12_R")
	)
	(segment
		(start 227.263452 -33.10636)
		(end 227.49383 -33.336738)
		(width 0.1016)
		(layer "In2.Cu")
		(net "LBI_DATA12_R")
	)
	(segment
		(start 226.493832 -32.33674)
		(end 226.493832 -32.450786)
		(width 0.1016)
		(layer "In2.Cu")
		(net "LBI_DATA12_R")
	)
	(segment
		(start 221.460822 -31.761684)
		(end 221.8055 -32.106362)
		(width 0.127)
		(layer "In2.Cu")
		(net "LBI_DATA12_R")
	)
	(segment
		(start 221.8055 -32.106362)
		(end 226.263454 -32.106362)
		(width 0.1016)
		(layer "In2.Cu")
		(net "LBI_DATA12_R")
	)
	(segment
		(start 228.261672 -34.10458)
		(end 228.499162 -34.34207)
		(width 0.1016)
		(layer "In2.Cu")
		(net "LBI_DATA12_R")
	)
	(segment
		(start 226.493832 -32.450786)
		(end 227.149406 -33.10636)
		(width 0.1016)
		(layer "In2.Cu")
		(net "LBI_DATA12_R")
	)
	(segment
		(start 228.499162 -34.899092)
		(end 229.100126 -35.500056)
		(width 0.1016)
		(layer "In2.Cu")
		(net "LBI_DATA12_R")
	)
	(segment
		(start 228.499162 -34.34207)
		(end 228.499162 -34.899092)
		(width 0.1016)
		(layer "In2.Cu")
		(net "LBI_DATA12_R")
	)
	(segment
		(start 217.105484 -31.761684)
		(end 221.460822 -31.761684)
		(width 0.127)
		(layer "In2.Cu")
		(net "LBI_DATA12_R")
	)
	(segment
		(start 228.147626 -34.10458)
		(end 228.261672 -34.10458)
		(width 0.1016)
		(layer "In2.Cu")
		(net "LBI_DATA12_R")
	)
	(segment
		(start 227.149406 -33.10636)
		(end 227.263452 -33.10636)
		(width 0.1016)
		(layer "In2.Cu")
		(net "LBI_DATA12_R")
	)
	(segment
		(start 227.49383 -33.450784)
		(end 228.147626 -34.10458)
		(width 0.1016)
		(layer "In2.Cu")
		(net "LBI_DATA12_R")
	)
	(segment
		(start 229.599998 -36.999926)
		(end 229.100126 -36.500054)
		(width 0.12065)
		(layer "F.Cu")
		(net "LBI_DATA11_R")
	)
	(via
		(at 229.100126 -36.500054)
		(size 0.4572)
		(drill 0.2032)
		(layers "F.Cu" "B.Cu")
		(net "LBI_DATA11_R")
	)
	(segment
		(start 229.59568 -35.57524)
		(end 229.100126 -36.070794)
		(width 0.12065)
		(layer "B.Cu")
		(net "LBI_DATA11_R")
	)
	(segment
		(start 229.100126 -36.070794)
		(end 229.100126 -36.500054)
		(width 0.12065)
		(layer "B.Cu")
		(net "LBI_DATA11_R")
	)
	(segment
		(start 229.59568 -34.99612)
		(end 229.59568 -35.57524)
		(width 0.12065)
		(layer "B.Cu")
		(net "LBI_DATA11_R")
	)
	(segment
		(start 229.599998 -37.999924)
		(end 229.100126 -37.500052)
		(width 0.12065)
		(layer "F.Cu")
		(net "LBI_DATA10")
	)
	(via
		(at 229.100126 -37.500052)
		(size 0.4572)
		(drill 0.2032)
		(layers "F.Cu" "B.Cu")
		(net "LBI_DATA10")
	)
	(segment
		(start 229.100126 -37.500052)
		(end 229.100126 -37.499036)
		(width 0.12065)
		(layer "B.Cu")
		(net "LBI_DATA10")
	)
	(segment
		(start 229.100126 -37.499036)
		(end 229.599998 -36.999164)
		(width 0.12065)
		(layer "B.Cu")
		(net "LBI_DATA10")
	)
	(segment
		(start 242.599972 -39.99992)
		(end 243.099844 -39.500048)
		(width 0.12065)
		(layer "F.Cu")
		(net "LBI_DATA_7")
	)
	(via
		(at 243.099844 -39.500048)
		(size 0.4572)
		(drill 0.2032)
		(layers "F.Cu" "B.Cu")
		(net "LBI_DATA_7")
	)
	(segment
		(start 243.59997 -40.999918)
		(end 243.59997 -40.000174)
		(width 0.12065)
		(layer "B.Cu")
		(net "LBI_DATA_7")
	)
	(segment
		(start 243.59997 -40.000174)
		(end 243.099844 -39.500048)
		(width 0.12065)
		(layer "B.Cu")
		(net "LBI_DATA_7")
	)
	(segment
		(start 242.599972 -37.999924)
		(end 243.099844 -37.500052)
		(width 0.12065)
		(layer "F.Cu")
		(net "LBI_DATA_6")
	)
	(via
		(at 243.099844 -37.500052)
		(size 0.4572)
		(drill 0.2032)
		(layers "F.Cu" "B.Cu")
		(net "LBI_DATA_6")
	)
	(segment
		(start 242.599972 -37.999924)
		(end 243.099844 -37.500052)
		(width 0.12065)
		(layer "B.Cu")
		(net "LBI_DATA_6")
	)
	(segment
		(start 242.599972 -38.999922)
		(end 243.099844 -38.50005)
		(width 0.12065)
		(layer "F.Cu")
		(net "LBI_DATA_5")
	)
	(via
		(at 241.256312 -27.883612)
		(size 0.508)
		(drill 0.254)
		(layers "F.Cu" "B.Cu")
		(net "LBI_DATA_5")
	)
	(via
		(at 243.099844 -38.50005)
		(size 0.4572)
		(drill 0.2032)
		(layers "F.Cu" "B.Cu")
		(net "LBI_DATA_5")
	)
	(segment
		(start 241.2238 -27.916124)
		(end 241.256312 -27.883612)
		(width 0.12065)
		(layer "B.Cu")
		(net "LBI_DATA_5")
	)
	(segment
		(start 241.2238 -28.6766)
		(end 241.2238 -27.916124)
		(width 0.12065)
		(layer "B.Cu")
		(net "LBI_DATA_5")
	)
	(segment
		(start 242.506246 -37.906452)
		(end 243.099844 -38.50005)
		(width 0.127)
		(layer "In5.Cu")
		(net "LBI_DATA_5")
	)
	(segment
		(start 242.014248 -34.036)
		(end 242.2906 -34.036)
		(width 0.127)
		(layer "In5.Cu")
		(net "LBI_DATA_5")
	)
	(segment
		(start 241.681 -33.702752)
		(end 242.014248 -34.036)
		(width 0.127)
		(layer "In5.Cu")
		(net "LBI_DATA_5")
	)
	(segment
		(start 240.665 -32.6898)
		(end 241.677952 -33.702752)
		(width 0.127)
		(layer "In5.Cu")
		(net "LBI_DATA_5")
	)
	(segment
		(start 241.256312 -31.539688)
		(end 240.665 -32.131)
		(width 0.127)
		(layer "In5.Cu")
		(net "LBI_DATA_5")
	)
	(segment
		(start 242.2906 -34.036)
		(end 242.506246 -34.251646)
		(width 0.127)
		(layer "In5.Cu")
		(net "LBI_DATA_5")
	)
	(segment
		(start 241.677952 -33.702752)
		(end 241.681 -33.702752)
		(width 0.127)
		(layer "In5.Cu")
		(net "LBI_DATA_5")
	)
	(segment
		(start 241.256312 -27.883612)
		(end 241.256312 -31.539688)
		(width 0.127)
		(layer "In5.Cu")
		(net "LBI_DATA_5")
	)
	(segment
		(start 240.665 -32.131)
		(end 240.665 -32.6898)
		(width 0.127)
		(layer "In5.Cu")
		(net "LBI_DATA_5")
	)
	(segment
		(start 242.506246 -34.251646)
		(end 242.506246 -37.906452)
		(width 0.127)
		(layer "In5.Cu")
		(net "LBI_DATA_5")
	)
	(segment
		(start 243.59997 -34.99993)
		(end 244.099842 -34.500058)
		(width 0.12065)
		(layer "F.Cu")
		(net "LBI_DATA_4")
	)
	(via
		(at 244.099842 -34.500058)
		(size 0.4572)
		(drill 0.2032)
		(layers "F.Cu" "B.Cu")
		(net "LBI_DATA_4")
	)
	(segment
		(start 243.59997 -34.99993)
		(end 244.099842 -34.500058)
		(width 0.12065)
		(layer "B.Cu")
		(net "LBI_DATA_4")
	)
	(segment
		(start 243.59997 -33.999932)
		(end 244.099842 -33.50006)
		(width 0.12065)
		(layer "F.Cu")
		(net "LBI_DATA_3")
	)
	(via
		(at 244.099842 -33.50006)
		(size 0.4572)
		(drill 0.2032)
		(layers "F.Cu" "B.Cu")
		(net "LBI_DATA_3")
	)
	(segment
		(start 243.59997 -33.000188)
		(end 244.099842 -33.50006)
		(width 0.12065)
		(layer "B.Cu")
		(net "LBI_DATA_3")
	)
	(segment
		(start 243.59997 -32.999934)
		(end 243.59997 -33.000188)
		(width 0.12065)
		(layer "B.Cu")
		(net "LBI_DATA_3")
	)
	(segment
		(start 243.59997 -35.999928)
		(end 244.099842 -35.500056)
		(width 0.12065)
		(layer "F.Cu")
		(net "LBI_DATA_2")
	)
	(via
		(at 241.272822 -27.020012)
		(size 0.508)
		(drill 0.254)
		(layers "F.Cu" "B.Cu")
		(net "LBI_DATA_2")
	)
	(via
		(at 244.099842 -35.500056)
		(size 0.4572)
		(drill 0.2032)
		(layers "F.Cu" "B.Cu")
		(net "LBI_DATA_2")
	)
	(segment
		(start 242.0366 -25.1206)
		(end 241.7572 -25.4)
		(width 0.12065)
		(layer "B.Cu")
		(net "LBI_DATA_2")
	)
	(segment
		(start 241.7572 -25.4)
		(end 241.310668 -25.4)
		(width 0.12065)
		(layer "B.Cu")
		(net "LBI_DATA_2")
	)
	(segment
		(start 240.731548 -25.97912)
		(end 240.731548 -26.478738)
		(width 0.12065)
		(layer "B.Cu")
		(net "LBI_DATA_2")
	)
	(segment
		(start 240.731548 -26.478738)
		(end 241.272822 -27.020012)
		(width 0.12065)
		(layer "B.Cu")
		(net "LBI_DATA_2")
	)
	(segment
		(start 241.310668 -25.4)
		(end 240.731548 -25.97912)
		(width 0.12065)
		(layer "B.Cu")
		(net "LBI_DATA_2")
	)
	(segment
		(start 242.05946 -33.09366)
		(end 242.268248 -33.09366)
		(width 0.127)
		(layer "In5.Cu")
		(net "LBI_DATA_2")
	)
	(segment
		(start 241.693446 -32.727646)
		(end 242.05946 -33.09366)
		(width 0.127)
		(layer "In5.Cu")
		(net "LBI_DATA_2")
	)
	(segment
		(start 242.5446 -33.814258)
		(end 242.824 -34.093658)
		(width 0.127)
		(layer "In5.Cu")
		(net "LBI_DATA_2")
	)
	(segment
		(start 242.506246 -33.388046)
		(end 242.5446 -33.4264)
		(width 0.127)
		(layer "In5.Cu")
		(net "LBI_DATA_2")
	)
	(segment
		(start 243.268246 -34.093658)
		(end 243.506244 -34.331656)
		(width 0.127)
		(layer "In5.Cu")
		(net "LBI_DATA_2")
	)
	(segment
		(start 243.506244 -34.331656)
		(end 243.506244 -34.906458)
		(width 0.127)
		(layer "In5.Cu")
		(net "LBI_DATA_2")
	)
	(segment
		(start 241.272822 -27.020012)
		(end 241.357658 -27.020012)
		(width 0.127)
		(layer "In5.Cu")
		(net "LBI_DATA_2")
	)
	(segment
		(start 242.506246 -33.331658)
		(end 242.506246 -33.388046)
		(width 0.127)
		(layer "In5.Cu")
		(net "LBI_DATA_2")
	)
	(segment
		(start 242.824 -34.093658)
		(end 243.268246 -34.093658)
		(width 0.127)
		(layer "In5.Cu")
		(net "LBI_DATA_2")
	)
	(segment
		(start 241.9096 -27.571954)
		(end 241.9096 -28.194)
		(width 0.127)
		(layer "In5.Cu")
		(net "LBI_DATA_2")
	)
	(segment
		(start 243.506244 -34.906458)
		(end 244.099842 -35.500056)
		(width 0.127)
		(layer "In5.Cu")
		(net "LBI_DATA_2")
	)
	(segment
		(start 241.357658 -27.020012)
		(end 241.9096 -27.571954)
		(width 0.127)
		(layer "In5.Cu")
		(net "LBI_DATA_2")
	)
	(segment
		(start 241.693446 -28.410154)
		(end 241.693446 -32.727646)
		(width 0.127)
		(layer "In5.Cu")
		(net "LBI_DATA_2")
	)
	(segment
		(start 241.9096 -28.194)
		(end 241.693446 -28.410154)
		(width 0.127)
		(layer "In5.Cu")
		(net "LBI_DATA_2")
	)
	(segment
		(start 242.268248 -33.09366)
		(end 242.506246 -33.331658)
		(width 0.127)
		(layer "In5.Cu")
		(net "LBI_DATA_2")
	)
	(segment
		(start 242.5446 -33.4264)
		(end 242.5446 -33.814258)
		(width 0.127)
		(layer "In5.Cu")
		(net "LBI_DATA_2")
	)
	(segment
		(start 243.59997 -36.999926)
		(end 244.099842 -36.500054)
		(width 0.12065)
		(layer "F.Cu")
		(net "LBI_DATA_1")
	)
	(via
		(at 244.099842 -36.500054)
		(size 0.4572)
		(drill 0.2032)
		(layers "F.Cu" "B.Cu")
		(net "LBI_DATA_1")
	)
	(segment
		(start 243.59997 -36.999926)
		(end 244.099842 -36.500054)
		(width 0.12065)
		(layer "B.Cu")
		(net "LBI_DATA_1")
	)
	(segment
		(start 244.599968 -33.999932)
		(end 245.09984 -33.50006)
		(width 0.12065)
		(layer "F.Cu")
		(net "LBI_DATA_0")
	)
	(via
		(at 241.071908 -19.040856)
		(size 0.508)
		(drill 0.254)
		(layers "F.Cu" "B.Cu")
		(net "LBI_DATA_0")
	)
	(via
		(at 245.09984 -33.50006)
		(size 0.4572)
		(drill 0.2032)
		(layers "F.Cu" "B.Cu")
		(net "LBI_DATA_0")
	)
	(segment
		(start 240.538 -18.681192)
		(end 240.897664 -19.040856)
		(width 0.12065)
		(layer "B.Cu")
		(net "LBI_DATA_0")
	)
	(segment
		(start 240.897664 -19.040856)
		(end 241.071908 -19.040856)
		(width 0.12065)
		(layer "B.Cu")
		(net "LBI_DATA_0")
	)
	(segment
		(start 240.538 -18.161)
		(end 240.538 -18.681192)
		(width 0.12065)
		(layer "B.Cu")
		(net "LBI_DATA_0")
	)
	(segment
		(start 245.09984 -33.13684)
		(end 244.6782 -32.7152)
		(width 0.127)
		(layer "In5.Cu")
		(net "LBI_DATA_0")
	)
	(segment
		(start 245.324884 -24.12746)
		(end 245.324884 -20.407884)
		(width 0.127)
		(layer "In5.Cu")
		(net "LBI_DATA_0")
	)
	(segment
		(start 244.1702 -19.2532)
		(end 242.93703 -19.2532)
		(width 0.127)
		(layer "In5.Cu")
		(net "LBI_DATA_0")
	)
	(segment
		(start 245.2878 -25.944576)
		(end 245.2878 -24.164544)
		(width 0.127)
		(layer "In5.Cu")
		(net "LBI_DATA_0")
	)
	(segment
		(start 245.324884 -20.407884)
		(end 244.1702 -19.2532)
		(width 0.127)
		(layer "In5.Cu")
		(net "LBI_DATA_0")
	)
	(segment
		(start 241.304826 -19.040856)
		(end 241.071908 -19.040856)
		(width 0.127)
		(layer "In5.Cu")
		(net "LBI_DATA_0")
	)
	(segment
		(start 242.93703 -19.2532)
		(end 242.28933 -18.6055)
		(width 0.127)
		(layer "In5.Cu")
		(net "LBI_DATA_0")
	)
	(segment
		(start 244.6782 -32.7152)
		(end 244.6782 -28.25496)
		(width 0.127)
		(layer "In5.Cu")
		(net "LBI_DATA_0")
	)
	(segment
		(start 242.28933 -18.6055)
		(end 241.740182 -18.6055)
		(width 0.127)
		(layer "In5.Cu")
		(net "LBI_DATA_0")
	)
	(segment
		(start 245.09984 -33.50006)
		(end 245.09984 -33.13684)
		(width 0.127)
		(layer "In5.Cu")
		(net "LBI_DATA_0")
	)
	(segment
		(start 241.740182 -18.6055)
		(end 241.304826 -19.040856)
		(width 0.127)
		(layer "In5.Cu")
		(net "LBI_DATA_0")
	)
	(segment
		(start 244.3988 -27.97556)
		(end 244.3988 -26.833576)
		(width 0.127)
		(layer "In5.Cu")
		(net "LBI_DATA_0")
	)
	(segment
		(start 244.3988 -26.833576)
		(end 245.2878 -25.944576)
		(width 0.127)
		(layer "In5.Cu")
		(net "LBI_DATA_0")
	)
	(segment
		(start 244.6782 -28.25496)
		(end 244.3988 -27.97556)
		(width 0.127)
		(layer "In5.Cu")
		(net "LBI_DATA_0")
	)
	(segment
		(start 245.2878 -24.164544)
		(end 245.324884 -24.12746)
		(width 0.127)
		(layer "In5.Cu")
		(net "LBI_DATA_0")
	)
	(segment
		(start 242.599972 -33.999932)
		(end 243.099844 -33.50006)
		(width 0.12065)
		(layer "F.Cu")
		(net "LBI_CE#3")
	)
	(via
		(at 243.099844 -33.50006)
		(size 0.4572)
		(drill 0.2032)
		(layers "F.Cu" "B.Cu")
		(net "LBI_CE#3")
	)
	(segment
		(start 242.8748 -29.025596)
		(end 242.706144 -29.194252)
		(width 0.1016)
		(layer "B.Cu")
		(net "LBI_CE#3")
	)
	(segment
		(start 242.706144 -33.10636)
		(end 243.099844 -33.50006)
		(width 0.1016)
		(layer "B.Cu")
		(net "LBI_CE#3")
	)
	(segment
		(start 243.967 -27.933396)
		(end 242.8748 -29.025596)
		(width 0.12065)
		(layer "B.Cu")
		(net "LBI_CE#3")
	)
	(segment
		(start 243.967 -26.67)
		(end 243.967 -27.933396)
		(width 0.12065)
		(layer "B.Cu")
		(net "LBI_CE#3")
	)
	(segment
		(start 242.706144 -29.194252)
		(end 242.706144 -33.10636)
		(width 0.1016)
		(layer "B.Cu")
		(net "LBI_CE#3")
	)
	(segment
		(start 241.599974 -33.999932)
		(end 242.099846 -33.50006)
		(width 0.12065)
		(layer "F.Cu")
		(net "LBI_CE#2")
	)
	(via
		(at 242.099846 -33.50006)
		(size 0.4572)
		(drill 0.2032)
		(layers "F.Cu" "B.Cu")
		(net "LBI_CE#2")
	)
	(segment
		(start 241.935 -27.110436)
		(end 241.935 -28.768548)
		(width 0.12065)
		(layer "B.Cu")
		(net "LBI_CE#2")
	)
	(segment
		(start 241.696494 -32.667194)
		(end 242.099846 -33.070546)
		(width 0.12065)
		(layer "B.Cu")
		(net "LBI_CE#2")
	)
	(segment
		(start 242.062 -26.983436)
		(end 241.935 -27.110436)
		(width 0.12065)
		(layer "B.Cu")
		(net "LBI_CE#2")
	)
	(segment
		(start 241.474244 -31.759398)
		(end 241.696494 -31.981648)
		(width 0.12065)
		(layer "B.Cu")
		(net "LBI_CE#2")
	)
	(segment
		(start 241.935 -28.768548)
		(end 241.474244 -29.229304)
		(width 0.12065)
		(layer "B.Cu")
		(net "LBI_CE#2")
	)
	(segment
		(start 241.696494 -31.981648)
		(end 241.696494 -32.667194)
		(width 0.12065)
		(layer "B.Cu")
		(net "LBI_CE#2")
	)
	(segment
		(start 242.062 -26.543)
		(end 242.062 -26.983436)
		(width 0.12065)
		(layer "B.Cu")
		(net "LBI_CE#2")
	)
	(segment
		(start 242.099846 -33.070546)
		(end 242.099846 -33.50006)
		(width 0.12065)
		(layer "B.Cu")
		(net "LBI_CE#2")
	)
	(segment
		(start 241.474244 -29.229304)
		(end 241.474244 -31.759398)
		(width 0.12065)
		(layer "B.Cu")
		(net "LBI_CE#2")
	)
	(segment
		(start 241.599974 -35.999928)
		(end 242.099846 -35.500056)
		(width 0.12065)
		(layer "F.Cu")
		(net "LBI_CE#0")
	)
	(via
		(at 242.099846 -35.500056)
		(size 0.4572)
		(drill 0.2032)
		(layers "F.Cu" "B.Cu")
		(net "LBI_CE#0")
	)
	(segment
		(start 240.576608 -32.25038)
		(end 240.576608 -33.526984)
		(width 0.12065)
		(layer "B.Cu")
		(net "LBI_CE#0")
	)
	(segment
		(start 240.861342 -29.433012)
		(end 240.861342 -31.965646)
		(width 0.12065)
		(layer "B.Cu")
		(net "LBI_CE#0")
	)
	(segment
		(start 240.405412 -28.977082)
		(end 240.861342 -29.433012)
		(width 0.12065)
		(layer "B.Cu")
		(net "LBI_CE#0")
	)
	(segment
		(start 241.697256 -35.500056)
		(end 242.099846 -35.500056)
		(width 0.12065)
		(layer "B.Cu")
		(net "LBI_CE#0")
	)
	(segment
		(start 239.8522 -25.019)
		(end 239.8522 -26.525474)
		(width 0.12065)
		(layer "B.Cu")
		(net "LBI_CE#0")
	)
	(segment
		(start 240.861342 -31.965646)
		(end 240.576608 -32.25038)
		(width 0.12065)
		(layer "B.Cu")
		(net "LBI_CE#0")
	)
	(segment
		(start 239.8522 -26.525474)
		(end 240.405412 -27.078686)
		(width 0.12065)
		(layer "B.Cu")
		(net "LBI_CE#0")
	)
	(segment
		(start 240.576608 -33.526984)
		(end 241.5286 -34.478976)
		(width 0.12065)
		(layer "B.Cu")
		(net "LBI_CE#0")
	)
	(segment
		(start 241.5286 -34.478976)
		(end 241.5286 -35.3314)
		(width 0.12065)
		(layer "B.Cu")
		(net "LBI_CE#0")
	)
	(segment
		(start 240.405412 -27.078686)
		(end 240.405412 -28.977082)
		(width 0.12065)
		(layer "B.Cu")
		(net "LBI_CE#0")
	)
	(segment
		(start 241.5286 -35.3314)
		(end 241.697256 -35.500056)
		(width 0.12065)
		(layer "B.Cu")
		(net "LBI_CE#0")
	)
	(segment
		(start 242.599972 -36.999926)
		(end 243.099844 -36.500054)
		(width 0.12065)
		(layer "F.Cu")
		(net "LBI_BYTEN#")
	)
	(via
		(at 243.099844 -36.500054)
		(size 0.4572)
		(drill 0.2032)
		(layers "F.Cu" "B.Cu")
		(net "LBI_BYTEN#")
	)
	(segment
		(start 242.599972 -36.000182)
		(end 243.099844 -36.500054)
		(width 0.12065)
		(layer "B.Cu")
		(net "LBI_BYTEN#")
	)
	(segment
		(start 242.599972 -35.999928)
		(end 242.599972 -36.000182)
		(width 0.12065)
		(layer "B.Cu")
		(net "LBI_BYTEN#")
	)
	(segment
		(start 234.599988 -33.999932)
		(end 234.100116 -33.50006)
		(width 0.12065)
		(layer "F.Cu")
		(net "LBI_ADDR_9")
	)
	(via
		(at 234.100116 -33.50006)
		(size 0.4572)
		(drill 0.2032)
		(layers "F.Cu" "B.Cu")
		(net "LBI_ADDR_9")
	)
	(segment
		(start 231.971596 -32.92856)
		(end 233.396536 -32.92856)
		(width 0.1016)
		(layer "B.Cu")
		(net "LBI_ADDR_9")
	)
	(segment
		(start 233.768138 -33.300162)
		(end 233.900218 -33.300162)
		(width 0.1016)
		(layer "B.Cu")
		(net "LBI_ADDR_9")
	)
	(segment
		(start 231.70642 -31.588456)
		(end 231.70642 -32.663384)
		(width 0.1016)
		(layer "B.Cu")
		(net "LBI_ADDR_9")
	)
	(segment
		(start 231.6988 -31.580836)
		(end 231.70642 -31.588456)
		(width 0.1016)
		(layer "B.Cu")
		(net "LBI_ADDR_9")
	)
	(segment
		(start 233.396536 -32.92856)
		(end 233.768138 -33.300162)
		(width 0.1016)
		(layer "B.Cu")
		(net "LBI_ADDR_9")
	)
	(segment
		(start 231.6988 -28.5242)
		(end 231.6988 -31.580836)
		(width 0.1016)
		(layer "B.Cu")
		(net "LBI_ADDR_9")
	)
	(segment
		(start 233.900218 -33.300162)
		(end 234.100116 -33.50006)
		(width 0.1016)
		(layer "B.Cu")
		(net "LBI_ADDR_9")
	)
	(segment
		(start 231.70642 -32.663384)
		(end 231.971596 -32.92856)
		(width 0.1016)
		(layer "B.Cu")
		(net "LBI_ADDR_9")
	)
	(segment
		(start 235.599986 -39.99992)
		(end 235.100114 -39.500048)
		(width 0.12065)
		(layer "F.Cu")
		(net "LBI_ADDR_8")
	)
	(via
		(at 235.100114 -39.500048)
		(size 0.4572)
		(drill 0.2032)
		(layers "F.Cu" "B.Cu")
		(net "LBI_ADDR_8")
	)
	(segment
		(start 234.59948 -41.0083)
		(end 234.59948 -40.000682)
		(width 0.12065)
		(layer "B.Cu")
		(net "LBI_ADDR_8")
	)
	(segment
		(start 234.59948 -40.000682)
		(end 235.100114 -39.500048)
		(width 0.12065)
		(layer "B.Cu")
		(net "LBI_ADDR_8")
	)
	(segment
		(start 235.599986 -37.999924)
		(end 235.100114 -37.500052)
		(width 0.12065)
		(layer "F.Cu")
		(net "LBI_ADDR_7_R")
	)
	(via
		(at 235.100114 -37.500052)
		(size 0.4572)
		(drill 0.2032)
		(layers "F.Cu" "B.Cu")
		(net "LBI_ADDR_7_R")
	)
	(via
		(at 218.140534 -19.177)
		(size 0.7112)
		(drill 0.3556)
		(layers "F.Cu" "B.Cu")
		(net "LBI_ADDR_7_R")
	)
	(via
		(at 218.140534 -17.935956)
		(size 0.508)
		(drill 0.254)
		(layers "F.Cu" "B.Cu")
		(net "LBI_ADDR_7_R")
	)
	(segment
		(start 222.25 -23.6855)
		(end 221.638622 -23.6855)
		(width 0.12065)
		(layer "B.Cu")
		(net "LBI_ADDR_7_R")
	)
	(segment
		(start 218.140534 -20.187412)
		(end 218.140534 -19.177)
		(width 0.12065)
		(layer "B.Cu")
		(net "LBI_ADDR_7_R")
	)
	(segment
		(start 221.638622 -23.6855)
		(end 218.140534 -20.187412)
		(width 0.12065)
		(layer "B.Cu")
		(net "LBI_ADDR_7_R")
	)
	(segment
		(start 218.140534 -19.177)
		(end 218.140534 -17.935956)
		(width 0.12065)
		(layer "B.Cu")
		(net "LBI_ADDR_7_R")
	)
	(segment
		(start 235.697014 -29.01188)
		(end 235.691934 -29.0068)
		(width 0.1016)
		(layer "In5.Cu")
		(net "LBI_ADDR_7_R")
	)
	(segment
		(start 218.191334 -17.885156)
		(end 218.140534 -17.935956)
		(width 0.127)
		(layer "In5.Cu")
		(net "LBI_ADDR_7_R")
	)
	(segment
		(start 235.691934 -29.0068)
		(end 234.5563 -27.871166)
		(width 0.127)
		(layer "In5.Cu")
		(net "LBI_ADDR_7_R")
	)
	(segment
		(start 233.9594 -24.441658)
		(end 233.9594 -21.572982)
		(width 0.127)
		(layer "In5.Cu")
		(net "LBI_ADDR_7_R")
	)
	(segment
		(start 234.7214 -36.0426)
		(end 235.441236 -36.0426)
		(width 0.1016)
		(layer "In5.Cu")
		(net "LBI_ADDR_7_R")
	)
	(segment
		(start 234.569 -36.968938)
		(end 234.569 -36.195)
		(width 0.1016)
		(layer "In5.Cu")
		(net "LBI_ADDR_7_R")
	)
	(segment
		(start 234.5563 -27.871166)
		(end 234.5563 -26.269188)
		(width 0.127)
		(layer "In5.Cu")
		(net "LBI_ADDR_7_R")
	)
	(segment
		(start 234.5563 -26.269188)
		(end 234.2515 -25.964388)
		(width 0.127)
		(layer "In5.Cu")
		(net "LBI_ADDR_7_R")
	)
	(segment
		(start 233.9594 -21.572982)
		(end 230.271574 -17.885156)
		(width 0.127)
		(layer "In5.Cu")
		(net "LBI_ADDR_7_R")
	)
	(segment
		(start 230.271574 -17.885156)
		(end 218.191334 -17.885156)
		(width 0.127)
		(layer "In5.Cu")
		(net "LBI_ADDR_7_R")
	)
	(segment
		(start 235.441236 -36.0426)
		(end 235.697014 -35.786822)
		(width 0.1016)
		(layer "In5.Cu")
		(net "LBI_ADDR_7_R")
	)
	(segment
		(start 234.569 -36.195)
		(end 234.7214 -36.0426)
		(width 0.1016)
		(layer "In5.Cu")
		(net "LBI_ADDR_7_R")
	)
	(segment
		(start 235.697014 -35.786822)
		(end 235.697014 -29.01188)
		(width 0.1016)
		(layer "In5.Cu")
		(net "LBI_ADDR_7_R")
	)
	(segment
		(start 234.2515 -24.733758)
		(end 233.9594 -24.441658)
		(width 0.127)
		(layer "In5.Cu")
		(net "LBI_ADDR_7_R")
	)
	(segment
		(start 234.2515 -25.964388)
		(end 234.2515 -24.733758)
		(width 0.127)
		(layer "In5.Cu")
		(net "LBI_ADDR_7_R")
	)
	(segment
		(start 235.100114 -37.500052)
		(end 234.569 -36.968938)
		(width 0.1016)
		(layer "In5.Cu")
		(net "LBI_ADDR_7_R")
	)
	(segment
		(start 235.599986 -36.999926)
		(end 235.100114 -36.500054)
		(width 0.12065)
		(layer "F.Cu")
		(net "LBI_ADDR_6_R")
	)
	(via
		(at 220.197426 -23.474426)
		(size 0.7112)
		(drill 0.3556)
		(layers "F.Cu" "B.Cu")
		(net "LBI_ADDR_6_R")
	)
	(via
		(at 235.100114 -36.500054)
		(size 0.4572)
		(drill 0.2032)
		(layers "F.Cu" "B.Cu")
		(net "LBI_ADDR_6_R")
	)
	(via
		(at 217.276934 -17.919954)
		(size 0.508)
		(drill 0.254)
		(layers "F.Cu" "B.Cu")
		(net "LBI_ADDR_6_R")
	)
	(segment
		(start 223.393 -23.6855)
		(end 223.393 -23.7744)
		(width 0.12065)
		(layer "B.Cu")
		(net "LBI_ADDR_6_R")
	)
	(segment
		(start 217.276934 -17.919954)
		(end 217.276934 -19.835876)
		(width 0.12065)
		(layer "B.Cu")
		(net "LBI_ADDR_6_R")
	)
	(segment
		(start 217.276934 -19.835876)
		(end 218.948 -21.506942)
		(width 0.12065)
		(layer "B.Cu")
		(net "LBI_ADDR_6_R")
	)
	(segment
		(start 223.027748 -24.139652)
		(end 220.862652 -24.139652)
		(width 0.12065)
		(layer "B.Cu")
		(net "LBI_ADDR_6_R")
	)
	(segment
		(start 218.948 -21.506942)
		(end 218.948 -22.225)
		(width 0.12065)
		(layer "B.Cu")
		(net "LBI_ADDR_6_R")
	)
	(segment
		(start 218.948 -22.225)
		(end 220.197426 -23.474426)
		(width 0.12065)
		(layer "B.Cu")
		(net "LBI_ADDR_6_R")
	)
	(segment
		(start 223.393 -23.7744)
		(end 223.027748 -24.139652)
		(width 0.12065)
		(layer "B.Cu")
		(net "LBI_ADDR_6_R")
	)
	(segment
		(start 220.862652 -24.139652)
		(end 220.197426 -23.474426)
		(width 0.12065)
		(layer "B.Cu")
		(net "LBI_ADDR_6_R")
	)
	(segment
		(start 236.263434 -35.893756)
		(end 236.493812 -35.663378)
		(width 0.1016)
		(layer "In5.Cu")
		(net "LBI_ADDR_6_R")
	)
	(segment
		(start 235.987844 -35.893756)
		(end 236.263434 -35.893756)
		(width 0.1016)
		(layer "In5.Cu")
		(net "LBI_ADDR_6_R")
	)
	(segment
		(start 234.6325 -25.964388)
		(end 234.6325 -24.57577)
		(width 0.127)
		(layer "In5.Cu")
		(net "LBI_ADDR_6_R")
	)
	(segment
		(start 234.6325 -24.57577)
		(end 234.3404 -24.28367)
		(width 0.127)
		(layer "In5.Cu")
		(net "LBI_ADDR_6_R")
	)
	(segment
		(start 235.100114 -36.500054)
		(end 235.381546 -36.500054)
		(width 0.1016)
		(layer "In5.Cu")
		(net "LBI_ADDR_6_R")
	)
	(segment
		(start 235.381546 -36.500054)
		(end 235.987844 -35.893756)
		(width 0.1016)
		(layer "In5.Cu")
		(net "LBI_ADDR_6_R")
	)
	(segment
		(start 234.3404 -24.28367)
		(end 234.3404 -21.414994)
		(width 0.127)
		(layer "In5.Cu")
		(net "LBI_ADDR_6_R")
	)
	(segment
		(start 236.493812 -35.663378)
		(end 236.493812 -29.074364)
		(width 0.1016)
		(layer "In5.Cu")
		(net "LBI_ADDR_6_R")
	)
	(segment
		(start 236.493812 -29.074364)
		(end 234.7849 -27.365452)
		(width 0.127)
		(layer "In5.Cu")
		(net "LBI_ADDR_6_R")
	)
	(segment
		(start 234.7849 -26.116788)
		(end 234.6325 -25.964388)
		(width 0.127)
		(layer "In5.Cu")
		(net "LBI_ADDR_6_R")
	)
	(segment
		(start 230.391462 -17.466056)
		(end 217.730832 -17.466056)
		(width 0.127)
		(layer "In5.Cu")
		(net "LBI_ADDR_6_R")
	)
	(segment
		(start 234.7849 -27.365452)
		(end 234.7849 -26.116788)
		(width 0.127)
		(layer "In5.Cu")
		(net "LBI_ADDR_6_R")
	)
	(segment
		(start 217.730832 -17.466056)
		(end 217.276934 -17.919954)
		(width 0.127)
		(layer "In5.Cu")
		(net "LBI_ADDR_6_R")
	)
	(segment
		(start 234.3404 -21.414994)
		(end 230.391462 -17.466056)
		(width 0.127)
		(layer "In5.Cu")
		(net "LBI_ADDR_6_R")
	)
	(segment
		(start 235.599986 -35.999928)
		(end 235.100114 -35.500056)
		(width 0.12065)
		(layer "F.Cu")
		(net "LBI_ADDR_5_R")
	)
	(via
		(at 216.412826 -17.929606)
		(size 0.508)
		(drill 0.254)
		(layers "F.Cu" "B.Cu")
		(net "LBI_ADDR_5_R")
	)
	(via
		(at 218.186 -21.971)
		(size 0.7112)
		(drill 0.3556)
		(layers "F.Cu" "B.Cu")
		(net "LBI_ADDR_5_R")
	)
	(via
		(at 235.100114 -35.500056)
		(size 0.4572)
		(drill 0.2032)
		(layers "F.Cu" "B.Cu")
		(net "LBI_ADDR_5_R")
	)
	(segment
		(start 216.412826 -17.929606)
		(end 216.412826 -19.483832)
		(width 0.12065)
		(layer "B.Cu")
		(net "LBI_ADDR_5_R")
	)
	(segment
		(start 224.536 -23.6855)
		(end 224.536 -24.0538)
		(width 0.12065)
		(layer "B.Cu")
		(net "LBI_ADDR_5_R")
	)
	(segment
		(start 220.208602 -24.501602)
		(end 218.186 -22.479)
		(width 0.12065)
		(layer "B.Cu")
		(net "LBI_ADDR_5_R")
	)
	(segment
		(start 224.536 -24.0538)
		(end 224.088198 -24.501602)
		(width 0.12065)
		(layer "B.Cu")
		(net "LBI_ADDR_5_R")
	)
	(segment
		(start 224.088198 -24.501602)
		(end 220.208602 -24.501602)
		(width 0.12065)
		(layer "B.Cu")
		(net "LBI_ADDR_5_R")
	)
	(segment
		(start 216.412826 -19.483832)
		(end 218.186 -21.257006)
		(width 0.12065)
		(layer "B.Cu")
		(net "LBI_ADDR_5_R")
	)
	(segment
		(start 218.186 -22.479)
		(end 218.186 -21.971)
		(width 0.12065)
		(layer "B.Cu")
		(net "LBI_ADDR_5_R")
	)
	(segment
		(start 218.186 -21.257006)
		(end 218.186 -21.971)
		(width 0.12065)
		(layer "B.Cu")
		(net "LBI_ADDR_5_R")
	)
	(segment
		(start 218.917012 -18.266156)
		(end 218.777312 -18.405856)
		(width 0.127)
		(layer "In5.Cu")
		(net "LBI_ADDR_5_R")
	)
	(segment
		(start 229.218744 -18.266156)
		(end 218.917012 -18.266156)
		(width 0.127)
		(layer "In5.Cu")
		(net "LBI_ADDR_5_R")
	)
	(segment
		(start 234.188 -26.281888)
		(end 233.8705 -25.964388)
		(width 0.127)
		(layer "In5.Cu")
		(net "LBI_ADDR_5_R")
	)
	(segment
		(start 235.493814 -35.066986)
		(end 235.493814 -30.058614)
		(width 0.1016)
		(layer "In5.Cu")
		(net "LBI_ADDR_5_R")
	)
	(segment
		(start 235.3818 -29.083)
		(end 234.188 -27.8892)
		(width 0.127)
		(layer "In5.Cu")
		(net "LBI_ADDR_5_R")
	)
	(segment
		(start 235.493814 -30.058614)
		(end 235.3818 -29.9466)
		(width 0.1016)
		(layer "In5.Cu")
		(net "LBI_ADDR_5_R")
	)
	(segment
		(start 235.3818 -29.9466)
		(end 235.3818 -29.083)
		(width 0.127)
		(layer "In5.Cu")
		(net "LBI_ADDR_5_R")
	)
	(segment
		(start 233.5784 -24.599646)
		(end 233.5784 -22.625812)
		(width 0.127)
		(layer "In5.Cu")
		(net "LBI_ADDR_5_R")
	)
	(segment
		(start 233.8705 -25.964388)
		(end 233.8705 -24.891746)
		(width 0.127)
		(layer "In5.Cu")
		(net "LBI_ADDR_5_R")
	)
	(segment
		(start 233.8705 -24.891746)
		(end 233.5784 -24.599646)
		(width 0.127)
		(layer "In5.Cu")
		(net "LBI_ADDR_5_R")
	)
	(segment
		(start 218.777312 -18.405856)
		(end 216.889076 -18.405856)
		(width 0.127)
		(layer "In5.Cu")
		(net "LBI_ADDR_5_R")
	)
	(segment
		(start 233.5784 -22.625812)
		(end 229.218744 -18.266156)
		(width 0.127)
		(layer "In5.Cu")
		(net "LBI_ADDR_5_R")
	)
	(segment
		(start 234.188 -27.8892)
		(end 234.188 -26.281888)
		(width 0.127)
		(layer "In5.Cu")
		(net "LBI_ADDR_5_R")
	)
	(segment
		(start 235.100114 -35.500056)
		(end 235.100114 -35.460686)
		(width 0.1016)
		(layer "In5.Cu")
		(net "LBI_ADDR_5_R")
	)
	(segment
		(start 235.100114 -35.460686)
		(end 235.493814 -35.066986)
		(width 0.1016)
		(layer "In5.Cu")
		(net "LBI_ADDR_5_R")
	)
	(segment
		(start 216.889076 -18.405856)
		(end 216.412826 -17.929606)
		(width 0.127)
		(layer "In5.Cu")
		(net "LBI_ADDR_5_R")
	)
	(segment
		(start 236.599984 -39.99992)
		(end 236.100112 -39.500048)
		(width 0.12065)
		(layer "F.Cu")
		(net "LBI_ADDR_4_R")
	)
	(via
		(at 236.100112 -39.500048)
		(size 0.4572)
		(drill 0.2032)
		(layers "F.Cu" "B.Cu")
		(net "LBI_ADDR_4_R")
	)
	(via
		(at 215.550242 -18.937478)
		(size 0.7112)
		(drill 0.3556)
		(layers "F.Cu" "B.Cu")
		(net "LBI_ADDR_4_R")
	)
	(via
		(at 215.550242 -17.972278)
		(size 0.508)
		(drill 0.254)
		(layers "F.Cu" "B.Cu")
		(net "LBI_ADDR_4_R")
	)
	(segment
		(start 215.550242 -18.937478)
		(end 215.550242 -17.972278)
		(width 0.12065)
		(layer "B.Cu")
		(net "LBI_ADDR_4_R")
	)
	(segment
		(start 224.500948 -24.863552)
		(end 219.647516 -24.863552)
		(width 0.12065)
		(layer "B.Cu")
		(net "LBI_ADDR_4_R")
	)
	(segment
		(start 215.550242 -19.133312)
		(end 215.550242 -18.937478)
		(width 0.12065)
		(layer "B.Cu")
		(net "LBI_ADDR_4_R")
	)
	(segment
		(start 219.647516 -24.863552)
		(end 217.397838 -22.613874)
		(width 0.12065)
		(layer "B.Cu")
		(net "LBI_ADDR_4_R")
	)
	(segment
		(start 217.397838 -22.613874)
		(end 217.397838 -20.980908)
		(width 0.12065)
		(layer "B.Cu")
		(net "LBI_ADDR_4_R")
	)
	(segment
		(start 225.679 -23.6855)
		(end 224.500948 -24.863552)
		(width 0.12065)
		(layer "B.Cu")
		(net "LBI_ADDR_4_R")
	)
	(segment
		(start 217.397838 -20.980908)
		(end 215.550242 -19.133312)
		(width 0.12065)
		(layer "B.Cu")
		(net "LBI_ADDR_4_R")
	)
	(segment
		(start 234.7214 -21.1074)
		(end 234.7214 -24.125682)
		(width 0.127)
		(layer "In5.Cu")
		(net "LBI_ADDR_4_R")
	)
	(segment
		(start 216.539826 -17.085056)
		(end 230.699056 -17.085056)
		(width 0.127)
		(layer "In5.Cu")
		(net "LBI_ADDR_4_R")
	)
	(segment
		(start 236.70641 -29.167328)
		(end 236.70641 -37.41039)
		(width 0.1016)
		(layer "In5.Cu")
		(net "LBI_ADDR_4_R")
	)
	(segment
		(start 236.70641 -28.32481)
		(end 236.70641 -28.9814)
		(width 0.1016)
		(layer "In5.Cu")
		(net "LBI_ADDR_4_R")
	)
	(segment
		(start 234.7214 -24.125682)
		(end 235.0135 -24.417782)
		(width 0.127)
		(layer "In5.Cu")
		(net "LBI_ADDR_4_R")
	)
	(segment
		(start 236.709966 -29.163772)
		(end 236.70641 -29.167328)
		(width 0.1016)
		(layer "In5.Cu")
		(net "LBI_ADDR_4_R")
	)
	(segment
		(start 230.699056 -17.085056)
		(end 234.7214 -21.1074)
		(width 0.127)
		(layer "In5.Cu")
		(net "LBI_ADDR_4_R")
	)
	(segment
		(start 215.652604 -17.972278)
		(end 216.539826 -17.085056)
		(width 0.127)
		(layer "In5.Cu")
		(net "LBI_ADDR_4_R")
	)
	(segment
		(start 236.474 -28.0924)
		(end 236.70641 -28.32481)
		(width 0.1016)
		(layer "In5.Cu")
		(net "LBI_ADDR_4_R")
	)
	(segment
		(start 215.550242 -17.972278)
		(end 215.652604 -17.972278)
		(width 0.127)
		(layer "In5.Cu")
		(net "LBI_ADDR_4_R")
	)
	(segment
		(start 236.70641 -37.41039)
		(end 236.493812 -37.622988)
		(width 0.1016)
		(layer "In5.Cu")
		(net "LBI_ADDR_4_R")
	)
	(segment
		(start 236.709966 -28.984956)
		(end 236.709966 -29.163772)
		(width 0.1016)
		(layer "In5.Cu")
		(net "LBI_ADDR_4_R")
	)
	(segment
		(start 235.0135 -24.417782)
		(end 235.0135 -26.6319)
		(width 0.127)
		(layer "In5.Cu")
		(net "LBI_ADDR_4_R")
	)
	(segment
		(start 236.493812 -37.622988)
		(end 236.493812 -38.994588)
		(width 0.1016)
		(layer "In5.Cu")
		(net "LBI_ADDR_4_R")
	)
	(segment
		(start 235.0135 -26.6319)
		(end 236.474 -28.0924)
		(width 0.127)
		(layer "In5.Cu")
		(net "LBI_ADDR_4_R")
	)
	(segment
		(start 236.493812 -38.994588)
		(end 236.100112 -39.388288)
		(width 0.1016)
		(layer "In5.Cu")
		(net "LBI_ADDR_4_R")
	)
	(segment
		(start 236.100112 -39.388288)
		(end 236.100112 -39.500048)
		(width 0.1016)
		(layer "In5.Cu")
		(net "LBI_ADDR_4_R")
	)
	(segment
		(start 236.70641 -28.9814)
		(end 236.709966 -28.984956)
		(width 0.1016)
		(layer "In5.Cu")
		(net "LBI_ADDR_4_R")
	)
	(segment
		(start 236.599984 -38.999922)
		(end 236.100112 -38.50005)
		(width 0.12065)
		(layer "F.Cu")
		(net "LBI_ADDR_3_R")
	)
	(via
		(at 227.211382 -25.636982)
		(size 0.7112)
		(drill 0.3556)
		(layers "F.Cu" "B.Cu")
		(net "LBI_ADDR_3_R")
	)
	(via
		(at 236.100112 -38.50005)
		(size 0.4572)
		(drill 0.2032)
		(layers "F.Cu" "B.Cu")
		(net "LBI_ADDR_3_R")
	)
	(segment
		(start 233.0958 -28.989274)
		(end 230.151686 -26.04516)
		(width 0.12065)
		(layer "B.Cu")
		(net "LBI_ADDR_3_R")
	)
	(segment
		(start 234.493816 -33.336738)
		(end 234.25404 -33.096962)
		(width 0.1016)
		(layer "B.Cu")
		(net "LBI_ADDR_3_R")
	)
	(segment
		(start 233.503216 -32.747712)
		(end 233.503216 -29.881068)
		(width 0.1016)
		(layer "B.Cu")
		(net "LBI_ADDR_3_R")
	)
	(segment
		(start 234.974638 -36.9316)
		(end 234.493816 -36.450778)
		(width 0.1016)
		(layer "B.Cu")
		(net "LBI_ADDR_3_R")
	)
	(segment
		(start 233.503216 -29.881068)
		(end 233.421174 -29.799026)
		(width 0.1016)
		(layer "B.Cu")
		(net "LBI_ADDR_3_R")
	)
	(segment
		(start 234.493816 -36.450778)
		(end 234.493816 -33.336738)
		(width 0.1016)
		(layer "B.Cu")
		(net "LBI_ADDR_3_R")
	)
	(segment
		(start 236.100112 -38.50005)
		(end 235.5215 -37.921438)
		(width 0.1016)
		(layer "B.Cu")
		(net "LBI_ADDR_3_R")
	)
	(segment
		(start 235.5215 -37.921438)
		(end 235.5215 -37.364416)
		(width 0.1016)
		(layer "B.Cu")
		(net "LBI_ADDR_3_R")
	)
	(segment
		(start 226.822 -25.2476)
		(end 227.211382 -25.636982)
		(width 0.12065)
		(layer "B.Cu")
		(net "LBI_ADDR_3_R")
	)
	(segment
		(start 227.61956 -26.04516)
		(end 227.211382 -25.636982)
		(width 0.12065)
		(layer "B.Cu")
		(net "LBI_ADDR_3_R")
	)
	(segment
		(start 235.5215 -37.364416)
		(end 235.088684 -36.9316)
		(width 0.1016)
		(layer "B.Cu")
		(net "LBI_ADDR_3_R")
	)
	(segment
		(start 234.25404 -33.096962)
		(end 233.852466 -33.096962)
		(width 0.1016)
		(layer "B.Cu")
		(net "LBI_ADDR_3_R")
	)
	(segment
		(start 235.088684 -36.9316)
		(end 234.974638 -36.9316)
		(width 0.1016)
		(layer "B.Cu")
		(net "LBI_ADDR_3_R")
	)
	(segment
		(start 226.822 -23.6855)
		(end 226.822 -25.2476)
		(width 0.12065)
		(layer "B.Cu")
		(net "LBI_ADDR_3_R")
	)
	(segment
		(start 230.151686 -26.04516)
		(end 227.61956 -26.04516)
		(width 0.12065)
		(layer "B.Cu")
		(net "LBI_ADDR_3_R")
	)
	(segment
		(start 233.852466 -33.096962)
		(end 233.503216 -32.747712)
		(width 0.1016)
		(layer "B.Cu")
		(net "LBI_ADDR_3_R")
	)
	(segment
		(start 233.421174 -29.799026)
		(end 233.0958 -29.473652)
		(width 0.12065)
		(layer "B.Cu")
		(net "LBI_ADDR_3_R")
	)
	(segment
		(start 233.0958 -29.473652)
		(end 233.0958 -28.989274)
		(width 0.12065)
		(layer "B.Cu")
		(net "LBI_ADDR_3_R")
	)
	(segment
		(start 236.599984 -35.999928)
		(end 236.100112 -35.500056)
		(width 0.12065)
		(layer "F.Cu")
		(net "LBI_ADDR_2_R")
	)
	(via
		(at 236.100112 -35.500056)
		(size 0.4572)
		(drill 0.2032)
		(layers "F.Cu" "B.Cu")
		(net "LBI_ADDR_2_R")
	)
	(via
		(at 229.150926 -24.871426)
		(size 0.7112)
		(drill 0.3556)
		(layers "F.Cu" "B.Cu")
		(net "LBI_ADDR_2_R")
	)
	(segment
		(start 234.936792 -34.893758)
		(end 234.697016 -34.653982)
		(width 0.1016)
		(layer "B.Cu")
		(net "LBI_ADDR_2_R")
	)
	(segment
		(start 233.706416 -32.663384)
		(end 233.706416 -29.572204)
		(width 0.1016)
		(layer "B.Cu")
		(net "LBI_ADDR_2_R")
	)
	(segment
		(start 230.3018 -25.68321)
		(end 229.96271 -25.68321)
		(width 0.12065)
		(layer "B.Cu")
		(net "LBI_ADDR_2_R")
	)
	(segment
		(start 236.100112 -35.500056)
		(end 235.493814 -34.893758)
		(width 0.1016)
		(layer "B.Cu")
		(net "LBI_ADDR_2_R")
	)
	(segment
		(start 233.706416 -29.572204)
		(end 233.696764 -29.562552)
		(width 0.1016)
		(layer "B.Cu")
		(net "LBI_ADDR_2_R")
	)
	(segment
		(start 234.338368 -32.893762)
		(end 233.936794 -32.893762)
		(width 0.1016)
		(layer "B.Cu")
		(net "LBI_ADDR_2_R")
	)
	(segment
		(start 234.697016 -34.653982)
		(end 234.697016 -33.25241)
		(width 0.1016)
		(layer "B.Cu")
		(net "LBI_ADDR_2_R")
	)
	(segment
		(start 233.696764 -29.562552)
		(end 233.696764 -29.078174)
		(width 0.12065)
		(layer "B.Cu")
		(net "LBI_ADDR_2_R")
	)
	(segment
		(start 229.96271 -25.68321)
		(end 229.150926 -24.871426)
		(width 0.12065)
		(layer "B.Cu")
		(net "LBI_ADDR_2_R")
	)
	(segment
		(start 227.965 -23.6855)
		(end 229.150926 -24.871426)
		(width 0.12065)
		(layer "B.Cu")
		(net "LBI_ADDR_2_R")
	)
	(segment
		(start 234.697016 -33.25241)
		(end 234.338368 -32.893762)
		(width 0.1016)
		(layer "B.Cu")
		(net "LBI_ADDR_2_R")
	)
	(segment
		(start 233.936794 -32.893762)
		(end 233.706416 -32.663384)
		(width 0.1016)
		(layer "B.Cu")
		(net "LBI_ADDR_2_R")
	)
	(segment
		(start 233.696764 -29.078174)
		(end 230.3018 -25.68321)
		(width 0.12065)
		(layer "B.Cu")
		(net "LBI_ADDR_2_R")
	)
	(segment
		(start 235.493814 -34.893758)
		(end 234.936792 -34.893758)
		(width 0.1016)
		(layer "B.Cu")
		(net "LBI_ADDR_2_R")
	)
	(segment
		(start 234.599988 -38.999922)
		(end 234.100116 -38.50005)
		(width 0.12065)
		(layer "F.Cu")
		(net "LBI_ADDR_12_R")
	)
	(via
		(at 234.100116 -38.50005)
		(size 0.4572)
		(drill 0.2032)
		(layers "F.Cu" "B.Cu")
		(net "LBI_ADDR_12_R")
	)
	(segment
		(start 235.599986 -38.999922)
		(end 234.599988 -38.999922)
		(width 0.12065)
		(layer "B.Cu")
		(net "LBI_ADDR_12_R")
	)
	(segment
		(start 234.599988 -38.999922)
		(end 234.100116 -38.50005)
		(width 0.12065)
		(layer "B.Cu")
		(net "LBI_ADDR_12_R")
	)
	(segment
		(start 234.599988 -35.999928)
		(end 234.100116 -35.500056)
		(width 0.12065)
		(layer "F.Cu")
		(net "LBI_ADDR_10")
	)
	(via
		(at 234.100116 -35.500056)
		(size 0.4572)
		(drill 0.2032)
		(layers "F.Cu" "B.Cu")
		(net "LBI_ADDR_10")
	)
	(segment
		(start 233.8832 -35.716972)
		(end 234.100116 -35.500056)
		(width 0.12065)
		(layer "B.Cu")
		(net "LBI_ADDR_10")
	)
	(segment
		(start 233.8832 -36.4236)
		(end 233.8832 -35.716972)
		(width 0.12065)
		(layer "B.Cu")
		(net "LBI_ADDR_10")
	)
	(segment
		(start 237.599982 -39.99992)
		(end 237.10011 -39.500048)
		(width 0.12065)
		(layer "F.Cu")
		(net "LBI_ADDR_1_R")
	)
	(via
		(at 237.10011 -39.500048)
		(size 0.4572)
		(drill 0.2032)
		(layers "F.Cu" "B.Cu")
		(net "LBI_ADDR_1_R")
	)
	(via
		(at 230.803704 -25.381204)
		(size 0.7112)
		(drill 0.3556)
		(layers "F.Cu" "B.Cu")
		(net "LBI_ADDR_1_R")
	)
	(via
		(at 236.1692 -26.8986)
		(size 0.508)
		(drill 0.254)
		(layers "F.Cu" "B.Cu")
		(net "LBI_ADDR_1_R")
	)
	(segment
		(start 236.1692 -26.8986)
		(end 232.3211 -26.8986)
		(width 0.12065)
		(layer "B.Cu")
		(net "LBI_ADDR_1_R")
	)
	(segment
		(start 230.803704 -25.381204)
		(end 229.108 -23.6855)
		(width 0.12065)
		(layer "B.Cu")
		(net "LBI_ADDR_1_R")
	)
	(segment
		(start 232.3211 -26.8986)
		(end 230.803704 -25.381204)
		(width 0.12065)
		(layer "B.Cu")
		(net "LBI_ADDR_1_R")
	)
	(segment
		(start 237.5154 -38.8112)
		(end 237.5154 -28.9052)
		(width 0.1016)
		(layer "In5.Cu")
		(net "LBI_ADDR_1_R")
	)
	(segment
		(start 237.5154 -28.4734)
		(end 236.1692 -27.1272)
		(width 0.127)
		(layer "In5.Cu")
		(net "LBI_ADDR_1_R")
	)
	(segment
		(start 237.10011 -39.500048)
		(end 237.10011 -39.22649)
		(width 0.1016)
		(layer "In5.Cu")
		(net "LBI_ADDR_1_R")
	)
	(segment
		(start 236.1692 -27.1272)
		(end 236.1692 -26.8986)
		(width 0.127)
		(layer "In5.Cu")
		(net "LBI_ADDR_1_R")
	)
	(segment
		(start 237.5154 -28.9052)
		(end 237.5154 -28.4734)
		(width 0.127)
		(layer "In5.Cu")
		(net "LBI_ADDR_1_R")
	)
	(segment
		(start 237.10011 -39.22649)
		(end 237.5154 -38.8112)
		(width 0.1016)
		(layer "In5.Cu")
		(net "LBI_ADDR_1_R")
	)
	(segment
		(start 237.599982 -38.999922)
		(end 237.10011 -38.50005)
		(width 0.12065)
		(layer "F.Cu")
		(net "LBI_ADDR_0_R")
	)
	(via
		(at 232.645204 -26.079704)
		(size 0.7112)
		(drill 0.3556)
		(layers "F.Cu" "B.Cu")
		(net "LBI_ADDR_0_R")
	)
	(via
		(at 237.10011 -38.50005)
		(size 0.4572)
		(drill 0.2032)
		(layers "F.Cu" "B.Cu")
		(net "LBI_ADDR_0_R")
	)
	(segment
		(start 237.49381 -38.10635)
		(end 237.49381 -36.336732)
		(width 0.1016)
		(layer "B.Cu")
		(net "LBI_ADDR_0_R")
	)
	(segment
		(start 232.94975 -26.38425)
		(end 232.645204 -26.079704)
		(width 0.12065)
		(layer "B.Cu")
		(net "LBI_ADDR_0_R")
	)
	(segment
		(start 235.852462 -34.09696)
		(end 235.503212 -33.74771)
		(width 0.1016)
		(layer "B.Cu")
		(net "LBI_ADDR_0_R")
	)
	(segment
		(start 236.7153 -27.3177)
		(end 236.7153 -26.7843)
		(width 0.12065)
		(layer "B.Cu")
		(net "LBI_ADDR_0_R")
	)
	(segment
		(start 237.263432 -36.106354)
		(end 236.861858 -36.106354)
		(width 0.1016)
		(layer "B.Cu")
		(net "LBI_ADDR_0_R")
	)
	(segment
		(start 237.10011 -38.50005)
		(end 237.49381 -38.10635)
		(width 0.1016)
		(layer "B.Cu")
		(net "LBI_ADDR_0_R")
	)
	(segment
		(start 236.50321 -34.327338)
		(end 236.272832 -34.09696)
		(width 0.1016)
		(layer "B.Cu")
		(net "LBI_ADDR_0_R")
	)
	(segment
		(start 230.251 -23.6855)
		(end 232.645204 -26.079704)
		(width 0.12065)
		(layer "B.Cu")
		(net "LBI_ADDR_0_R")
	)
	(segment
		(start 235.503212 -33.74771)
		(end 235.503212 -30.226)
		(width 0.1016)
		(layer "B.Cu")
		(net "LBI_ADDR_0_R")
	)
	(segment
		(start 236.31525 -26.38425)
		(end 232.94975 -26.38425)
		(width 0.12065)
		(layer "B.Cu")
		(net "LBI_ADDR_0_R")
	)
	(segment
		(start 236.7153 -26.7843)
		(end 236.31525 -26.38425)
		(width 0.12065)
		(layer "B.Cu")
		(net "LBI_ADDR_0_R")
	)
	(segment
		(start 236.50321 -35.747706)
		(end 236.50321 -34.327338)
		(width 0.1016)
		(layer "B.Cu")
		(net "LBI_ADDR_0_R")
	)
	(segment
		(start 237.49381 -36.336732)
		(end 237.263432 -36.106354)
		(width 0.1016)
		(layer "B.Cu")
		(net "LBI_ADDR_0_R")
	)
	(segment
		(start 236.272832 -34.09696)
		(end 235.852462 -34.09696)
		(width 0.1016)
		(layer "B.Cu")
		(net "LBI_ADDR_0_R")
	)
	(segment
		(start 236.861858 -36.106354)
		(end 236.50321 -35.747706)
		(width 0.1016)
		(layer "B.Cu")
		(net "LBI_ADDR_0_R")
	)
	(segment
		(start 235.503212 -30.226)
		(end 235.503212 -28.529788)
		(width 0.12065)
		(layer "B.Cu")
		(net "LBI_ADDR_0_R")
	)
	(segment
		(start 235.503212 -28.529788)
		(end 236.7153 -27.3177)
		(width 0.12065)
		(layer "B.Cu")
		(net "LBI_ADDR_0_R")
	)
	(segment
		(start 51.9938 -121.870216)
		(end 51.9938 -122.33402)
		(width 0.12065)
		(layer "F.Cu")
		(net "JTAG_BMC_TRST_N")
	)
	(segment
		(start 49.981612 -123.373388)
		(end 49.784254 -123.373388)
		(width 0.12065)
		(layer "F.Cu")
		(net "JTAG_BMC_TRST_N")
	)
	(segment
		(start 51.9938 -122.33402)
		(end 52.584604 -122.924824)
		(width 0.12065)
		(layer "F.Cu")
		(net "JTAG_BMC_TRST_N")
	)
	(segment
		(start 53.2765 -120.3325)
		(end 53.34 -120.269)
		(width 0.12065)
		(layer "F.Cu")
		(net "JTAG_BMC_TRST_N")
	)
	(segment
		(start 51.9938 -121.870216)
		(end 51.484784 -121.870216)
		(width 0.12065)
		(layer "F.Cu")
		(net "JTAG_BMC_TRST_N")
	)
	(segment
		(start 52.584604 -122.664982)
		(end 52.584604 -122.924824)
		(width 0.12065)
		(layer "F.Cu")
		(net "JTAG_BMC_TRST_N")
	)
	(segment
		(start 59.817 -125.867922)
		(end 59.817 -126.746)
		(width 0.12065)
		(layer "F.Cu")
		(net "JTAG_BMC_TRST_N")
	)
	(segment
		(start 53.2765 -122.428)
		(end 52.821586 -122.428)
		(width 0.12065)
		(layer "F.Cu")
		(net "JTAG_BMC_TRST_N")
	)
	(segment
		(start 53.2765 -122.428)
		(end 53.2765 -121.412)
		(width 0.12065)
		(layer "F.Cu")
		(net "JTAG_BMC_TRST_N")
	)
	(segment
		(start 60.131198 -125.26518)
		(end 60.131198 -125.553724)
		(width 0.12065)
		(layer "F.Cu")
		(net "JTAG_BMC_TRST_N")
	)
	(segment
		(start 60.131198 -125.553724)
		(end 59.817 -125.867922)
		(width 0.12065)
		(layer "F.Cu")
		(net "JTAG_BMC_TRST_N")
	)
	(segment
		(start 52.821586 -122.428)
		(end 52.584604 -122.664982)
		(width 0.12065)
		(layer "F.Cu")
		(net "JTAG_BMC_TRST_N")
	)
	(segment
		(start 51.484784 -121.870216)
		(end 49.981612 -123.373388)
		(width 0.12065)
		(layer "F.Cu")
		(net "JTAG_BMC_TRST_N")
	)
	(segment
		(start 53.2765 -121.412)
		(end 53.2765 -120.3325)
		(width 0.12065)
		(layer "F.Cu")
		(net "JTAG_BMC_TRST_N")
	)
	(segment
		(start 47.87265 -125.284992)
		(end 46.50486 -125.284992)
		(width 0.12065)
		(layer "F.Cu")
		(net "JTAG_BMC_TRST_N")
	)
	(segment
		(start 49.784254 -123.373388)
		(end 47.87265 -125.284992)
		(width 0.12065)
		(layer "F.Cu")
		(net "JTAG_BMC_TRST_N")
	)
	(via
		(at 52.584604 -122.924824)
		(size 0.508)
		(drill 0.254)
		(layers "F.Cu" "B.Cu")
		(net "JTAG_BMC_TRST_N")
	)
	(via
		(at 60.131198 -125.26518)
		(size 0.508)
		(drill 0.254)
		(layers "F.Cu" "B.Cu")
		(net "JTAG_BMC_TRST_N")
	)
	(segment
		(start 53.250084 -122.259344)
		(end 55.796942 -122.259344)
		(width 0.127)
		(layer "In2.Cu")
		(net "JTAG_BMC_TRST_N")
	)
	(segment
		(start 52.584604 -122.924824)
		(end 53.250084 -122.259344)
		(width 0.127)
		(layer "In2.Cu")
		(net "JTAG_BMC_TRST_N")
	)
	(segment
		(start 59.622182 -123.172982)
		(end 59.622182 -124.756164)
		(width 0.127)
		(layer "In2.Cu")
		(net "JTAG_BMC_TRST_N")
	)
	(segment
		(start 58.801 -122.3518)
		(end 59.622182 -123.172982)
		(width 0.127)
		(layer "In2.Cu")
		(net "JTAG_BMC_TRST_N")
	)
	(segment
		(start 55.796942 -122.259344)
		(end 55.889398 -122.3518)
		(width 0.127)
		(layer "In2.Cu")
		(net "JTAG_BMC_TRST_N")
	)
	(segment
		(start 59.622182 -124.756164)
		(end 60.131198 -125.26518)
		(width 0.127)
		(layer "In2.Cu")
		(net "JTAG_BMC_TRST_N")
	)
	(segment
		(start 55.889398 -122.3518)
		(end 58.801 -122.3518)
		(width 0.127)
		(layer "In2.Cu")
		(net "JTAG_BMC_TRST_N")
	)
	(segment
		(start 51.463702 -126.81204)
		(end 51.65471 -126.81204)
		(width 0.12065)
		(layer "F.Cu")
		(net "JTAG_BMC_TMS")
	)
	(segment
		(start 50.362866 -126.04242)
		(end 50.694082 -126.04242)
		(width 0.12065)
		(layer "F.Cu")
		(net "JTAG_BMC_TMS")
	)
	(segment
		(start 60.89015 -126.124208)
		(end 60.89015 -122.48515)
		(width 0.12065)
		(layer "F.Cu")
		(net "JTAG_BMC_TMS")
	)
	(segment
		(start 51.65471 -126.81204)
		(end 51.689 -126.77775)
		(width 0.12065)
		(layer "F.Cu")
		(net "JTAG_BMC_TMS")
	)
	(segment
		(start 51.689 -126.77775)
		(end 52.018946 -126.447804)
		(width 0.12065)
		(layer "F.Cu")
		(net "JTAG_BMC_TMS")
	)
	(segment
		(start 50.362866 -126.04242)
		(end 49.46777 -126.04242)
		(width 0.12065)
		(layer "F.Cu")
		(net "JTAG_BMC_TMS")
	)
	(segment
		(start 52.018946 -126.1364)
		(end 52.212494 -125.942852)
		(width 0.12065)
		(layer "F.Cu")
		(net "JTAG_BMC_TMS")
	)
	(segment
		(start 50.694082 -126.04242)
		(end 51.463702 -126.81204)
		(width 0.12065)
		(layer "F.Cu")
		(net "JTAG_BMC_TMS")
	)
	(segment
		(start 48.26 -127.25019)
		(end 46.070012 -127.25019)
		(width 0.12065)
		(layer "F.Cu")
		(net "JTAG_BMC_TMS")
	)
	(segment
		(start 46.070012 -127.25019)
		(end 45.70476 -126.884938)
		(width 0.12065)
		(layer "F.Cu")
		(net "JTAG_BMC_TMS")
	)
	(segment
		(start 49.46777 -126.04242)
		(end 48.26 -127.25019)
		(width 0.12065)
		(layer "F.Cu")
		(net "JTAG_BMC_TMS")
	)
	(segment
		(start 52.936648 -125.942852)
		(end 53.3019 -125.5776)
		(width 0.12065)
		(layer "F.Cu")
		(net "JTAG_BMC_TMS")
	)
	(segment
		(start 52.212494 -125.942852)
		(end 52.936648 -125.942852)
		(width 0.12065)
		(layer "F.Cu")
		(net "JTAG_BMC_TMS")
	)
	(segment
		(start 61.0616 -126.295658)
		(end 60.89015 -126.124208)
		(width 0.12065)
		(layer "F.Cu")
		(net "JTAG_BMC_TMS")
	)
	(segment
		(start 51.689 -126.77775)
		(end 51.689 -126.7968)
		(width 0.12065)
		(layer "F.Cu")
		(net "JTAG_BMC_TMS")
	)
	(segment
		(start 52.018946 -126.447804)
		(end 52.018946 -126.1364)
		(width 0.12065)
		(layer "F.Cu")
		(net "JTAG_BMC_TMS")
	)
	(segment
		(start 60.071 -121.666)
		(end 59.817 -121.666)
		(width 0.12065)
		(layer "F.Cu")
		(net "JTAG_BMC_TMS")
	)
	(segment
		(start 61.0743 -126.8476)
		(end 61.0616 -126.8476)
		(width 0.12065)
		(layer "F.Cu")
		(net "JTAG_BMC_TMS")
	)
	(segment
		(start 60.89015 -122.48515)
		(end 60.071 -121.666)
		(width 0.12065)
		(layer "F.Cu")
		(net "JTAG_BMC_TMS")
	)
	(segment
		(start 61.0616 -126.8476)
		(end 61.0616 -126.295658)
		(width 0.12065)
		(layer "F.Cu")
		(net "JTAG_BMC_TMS")
	)
	(via
		(at 51.689 -126.7968)
		(size 0.508)
		(drill 0.254)
		(layers "F.Cu" "B.Cu")
		(net "JTAG_BMC_TMS")
	)
	(via
		(at 61.0743 -126.8476)
		(size 0.508)
		(drill 0.254)
		(layers "F.Cu" "B.Cu")
		(net "JTAG_BMC_TMS")
	)
	(segment
		(start 61.0616 -126.8476)
		(end 61.003942 -126.905258)
		(width 0.127)
		(layer "In2.Cu")
		(net "JTAG_BMC_TMS")
	)
	(segment
		(start 58.586878 -126.905258)
		(end 58.12282 -126.4412)
		(width 0.127)
		(layer "In2.Cu")
		(net "JTAG_BMC_TMS")
	)
	(segment
		(start 55.223918 -126.5936)
		(end 54.808882 -126.5936)
		(width 0.127)
		(layer "In2.Cu")
		(net "JTAG_BMC_TMS")
	)
	(segment
		(start 52.256182 -126.9111)
		(end 52.116482 -126.7714)
		(width 0.127)
		(layer "In2.Cu")
		(net "JTAG_BMC_TMS")
	)
	(segment
		(start 52.116482 -126.7714)
		(end 51.7144 -126.7714)
		(width 0.127)
		(layer "In2.Cu")
		(net "JTAG_BMC_TMS")
	)
	(segment
		(start 53.2384 -126.4412)
		(end 52.7685 -126.9111)
		(width 0.127)
		(layer "In2.Cu")
		(net "JTAG_BMC_TMS")
	)
	(segment
		(start 54.656482 -126.4412)
		(end 53.2384 -126.4412)
		(width 0.127)
		(layer "In2.Cu")
		(net "JTAG_BMC_TMS")
	)
	(segment
		(start 52.7685 -126.9111)
		(end 52.256182 -126.9111)
		(width 0.127)
		(layer "In2.Cu")
		(net "JTAG_BMC_TMS")
	)
	(segment
		(start 58.12282 -126.4412)
		(end 55.376318 -126.4412)
		(width 0.127)
		(layer "In2.Cu")
		(net "JTAG_BMC_TMS")
	)
	(segment
		(start 55.376318 -126.4412)
		(end 55.223918 -126.5936)
		(width 0.127)
		(layer "In2.Cu")
		(net "JTAG_BMC_TMS")
	)
	(segment
		(start 54.808882 -126.5936)
		(end 54.656482 -126.4412)
		(width 0.127)
		(layer "In2.Cu")
		(net "JTAG_BMC_TMS")
	)
	(segment
		(start 61.0743 -126.8476)
		(end 61.0616 -126.8476)
		(width 0.127)
		(layer "In2.Cu")
		(net "JTAG_BMC_TMS")
	)
	(segment
		(start 61.003942 -126.905258)
		(end 58.586878 -126.905258)
		(width 0.127)
		(layer "In2.Cu")
		(net "JTAG_BMC_TMS")
	)
	(segment
		(start 51.7144 -126.7714)
		(end 51.689 -126.7968)
		(width 0.127)
		(layer "In2.Cu")
		(net "JTAG_BMC_TMS")
	)
	(segment
		(start 62.357 -125.3236)
		(end 62.611 -125.3236)
		(width 0.12065)
		(layer "F.Cu")
		(net "JTAG_BMC_TDO")
	)
	(segment
		(start 44.904914 -126.884938)
		(end 45.30471 -126.485142)
		(width 0.12065)
		(layer "F.Cu")
		(net "JTAG_BMC_TDO")
	)
	(segment
		(start 60.4012 -114.046)
		(end 61.976 -115.6208)
		(width 0.12065)
		(layer "F.Cu")
		(net "JTAG_BMC_TDO")
	)
	(segment
		(start 59.817 -114.046)
		(end 60.4012 -114.046)
		(width 0.12065)
		(layer "F.Cu")
		(net "JTAG_BMC_TDO")
	)
	(segment
		(start 61.976 -124.9426)
		(end 62.357 -125.3236)
		(width 0.12065)
		(layer "F.Cu")
		(net "JTAG_BMC_TDO")
	)
	(segment
		(start 61.976 -115.6208)
		(end 61.976 -124.9426)
		(width 0.12065)
		(layer "F.Cu")
		(net "JTAG_BMC_TDO")
	)
	(via
		(at 52.5018 -125.476)
		(size 0.508)
		(drill 0.254)
		(layers "F.Cu" "B.Cu")
		(net "JTAG_BMC_TDO")
	)
	(via
		(at 45.30471 -126.485142)
		(size 0.4572)
		(drill 0.2032)
		(layers "F.Cu" "B.Cu")
		(net "JTAG_BMC_TDO")
	)
	(via
		(at 62.611 -125.3236)
		(size 0.508)
		(drill 0.254)
		(layers "F.Cu" "B.Cu")
		(net "JTAG_BMC_TDO")
	)
	(segment
		(start 49.19472 -126.44628)
		(end 48.636682 -126.44628)
		(width 0.12065)
		(layer "B.Cu")
		(net "JTAG_BMC_TDO")
	)
	(segment
		(start 45.941488 -126.446534)
		(end 45.581316 -126.446534)
		(width 0.12065)
		(layer "B.Cu")
		(net "JTAG_BMC_TDO")
	)
	(segment
		(start 51.907948 -125.349)
		(end 52.034948 -125.476)
		(width 0.12065)
		(layer "B.Cu")
		(net "JTAG_BMC_TDO")
	)
	(segment
		(start 45.581316 -126.446534)
		(end 45.542708 -126.485142)
		(width 0.12065)
		(layer "B.Cu")
		(net "JTAG_BMC_TDO")
	)
	(segment
		(start 50.292 -125.349)
		(end 51.907948 -125.349)
		(width 0.12065)
		(layer "B.Cu")
		(net "JTAG_BMC_TDO")
	)
	(segment
		(start 52.034948 -125.476)
		(end 52.5018 -125.476)
		(width 0.12065)
		(layer "B.Cu")
		(net "JTAG_BMC_TDO")
	)
	(segment
		(start 45.542708 -126.485142)
		(end 45.30471 -126.485142)
		(width 0.12065)
		(layer "B.Cu")
		(net "JTAG_BMC_TDO")
	)
	(segment
		(start 53.34 -124.902976)
		(end 53.074824 -124.902976)
		(width 0.12065)
		(layer "B.Cu")
		(net "JTAG_BMC_TDO")
	)
	(segment
		(start 53.074824 -124.902976)
		(end 52.5018 -125.476)
		(width 0.12065)
		(layer "B.Cu")
		(net "JTAG_BMC_TDO")
	)
	(segment
		(start 50.292 -125.349)
		(end 49.19472 -126.44628)
		(width 0.12065)
		(layer "B.Cu")
		(net "JTAG_BMC_TDO")
	)
	(segment
		(start 48.636682 -126.44628)
		(end 45.941488 -126.446534)
		(width 0.12065)
		(layer "B.Cu")
		(net "JTAG_BMC_TDO")
	)
	(segment
		(start 56.255158 -123.698)
		(end 57.855358 -125.2982)
		(width 0.127)
		(layer "In2.Cu")
		(net "JTAG_BMC_TDO")
	)
	(segment
		(start 60.43676 -125.6538)
		(end 60.76696 -125.3236)
		(width 0.127)
		(layer "In2.Cu")
		(net "JTAG_BMC_TDO")
	)
	(segment
		(start 59.060842 -125.762258)
		(end 60.306966 -125.762258)
		(width 0.127)
		(layer "In2.Cu")
		(net "JTAG_BMC_TDO")
	)
	(segment
		(start 52.5018 -125.476)
		(end 52.5018 -124.5616)
		(width 0.127)
		(layer "In2.Cu")
		(net "JTAG_BMC_TDO")
	)
	(segment
		(start 60.76696 -125.3236)
		(end 62.611 -125.3236)
		(width 0.127)
		(layer "In2.Cu")
		(net "JTAG_BMC_TDO")
	)
	(segment
		(start 58.596784 -125.2982)
		(end 59.060842 -125.762258)
		(width 0.127)
		(layer "In2.Cu")
		(net "JTAG_BMC_TDO")
	)
	(segment
		(start 60.306966 -125.762258)
		(end 60.415424 -125.6538)
		(width 0.127)
		(layer "In2.Cu")
		(net "JTAG_BMC_TDO")
	)
	(segment
		(start 57.855358 -125.2982)
		(end 58.596784 -125.2982)
		(width 0.127)
		(layer "In2.Cu")
		(net "JTAG_BMC_TDO")
	)
	(segment
		(start 53.3654 -123.698)
		(end 56.255158 -123.698)
		(width 0.127)
		(layer "In2.Cu")
		(net "JTAG_BMC_TDO")
	)
	(segment
		(start 60.415424 -125.6538)
		(end 60.43676 -125.6538)
		(width 0.127)
		(layer "In2.Cu")
		(net "JTAG_BMC_TDO")
	)
	(segment
		(start 52.5018 -124.5616)
		(end 53.3654 -123.698)
		(width 0.127)
		(layer "In2.Cu")
		(net "JTAG_BMC_TDO")
	)
	(segment
		(start 47.446692 -126.084838)
		(end 46.50486 -126.084838)
		(width 0.12065)
		(layer "F.Cu")
		(net "JTAG_BMC_TDI")
	)
	(segment
		(start 59.25566 -125.292358)
		(end 59.817 -124.731018)
		(width 0.12065)
		(layer "F.Cu")
		(net "JTAG_BMC_TDI")
	)
	(segment
		(start 52.077112 -123.444)
		(end 53.2765 -123.444)
		(width 0.12065)
		(layer "F.Cu")
		(net "JTAG_BMC_TDI")
	)
	(segment
		(start 49.796192 -123.735338)
		(end 47.446692 -126.084838)
		(width 0.12065)
		(layer "F.Cu")
		(net "JTAG_BMC_TDI")
	)
	(segment
		(start 51.118516 -123.068588)
		(end 51.7017 -123.068588)
		(width 0.12065)
		(layer "F.Cu")
		(net "JTAG_BMC_TDI")
	)
	(segment
		(start 50.756566 -123.430538)
		(end 51.118516 -123.068588)
		(width 0.12065)
		(layer "F.Cu")
		(net "JTAG_BMC_TDI")
	)
	(segment
		(start 51.7017 -123.068588)
		(end 52.077112 -123.444)
		(width 0.12065)
		(layer "F.Cu")
		(net "JTAG_BMC_TDI")
	)
	(segment
		(start 50.451766 -123.735338)
		(end 49.796192 -123.735338)
		(width 0.12065)
		(layer "F.Cu")
		(net "JTAG_BMC_TDI")
	)
	(segment
		(start 50.756566 -123.430538)
		(end 50.451766 -123.735338)
		(width 0.12065)
		(layer "F.Cu")
		(net "JTAG_BMC_TDI")
	)
	(segment
		(start 59.817 -124.731018)
		(end 59.817 -124.206)
		(width 0.12065)
		(layer "F.Cu")
		(net "JTAG_BMC_TDI")
	)
	(via
		(at 59.25566 -125.292358)
		(size 0.508)
		(drill 0.254)
		(layers "F.Cu" "B.Cu")
		(net "JTAG_BMC_TDI")
	)
	(via
		(at 51.7017 -123.068588)
		(size 0.508)
		(drill 0.254)
		(layers "F.Cu" "B.Cu")
		(net "JTAG_BMC_TDI")
	)
	(segment
		(start 52.907946 -123.2662)
		(end 56.388 -123.2662)
		(width 0.127)
		(layer "In2.Cu")
		(net "JTAG_BMC_TDI")
	)
	(segment
		(start 58.880502 -124.9172)
		(end 59.25566 -125.292358)
		(width 0.127)
		(layer "In2.Cu")
		(net "JTAG_BMC_TDI")
	)
	(segment
		(start 51.899312 -123.2662)
		(end 52.261262 -123.2662)
		(width 0.127)
		(layer "In2.Cu")
		(net "JTAG_BMC_TDI")
	)
	(segment
		(start 52.389786 -123.394724)
		(end 52.779422 -123.394724)
		(width 0.127)
		(layer "In2.Cu")
		(net "JTAG_BMC_TDI")
	)
	(segment
		(start 52.779422 -123.394724)
		(end 52.907946 -123.2662)
		(width 0.127)
		(layer "In2.Cu")
		(net "JTAG_BMC_TDI")
	)
	(segment
		(start 58.039 -124.9172)
		(end 58.880502 -124.9172)
		(width 0.127)
		(layer "In2.Cu")
		(net "JTAG_BMC_TDI")
	)
	(segment
		(start 51.7017 -123.068588)
		(end 51.899312 -123.2662)
		(width 0.127)
		(layer "In2.Cu")
		(net "JTAG_BMC_TDI")
	)
	(segment
		(start 56.388 -123.2662)
		(end 58.039 -124.9172)
		(width 0.127)
		(layer "In2.Cu")
		(net "JTAG_BMC_TDI")
	)
	(segment
		(start 52.261262 -123.2662)
		(end 52.389786 -123.394724)
		(width 0.127)
		(layer "In2.Cu")
		(net "JTAG_BMC_TDI")
	)
	(segment
		(start 49.834546 -124.106178)
		(end 50.532284 -124.106178)
		(width 0.12065)
		(layer "F.Cu")
		(net "JTAG_BMC_TCK")
	)
	(segment
		(start 61.2521 -125.434344)
		(end 61.2521 -120.3071)
		(width 0.12065)
		(layer "F.Cu")
		(net "JTAG_BMC_TCK")
	)
	(segment
		(start 45.70476 -126.084838)
		(end 46.070012 -126.45009)
		(width 0.12065)
		(layer "F.Cu")
		(net "JTAG_BMC_TCK")
	)
	(segment
		(start 53.2765 -124.46)
		(end 51.943 -124.46)
		(width 0.12065)
		(layer "F.Cu")
		(net "JTAG_BMC_TCK")
	)
	(segment
		(start 61.6712 -125.853444)
		(end 61.2521 -125.434344)
		(width 0.12065)
		(layer "F.Cu")
		(net "JTAG_BMC_TCK")
	)
	(segment
		(start 47.490634 -126.45009)
		(end 49.834546 -124.106178)
		(width 0.12065)
		(layer "F.Cu")
		(net "JTAG_BMC_TCK")
	)
	(segment
		(start 46.070012 -126.45009)
		(end 47.490634 -126.45009)
		(width 0.12065)
		(layer "F.Cu")
		(net "JTAG_BMC_TCK")
	)
	(segment
		(start 61.2521 -120.3071)
		(end 60.071 -119.126)
		(width 0.12065)
		(layer "F.Cu")
		(net "JTAG_BMC_TCK")
	)
	(segment
		(start 51.943 -124.46)
		(end 51.689 -124.46)
		(width 0.12065)
		(layer "F.Cu")
		(net "JTAG_BMC_TCK")
	)
	(segment
		(start 51.689 -124.46)
		(end 51.542188 -124.606812)
		(width 0.12065)
		(layer "F.Cu")
		(net "JTAG_BMC_TCK")
	)
	(segment
		(start 51.542188 -124.606812)
		(end 51.032918 -124.606812)
		(width 0.12065)
		(layer "F.Cu")
		(net "JTAG_BMC_TCK")
	)
	(segment
		(start 50.532284 -124.106178)
		(end 51.032918 -124.606812)
		(width 0.12065)
		(layer "F.Cu")
		(net "JTAG_BMC_TCK")
	)
	(segment
		(start 60.071 -119.126)
		(end 59.817 -119.126)
		(width 0.12065)
		(layer "F.Cu")
		(net "JTAG_BMC_TCK")
	)
	(via
		(at 61.6712 -125.853444)
		(size 0.508)
		(drill 0.254)
		(layers "F.Cu" "B.Cu")
		(net "JTAG_BMC_TCK")
	)
	(via
		(at 51.032918 -124.606812)
		(size 0.508)
		(drill 0.254)
		(layers "F.Cu" "B.Cu")
		(net "JTAG_BMC_TCK")
	)
	(segment
		(start 50.9016 -125.976888)
		(end 50.9016 -125.2474)
		(width 0.127)
		(layer "In2.Cu")
		(net "JTAG_BMC_TCK")
	)
	(segment
		(start 60.776104 -125.853444)
		(end 60.594748 -126.0348)
		(width 0.127)
		(layer "In2.Cu")
		(net "JTAG_BMC_TCK")
	)
	(segment
		(start 60.573412 -126.0348)
		(end 60.464954 -126.143258)
		(width 0.127)
		(layer "In2.Cu")
		(net "JTAG_BMC_TCK")
	)
	(segment
		(start 51.869848 -126.361952)
		(end 51.286664 -126.361952)
		(width 0.127)
		(layer "In2.Cu")
		(net "JTAG_BMC_TCK")
	)
	(segment
		(start 53.7845 -124.9172)
		(end 52.7558 -125.9459)
		(width 0.127)
		(layer "In2.Cu")
		(net "JTAG_BMC_TCK")
	)
	(segment
		(start 52.7558 -125.9459)
		(end 52.2859 -125.9459)
		(width 0.127)
		(layer "In2.Cu")
		(net "JTAG_BMC_TCK")
	)
	(segment
		(start 52.2859 -125.9459)
		(end 51.869848 -126.361952)
		(width 0.127)
		(layer "In2.Cu")
		(net "JTAG_BMC_TCK")
	)
	(segment
		(start 57.277 -125.6792)
		(end 56.515 -124.9172)
		(width 0.127)
		(layer "In2.Cu")
		(net "JTAG_BMC_TCK")
	)
	(segment
		(start 61.6712 -125.853444)
		(end 60.776104 -125.853444)
		(width 0.127)
		(layer "In2.Cu")
		(net "JTAG_BMC_TCK")
	)
	(segment
		(start 51.032918 -125.116082)
		(end 51.032918 -124.606812)
		(width 0.127)
		(layer "In2.Cu")
		(net "JTAG_BMC_TCK")
	)
	(segment
		(start 60.594748 -126.0348)
		(end 60.573412 -126.0348)
		(width 0.127)
		(layer "In2.Cu")
		(net "JTAG_BMC_TCK")
	)
	(segment
		(start 58.902854 -126.143258)
		(end 58.438796 -125.6792)
		(width 0.127)
		(layer "In2.Cu")
		(net "JTAG_BMC_TCK")
	)
	(segment
		(start 58.438796 -125.6792)
		(end 57.277 -125.6792)
		(width 0.127)
		(layer "In2.Cu")
		(net "JTAG_BMC_TCK")
	)
	(segment
		(start 50.9016 -125.2474)
		(end 51.032918 -125.116082)
		(width 0.127)
		(layer "In2.Cu")
		(net "JTAG_BMC_TCK")
	)
	(segment
		(start 51.286664 -126.361952)
		(end 50.9016 -125.976888)
		(width 0.127)
		(layer "In2.Cu")
		(net "JTAG_BMC_TCK")
	)
	(segment
		(start 60.464954 -126.143258)
		(end 58.902854 -126.143258)
		(width 0.127)
		(layer "In2.Cu")
		(net "JTAG_BMC_TCK")
	)
	(segment
		(start 56.515 -124.9172)
		(end 53.7845 -124.9172)
		(width 0.127)
		(layer "In2.Cu")
		(net "JTAG_BMC_TCK")
	)
	(segment
		(start 334.860392 -184.111392)
		(end 334.860392 -181.601618)
		(width 0.12065)
		(layer "F.Cu")
		(net "IOEXP4_GPIO14")
	)
	(segment
		(start 335.153 -184.404)
		(end 334.860392 -184.111392)
		(width 0.12065)
		(layer "F.Cu")
		(net "IOEXP4_GPIO14")
	)
	(segment
		(start 335.153 -185.801)
		(end 335.64576 -185.30824)
		(width 0.12065)
		(layer "F.Cu")
		(net "IOEXP4_GPIO13")
	)
	(segment
		(start 335.64576 -184.65292)
		(end 335.70545 -184.59323)
		(width 0.12065)
		(layer "F.Cu")
		(net "IOEXP4_GPIO13")
	)
	(segment
		(start 335.70545 -184.59323)
		(end 335.70545 -183.25465)
		(width 0.12065)
		(layer "F.Cu")
		(net "IOEXP4_GPIO13")
	)
	(segment
		(start 335.64576 -185.30824)
		(end 335.64576 -184.65292)
		(width 0.12065)
		(layer "F.Cu")
		(net "IOEXP4_GPIO13")
	)
	(segment
		(start 335.510632 -183.059832)
		(end 335.510632 -181.601618)
		(width 0.12065)
		(layer "F.Cu")
		(net "IOEXP4_GPIO13")
	)
	(segment
		(start 335.70545 -183.25465)
		(end 335.510632 -183.059832)
		(width 0.12065)
		(layer "F.Cu")
		(net "IOEXP4_GPIO13")
	)
	(segment
		(start 336.00771 -184.803034)
		(end 336.160872 -184.649872)
		(width 0.12065)
		(layer "F.Cu")
		(net "IOEXP4_GPIO12")
	)
	(segment
		(start 336.00771 -186.34329)
		(end 336.00771 -184.803034)
		(width 0.12065)
		(layer "F.Cu")
		(net "IOEXP4_GPIO12")
	)
	(segment
		(start 335.153 -187.198)
		(end 336.00771 -186.34329)
		(width 0.12065)
		(layer "F.Cu")
		(net "IOEXP4_GPIO12")
	)
	(segment
		(start 336.160872 -184.649872)
		(end 336.160872 -181.601618)
		(width 0.12065)
		(layer "F.Cu")
		(net "IOEXP4_GPIO12")
	)
	(segment
		(start 332.909672 -175.302672)
		(end 331.978 -174.371)
		(width 0.12065)
		(layer "F.Cu")
		(net "IOEXP4_AD2")
	)
	(segment
		(start 331.756512 -172.876718)
		(end 331.756512 -174.149512)
		(width 0.12065)
		(layer "F.Cu")
		(net "IOEXP4_AD2")
	)
	(segment
		(start 332.909672 -175.962818)
		(end 332.909672 -175.302672)
		(width 0.12065)
		(layer "F.Cu")
		(net "IOEXP4_AD2")
	)
	(segment
		(start 331.756512 -174.149512)
		(end 331.978 -174.371)
		(width 0.12065)
		(layer "F.Cu")
		(net "IOEXP4_AD2")
	)
	(via
		(at 331.978 -174.371)
		(size 0.508)
		(drill 0.254)
		(layers "F.Cu" "B.Cu")
		(net "IOEXP4_AD2")
	)
	(via
		(at 331.142086 -174.994824)
		(size 0.7112)
		(drill 0.3556)
		(layers "F.Cu" "B.Cu")
		(net "IOEXP4_AD2")
	)
	(segment
		(start 331.216 -173.41723)
		(end 331.216 -174.30623)
		(width 0.12065)
		(layer "B.Cu")
		(net "IOEXP4_AD2")
	)
	(segment
		(start 331.756512 -172.876718)
		(end 331.216 -173.41723)
		(width 0.12065)
		(layer "B.Cu")
		(net "IOEXP4_AD2")
	)
	(segment
		(start 331.07376 -174.44847)
		(end 331.07376 -174.926498)
		(width 0.12065)
		(layer "B.Cu")
		(net "IOEXP4_AD2")
	)
	(segment
		(start 331.978 -174.371)
		(end 331.354176 -174.994824)
		(width 0.12065)
		(layer "B.Cu")
		(net "IOEXP4_AD2")
	)
	(segment
		(start 331.07376 -174.926498)
		(end 331.142086 -174.994824)
		(width 0.12065)
		(layer "B.Cu")
		(net "IOEXP4_AD2")
	)
	(segment
		(start 331.216 -174.30623)
		(end 331.07376 -174.44847)
		(width 0.12065)
		(layer "B.Cu")
		(net "IOEXP4_AD2")
	)
	(segment
		(start 331.354176 -174.994824)
		(end 331.142086 -174.994824)
		(width 0.12065)
		(layer "B.Cu")
		(net "IOEXP4_AD2")
	)
	(segment
		(start 332.259432 -175.312578)
		(end 331.063854 -174.117)
		(width 0.12065)
		(layer "F.Cu")
		(net "IOEXP4_AD1")
	)
	(segment
		(start 331.063854 -174.117)
		(end 330.740512 -174.117)
		(width 0.12065)
		(layer "F.Cu")
		(net "IOEXP4_AD1")
	)
	(segment
		(start 332.259432 -175.962818)
		(end 332.259432 -175.312578)
		(width 0.12065)
		(layer "F.Cu")
		(net "IOEXP4_AD1")
	)
	(segment
		(start 330.740512 -172.876718)
		(end 330.740512 -174.117)
		(width 0.12065)
		(layer "F.Cu")
		(net "IOEXP4_AD1")
	)
	(via
		(at 329.696318 -173.736)
		(size 0.7112)
		(drill 0.3556)
		(layers "F.Cu" "B.Cu")
		(net "IOEXP4_AD1")
	)
	(via
		(at 330.740512 -174.117)
		(size 0.508)
		(drill 0.254)
		(layers "F.Cu" "B.Cu")
		(net "IOEXP4_AD1")
	)
	(segment
		(start 330.077318 -174.117)
		(end 329.696318 -173.736)
		(width 0.12065)
		(layer "B.Cu")
		(net "IOEXP4_AD1")
	)
	(segment
		(start 330.740512 -174.117)
		(end 330.077318 -174.117)
		(width 0.12065)
		(layer "B.Cu")
		(net "IOEXP4_AD1")
	)
	(segment
		(start 330.740512 -172.876718)
		(end 330.5556 -172.876718)
		(width 0.12065)
		(layer "B.Cu")
		(net "IOEXP4_AD1")
	)
	(segment
		(start 330.5556 -172.876718)
		(end 329.696318 -173.736)
		(width 0.12065)
		(layer "B.Cu")
		(net "IOEXP4_AD1")
	)
	(segment
		(start 333.559912 -182.949088)
		(end 332.867 -183.642)
		(width 0.12065)
		(layer "F.Cu")
		(net "IOEXP4_AD0")
	)
	(segment
		(start 332.7908 -184.4421)
		(end 332.7908 -183.7182)
		(width 0.12065)
		(layer "F.Cu")
		(net "IOEXP4_AD0")
	)
	(segment
		(start 332.7908 -183.7182)
		(end 332.867 -183.642)
		(width 0.12065)
		(layer "F.Cu")
		(net "IOEXP4_AD0")
	)
	(segment
		(start 333.559912 -181.601618)
		(end 333.559912 -182.949088)
		(width 0.12065)
		(layer "F.Cu")
		(net "IOEXP4_AD0")
	)
	(via
		(at 332.867 -183.642)
		(size 0.508)
		(drill 0.254)
		(layers "F.Cu" "B.Cu")
		(net "IOEXP4_AD0")
	)
	(via
		(at 331.6351 -184.277)
		(size 0.7112)
		(drill 0.3556)
		(layers "F.Cu" "B.Cu")
		(net "IOEXP4_AD0")
	)
	(segment
		(start 331.6351 -183.8579)
		(end 331.6351 -184.277)
		(width 0.12065)
		(layer "B.Cu")
		(net "IOEXP4_AD0")
	)
	(segment
		(start 331.851 -183.642)
		(end 331.6351 -183.8579)
		(width 0.12065)
		(layer "B.Cu")
		(net "IOEXP4_AD0")
	)
	(segment
		(start 331.8002 -184.4421)
		(end 331.6351 -184.277)
		(width 0.12065)
		(layer "B.Cu")
		(net "IOEXP4_AD0")
	)
	(segment
		(start 332.867 -183.642)
		(end 331.851 -183.642)
		(width 0.12065)
		(layer "B.Cu")
		(net "IOEXP4_AD0")
	)
	(segment
		(start 332.7654 -184.4421)
		(end 331.8002 -184.4421)
		(width 0.12065)
		(layer "B.Cu")
		(net "IOEXP4_AD0")
	)
	(segment
		(start 219.950284 -193.383662)
		(end 219.862146 -193.295524)
		(width 0.12065)
		(layer "F.Cu")
		(net "IOEXP3_AD2")
	)
	(segment
		(start 219.862146 -192.938146)
		(end 219.456 -192.532)
		(width 0.12065)
		(layer "F.Cu")
		(net "IOEXP3_AD2")
	)
	(segment
		(start 218.797124 -191.045592)
		(end 218.797124 -191.820292)
		(width 0.12065)
		(layer "F.Cu")
		(net "IOEXP3_AD2")
	)
	(segment
		(start 219.950284 -194.131692)
		(end 219.950284 -193.383662)
		(width 0.12065)
		(layer "F.Cu")
		(net "IOEXP3_AD2")
	)
	(segment
		(start 218.797124 -191.820292)
		(end 218.797124 -191.873124)
		(width 0.12065)
		(layer "F.Cu")
		(net "IOEXP3_AD2")
	)
	(segment
		(start 219.862146 -193.295524)
		(end 219.862146 -192.938146)
		(width 0.12065)
		(layer "F.Cu")
		(net "IOEXP3_AD2")
	)
	(segment
		(start 218.797124 -191.873124)
		(end 219.456 -192.532)
		(width 0.12065)
		(layer "F.Cu")
		(net "IOEXP3_AD2")
	)
	(via
		(at 219.456 -192.532)
		(size 0.7112)
		(drill 0.3556)
		(layers "F.Cu" "B.Cu")
		(net "IOEXP3_AD2")
	)
	(via
		(at 218.797124 -191.820292)
		(size 0.508)
		(drill 0.254)
		(layers "F.Cu" "B.Cu")
		(net "IOEXP3_AD2")
	)
	(segment
		(start 218.670124 -191.693292)
		(end 218.797124 -191.820292)
		(width 0.12065)
		(layer "B.Cu")
		(net "IOEXP3_AD2")
	)
	(segment
		(start 218.670124 -191.045592)
		(end 218.670124 -191.693292)
		(width 0.12065)
		(layer "B.Cu")
		(net "IOEXP3_AD2")
	)
	(segment
		(start 219.300044 -193.481452)
		(end 218.104466 -192.285874)
		(width 0.12065)
		(layer "F.Cu")
		(net "IOEXP3_AD1")
	)
	(segment
		(start 218.035124 -192.285874)
		(end 217.781124 -192.031874)
		(width 0.12065)
		(layer "F.Cu")
		(net "IOEXP3_AD1")
	)
	(segment
		(start 219.300044 -194.131692)
		(end 219.300044 -193.481452)
		(width 0.12065)
		(layer "F.Cu")
		(net "IOEXP3_AD1")
	)
	(segment
		(start 217.781124 -191.045592)
		(end 217.781124 -191.820292)
		(width 0.12065)
		(layer "F.Cu")
		(net "IOEXP3_AD1")
	)
	(segment
		(start 217.781124 -192.031874)
		(end 217.781124 -191.820292)
		(width 0.12065)
		(layer "F.Cu")
		(net "IOEXP3_AD1")
	)
	(segment
		(start 218.104466 -192.285874)
		(end 218.035124 -192.285874)
		(width 0.12065)
		(layer "F.Cu")
		(net "IOEXP3_AD1")
	)
	(via
		(at 217.781124 -191.820292)
		(size 0.508)
		(drill 0.254)
		(layers "F.Cu" "B.Cu")
		(net "IOEXP3_AD1")
	)
	(via
		(at 216.281 -191.262)
		(size 0.7112)
		(drill 0.3556)
		(layers "F.Cu" "B.Cu")
		(net "IOEXP3_AD1")
	)
	(segment
		(start 216.497408 -191.045592)
		(end 216.281 -191.262)
		(width 0.12065)
		(layer "B.Cu")
		(net "IOEXP3_AD1")
	)
	(segment
		(start 216.839292 -191.820292)
		(end 216.281 -191.262)
		(width 0.12065)
		(layer "B.Cu")
		(net "IOEXP3_AD1")
	)
	(segment
		(start 217.781124 -191.820292)
		(end 216.839292 -191.820292)
		(width 0.12065)
		(layer "B.Cu")
		(net "IOEXP3_AD1")
	)
	(segment
		(start 217.654124 -191.045592)
		(end 216.497408 -191.045592)
		(width 0.12065)
		(layer "B.Cu")
		(net "IOEXP3_AD1")
	)
	(segment
		(start 219.831412 -202.610974)
		(end 219.831412 -202.166474)
		(width 0.12065)
		(layer "F.Cu")
		(net "IOEXP3_AD0")
	)
	(segment
		(start 220.600524 -199.770492)
		(end 220.600524 -201.397362)
		(width 0.12065)
		(layer "F.Cu")
		(net "IOEXP3_AD0")
	)
	(segment
		(start 220.600524 -201.397362)
		(end 220.187012 -201.810874)
		(width 0.12065)
		(layer "F.Cu")
		(net "IOEXP3_AD0")
	)
	(segment
		(start 219.831412 -202.166474)
		(end 220.187012 -201.810874)
		(width 0.12065)
		(layer "F.Cu")
		(net "IOEXP3_AD0")
	)
	(via
		(at 218.821 -202.438)
		(size 0.7112)
		(drill 0.3556)
		(layers "F.Cu" "B.Cu")
		(net "IOEXP3_AD0")
	)
	(via
		(at 220.187012 -201.810874)
		(size 0.508)
		(drill 0.254)
		(layers "F.Cu" "B.Cu")
		(net "IOEXP3_AD0")
	)
	(segment
		(start 220.187012 -201.810874)
		(end 219.75953 -201.810874)
		(width 0.12065)
		(layer "B.Cu")
		(net "IOEXP3_AD0")
	)
	(segment
		(start 219.806012 -202.610974)
		(end 218.993974 -202.610974)
		(width 0.12065)
		(layer "B.Cu")
		(net "IOEXP3_AD0")
	)
	(segment
		(start 219.385896 -202.184508)
		(end 219.074492 -202.184508)
		(width 0.12065)
		(layer "B.Cu")
		(net "IOEXP3_AD0")
	)
	(segment
		(start 218.993974 -202.610974)
		(end 218.821 -202.438)
		(width 0.12065)
		(layer "B.Cu")
		(net "IOEXP3_AD0")
	)
	(segment
		(start 219.074492 -202.184508)
		(end 218.821 -202.438)
		(width 0.12065)
		(layer "B.Cu")
		(net "IOEXP3_AD0")
	)
	(segment
		(start 219.75953 -201.810874)
		(end 219.385896 -202.184508)
		(width 0.12065)
		(layer "B.Cu")
		(net "IOEXP3_AD0")
	)
	(segment
		(start 124.475494 -198.015352)
		(end 124.338588 -198.152258)
		(width 0.12065)
		(layer "F.Cu")
		(net "IOEXP2_AD2")
	)
	(segment
		(start 126.097284 -199.39762)
		(end 125.25375 -198.554086)
		(width 0.12065)
		(layer "F.Cu")
		(net "IOEXP2_AD2")
	)
	(segment
		(start 124.944124 -196.887592)
		(end 124.475494 -197.356222)
		(width 0.12065)
		(layer "F.Cu")
		(net "IOEXP2_AD2")
	)
	(segment
		(start 124.475494 -197.356222)
		(end 124.475494 -198.015352)
		(width 0.12065)
		(layer "F.Cu")
		(net "IOEXP2_AD2")
	)
	(segment
		(start 124.644404 -198.554086)
		(end 124.338588 -198.24827)
		(width 0.12065)
		(layer "F.Cu")
		(net "IOEXP2_AD2")
	)
	(segment
		(start 126.097284 -199.973692)
		(end 126.097284 -199.39762)
		(width 0.12065)
		(layer "F.Cu")
		(net "IOEXP2_AD2")
	)
	(segment
		(start 124.338588 -198.24827)
		(end 124.338588 -198.152258)
		(width 0.12065)
		(layer "F.Cu")
		(net "IOEXP2_AD2")
	)
	(segment
		(start 125.25375 -198.554086)
		(end 124.644404 -198.554086)
		(width 0.12065)
		(layer "F.Cu")
		(net "IOEXP2_AD2")
	)
	(via
		(at 123.373896 -198.118222)
		(size 0.7112)
		(drill 0.3556)
		(layers "F.Cu" "B.Cu")
		(net "IOEXP2_AD2")
	)
	(via
		(at 124.338588 -198.152258)
		(size 0.508)
		(drill 0.254)
		(layers "F.Cu" "B.Cu")
		(net "IOEXP2_AD2")
	)
	(segment
		(start 124.944124 -196.887592)
		(end 124.944124 -197.546722)
		(width 0.12065)
		(layer "B.Cu")
		(net "IOEXP2_AD2")
	)
	(segment
		(start 124.304552 -198.118222)
		(end 123.373896 -198.118222)
		(width 0.12065)
		(layer "B.Cu")
		(net "IOEXP2_AD2")
	)
	(segment
		(start 124.338588 -198.152258)
		(end 124.304552 -198.118222)
		(width 0.12065)
		(layer "B.Cu")
		(net "IOEXP2_AD2")
	)
	(segment
		(start 124.944124 -197.546722)
		(end 124.338588 -198.152258)
		(width 0.12065)
		(layer "B.Cu")
		(net "IOEXP2_AD2")
	)
	(segment
		(start 123.928124 -196.887592)
		(end 123.240546 -196.887592)
		(width 0.12065)
		(layer "F.Cu")
		(net "IOEXP2_AD1")
	)
	(segment
		(start 125.447044 -199.973692)
		(end 125.447044 -199.413876)
		(width 0.12065)
		(layer "F.Cu")
		(net "IOEXP2_AD1")
	)
	(segment
		(start 122.940318 -197.742556)
		(end 122.940318 -198.094092)
		(width 0.12065)
		(layer "F.Cu")
		(net "IOEXP2_AD1")
	)
	(segment
		(start 123.240546 -196.887592)
		(end 122.66295 -197.465188)
		(width 0.12065)
		(layer "F.Cu")
		(net "IOEXP2_AD1")
	)
	(segment
		(start 122.66295 -197.465188)
		(end 122.940318 -197.742556)
		(width 0.12065)
		(layer "F.Cu")
		(net "IOEXP2_AD1")
	)
	(segment
		(start 125.447044 -199.413876)
		(end 125.027436 -198.994268)
		(width 0.12065)
		(layer "F.Cu")
		(net "IOEXP2_AD1")
	)
	(segment
		(start 124.149612 -198.994268)
		(end 123.698762 -198.543418)
		(width 0.12065)
		(layer "F.Cu")
		(net "IOEXP2_AD1")
	)
	(segment
		(start 122.940318 -198.094092)
		(end 123.14682 -198.300594)
		(width 0.12065)
		(layer "F.Cu")
		(net "IOEXP2_AD1")
	)
	(segment
		(start 123.389644 -198.543418)
		(end 123.14682 -198.300594)
		(width 0.12065)
		(layer "F.Cu")
		(net "IOEXP2_AD1")
	)
	(segment
		(start 125.027436 -198.994268)
		(end 124.149612 -198.994268)
		(width 0.12065)
		(layer "F.Cu")
		(net "IOEXP2_AD1")
	)
	(segment
		(start 123.698762 -198.543418)
		(end 123.389644 -198.543418)
		(width 0.12065)
		(layer "F.Cu")
		(net "IOEXP2_AD1")
	)
	(via
		(at 122.66295 -197.465188)
		(size 0.508)
		(drill 0.254)
		(layers "F.Cu" "B.Cu")
		(net "IOEXP2_AD1")
	)
	(via
		(at 123.14682 -198.300594)
		(size 0.7112)
		(drill 0.3556)
		(layers "F.Cu" "B.Cu")
		(net "IOEXP2_AD1")
	)
	(segment
		(start 123.47702 -196.887592)
		(end 122.899424 -197.465188)
		(width 0.12065)
		(layer "B.Cu")
		(net "IOEXP2_AD1")
	)
	(segment
		(start 122.899424 -197.465188)
		(end 122.66295 -197.465188)
		(width 0.12065)
		(layer "B.Cu")
		(net "IOEXP2_AD1")
	)
	(segment
		(start 123.928124 -196.887592)
		(end 123.47702 -196.887592)
		(width 0.12065)
		(layer "B.Cu")
		(net "IOEXP2_AD1")
	)
	(segment
		(start 125.978412 -207.904588)
		(end 126.238 -207.645)
		(width 0.12065)
		(layer "F.Cu")
		(net "IOEXP2_AD0")
	)
	(segment
		(start 126.747524 -206.614776)
		(end 126.74346 -206.61884)
		(width 0.12065)
		(layer "F.Cu")
		(net "IOEXP2_AD0")
	)
	(segment
		(start 126.74346 -207.13954)
		(end 126.238 -207.645)
		(width 0.12065)
		(layer "F.Cu")
		(net "IOEXP2_AD0")
	)
	(segment
		(start 126.74346 -206.61884)
		(end 126.74346 -207.13954)
		(width 0.12065)
		(layer "F.Cu")
		(net "IOEXP2_AD0")
	)
	(segment
		(start 125.978412 -208.452974)
		(end 125.978412 -207.904588)
		(width 0.12065)
		(layer "F.Cu")
		(net "IOEXP2_AD0")
	)
	(segment
		(start 126.747524 -205.612492)
		(end 126.747524 -206.614776)
		(width 0.12065)
		(layer "F.Cu")
		(net "IOEXP2_AD0")
	)
	(via
		(at 125.038612 -208.407)
		(size 0.7112)
		(drill 0.3556)
		(layers "F.Cu" "B.Cu")
		(net "IOEXP2_AD0")
	)
	(via
		(at 126.238 -207.645)
		(size 0.508)
		(drill 0.254)
		(layers "F.Cu" "B.Cu")
		(net "IOEXP2_AD0")
	)
	(segment
		(start 125.953012 -208.452974)
		(end 125.084586 -208.452974)
		(width 0.12065)
		(layer "B.Cu")
		(net "IOEXP2_AD0")
	)
	(segment
		(start 125.36805 -207.87995)
		(end 125.038612 -208.209388)
		(width 0.12065)
		(layer "B.Cu")
		(net "IOEXP2_AD0")
	)
	(segment
		(start 126.238 -207.645)
		(end 126.00305 -207.87995)
		(width 0.12065)
		(layer "B.Cu")
		(net "IOEXP2_AD0")
	)
	(segment
		(start 125.038612 -208.209388)
		(end 125.038612 -208.407)
		(width 0.12065)
		(layer "B.Cu")
		(net "IOEXP2_AD0")
	)
	(segment
		(start 126.00305 -207.87995)
		(end 125.36805 -207.87995)
		(width 0.12065)
		(layer "B.Cu")
		(net "IOEXP2_AD0")
	)
	(segment
		(start 125.084586 -208.452974)
		(end 125.038612 -208.407)
		(width 0.12065)
		(layer "B.Cu")
		(net "IOEXP2_AD0")
	)
	(segment
		(start 71.868284 -186.129168)
		(end 71.157846 -185.41873)
		(width 0.12065)
		(layer "F.Cu")
		(net "IOEXP1_AD2")
	)
	(segment
		(start 71.019416 -185.41873)
		(end 71.016876 -185.41619)
		(width 0.12065)
		(layer "F.Cu")
		(net "IOEXP1_AD2")
	)
	(segment
		(start 70.791832 -185.41619)
		(end 70.004686 -184.629044)
		(width 0.12065)
		(layer "F.Cu")
		(net "IOEXP1_AD2")
	)
	(segment
		(start 70.715124 -183.679592)
		(end 70.715124 -183.918606)
		(width 0.12065)
		(layer "F.Cu")
		(net "IOEXP1_AD2")
	)
	(segment
		(start 71.868284 -186.765692)
		(end 71.868284 -186.129168)
		(width 0.12065)
		(layer "F.Cu")
		(net "IOEXP1_AD2")
	)
	(segment
		(start 71.016876 -185.41619)
		(end 70.791832 -185.41619)
		(width 0.12065)
		(layer "F.Cu")
		(net "IOEXP1_AD2")
	)
	(segment
		(start 71.157846 -185.41873)
		(end 71.019416 -185.41873)
		(width 0.12065)
		(layer "F.Cu")
		(net "IOEXP1_AD2")
	)
	(segment
		(start 70.715124 -183.918606)
		(end 70.004686 -184.629044)
		(width 0.12065)
		(layer "F.Cu")
		(net "IOEXP1_AD2")
	)
	(via
		(at 68.68922 -184.337452)
		(size 0.7112)
		(drill 0.3556)
		(layers "F.Cu" "B.Cu")
		(net "IOEXP1_AD2")
	)
	(via
		(at 70.004686 -184.629044)
		(size 0.508)
		(drill 0.254)
		(layers "F.Cu" "B.Cu")
		(net "IOEXP1_AD2")
	)
	(segment
		(start 69.8627 -184.77103)
		(end 69.122798 -184.77103)
		(width 0.12065)
		(layer "B.Cu")
		(net "IOEXP1_AD2")
	)
	(segment
		(start 70.715124 -183.679592)
		(end 70.715124 -183.918606)
		(width 0.12065)
		(layer "B.Cu")
		(net "IOEXP1_AD2")
	)
	(segment
		(start 70.715124 -183.918606)
		(end 70.004686 -184.629044)
		(width 0.12065)
		(layer "B.Cu")
		(net "IOEXP1_AD2")
	)
	(segment
		(start 70.004686 -184.629044)
		(end 69.8627 -184.77103)
		(width 0.12065)
		(layer "B.Cu")
		(net "IOEXP1_AD2")
	)
	(segment
		(start 69.122798 -184.77103)
		(end 68.68922 -184.337452)
		(width 0.12065)
		(layer "B.Cu")
		(net "IOEXP1_AD2")
	)
	(segment
		(start 67.81292 -184.127394)
		(end 67.81292 -183.858916)
		(width 0.12065)
		(layer "F.Cu")
		(net "IOEXP1_AD1")
	)
	(segment
		(start 68.093336 -183.5785)
		(end 67.81292 -183.858916)
		(width 0.12065)
		(layer "F.Cu")
		(net "IOEXP1_AD1")
	)
	(segment
		(start 71.218044 -186.129422)
		(end 70.866762 -185.77814)
		(width 0.12065)
		(layer "F.Cu")
		(net "IOEXP1_AD1")
	)
	(segment
		(start 71.218044 -186.765692)
		(end 71.218044 -186.129422)
		(width 0.12065)
		(layer "F.Cu")
		(net "IOEXP1_AD1")
	)
	(segment
		(start 69.463666 -185.77814)
		(end 67.81292 -184.127394)
		(width 0.12065)
		(layer "F.Cu")
		(net "IOEXP1_AD1")
	)
	(segment
		(start 69.598032 -183.5785)
		(end 68.093336 -183.5785)
		(width 0.12065)
		(layer "F.Cu")
		(net "IOEXP1_AD1")
	)
	(segment
		(start 70.866762 -185.77814)
		(end 69.463666 -185.77814)
		(width 0.12065)
		(layer "F.Cu")
		(net "IOEXP1_AD1")
	)
	(segment
		(start 69.699124 -183.679592)
		(end 69.598032 -183.5785)
		(width 0.12065)
		(layer "F.Cu")
		(net "IOEXP1_AD1")
	)
	(via
		(at 67.81292 -183.858916)
		(size 0.508)
		(drill 0.254)
		(layers "F.Cu" "B.Cu")
		(net "IOEXP1_AD1")
	)
	(via
		(at 67.820794 -182.579518)
		(size 0.7112)
		(drill 0.3556)
		(layers "F.Cu" "B.Cu")
		(net "IOEXP1_AD1")
	)
	(segment
		(start 69.440298 -183.679592)
		(end 68.340224 -182.579518)
		(width 0.12065)
		(layer "B.Cu")
		(net "IOEXP1_AD1")
	)
	(segment
		(start 68.340224 -182.579518)
		(end 67.820794 -182.579518)
		(width 0.12065)
		(layer "B.Cu")
		(net "IOEXP1_AD1")
	)
	(segment
		(start 69.699124 -183.679592)
		(end 69.440298 -183.679592)
		(width 0.12065)
		(layer "B.Cu")
		(net "IOEXP1_AD1")
	)
	(segment
		(start 67.81292 -182.587392)
		(end 67.820794 -182.579518)
		(width 0.12065)
		(layer "B.Cu")
		(net "IOEXP1_AD1")
	)
	(segment
		(start 67.81292 -183.858916)
		(end 67.81292 -182.587392)
		(width 0.12065)
		(layer "B.Cu")
		(net "IOEXP1_AD1")
	)
	(segment
		(start 72.009 -193.7512)
		(end 72.009 -194.470274)
		(width 0.12065)
		(layer "F.Cu")
		(net "IOEXP1_AD0")
	)
	(segment
		(start 72.518524 -193.241676)
		(end 72.009 -193.7512)
		(width 0.12065)
		(layer "F.Cu")
		(net "IOEXP1_AD0")
	)
	(segment
		(start 71.749412 -195.244974)
		(end 72.009 -194.985386)
		(width 0.12065)
		(layer "F.Cu")
		(net "IOEXP1_AD0")
	)
	(segment
		(start 72.518524 -192.404492)
		(end 72.518524 -193.241676)
		(width 0.12065)
		(layer "F.Cu")
		(net "IOEXP1_AD0")
	)
	(segment
		(start 72.009 -194.985386)
		(end 72.009 -194.470274)
		(width 0.12065)
		(layer "F.Cu")
		(net "IOEXP1_AD0")
	)
	(via
		(at 70.739 -195.199)
		(size 0.7112)
		(drill 0.3556)
		(layers "F.Cu" "B.Cu")
		(net "IOEXP1_AD0")
	)
	(via
		(at 72.009 -194.470274)
		(size 0.508)
		(drill 0.254)
		(layers "F.Cu" "B.Cu")
		(net "IOEXP1_AD0")
	)
	(segment
		(start 71.84517 -194.634104)
		(end 71.049896 -194.634104)
		(width 0.12065)
		(layer "B.Cu")
		(net "IOEXP1_AD0")
	)
	(segment
		(start 71.049896 -194.634104)
		(end 70.739 -194.945)
		(width 0.12065)
		(layer "B.Cu")
		(net "IOEXP1_AD0")
	)
	(segment
		(start 70.784974 -195.244974)
		(end 70.739 -195.199)
		(width 0.12065)
		(layer "B.Cu")
		(net "IOEXP1_AD0")
	)
	(segment
		(start 70.739 -194.945)
		(end 70.739 -195.199)
		(width 0.12065)
		(layer "B.Cu")
		(net "IOEXP1_AD0")
	)
	(segment
		(start 71.724012 -195.244974)
		(end 70.784974 -195.244974)
		(width 0.12065)
		(layer "B.Cu")
		(net "IOEXP1_AD0")
	)
	(segment
		(start 72.009 -194.470274)
		(end 71.84517 -194.634104)
		(width 0.12065)
		(layer "B.Cu")
		(net "IOEXP1_AD0")
	)
	(segment
		(start 333.883 -153.67)
		(end 333.883 -118.14048)
		(width 0.12065)
		(layer "F.Cu")
		(net "IOEXP_INT#_4")
	)
	(segment
		(start 307.090064 -106.553)
		(end 263.26465 -62.727586)
		(width 0.12065)
		(layer "F.Cu")
		(net "IOEXP_INT#_4")
	)
	(segment
		(start 330.454 -157.099)
		(end 333.883 -153.67)
		(width 0.12065)
		(layer "F.Cu")
		(net "IOEXP_INT#_4")
	)
	(segment
		(start 322.29552 -106.553)
		(end 307.090064 -106.553)
		(width 0.12065)
		(layer "F.Cu")
		(net "IOEXP_INT#_4")
	)
	(segment
		(start 331.089 -176.657)
		(end 330.708 -176.657)
		(width 0.12065)
		(layer "F.Cu")
		(net "IOEXP_INT#_4")
	)
	(segment
		(start 263.26465 -30.850586)
		(end 260.980682 -28.566618)
		(width 0.12065)
		(layer "F.Cu")
		(net "IOEXP_INT#_4")
	)
	(segment
		(start 260.980682 -28.566618)
		(end 260.980682 -27.541474)
		(width 0.12065)
		(layer "F.Cu")
		(net "IOEXP_INT#_4")
	)
	(segment
		(start 247.599962 -38.999922)
		(end 248.099834 -38.50005)
		(width 0.12065)
		(layer "F.Cu")
		(net "IOEXP_INT#_4")
	)
	(segment
		(start 331.609192 -176.136808)
		(end 331.089 -176.657)
		(width 0.12065)
		(layer "F.Cu")
		(net "IOEXP_INT#_4")
	)
	(segment
		(start 261.112 -26.7335)
		(end 261.112 -27.410156)
		(width 0.12065)
		(layer "F.Cu")
		(net "IOEXP_INT#_4")
	)
	(segment
		(start 333.883 -118.14048)
		(end 322.29552 -106.553)
		(width 0.12065)
		(layer "F.Cu")
		(net "IOEXP_INT#_4")
	)
	(segment
		(start 261.112 -27.410156)
		(end 260.980682 -27.541474)
		(width 0.12065)
		(layer "F.Cu")
		(net "IOEXP_INT#_4")
	)
	(segment
		(start 263.26465 -62.727586)
		(end 263.26465 -30.850586)
		(width 0.12065)
		(layer "F.Cu")
		(net "IOEXP_INT#_4")
	)
	(segment
		(start 331.609192 -175.962818)
		(end 331.609192 -176.136808)
		(width 0.12065)
		(layer "F.Cu")
		(net "IOEXP_INT#_4")
	)
	(via
		(at 331.579728 -158.224728)
		(size 0.7112)
		(drill 0.3556)
		(layers "F.Cu" "B.Cu")
		(net "IOEXP_INT#_4")
	)
	(via
		(at 260.980682 -27.541474)
		(size 0.508)
		(drill 0.254)
		(layers "F.Cu" "B.Cu")
		(net "IOEXP_INT#_4")
	)
	(via
		(at 330.708 -176.657)
		(size 0.508)
		(drill 0.254)
		(layers "F.Cu" "B.Cu")
		(net "IOEXP_INT#_4")
	)
	(via
		(at 330.454 -157.099)
		(size 0.508)
		(drill 0.254)
		(layers "F.Cu" "B.Cu")
		(net "IOEXP_INT#_4")
	)
	(via
		(at 248.099834 -38.50005)
		(size 0.4572)
		(drill 0.2032)
		(layers "F.Cu" "B.Cu")
		(net "IOEXP_INT#_4")
	)
	(segment
		(start 330.454 -157.099)
		(end 331.579728 -158.224728)
		(width 0.12065)
		(layer "B.Cu")
		(net "IOEXP_INT#_4")
	)
	(segment
		(start 329.127866 -171.794424)
		(end 330.193142 -170.729148)
		(width 0.12065)
		(layer "B.Cu")
		(net "IOEXP_INT#_4")
	)
	(segment
		(start 336.43443 -169.44975)
		(end 336.43443 -163.07943)
		(width 0.12065)
		(layer "B.Cu")
		(net "IOEXP_INT#_4")
	)
	(segment
		(start 329.127866 -175.076866)
		(end 329.127866 -171.794424)
		(width 0.12065)
		(layer "B.Cu")
		(net "IOEXP_INT#_4")
	)
	(segment
		(start 335.155032 -170.729148)
		(end 336.43443 -169.44975)
		(width 0.12065)
		(layer "B.Cu")
		(net "IOEXP_INT#_4")
	)
	(segment
		(start 330.193142 -170.729148)
		(end 335.155032 -170.729148)
		(width 0.12065)
		(layer "B.Cu")
		(net "IOEXP_INT#_4")
	)
	(segment
		(start 336.43443 -163.07943)
		(end 331.579728 -158.224728)
		(width 0.12065)
		(layer "B.Cu")
		(net "IOEXP_INT#_4")
	)
	(segment
		(start 330.708 -176.657)
		(end 329.127866 -175.076866)
		(width 0.12065)
		(layer "B.Cu")
		(net "IOEXP_INT#_4")
	)
	(segment
		(start 254.338074 -31.106364)
		(end 254.70612 -30.738318)
		(width 0.1016)
		(layer "In2.Cu")
		(net "IOEXP_INT#_4")
	)
	(segment
		(start 250.706128 -34.336736)
		(end 250.945904 -34.09696)
		(width 0.1016)
		(layer "In2.Cu")
		(net "IOEXP_INT#_4")
	)
	(segment
		(start 250.945904 -34.09696)
		(end 251.534168 -34.09696)
		(width 0.1016)
		(layer "In2.Cu")
		(net "IOEXP_INT#_4")
	)
	(segment
		(start 253.706122 -31.336742)
		(end 253.9365 -31.106364)
		(width 0.1016)
		(layer "In2.Cu")
		(net "IOEXP_INT#_4")
	)
	(segment
		(start 253.706122 -31.761176)
		(end 253.706122 -31.336742)
		(width 0.1016)
		(layer "In2.Cu")
		(net "IOEXP_INT#_4")
	)
	(segment
		(start 253.360936 -32.106362)
		(end 253.706122 -31.761176)
		(width 0.1016)
		(layer "In2.Cu")
		(net "IOEXP_INT#_4")
	)
	(segment
		(start 254.70612 -30.336744)
		(end 254.936498 -30.106366)
		(width 0.1016)
		(layer "In2.Cu")
		(net "IOEXP_INT#_4")
	)
	(segment
		(start 248.099834 -38.057074)
		(end 248.696734 -37.460174)
		(width 0.1016)
		(layer "In2.Cu")
		(net "IOEXP_INT#_4")
	)
	(segment
		(start 249.945652 -35.097212)
		(end 250.347226 -35.097212)
		(width 0.1016)
		(layer "In2.Cu")
		(net "IOEXP_INT#_4")
	)
	(segment
		(start 251.534168 -34.09696)
		(end 252.706124 -32.925004)
		(width 0.1016)
		(layer "In2.Cu")
		(net "IOEXP_INT#_4")
	)
	(segment
		(start 248.696734 -36.34613)
		(end 248.945908 -36.096956)
		(width 0.1016)
		(layer "In2.Cu")
		(net "IOEXP_INT#_4")
	)
	(segment
		(start 260.980682 -28.00985)
		(end 260.980682 -27.541474)
		(width 0.127)
		(layer "In2.Cu")
		(net "IOEXP_INT#_4")
	)
	(segment
		(start 254.936498 -30.106366)
		(end 258.671568 -30.106366)
		(width 0.1016)
		(layer "In2.Cu")
		(net "IOEXP_INT#_4")
	)
	(segment
		(start 250.347226 -35.097212)
		(end 250.706128 -34.73831)
		(width 0.1016)
		(layer "In2.Cu")
		(net "IOEXP_INT#_4")
	)
	(segment
		(start 259.689092 -29.30144)
		(end 260.980682 -28.00985)
		(width 0.127)
		(layer "In2.Cu")
		(net "IOEXP_INT#_4")
	)
	(segment
		(start 249.696732 -35.346132)
		(end 249.945652 -35.097212)
		(width 0.1016)
		(layer "In2.Cu")
		(net "IOEXP_INT#_4")
	)
	(segment
		(start 252.706124 -32.925004)
		(end 252.706124 -32.33674)
		(width 0.1016)
		(layer "In2.Cu")
		(net "IOEXP_INT#_4")
	)
	(segment
		(start 248.945908 -36.096956)
		(end 249.347482 -36.096956)
		(width 0.1016)
		(layer "In2.Cu")
		(net "IOEXP_INT#_4")
	)
	(segment
		(start 252.706124 -32.33674)
		(end 252.936502 -32.106362)
		(width 0.1016)
		(layer "In2.Cu")
		(net "IOEXP_INT#_4")
	)
	(segment
		(start 249.347482 -36.096956)
		(end 249.696732 -35.747706)
		(width 0.1016)
		(layer "In2.Cu")
		(net "IOEXP_INT#_4")
	)
	(segment
		(start 259.476494 -29.30144)
		(end 259.689092 -29.30144)
		(width 0.1016)
		(layer "In2.Cu")
		(net "IOEXP_INT#_4")
	)
	(segment
		(start 248.696734 -37.460174)
		(end 248.696734 -36.34613)
		(width 0.1016)
		(layer "In2.Cu")
		(net "IOEXP_INT#_4")
	)
	(segment
		(start 249.696732 -35.747706)
		(end 249.696732 -35.346132)
		(width 0.1016)
		(layer "In2.Cu")
		(net "IOEXP_INT#_4")
	)
	(segment
		(start 254.70612 -30.738318)
		(end 254.70612 -30.336744)
		(width 0.1016)
		(layer "In2.Cu")
		(net "IOEXP_INT#_4")
	)
	(segment
		(start 250.706128 -34.73831)
		(end 250.706128 -34.336736)
		(width 0.1016)
		(layer "In2.Cu")
		(net "IOEXP_INT#_4")
	)
	(segment
		(start 253.9365 -31.106364)
		(end 254.338074 -31.106364)
		(width 0.1016)
		(layer "In2.Cu")
		(net "IOEXP_INT#_4")
	)
	(segment
		(start 258.671568 -30.106366)
		(end 259.476494 -29.30144)
		(width 0.1016)
		(layer "In2.Cu")
		(net "IOEXP_INT#_4")
	)
	(segment
		(start 248.099834 -38.50005)
		(end 248.099834 -38.057074)
		(width 0.1016)
		(layer "In2.Cu")
		(net "IOEXP_INT#_4")
	)
	(segment
		(start 252.936502 -32.106362)
		(end 253.360936 -32.106362)
		(width 0.1016)
		(layer "In2.Cu")
		(net "IOEXP_INT#_4")
	)
	(segment
		(start 218.424252 -193.481452)
		(end 217.915236 -193.481452)
		(width 0.12065)
		(layer "F.Cu")
		(net "IOEXP_INT#_3")
	)
	(segment
		(start 262.763 -27.559)
		(end 263.07034 -27.86634)
		(width 0.12065)
		(layer "F.Cu")
		(net "IOEXP_INT#_3")
	)
	(segment
		(start 262.255 -26.7335)
		(end 262.255 -27.051)
		(width 0.12065)
		(layer "F.Cu")
		(net "IOEXP_INT#_3")
	)
	(segment
		(start 227.2538 -184.5818)
		(end 227.09886 -184.73674)
		(width 0.12065)
		(layer "F.Cu")
		(net "IOEXP_INT#_3")
	)
	(segment
		(start 218.649804 -194.131692)
		(end 218.649804 -193.707004)
		(width 0.12065)
		(layer "F.Cu")
		(net "IOEXP_INT#_3")
	)
	(segment
		(start 306.814728 -105.7656)
		(end 322.6943 -105.7656)
		(width 0.12065)
		(layer "F.Cu")
		(net "IOEXP_INT#_3")
	)
	(segment
		(start 227.09886 -184.73674)
		(end 227.09886 -187.11926)
		(width 0.12065)
		(layer "F.Cu")
		(net "IOEXP_INT#_3")
	)
	(segment
		(start 276.7076 -150.2664)
		(end 234.315 -150.2664)
		(width 0.12065)
		(layer "F.Cu")
		(net "IOEXP_INT#_3")
	)
	(segment
		(start 227.09886 -187.11926)
		(end 227.5332 -187.5536)
		(width 0.12065)
		(layer "F.Cu")
		(net "IOEXP_INT#_3")
	)
	(segment
		(start 263.6266 -62.577472)
		(end 306.814728 -105.7656)
		(width 0.12065)
		(layer "F.Cu")
		(net "IOEXP_INT#_3")
	)
	(segment
		(start 263.07034 -27.86634)
		(end 263.07034 -29.31414)
		(width 0.12065)
		(layer "F.Cu")
		(net "IOEXP_INT#_3")
	)
	(segment
		(start 218.649804 -193.707004)
		(end 218.424252 -193.481452)
		(width 0.12065)
		(layer "F.Cu")
		(net "IOEXP_INT#_3")
	)
	(segment
		(start 330.7842 -158.0896)
		(end 284.5308 -158.0896)
		(width 0.12065)
		(layer "F.Cu")
		(net "IOEXP_INT#_3")
	)
	(segment
		(start 234.315 -150.2664)
		(end 227.2538 -157.3276)
		(width 0.12065)
		(layer "F.Cu")
		(net "IOEXP_INT#_3")
	)
	(segment
		(start 334.4418 -117.5131)
		(end 334.4418 -154.432)
		(width 0.12065)
		(layer "F.Cu")
		(net "IOEXP_INT#_3")
	)
	(segment
		(start 227.2538 -157.3276)
		(end 227.2538 -184.5818)
		(width 0.12065)
		(layer "F.Cu")
		(net "IOEXP_INT#_3")
	)
	(segment
		(start 284.5308 -158.0896)
		(end 276.7076 -150.2664)
		(width 0.12065)
		(layer "F.Cu")
		(net "IOEXP_INT#_3")
	)
	(segment
		(start 334.4418 -154.432)
		(end 330.7842 -158.0896)
		(width 0.12065)
		(layer "F.Cu")
		(net "IOEXP_INT#_3")
	)
	(segment
		(start 217.915236 -193.481452)
		(end 216.928446 -192.494662)
		(width 0.12065)
		(layer "F.Cu")
		(net "IOEXP_INT#_3")
	)
	(segment
		(start 216.928446 -192.494662)
		(end 216.928446 -192.423542)
		(width 0.12065)
		(layer "F.Cu")
		(net "IOEXP_INT#_3")
	)
	(segment
		(start 248.59996 -33.999932)
		(end 249.099832 -33.50006)
		(width 0.12065)
		(layer "F.Cu")
		(net "IOEXP_INT#_3")
	)
	(segment
		(start 263.6266 -29.8704)
		(end 263.6266 -62.577472)
		(width 0.12065)
		(layer "F.Cu")
		(net "IOEXP_INT#_3")
	)
	(segment
		(start 322.6943 -105.7656)
		(end 334.4418 -117.5131)
		(width 0.12065)
		(layer "F.Cu")
		(net "IOEXP_INT#_3")
	)
	(segment
		(start 262.255 -27.051)
		(end 262.763 -27.559)
		(width 0.12065)
		(layer "F.Cu")
		(net "IOEXP_INT#_3")
	)
	(segment
		(start 263.07034 -29.31414)
		(end 263.6266 -29.8704)
		(width 0.12065)
		(layer "F.Cu")
		(net "IOEXP_INT#_3")
	)
	(via
		(at 249.099832 -33.50006)
		(size 0.4572)
		(drill 0.2032)
		(layers "F.Cu" "B.Cu")
		(net "IOEXP_INT#_3")
	)
	(via
		(at 216.928446 -192.423542)
		(size 0.508)
		(drill 0.254)
		(layers "F.Cu" "B.Cu")
		(net "IOEXP_INT#_3")
	)
	(via
		(at 262.763 -27.559)
		(size 0.508)
		(drill 0.254)
		(layers "F.Cu" "B.Cu")
		(net "IOEXP_INT#_3")
	)
	(via
		(at 216.102946 -188.798454)
		(size 0.7112)
		(drill 0.3556)
		(layers "F.Cu" "B.Cu")
		(net "IOEXP_INT#_3")
	)
	(via
		(at 227.5332 -187.5536)
		(size 0.508)
		(drill 0.254)
		(layers "F.Cu" "B.Cu")
		(net "IOEXP_INT#_3")
	)
	(segment
		(start 227.2284 -187.2488)
		(end 217.6526 -187.2488)
		(width 0.12065)
		(layer "B.Cu")
		(net "IOEXP_INT#_3")
	)
	(segment
		(start 227.5332 -187.5536)
		(end 227.2284 -187.2488)
		(width 0.12065)
		(layer "B.Cu")
		(net "IOEXP_INT#_3")
	)
	(segment
		(start 215.5444 -191.3382)
		(end 215.5444 -189.357)
		(width 0.12065)
		(layer "B.Cu")
		(net "IOEXP_INT#_3")
	)
	(segment
		(start 216.928446 -192.423542)
		(end 216.629742 -192.423542)
		(width 0.12065)
		(layer "B.Cu")
		(net "IOEXP_INT#_3")
	)
	(segment
		(start 216.629742 -192.423542)
		(end 215.5444 -191.3382)
		(width 0.12065)
		(layer "B.Cu")
		(net "IOEXP_INT#_3")
	)
	(segment
		(start 217.6526 -187.2488)
		(end 216.102946 -188.798454)
		(width 0.12065)
		(layer "B.Cu")
		(net "IOEXP_INT#_3")
	)
	(segment
		(start 215.5444 -189.357)
		(end 216.102946 -188.798454)
		(width 0.12065)
		(layer "B.Cu")
		(net "IOEXP_INT#_3")
	)
	(segment
		(start 249.25528 -33.50006)
		(end 249.099832 -33.50006)
		(width 0.1016)
		(layer "In2.Cu")
		(net "IOEXP_INT#_3")
	)
	(segment
		(start 251.852176 -30.903164)
		(end 251.493528 -31.261812)
		(width 0.1016)
		(layer "In2.Cu")
		(net "IOEXP_INT#_3")
	)
	(segment
		(start 261.695692 -26.715974)
		(end 260.961124 -26.715974)
		(width 0.127)
		(layer "In2.Cu")
		(net "IOEXP_INT#_3")
	)
	(segment
		(start 251.493528 -31.663386)
		(end 251.26315 -31.893764)
		(width 0.1016)
		(layer "In2.Cu")
		(net "IOEXP_INT#_3")
	)
	(segment
		(start 253.365 -28.3718)
		(end 252.8189 -28.9179)
		(width 0.127)
		(layer "In2.Cu")
		(net "IOEXP_INT#_3")
	)
	(segment
		(start 250.861576 -31.893764)
		(end 250.49353 -32.26181)
		(width 0.1016)
		(layer "In2.Cu")
		(net "IOEXP_INT#_3")
	)
	(segment
		(start 250.263152 -32.893762)
		(end 249.861578 -32.893762)
		(width 0.1016)
		(layer "In2.Cu")
		(net "IOEXP_INT#_3")
	)
	(segment
		(start 252.493526 -29.243274)
		(end 252.493526 -30.663388)
		(width 0.1016)
		(layer "In2.Cu")
		(net "IOEXP_INT#_3")
	)
	(segment
		(start 249.861578 -32.893762)
		(end 249.25528 -33.50006)
		(width 0.1016)
		(layer "In2.Cu")
		(net "IOEXP_INT#_3")
	)
	(segment
		(start 252.8189 -28.9179)
		(end 252.493526 -29.243274)
		(width 0.1016)
		(layer "In2.Cu")
		(net "IOEXP_INT#_3")
	)
	(segment
		(start 251.26315 -31.893764)
		(end 250.861576 -31.893764)
		(width 0.1016)
		(layer "In2.Cu")
		(net "IOEXP_INT#_3")
	)
	(segment
		(start 262.538718 -27.559)
		(end 261.695692 -26.715974)
		(width 0.127)
		(layer "In2.Cu")
		(net "IOEXP_INT#_3")
	)
	(segment
		(start 252.493526 -30.663388)
		(end 252.25375 -30.903164)
		(width 0.1016)
		(layer "In2.Cu")
		(net "IOEXP_INT#_3")
	)
	(segment
		(start 250.49353 -32.26181)
		(end 250.49353 -32.663384)
		(width 0.1016)
		(layer "In2.Cu")
		(net "IOEXP_INT#_3")
	)
	(segment
		(start 251.493528 -31.261812)
		(end 251.493528 -31.663386)
		(width 0.1016)
		(layer "In2.Cu")
		(net "IOEXP_INT#_3")
	)
	(segment
		(start 260.961124 -26.715974)
		(end 260.829298 -26.8478)
		(width 0.127)
		(layer "In2.Cu")
		(net "IOEXP_INT#_3")
	)
	(segment
		(start 255.784858 -28.3718)
		(end 253.365 -28.3718)
		(width 0.127)
		(layer "In2.Cu")
		(net "IOEXP_INT#_3")
	)
	(segment
		(start 252.25375 -30.903164)
		(end 251.852176 -30.903164)
		(width 0.1016)
		(layer "In2.Cu")
		(net "IOEXP_INT#_3")
	)
	(segment
		(start 257.308858 -26.8478)
		(end 255.784858 -28.3718)
		(width 0.127)
		(layer "In2.Cu")
		(net "IOEXP_INT#_3")
	)
	(segment
		(start 260.829298 -26.8478)
		(end 257.308858 -26.8478)
		(width 0.127)
		(layer "In2.Cu")
		(net "IOEXP_INT#_3")
	)
	(segment
		(start 250.49353 -32.663384)
		(end 250.263152 -32.893762)
		(width 0.1016)
		(layer "In2.Cu")
		(net "IOEXP_INT#_3")
	)
	(segment
		(start 262.763 -27.559)
		(end 262.538718 -27.559)
		(width 0.127)
		(layer "In2.Cu")
		(net "IOEXP_INT#_3")
	)
	(segment
		(start 246.599964 -35.999928)
		(end 247.099836 -35.500056)
		(width 0.12065)
		(layer "F.Cu")
		(net "IOEXP_INT#_2")
	)
	(segment
		(start 122.488706 -200.656952)
		(end 122.03303 -200.201276)
		(width 0.12065)
		(layer "F.Cu")
		(net "IOEXP_INT#_2")
	)
	(segment
		(start 122.03303 -199.36968)
		(end 121.9454 -199.28205)
		(width 0.12065)
		(layer "F.Cu")
		(net "IOEXP_INT#_2")
	)
	(segment
		(start 123.254516 -200.656952)
		(end 122.488706 -200.656952)
		(width 0.12065)
		(layer "F.Cu")
		(net "IOEXP_INT#_2")
	)
	(segment
		(start 262.0772 -31.369)
		(end 262.0772 -63.8556)
		(width 0.12065)
		(layer "F.Cu")
		(net "IOEXP_INT#_2")
	)
	(segment
		(start 258.050792 -26.7335)
		(end 258.050792 -27.559)
		(width 0.12065)
		(layer "F.Cu")
		(net "IOEXP_INT#_2")
	)
	(segment
		(start 262.0772 -63.8556)
		(end 303.9364 -105.7148)
		(width 0.12065)
		(layer "F.Cu")
		(net "IOEXP_INT#_2")
	)
	(segment
		(start 258.050792 -27.559)
		(end 258.2672 -27.559)
		(width 0.12065)
		(layer "F.Cu")
		(net "IOEXP_INT#_2")
	)
	(segment
		(start 123.937776 -199.973692)
		(end 123.254516 -200.656952)
		(width 0.12065)
		(layer "F.Cu")
		(net "IOEXP_INT#_2")
	)
	(segment
		(start 124.796804 -199.973692)
		(end 123.937776 -199.973692)
		(width 0.12065)
		(layer "F.Cu")
		(net "IOEXP_INT#_2")
	)
	(segment
		(start 258.2672 -27.559)
		(end 262.0772 -31.369)
		(width 0.12065)
		(layer "F.Cu")
		(net "IOEXP_INT#_2")
	)
	(segment
		(start 122.03303 -200.201276)
		(end 122.03303 -199.36968)
		(width 0.12065)
		(layer "F.Cu")
		(net "IOEXP_INT#_2")
	)
	(via
		(at 303.9364 -105.7148)
		(size 0.508)
		(drill 0.254)
		(layers "F.Cu" "B.Cu")
		(net "IOEXP_INT#_2")
	)
	(via
		(at 156.337 -106.7054)
		(size 0.508)
		(drill 0.254)
		(layers "F.Cu" "B.Cu")
		(net "IOEXP_INT#_2")
	)
	(via
		(at 258.050792 -27.559)
		(size 0.508)
		(drill 0.254)
		(layers "F.Cu" "B.Cu")
		(net "IOEXP_INT#_2")
	)
	(via
		(at 85.0392 -180.848)
		(size 0.508)
		(drill 0.254)
		(layers "F.Cu" "B.Cu")
		(net "IOEXP_INT#_2")
	)
	(via
		(at 121.9454 -199.28205)
		(size 0.508)
		(drill 0.254)
		(layers "F.Cu" "B.Cu")
		(net "IOEXP_INT#_2")
	)
	(via
		(at 247.099836 -35.500056)
		(size 0.4572)
		(drill 0.2032)
		(layers "F.Cu" "B.Cu")
		(net "IOEXP_INT#_2")
	)
	(via
		(at 299.649642 -106.369358)
		(size 0.7112)
		(drill 0.3556)
		(layers "F.Cu" "B.Cu")
		(net "IOEXP_INT#_2")
	)
	(segment
		(start 121.624598 -199.602852)
		(end 121.9454 -199.28205)
		(width 0.12065)
		(layer "B.Cu")
		(net "IOEXP_INT#_2")
	)
	(segment
		(start 303.9364 -105.7148)
		(end 300.3042 -105.7148)
		(width 0.12065)
		(layer "B.Cu")
		(net "IOEXP_INT#_2")
	)
	(segment
		(start 116.040916 -199.602852)
		(end 121.624598 -199.602852)
		(width 0.12065)
		(layer "B.Cu")
		(net "IOEXP_INT#_2")
	)
	(segment
		(start 300.3042 -105.7148)
		(end 299.649642 -106.369358)
		(width 0.12065)
		(layer "B.Cu")
		(net "IOEXP_INT#_2")
	)
	(segment
		(start 156.3878 -106.7562)
		(end 156.337 -106.7054)
		(width 0.12065)
		(layer "B.Cu")
		(net "IOEXP_INT#_2")
	)
	(segment
		(start 85.0392 -180.848)
		(end 85.418422 -181.227222)
		(width 0.12065)
		(layer "B.Cu")
		(net "IOEXP_INT#_2")
	)
	(segment
		(start 299.649642 -106.369358)
		(end 299.2628 -106.7562)
		(width 0.12065)
		(layer "B.Cu")
		(net "IOEXP_INT#_2")
	)
	(segment
		(start 299.2628 -106.7562)
		(end 156.3878 -106.7562)
		(width 0.12065)
		(layer "B.Cu")
		(net "IOEXP_INT#_2")
	)
	(segment
		(start 85.418422 -181.227222)
		(end 97.665286 -181.227222)
		(width 0.12065)
		(layer "B.Cu")
		(net "IOEXP_INT#_2")
	)
	(segment
		(start 97.665286 -181.227222)
		(end 116.040916 -199.602852)
		(width 0.12065)
		(layer "B.Cu")
		(net "IOEXP_INT#_2")
	)
	(segment
		(start 85.0392 -180.848)
		(end 85.0392 -174.117)
		(width 0.127)
		(layer "In2.Cu")
		(net "IOEXP_INT#_2")
	)
	(segment
		(start 249.493532 -34.66338)
		(end 249.493532 -33.995868)
		(width 0.1016)
		(layer "In2.Cu")
		(net "IOEXP_INT#_2")
	)
	(segment
		(start 156.337 -107.188)
		(end 156.337 -106.7054)
		(width 0.127)
		(layer "In2.Cu")
		(net "IOEXP_INT#_2")
	)
	(segment
		(start 251.83846 -31.893764)
		(end 252.263148 -31.893764)
		(width 0.1016)
		(layer "In2.Cu")
		(net "IOEXP_INT#_2")
	)
	(segment
		(start 248.891044 -34.903156)
		(end 248.900442 -34.893758)
		(width 0.1016)
		(layer "In2.Cu")
		(net "IOEXP_INT#_2")
	)
	(segment
		(start 248.900442 -34.893758)
		(end 249.263154 -34.893758)
		(width 0.1016)
		(layer "In2.Cu")
		(net "IOEXP_INT#_2")
	)
	(segment
		(start 250.263152 -33.89376)
		(end 250.49353 -33.663382)
		(width 0.1016)
		(layer "In2.Cu")
		(net "IOEXP_INT#_2")
	)
	(segment
		(start 247.255284 -35.500056)
		(end 247.852184 -34.903156)
		(width 0.1016)
		(layer "In2.Cu")
		(net "IOEXP_INT#_2")
	)
	(segment
		(start 247.852184 -34.903156)
		(end 248.891044 -34.903156)
		(width 0.1016)
		(layer "In2.Cu")
		(net "IOEXP_INT#_2")
	)
	(segment
		(start 252.493526 -31.663386)
		(end 252.493526 -31.238444)
		(width 0.1016)
		(layer "In2.Cu")
		(net "IOEXP_INT#_2")
	)
	(segment
		(start 253.890272 -28.865068)
		(end 254.556768 -28.865068)
		(width 0.1016)
		(layer "In2.Cu")
		(net "IOEXP_INT#_2")
	)
	(segment
		(start 249.263154 -34.893758)
		(end 249.493532 -34.66338)
		(width 0.1016)
		(layer "In2.Cu")
		(net "IOEXP_INT#_2")
	)
	(segment
		(start 249.493532 -33.995868)
		(end 249.59564 -33.89376)
		(width 0.1016)
		(layer "In2.Cu")
		(net "IOEXP_INT#_2")
	)
	(segment
		(start 250.838462 -32.893762)
		(end 251.26315 -32.893762)
		(width 0.1016)
		(layer "In2.Cu")
		(net "IOEXP_INT#_2")
	)
	(segment
		(start 147.9296 -111.2266)
		(end 152.2984 -111.2266)
		(width 0.127)
		(layer "In2.Cu")
		(net "IOEXP_INT#_2")
	)
	(segment
		(start 258.064 -27.686)
		(end 258.050792 -27.672792)
		(width 0.127)
		(layer "In2.Cu")
		(net "IOEXP_INT#_2")
	)
	(segment
		(start 252.263148 -31.893764)
		(end 252.493526 -31.663386)
		(width 0.1016)
		(layer "In2.Cu")
		(net "IOEXP_INT#_2")
	)
	(segment
		(start 258.064 -28.194)
		(end 258.064 -27.686)
		(width 0.127)
		(layer "In2.Cu")
		(net "IOEXP_INT#_2")
	)
	(segment
		(start 252.838458 -30.893766)
		(end 253.263146 -30.893766)
		(width 0.1016)
		(layer "In2.Cu")
		(net "IOEXP_INT#_2")
	)
	(segment
		(start 250.49353 -33.23844)
		(end 250.838462 -32.893762)
		(width 0.1016)
		(layer "In2.Cu")
		(net "IOEXP_INT#_2")
	)
	(segment
		(start 253.263146 -30.893766)
		(end 253.493524 -30.663388)
		(width 0.1016)
		(layer "In2.Cu")
		(net "IOEXP_INT#_2")
	)
	(segment
		(start 251.493528 -32.238442)
		(end 251.83846 -31.893764)
		(width 0.1016)
		(layer "In2.Cu")
		(net "IOEXP_INT#_2")
	)
	(segment
		(start 152.2984 -111.2266)
		(end 156.337 -107.188)
		(width 0.127)
		(layer "In2.Cu")
		(net "IOEXP_INT#_2")
	)
	(segment
		(start 247.099836 -35.500056)
		(end 247.255284 -35.500056)
		(width 0.1016)
		(layer "In2.Cu")
		(net "IOEXP_INT#_2")
	)
	(segment
		(start 251.493528 -32.663384)
		(end 251.493528 -32.238442)
		(width 0.1016)
		(layer "In2.Cu")
		(net "IOEXP_INT#_2")
	)
	(segment
		(start 252.493526 -31.238444)
		(end 252.838458 -30.893766)
		(width 0.1016)
		(layer "In2.Cu")
		(net "IOEXP_INT#_2")
	)
	(segment
		(start 250.49353 -33.663382)
		(end 250.49353 -33.23844)
		(width 0.1016)
		(layer "In2.Cu")
		(net "IOEXP_INT#_2")
	)
	(segment
		(start 257.392932 -28.865068)
		(end 258.064 -28.194)
		(width 0.127)
		(layer "In2.Cu")
		(net "IOEXP_INT#_2")
	)
	(segment
		(start 258.050792 -27.672792)
		(end 258.050792 -27.559)
		(width 0.127)
		(layer "In2.Cu")
		(net "IOEXP_INT#_2")
	)
	(segment
		(start 253.493524 -30.663388)
		(end 253.493524 -29.261816)
		(width 0.1016)
		(layer "In2.Cu")
		(net "IOEXP_INT#_2")
	)
	(segment
		(start 254.556768 -28.865068)
		(end 257.392932 -28.865068)
		(width 0.127)
		(layer "In2.Cu")
		(net "IOEXP_INT#_2")
	)
	(segment
		(start 253.493524 -29.261816)
		(end 253.890272 -28.865068)
		(width 0.1016)
		(layer "In2.Cu")
		(net "IOEXP_INT#_2")
	)
	(segment
		(start 249.59564 -33.89376)
		(end 250.263152 -33.89376)
		(width 0.1016)
		(layer "In2.Cu")
		(net "IOEXP_INT#_2")
	)
	(segment
		(start 85.0392 -174.117)
		(end 147.9296 -111.2266)
		(width 0.127)
		(layer "In2.Cu")
		(net "IOEXP_INT#_2")
	)
	(segment
		(start 251.26315 -32.893762)
		(end 251.493528 -32.663384)
		(width 0.1016)
		(layer "In2.Cu")
		(net "IOEXP_INT#_2")
	)
	(segment
		(start 246.599964 -38.999922)
		(end 247.099836 -38.50005)
		(width 0.12065)
		(layer "F.Cu")
		(net "IOEXP_INT#_1")
	)
	(segment
		(start 68.386706 -185.626248)
		(end 66.7004 -187.312554)
		(width 0.12065)
		(layer "F.Cu")
		(net "IOEXP_INT#_1")
	)
	(segment
		(start 66.7004 -187.312554)
		(end 66.707512 -187.319666)
		(width 0.12065)
		(layer "F.Cu")
		(net "IOEXP_INT#_1")
	)
	(segment
		(start 261.198868 -29.978604)
		(end 262.54075 -31.320486)
		(width 0.12065)
		(layer "F.Cu")
		(net "IOEXP_INT#_1")
	)
	(segment
		(start 261.169404 -29.978604)
		(end 261.198868 -29.978604)
		(width 0.12065)
		(layer "F.Cu")
		(net "IOEXP_INT#_1")
	)
	(segment
		(start 70.567804 -186.765692)
		(end 69.939154 -186.765692)
		(width 0.12065)
		(layer "F.Cu")
		(net "IOEXP_INT#_1")
	)
	(segment
		(start 259.0546 -26.7589)
		(end 259.0546 -27.559)
		(width 0.12065)
		(layer "F.Cu")
		(net "IOEXP_INT#_1")
	)
	(segment
		(start 259.0546 -27.559)
		(end 259.0546 -27.8638)
		(width 0.12065)
		(layer "F.Cu")
		(net "IOEXP_INT#_1")
	)
	(segment
		(start 68.79971 -185.626248)
		(end 68.386706 -185.626248)
		(width 0.12065)
		(layer "F.Cu")
		(net "IOEXP_INT#_1")
	)
	(segment
		(start 66.707512 -187.319666)
		(end 66.707512 -189.09538)
		(width 0.12065)
		(layer "F.Cu")
		(net "IOEXP_INT#_1")
	)
	(segment
		(start 262.54075 -63.63335)
		(end 305.054 -106.1466)
		(width 0.12065)
		(layer "F.Cu")
		(net "IOEXP_INT#_1")
	)
	(segment
		(start 259.0546 -27.8638)
		(end 261.169404 -29.978604)
		(width 0.12065)
		(layer "F.Cu")
		(net "IOEXP_INT#_1")
	)
	(segment
		(start 259.08 -26.7335)
		(end 259.0546 -26.7589)
		(width 0.12065)
		(layer "F.Cu")
		(net "IOEXP_INT#_1")
	)
	(segment
		(start 262.54075 -31.320486)
		(end 262.54075 -63.63335)
		(width 0.12065)
		(layer "F.Cu")
		(net "IOEXP_INT#_1")
	)
	(segment
		(start 69.939154 -186.765692)
		(end 68.79971 -185.626248)
		(width 0.12065)
		(layer "F.Cu")
		(net "IOEXP_INT#_1")
	)
	(via
		(at 66.707512 -189.09538)
		(size 0.508)
		(drill 0.254)
		(layers "F.Cu" "B.Cu")
		(net "IOEXP_INT#_1")
	)
	(via
		(at 247.099836 -38.50005)
		(size 0.4572)
		(drill 0.2032)
		(layers "F.Cu" "B.Cu")
		(net "IOEXP_INT#_1")
	)
	(via
		(at 305.054 -106.1466)
		(size 0.508)
		(drill 0.254)
		(layers "F.Cu" "B.Cu")
		(net "IOEXP_INT#_1")
	)
	(via
		(at 304.326036 -106.874564)
		(size 0.7112)
		(drill 0.3556)
		(layers "F.Cu" "B.Cu")
		(net "IOEXP_INT#_1")
	)
	(via
		(at 259.0546 -27.559)
		(size 0.508)
		(drill 0.254)
		(layers "F.Cu" "B.Cu")
		(net "IOEXP_INT#_1")
	)
	(via
		(at 153.5176 -106.9848)
		(size 0.508)
		(drill 0.254)
		(layers "F.Cu" "B.Cu")
		(net "IOEXP_INT#_1")
	)
	(segment
		(start 153.797 -107.2642)
		(end 153.5176 -106.9848)
		(width 0.12065)
		(layer "B.Cu")
		(net "IOEXP_INT#_1")
	)
	(segment
		(start 303.9364 -107.2642)
		(end 153.797 -107.2642)
		(width 0.12065)
		(layer "B.Cu")
		(net "IOEXP_INT#_1")
	)
	(segment
		(start 304.326036 -106.874564)
		(end 303.9364 -107.2642)
		(width 0.12065)
		(layer "B.Cu")
		(net "IOEXP_INT#_1")
	)
	(segment
		(start 304.326036 -106.874564)
		(end 305.054 -106.1466)
		(width 0.12065)
		(layer "B.Cu")
		(net "IOEXP_INT#_1")
	)
	(segment
		(start 251.347478 -33.096962)
		(end 251.696728 -32.747712)
		(width 0.1016)
		(layer "In2.Cu")
		(net "IOEXP_INT#_1")
	)
	(segment
		(start 251.788676 -32.231076)
		(end 251.922788 -32.096964)
		(width 0.1016)
		(layer "In2.Cu")
		(net "IOEXP_INT#_1")
	)
	(segment
		(start 84.3788 -186.0804)
		(end 84.3788 -173.736)
		(width 0.127)
		(layer "In2.Cu")
		(net "IOEXP_INT#_1")
	)
	(segment
		(start 151.6888 -110.5408)
		(end 153.5176 -108.712)
		(width 0.127)
		(layer "In2.Cu")
		(net "IOEXP_INT#_1")
	)
	(segment
		(start 251.088398 -33.096962)
		(end 251.347478 -33.096962)
		(width 0.1016)
		(layer "In2.Cu")
		(net "IOEXP_INT#_1")
	)
	(segment
		(start 251.696728 -32.747712)
		(end 251.696728 -32.32277)
		(width 0.1016)
		(layer "In2.Cu")
		(net "IOEXP_INT#_1")
	)
	(segment
		(start 251.079 -33.10636)
		(end 251.088398 -33.096962)
		(width 0.1016)
		(layer "In2.Cu")
		(net "IOEXP_INT#_1")
	)
	(segment
		(start 66.892932 -189.2808)
		(end 74.597768 -189.2808)
		(width 0.127)
		(layer "In2.Cu")
		(net "IOEXP_INT#_1")
	)
	(segment
		(start 259.0546 -27.94)
		(end 259.0546 -27.559)
		(width 0.127)
		(layer "In2.Cu")
		(net "IOEXP_INT#_1")
	)
	(segment
		(start 253.347474 -31.096966)
		(end 253.706122 -30.738318)
		(width 0.1016)
		(layer "In2.Cu")
		(net "IOEXP_INT#_1")
	)
	(segment
		(start 249.696732 -34.747708)
		(end 249.696732 -34.148268)
		(width 0.1016)
		(layer "In2.Cu")
		(net "IOEXP_INT#_1")
	)
	(segment
		(start 252.696726 -31.747714)
		(end 252.696726 -31.322772)
		(width 0.1016)
		(layer "In2.Cu")
		(net "IOEXP_INT#_1")
	)
	(segment
		(start 250.936506 -33.10636)
		(end 251.079 -33.10636)
		(width 0.1016)
		(layer "In2.Cu")
		(net "IOEXP_INT#_1")
	)
	(segment
		(start 253.706122 -29.336746)
		(end 253.9492 -29.093668)
		(width 0.1016)
		(layer "In2.Cu")
		(net "IOEXP_INT#_1")
	)
	(segment
		(start 253.706122 -30.738318)
		(end 253.706122 -29.336746)
		(width 0.1016)
		(layer "In2.Cu")
		(net "IOEXP_INT#_1")
	)
	(segment
		(start 252.696726 -31.322772)
		(end 252.703076 -31.316676)
		(width 0.1016)
		(layer "In2.Cu")
		(net "IOEXP_INT#_1")
	)
	(segment
		(start 249.347482 -35.096958)
		(end 249.696732 -34.747708)
		(width 0.1016)
		(layer "In2.Cu")
		(net "IOEXP_INT#_1")
	)
	(segment
		(start 252.922786 -31.096966)
		(end 253.347474 -31.096966)
		(width 0.1016)
		(layer "In2.Cu")
		(net "IOEXP_INT#_1")
	)
	(segment
		(start 252.347476 -32.096964)
		(end 252.696726 -31.747714)
		(width 0.1016)
		(layer "In2.Cu")
		(net "IOEXP_INT#_1")
	)
	(segment
		(start 248.975372 -35.106356)
		(end 248.98477 -35.096958)
		(width 0.1016)
		(layer "In2.Cu")
		(net "IOEXP_INT#_1")
	)
	(segment
		(start 247.706134 -35.336734)
		(end 247.936512 -35.106356)
		(width 0.1016)
		(layer "In2.Cu")
		(net "IOEXP_INT#_1")
	)
	(segment
		(start 250.706128 -33.336738)
		(end 250.936506 -33.10636)
		(width 0.1016)
		(layer "In2.Cu")
		(net "IOEXP_INT#_1")
	)
	(segment
		(start 66.707512 -189.09538)
		(end 66.892932 -189.2808)
		(width 0.127)
		(layer "In2.Cu")
		(net "IOEXP_INT#_1")
	)
	(segment
		(start 247.706134 -37.993066)
		(end 247.706134 -35.336734)
		(width 0.1016)
		(layer "In2.Cu")
		(net "IOEXP_INT#_1")
	)
	(segment
		(start 74.597768 -189.2808)
		(end 74.690732 -189.187836)
		(width 0.127)
		(layer "In2.Cu")
		(net "IOEXP_INT#_1")
	)
	(segment
		(start 247.099836 -38.50005)
		(end 247.19915 -38.50005)
		(width 0.1016)
		(layer "In2.Cu")
		(net "IOEXP_INT#_1")
	)
	(segment
		(start 249.696732 -34.148268)
		(end 249.74804 -34.09696)
		(width 0.1016)
		(layer "In2.Cu")
		(net "IOEXP_INT#_1")
	)
	(segment
		(start 250.69673 -33.74771)
		(end 250.69673 -33.38068)
		(width 0.1016)
		(layer "In2.Cu")
		(net "IOEXP_INT#_1")
	)
	(segment
		(start 251.696728 -32.32277)
		(end 251.788676 -32.231076)
		(width 0.1016)
		(layer "In2.Cu")
		(net "IOEXP_INT#_1")
	)
	(segment
		(start 147.574 -110.5408)
		(end 151.6888 -110.5408)
		(width 0.127)
		(layer "In2.Cu")
		(net "IOEXP_INT#_1")
	)
	(segment
		(start 81.271364 -189.187836)
		(end 84.3788 -186.0804)
		(width 0.127)
		(layer "In2.Cu")
		(net "IOEXP_INT#_1")
	)
	(segment
		(start 251.922788 -32.096964)
		(end 252.347476 -32.096964)
		(width 0.1016)
		(layer "In2.Cu")
		(net "IOEXP_INT#_1")
	)
	(segment
		(start 257.900932 -29.093668)
		(end 259.0546 -27.94)
		(width 0.127)
		(layer "In2.Cu")
		(net "IOEXP_INT#_1")
	)
	(segment
		(start 252.703076 -31.316676)
		(end 252.922786 -31.096966)
		(width 0.1016)
		(layer "In2.Cu")
		(net "IOEXP_INT#_1")
	)
	(segment
		(start 250.706128 -33.371282)
		(end 250.706128 -33.336738)
		(width 0.1016)
		(layer "In2.Cu")
		(net "IOEXP_INT#_1")
	)
	(segment
		(start 250.69673 -33.38068)
		(end 250.706128 -33.371282)
		(width 0.1016)
		(layer "In2.Cu")
		(net "IOEXP_INT#_1")
	)
	(segment
		(start 250.34748 -34.09696)
		(end 250.69673 -33.74771)
		(width 0.1016)
		(layer "In2.Cu")
		(net "IOEXP_INT#_1")
	)
	(segment
		(start 247.19915 -38.50005)
		(end 247.706134 -37.993066)
		(width 0.1016)
		(layer "In2.Cu")
		(net "IOEXP_INT#_1")
	)
	(segment
		(start 247.936512 -35.106356)
		(end 248.975372 -35.106356)
		(width 0.1016)
		(layer "In2.Cu")
		(net "IOEXP_INT#_1")
	)
	(segment
		(start 254.423926 -29.093668)
		(end 257.900932 -29.093668)
		(width 0.127)
		(layer "In2.Cu")
		(net "IOEXP_INT#_1")
	)
	(segment
		(start 253.9492 -29.093668)
		(end 254.423926 -29.093668)
		(width 0.1016)
		(layer "In2.Cu")
		(net "IOEXP_INT#_1")
	)
	(segment
		(start 74.690732 -189.187836)
		(end 81.271364 -189.187836)
		(width 0.127)
		(layer "In2.Cu")
		(net "IOEXP_INT#_1")
	)
	(segment
		(start 248.98477 -35.096958)
		(end 249.347482 -35.096958)
		(width 0.1016)
		(layer "In2.Cu")
		(net "IOEXP_INT#_1")
	)
	(segment
		(start 153.5176 -108.712)
		(end 153.5176 -106.9848)
		(width 0.127)
		(layer "In2.Cu")
		(net "IOEXP_INT#_1")
	)
	(segment
		(start 84.3788 -173.736)
		(end 147.574 -110.5408)
		(width 0.127)
		(layer "In2.Cu")
		(net "IOEXP_INT#_1")
	)
	(segment
		(start 249.74804 -34.09696)
		(end 250.34748 -34.09696)
		(width 0.1016)
		(layer "In2.Cu")
		(net "IOEXP_INT#_1")
	)
	(segment
		(start 62.16904 -88.60536)
		(end 62.0776 -88.6968)
		(width 0.12065)
		(layer "F.Cu")
		(net "INVERTER_G2")
	)
	(segment
		(start 63.4492 -88.60536)
		(end 62.16904 -88.60536)
		(width 0.12065)
		(layer "F.Cu")
		(net "INVERTER_G2")
	)
	(segment
		(start 62.0776 -89.13495)
		(end 62.19825 -89.2556)
		(width 0.12065)
		(layer "F.Cu")
		(net "INVERTER_G2")
	)
	(segment
		(start 64.0715 -86.3854)
		(end 64.0715 -87.249)
		(width 0.12065)
		(layer "F.Cu")
		(net "INVERTER_G2")
	)
	(segment
		(start 62.0776 -88.6968)
		(end 62.0776 -89.13495)
		(width 0.12065)
		(layer "F.Cu")
		(net "INVERTER_G2")
	)
	(segment
		(start 63.4492 -88.0364)
		(end 63.4492 -88.60536)
		(width 0.12065)
		(layer "F.Cu")
		(net "INVERTER_G2")
	)
	(segment
		(start 64.0715 -87.249)
		(end 64.0715 -87.4141)
		(width 0.12065)
		(layer "F.Cu")
		(net "INVERTER_G2")
	)
	(segment
		(start 62.19825 -89.2556)
		(end 63.4492 -89.2556)
		(width 0.12065)
		(layer "F.Cu")
		(net "INVERTER_G2")
	)
	(segment
		(start 64.0715 -87.4141)
		(end 63.4492 -88.0364)
		(width 0.12065)
		(layer "F.Cu")
		(net "INVERTER_G2")
	)
	(segment
		(start 63.9699 -86.2838)
		(end 64.0715 -86.3854)
		(width 0.12065)
		(layer "F.Cu")
		(net "INVERTER_G2")
	)
	(via
		(at 64.0715 -87.249)
		(size 0.7112)
		(drill 0.3556)
		(layers "F.Cu" "B.Cu")
		(net "INVERTER_G2")
	)
	(segment
		(start 66.701416 -88.90381)
		(end 67.749166 -87.85606)
		(width 0.12065)
		(layer "F.Cu")
		(net "INVERTER_G1")
	)
	(segment
		(start 65.3288 -89.2556)
		(end 66.349626 -89.2556)
		(width 0.12065)
		(layer "F.Cu")
		(net "INVERTER_G1")
	)
	(segment
		(start 66.349626 -89.2556)
		(end 66.701416 -88.90381)
		(width 0.12065)
		(layer "F.Cu")
		(net "INVERTER_G1")
	)
	(via
		(at 66.701416 -88.90381)
		(size 0.7112)
		(drill 0.3556)
		(layers "F.Cu" "B.Cu")
		(net "INVERTER_G1")
	)
	(segment
		(start 46.50994 -186.57824)
		(end 45.0469 -186.57824)
		(width 0.12065)
		(layer "F.Cu")
		(net "I2C9_BUFF_EN")
	)
	(segment
		(start 48.237902 -187.157868)
		(end 48.062134 -186.9821)
		(width 0.12065)
		(layer "F.Cu")
		(net "I2C9_BUFF_EN")
	)
	(segment
		(start 46.9138 -186.9821)
		(end 46.50994 -186.57824)
		(width 0.12065)
		(layer "F.Cu")
		(net "I2C9_BUFF_EN")
	)
	(segment
		(start 48.062134 -186.9821)
		(end 46.9138 -186.9821)
		(width 0.12065)
		(layer "F.Cu")
		(net "I2C9_BUFF_EN")
	)
	(via
		(at 48.237902 -187.157868)
		(size 0.7112)
		(drill 0.3556)
		(layers "F.Cu" "B.Cu")
		(net "I2C9_BUFF_EN")
	)
	(segment
		(start 39.0398 -188.1251)
		(end 39.44366 -188.52896)
		(width 0.12065)
		(layer "F.Cu")
		(net "I2C9_BUF_READY")
	)
	(segment
		(start 39.0398 -188.1251)
		(end 38.010846 -188.1251)
		(width 0.12065)
		(layer "F.Cu")
		(net "I2C9_BUF_READY")
	)
	(segment
		(start 38.010846 -188.1251)
		(end 37.907214 -188.021468)
		(width 0.12065)
		(layer "F.Cu")
		(net "I2C9_BUF_READY")
	)
	(segment
		(start 39.44366 -188.52896)
		(end 40.9067 -188.52896)
		(width 0.12065)
		(layer "F.Cu")
		(net "I2C9_BUF_READY")
	)
	(via
		(at 37.907214 -188.021468)
		(size 0.7112)
		(drill 0.3556)
		(layers "F.Cu" "B.Cu")
		(net "I2C9_BUF_READY")
	)
	(segment
		(start 55.118 -180.9115)
		(end 54.71414 -180.50764)
		(width 0.12065)
		(layer "F.Cu")
		(net "I2C8_BUFF_EN")
	)
	(segment
		(start 55.118 -180.9115)
		(end 56.1848 -180.9115)
		(width 0.12065)
		(layer "F.Cu")
		(net "I2C8_BUFF_EN")
	)
	(segment
		(start 54.71414 -180.50764)
		(end 53.2511 -180.50764)
		(width 0.12065)
		(layer "F.Cu")
		(net "I2C8_BUFF_EN")
	)
	(via
		(at 56.1848 -180.9115)
		(size 0.7112)
		(drill 0.3556)
		(layers "F.Cu" "B.Cu")
		(net "I2C8_BUFF_EN")
	)
	(segment
		(start 47.64786 -182.45836)
		(end 49.1109 -182.45836)
		(width 0.12065)
		(layer "F.Cu")
		(net "I2C8_BUF_READY")
	)
	(segment
		(start 46.251622 -182.0545)
		(end 46.195742 -181.99862)
		(width 0.12065)
		(layer "F.Cu")
		(net "I2C8_BUF_READY")
	)
	(segment
		(start 47.244 -182.0545)
		(end 47.64786 -182.45836)
		(width 0.12065)
		(layer "F.Cu")
		(net "I2C8_BUF_READY")
	)
	(segment
		(start 47.244 -182.0545)
		(end 46.251622 -182.0545)
		(width 0.12065)
		(layer "F.Cu")
		(net "I2C8_BUF_READY")
	)
	(via
		(at 46.195742 -181.99862)
		(size 0.7112)
		(drill 0.3556)
		(layers "F.Cu" "B.Cu")
		(net "I2C8_BUF_READY")
	)
	(segment
		(start 55.391812 -195.282312)
		(end 55.391812 -195.93687)
		(width 0.12065)
		(layer "F.Cu")
		(net "I2C7_BUFF_EN")
	)
	(segment
		(start 55.118 -195.0085)
		(end 55.391812 -195.282312)
		(width 0.12065)
		(layer "F.Cu")
		(net "I2C7_BUFF_EN")
	)
	(segment
		(start 55.391812 -195.93687)
		(end 55.39232 -195.937378)
		(width 0.12065)
		(layer "F.Cu")
		(net "I2C7_BUFF_EN")
	)
	(segment
		(start 54.71414 -194.60464)
		(end 53.2511 -194.60464)
		(width 0.12065)
		(layer "F.Cu")
		(net "I2C7_BUFF_EN")
	)
	(segment
		(start 55.118 -195.0085)
		(end 54.71414 -194.60464)
		(width 0.12065)
		(layer "F.Cu")
		(net "I2C7_BUFF_EN")
	)
	(via
		(at 55.39232 -195.937378)
		(size 0.7112)
		(drill 0.3556)
		(layers "F.Cu" "B.Cu")
		(net "I2C7_BUFF_EN")
	)
	(segment
		(start 47.244 -196.1515)
		(end 47.119032 -196.026532)
		(width 0.12065)
		(layer "F.Cu")
		(net "I2C7_BUF_READY")
	)
	(segment
		(start 47.64786 -196.55536)
		(end 49.1109 -196.55536)
		(width 0.12065)
		(layer "F.Cu")
		(net "I2C7_BUF_READY")
	)
	(segment
		(start 47.119032 -196.026532)
		(end 46.251368 -196.026532)
		(width 0.12065)
		(layer "F.Cu")
		(net "I2C7_BUF_READY")
	)
	(segment
		(start 47.244 -196.1515)
		(end 47.64786 -196.55536)
		(width 0.12065)
		(layer "F.Cu")
		(net "I2C7_BUF_READY")
	)
	(via
		(at 46.251368 -196.026532)
		(size 0.7112)
		(drill 0.3556)
		(layers "F.Cu" "B.Cu")
		(net "I2C7_BUF_READY")
	)
	(segment
		(start 45.185076 -201.077576)
		(end 45.185076 -203.214986)
		(width 0.12065)
		(layer "F.Cu")
		(net "I2C6_BUFF_EN")
	)
	(segment
		(start 44.68114 -200.57364)
		(end 43.2181 -200.57364)
		(width 0.12065)
		(layer "F.Cu")
		(net "I2C6_BUFF_EN")
	)
	(segment
		(start 45.085 -200.9775)
		(end 45.185076 -201.077576)
		(width 0.12065)
		(layer "F.Cu")
		(net "I2C6_BUFF_EN")
	)
	(segment
		(start 45.185076 -203.214986)
		(end 44.981368 -203.418694)
		(width 0.12065)
		(layer "F.Cu")
		(net "I2C6_BUFF_EN")
	)
	(segment
		(start 45.085 -200.9775)
		(end 44.68114 -200.57364)
		(width 0.12065)
		(layer "F.Cu")
		(net "I2C6_BUFF_EN")
	)
	(via
		(at 44.981368 -203.418694)
		(size 0.7112)
		(drill 0.3556)
		(layers "F.Cu" "B.Cu")
		(net "I2C6_BUFF_EN")
	)
	(segment
		(start 37.211 -202.1205)
		(end 37.61486 -202.52436)
		(width 0.12065)
		(layer "F.Cu")
		(net "I2C6_BUF_READY")
	)
	(segment
		(start 37.61486 -202.52436)
		(end 39.0779 -202.52436)
		(width 0.12065)
		(layer "F.Cu")
		(net "I2C6_BUF_READY")
	)
	(segment
		(start 36.249864 -202.1205)
		(end 36.192968 -202.063604)
		(width 0.12065)
		(layer "F.Cu")
		(net "I2C6_BUF_READY")
	)
	(segment
		(start 37.211 -202.1205)
		(end 36.249864 -202.1205)
		(width 0.12065)
		(layer "F.Cu")
		(net "I2C6_BUF_READY")
	)
	(via
		(at 36.192968 -202.063604)
		(size 0.7112)
		(drill 0.3556)
		(layers "F.Cu" "B.Cu")
		(net "I2C6_BUF_READY")
	)
	(segment
		(start 31.6992 -189.3062)
		(end 32.7279 -189.3062)
		(width 0.12065)
		(layer "F.Cu")
		(net "I2C5_BUFF_EN")
	)
	(segment
		(start 31.5849 -188.64326)
		(end 31.5849 -189.1919)
		(width 0.12065)
		(layer "F.Cu")
		(net "I2C5_BUFF_EN")
	)
	(segment
		(start 31.93796 -188.2902)
		(end 31.5849 -188.64326)
		(width 0.12065)
		(layer "F.Cu")
		(net "I2C5_BUFF_EN")
	)
	(segment
		(start 31.5849 -189.1919)
		(end 31.6992 -189.3062)
		(width 0.12065)
		(layer "F.Cu")
		(net "I2C5_BUFF_EN")
	)
	(segment
		(start 32.7279 -189.3062)
		(end 32.7533 -189.2808)
		(width 0.12065)
		(layer "F.Cu")
		(net "I2C5_BUFF_EN")
	)
	(segment
		(start 31.93796 -187.4393)
		(end 31.93796 -188.2902)
		(width 0.12065)
		(layer "F.Cu")
		(net "I2C5_BUFF_EN")
	)
	(via
		(at 31.6992 -189.3062)
		(size 0.7112)
		(drill 0.3556)
		(layers "F.Cu" "B.Cu")
		(net "I2C5_BUFF_EN")
	)
	(segment
		(start 125.3998 -95.5167)
		(end 125.3998 -96.180148)
		(width 0.12065)
		(layer "F.Cu")
		(net "I2C10_BUFF_EN")
	)
	(segment
		(start 124.99594 -95.11284)
		(end 125.3998 -95.5167)
		(width 0.12065)
		(layer "F.Cu")
		(net "I2C10_BUFF_EN")
	)
	(segment
		(start 123.5329 -95.11284)
		(end 124.99594 -95.11284)
		(width 0.12065)
		(layer "F.Cu")
		(net "I2C10_BUFF_EN")
	)
	(segment
		(start 125.3998 -96.180148)
		(end 125.706632 -96.48698)
		(width 0.12065)
		(layer "F.Cu")
		(net "I2C10_BUFF_EN")
	)
	(via
		(at 125.706632 -96.48698)
		(size 0.7112)
		(drill 0.3556)
		(layers "F.Cu" "B.Cu")
		(net "I2C10_BUFF_EN")
	)
	(segment
		(start 117.4623 -96.5962)
		(end 117.5258 -96.6597)
		(width 0.12065)
		(layer "F.Cu")
		(net "I2C10_BUF_READY")
	)
	(segment
		(start 117.92966 -97.06356)
		(end 119.3927 -97.06356)
		(width 0.12065)
		(layer "F.Cu")
		(net "I2C10_BUF_READY")
	)
	(segment
		(start 116.339366 -96.59747)
		(end 116.340636 -96.5962)
		(width 0.12065)
		(layer "F.Cu")
		(net "I2C10_BUF_READY")
	)
	(segment
		(start 117.5258 -96.6597)
		(end 117.92966 -97.06356)
		(width 0.12065)
		(layer "F.Cu")
		(net "I2C10_BUF_READY")
	)
	(segment
		(start 116.340636 -96.5962)
		(end 117.4623 -96.5962)
		(width 0.12065)
		(layer "F.Cu")
		(net "I2C10_BUF_READY")
	)
	(via
		(at 116.339366 -96.59747)
		(size 0.7112)
		(drill 0.3556)
		(layers "F.Cu" "B.Cu")
		(net "I2C10_BUF_READY")
	)
	(segment
		(start 55.483252 -127.041148)
		(end 52.93233 -127.041148)
		(width 0.12065)
		(layer "F.Cu")
		(net "I2C_MUX_RESET_PEB_R")
	)
	(segment
		(start 46.070012 -128.050036)
		(end 45.70476 -127.684784)
		(width 0.12065)
		(layer "F.Cu")
		(net "I2C_MUX_RESET_PEB_R")
	)
	(segment
		(start 51.923442 -128.050036)
		(end 46.070012 -128.050036)
		(width 0.12065)
		(layer "F.Cu")
		(net "I2C_MUX_RESET_PEB_R")
	)
	(segment
		(start 55.944262 -126.580138)
		(end 56.172608 -126.808484)
		(width 0.12065)
		(layer "F.Cu")
		(net "I2C_MUX_RESET_PEB_R")
	)
	(segment
		(start 56.7182 -125.8062)
		(end 55.944262 -126.580138)
		(width 0.12065)
		(layer "F.Cu")
		(net "I2C_MUX_RESET_PEB_R")
	)
	(segment
		(start 56.873648 -125.8062)
		(end 56.7182 -125.8062)
		(width 0.12065)
		(layer "F.Cu")
		(net "I2C_MUX_RESET_PEB_R")
	)
	(segment
		(start 55.944262 -126.580138)
		(end 55.483252 -127.041148)
		(width 0.12065)
		(layer "F.Cu")
		(net "I2C_MUX_RESET_PEB_R")
	)
	(segment
		(start 52.93233 -127.041148)
		(end 51.923442 -128.050036)
		(width 0.12065)
		(layer "F.Cu")
		(net "I2C_MUX_RESET_PEB_R")
	)
	(via
		(at 56.172608 -126.808484)
		(size 0.7112)
		(drill 0.3556)
		(layers "F.Cu" "B.Cu")
		(net "I2C_MUX_RESET_PEB_R")
	)
	(segment
		(start 58.880248 -122.018552)
		(end 58.547 -122.3518)
		(width 0.12065)
		(layer "F.Cu")
		(net "I2C_MUX_RESET_PEB")
	)
	(segment
		(start 58.547 -125.5522)
		(end 58.293 -125.8062)
		(width 0.12065)
		(layer "F.Cu")
		(net "I2C_MUX_RESET_PEB")
	)
	(segment
		(start 58.293 -125.8062)
		(end 57.762648 -125.8062)
		(width 0.12065)
		(layer "F.Cu")
		(net "I2C_MUX_RESET_PEB")
	)
	(segment
		(start 22.733 -118.049548)
		(end 23.459948 -117.3226)
		(width 0.12065)
		(layer "F.Cu")
		(net "I2C_MUX_RESET_PEB")
	)
	(segment
		(start 22.733 -118.5164)
		(end 22.733 -118.049548)
		(width 0.12065)
		(layer "F.Cu")
		(net "I2C_MUX_RESET_PEB")
	)
	(segment
		(start 23.8506 -117.3226)
		(end 25.733248 -115.439952)
		(width 0.12065)
		(layer "F.Cu")
		(net "I2C_MUX_RESET_PEB")
	)
	(segment
		(start 25.733248 -115.263422)
		(end 26.15057 -114.8461)
		(width 0.12065)
		(layer "F.Cu")
		(net "I2C_MUX_RESET_PEB")
	)
	(segment
		(start 58.0898 -114.7318)
		(end 58.0898 -116.0272)
		(width 0.12065)
		(layer "F.Cu")
		(net "I2C_MUX_RESET_PEB")
	)
	(segment
		(start 29.30398 -114.8461)
		(end 29.52369 -114.62639)
		(width 0.12065)
		(layer "F.Cu")
		(net "I2C_MUX_RESET_PEB")
	)
	(segment
		(start 59.8805 -106.553)
		(end 59.8805 -109.6899)
		(width 0.12065)
		(layer "F.Cu")
		(net "I2C_MUX_RESET_PEB")
	)
	(segment
		(start 58.880248 -116.817648)
		(end 58.880248 -122.018552)
		(width 0.12065)
		(layer "F.Cu")
		(net "I2C_MUX_RESET_PEB")
	)
	(segment
		(start 58.0898 -116.0272)
		(end 58.880248 -116.817648)
		(width 0.12065)
		(layer "F.Cu")
		(net "I2C_MUX_RESET_PEB")
	)
	(segment
		(start 25.733248 -115.439952)
		(end 25.733248 -115.263422)
		(width 0.12065)
		(layer "F.Cu")
		(net "I2C_MUX_RESET_PEB")
	)
	(segment
		(start 29.52369 -114.62639)
		(end 30.48 -114.62639)
		(width 0.12065)
		(layer "F.Cu")
		(net "I2C_MUX_RESET_PEB")
	)
	(segment
		(start 59.8805 -109.6899)
		(end 58.607452 -110.962948)
		(width 0.12065)
		(layer "F.Cu")
		(net "I2C_MUX_RESET_PEB")
	)
	(segment
		(start 58.607452 -110.962948)
		(end 58.607452 -114.214148)
		(width 0.12065)
		(layer "F.Cu")
		(net "I2C_MUX_RESET_PEB")
	)
	(segment
		(start 26.15057 -114.8461)
		(end 29.30398 -114.8461)
		(width 0.12065)
		(layer "F.Cu")
		(net "I2C_MUX_RESET_PEB")
	)
	(segment
		(start 58.547 -122.3518)
		(end 58.547 -125.5522)
		(width 0.12065)
		(layer "F.Cu")
		(net "I2C_MUX_RESET_PEB")
	)
	(segment
		(start 58.607452 -114.214148)
		(end 58.0898 -114.7318)
		(width 0.12065)
		(layer "F.Cu")
		(net "I2C_MUX_RESET_PEB")
	)
	(segment
		(start 23.459948 -117.3226)
		(end 23.8506 -117.3226)
		(width 0.12065)
		(layer "F.Cu")
		(net "I2C_MUX_RESET_PEB")
	)
	(via
		(at 6.6294 -170.4848)
		(size 0.508)
		(drill 0.254)
		(layers "F.Cu" "B.Cu")
		(net "I2C_MUX_RESET_PEB")
	)
	(via
		(at 22.733 -118.5164)
		(size 0.508)
		(drill 0.254)
		(layers "F.Cu" "B.Cu")
		(net "I2C_MUX_RESET_PEB")
	)
	(via
		(at 30.48 -114.62639)
		(size 0.508)
		(drill 0.254)
		(layers "F.Cu" "B.Cu")
		(net "I2C_MUX_RESET_PEB")
	)
	(via
		(at 227.584 -174.244)
		(size 0.7112)
		(drill 0.3556)
		(layers "F.Cu" "B.Cu")
		(net "I2C_MUX_RESET_PEB")
	)
	(via
		(at 59.8805 -106.553)
		(size 0.508)
		(drill 0.254)
		(layers "F.Cu" "B.Cu")
		(net "I2C_MUX_RESET_PEB")
	)
	(segment
		(start 52.97551 -169.4307)
		(end 52.464208 -168.919398)
		(width 0.12065)
		(layer "B.Cu")
		(net "I2C_MUX_RESET_PEB")
	)
	(segment
		(start 53.585364 -169.4307)
		(end 53.58511 -169.430954)
		(width 0.12065)
		(layer "B.Cu")
		(net "I2C_MUX_RESET_PEB")
	)
	(segment
		(start 227.584 -184.023)
		(end 227.203 -184.404)
		(width 0.12065)
		(layer "B.Cu")
		(net "I2C_MUX_RESET_PEB")
	)
	(segment
		(start 6.6802 -170.434)
		(end 6.6294 -170.4848)
		(width 0.12065)
		(layer "B.Cu")
		(net "I2C_MUX_RESET_PEB")
	)
	(segment
		(start 261.300214 -225.92538)
		(end 261.300214 -212.929978)
		(width 0.12065)
		(layer "B.Cu")
		(net "I2C_MUX_RESET_PEB")
	)
	(segment
		(start 12.0142 -169.926)
		(end 10.668 -169.926)
		(width 0.12065)
		(layer "B.Cu")
		(net "I2C_MUX_RESET_PEB")
	)
	(segment
		(start 227.584 -174.244)
		(end 227.584 -184.023)
		(width 0.12065)
		(layer "B.Cu")
		(net "I2C_MUX_RESET_PEB")
	)
	(segment
		(start 53.285136 -169.431208)
		(end 52.985416 -169.431208)
		(width 0.12065)
		(layer "B.Cu")
		(net "I2C_MUX_RESET_PEB")
	)
	(segment
		(start 227.203 -184.404)
		(end 128.256792 -184.404)
		(width 0.12065)
		(layer "B.Cu")
		(net "I2C_MUX_RESET_PEB")
	)
	(segment
		(start 52.984908 -169.4307)
		(end 52.97551 -169.4307)
		(width 0.12065)
		(layer "B.Cu")
		(net "I2C_MUX_RESET_PEB")
	)
	(segment
		(start 53.28539 -169.430954)
		(end 53.285136 -169.431208)
		(width 0.12065)
		(layer "B.Cu")
		(net "I2C_MUX_RESET_PEB")
	)
	(segment
		(start 85.337904 -175.08855)
		(end 79.680054 -169.4307)
		(width 0.12065)
		(layer "B.Cu")
		(net "I2C_MUX_RESET_PEB")
	)
	(segment
		(start 228.66985 -158.42615)
		(end 227.584 -159.512)
		(width 0.12065)
		(layer "B.Cu")
		(net "I2C_MUX_RESET_PEB")
	)
	(segment
		(start 261.300214 -212.929978)
		(end 259.6134 -211.243164)
		(width 0.12065)
		(layer "B.Cu")
		(net "I2C_MUX_RESET_PEB")
	)
	(segment
		(start 90.663776 -175.088296)
		(end 90.663522 -175.08855)
		(width 0.12065)
		(layer "B.Cu")
		(net "I2C_MUX_RESET_PEB")
	)
	(segment
		(start 128.256792 -184.404)
		(end 118.941088 -175.088296)
		(width 0.12065)
		(layer "B.Cu")
		(net "I2C_MUX_RESET_PEB")
	)
	(segment
		(start 53.58511 -169.430954)
		(end 53.28539 -169.430954)
		(width 0.12065)
		(layer "B.Cu")
		(net "I2C_MUX_RESET_PEB")
	)
	(segment
		(start 90.663522 -175.08855)
		(end 85.337904 -175.08855)
		(width 0.12065)
		(layer "B.Cu")
		(net "I2C_MUX_RESET_PEB")
	)
	(segment
		(start 10.16 -170.434)
		(end 6.6802 -170.434)
		(width 0.12065)
		(layer "B.Cu")
		(net "I2C_MUX_RESET_PEB")
	)
	(segment
		(start 259.6134 -211.243164)
		(end 259.6134 -162.970464)
		(width 0.12065)
		(layer "B.Cu")
		(net "I2C_MUX_RESET_PEB")
	)
	(segment
		(start 15.727172 -170.0911)
		(end 15.726918 -170.090846)
		(width 0.12065)
		(layer "B.Cu")
		(net "I2C_MUX_RESET_PEB")
	)
	(segment
		(start 36.082986 -168.919398)
		(end 34.911284 -170.0911)
		(width 0.12065)
		(layer "B.Cu")
		(net "I2C_MUX_RESET_PEB")
	)
	(segment
		(start 259.6134 -162.970464)
		(end 255.069086 -158.42615)
		(width 0.12065)
		(layer "B.Cu")
		(net "I2C_MUX_RESET_PEB")
	)
	(segment
		(start 14.412214 -170.0911)
		(end 14.221714 -170.2816)
		(width 0.12065)
		(layer "B.Cu")
		(net "I2C_MUX_RESET_PEB")
	)
	(segment
		(start 14.221714 -170.2816)
		(end 12.3698 -170.2816)
		(width 0.12065)
		(layer "B.Cu")
		(net "I2C_MUX_RESET_PEB")
	)
	(segment
		(start 52.985416 -169.431208)
		(end 52.984908 -169.4307)
		(width 0.12065)
		(layer "B.Cu")
		(net "I2C_MUX_RESET_PEB")
	)
	(segment
		(start 79.680054 -169.4307)
		(end 53.585364 -169.4307)
		(width 0.12065)
		(layer "B.Cu")
		(net "I2C_MUX_RESET_PEB")
	)
	(segment
		(start 12.3698 -170.2816)
		(end 12.0142 -169.926)
		(width 0.12065)
		(layer "B.Cu")
		(net "I2C_MUX_RESET_PEB")
	)
	(segment
		(start 10.668 -169.926)
		(end 10.16 -170.434)
		(width 0.12065)
		(layer "B.Cu")
		(net "I2C_MUX_RESET_PEB")
	)
	(segment
		(start 14.826742 -170.090846)
		(end 14.826488 -170.0911)
		(width 0.12065)
		(layer "B.Cu")
		(net "I2C_MUX_RESET_PEB")
	)
	(segment
		(start 255.069086 -158.42615)
		(end 228.66985 -158.42615)
		(width 0.12065)
		(layer "B.Cu")
		(net "I2C_MUX_RESET_PEB")
	)
	(segment
		(start 227.584 -159.512)
		(end 227.584 -174.244)
		(width 0.12065)
		(layer "B.Cu")
		(net "I2C_MUX_RESET_PEB")
	)
	(segment
		(start 52.464208 -168.919398)
		(end 36.082986 -168.919398)
		(width 0.12065)
		(layer "B.Cu")
		(net "I2C_MUX_RESET_PEB")
	)
	(segment
		(start 14.826488 -170.0911)
		(end 14.412214 -170.0911)
		(width 0.12065)
		(layer "B.Cu")
		(net "I2C_MUX_RESET_PEB")
	)
	(segment
		(start 34.911284 -170.0911)
		(end 15.727172 -170.0911)
		(width 0.12065)
		(layer "B.Cu")
		(net "I2C_MUX_RESET_PEB")
	)
	(segment
		(start 15.726918 -170.090846)
		(end 14.826742 -170.090846)
		(width 0.12065)
		(layer "B.Cu")
		(net "I2C_MUX_RESET_PEB")
	)
	(segment
		(start 118.941088 -175.088296)
		(end 90.663776 -175.088296)
		(width 0.12065)
		(layer "B.Cu")
		(net "I2C_MUX_RESET_PEB")
	)
	(segment
		(start 37.244782 -106.265218)
		(end 35.2806 -108.2294)
		(width 0.127)
		(layer "In2.Cu")
		(net "I2C_MUX_RESET_PEB")
	)
	(segment
		(start 33.4772 -110.617)
		(end 33.4772 -111.5314)
		(width 0.127)
		(layer "In2.Cu")
		(net "I2C_MUX_RESET_PEB")
	)
	(segment
		(start 47.097696 -104.5845)
		(end 45.416978 -106.265218)
		(width 0.127)
		(layer "In2.Cu")
		(net "I2C_MUX_RESET_PEB")
	)
	(segment
		(start 45.416978 -106.265218)
		(end 37.244782 -106.265218)
		(width 0.127)
		(layer "In2.Cu")
		(net "I2C_MUX_RESET_PEB")
	)
	(segment
		(start 33.4772 -111.5314)
		(end 30.48 -114.5286)
		(width 0.127)
		(layer "In2.Cu")
		(net "I2C_MUX_RESET_PEB")
	)
	(segment
		(start 59.1947 -105.8672)
		(end 57.7596 -105.8672)
		(width 0.127)
		(layer "In2.Cu")
		(net "I2C_MUX_RESET_PEB")
	)
	(segment
		(start 35.2806 -108.2294)
		(end 35.2806 -108.8136)
		(width 0.127)
		(layer "In2.Cu")
		(net "I2C_MUX_RESET_PEB")
	)
	(segment
		(start 56.4769 -104.5845)
		(end 47.097696 -104.5845)
		(width 0.127)
		(layer "In2.Cu")
		(net "I2C_MUX_RESET_PEB")
	)
	(segment
		(start 35.2806 -108.8136)
		(end 33.4772 -110.617)
		(width 0.127)
		(layer "In2.Cu")
		(net "I2C_MUX_RESET_PEB")
	)
	(segment
		(start 59.8805 -106.553)
		(end 59.1947 -105.8672)
		(width 0.127)
		(layer "In2.Cu")
		(net "I2C_MUX_RESET_PEB")
	)
	(segment
		(start 57.7596 -105.8672)
		(end 56.4769 -104.5845)
		(width 0.127)
		(layer "In2.Cu")
		(net "I2C_MUX_RESET_PEB")
	)
	(segment
		(start 30.48 -114.5286)
		(end 30.48 -114.62639)
		(width 0.127)
		(layer "In2.Cu")
		(net "I2C_MUX_RESET_PEB")
	)
	(segment
		(start 21.9202 -121.381012)
		(end 21.9202 -121.644918)
		(width 0.127)
		(layer "In5.Cu")
		(net "I2C_MUX_RESET_PEB")
	)
	(segment
		(start 22.249892 -120.661684)
		(end 22.249892 -121.05132)
		(width 0.127)
		(layer "In5.Cu")
		(net "I2C_MUX_RESET_PEB")
	)
	(segment
		(start 15.489428 -125.009656)
		(end 6.9723 -133.526784)
		(width 0.127)
		(layer "In5.Cu")
		(net "I2C_MUX_RESET_PEB")
	)
	(segment
		(start 22.249892 -121.05132)
		(end 21.9202 -121.381012)
		(width 0.127)
		(layer "In5.Cu")
		(net "I2C_MUX_RESET_PEB")
	)
	(segment
		(start 21.9202 -120.331992)
		(end 22.249892 -120.661684)
		(width 0.127)
		(layer "In5.Cu")
		(net "I2C_MUX_RESET_PEB")
	)
	(segment
		(start 18.555462 -125.009656)
		(end 15.489428 -125.009656)
		(width 0.127)
		(layer "In5.Cu")
		(net "I2C_MUX_RESET_PEB")
	)
	(segment
		(start 21.9202 -119.3292)
		(end 21.9202 -120.331992)
		(width 0.127)
		(layer "In5.Cu")
		(net "I2C_MUX_RESET_PEB")
	)
	(segment
		(start 6.9723 -170.1419)
		(end 6.6294 -170.4848)
		(width 0.127)
		(layer "In5.Cu")
		(net "I2C_MUX_RESET_PEB")
	)
	(segment
		(start 21.9202 -121.644918)
		(end 18.555462 -125.009656)
		(width 0.127)
		(layer "In5.Cu")
		(net "I2C_MUX_RESET_PEB")
	)
	(segment
		(start 22.733 -118.5164)
		(end 21.9202 -119.3292)
		(width 0.127)
		(layer "In5.Cu")
		(net "I2C_MUX_RESET_PEB")
	)
	(segment
		(start 6.9723 -133.526784)
		(end 6.9723 -170.1419)
		(width 0.127)
		(layer "In5.Cu")
		(net "I2C_MUX_RESET_PEB")
	)
	(segment
		(start 39.9669 -96.583246)
		(end 40.691816 -97.308162)
		(width 0.12065)
		(layer "F.Cu")
		(net "I2C_MUX_4A")
	)
	(segment
		(start 40.691816 -97.308162)
		(end 40.691816 -97.586546)
		(width 0.12065)
		(layer "F.Cu")
		(net "I2C_MUX_4A")
	)
	(segment
		(start 39.976298 -98.302064)
		(end 38.1 -98.302064)
		(width 0.12065)
		(layer "F.Cu")
		(net "I2C_MUX_4A")
	)
	(segment
		(start 40.691816 -97.586546)
		(end 39.976298 -98.302064)
		(width 0.12065)
		(layer "F.Cu")
		(net "I2C_MUX_4A")
	)
	(segment
		(start 39.9669 -96.3168)
		(end 39.9669 -96.583246)
		(width 0.12065)
		(layer "F.Cu")
		(net "I2C_MUX_4A")
	)
	(via
		(at 40.691816 -97.586546)
		(size 0.7112)
		(drill 0.3556)
		(layers "F.Cu" "B.Cu")
		(net "I2C_MUX_4A")
	)
	(segment
		(start 37.084 -94.1705)
		(end 37.07511 -94.17939)
		(width 0.12065)
		(layer "F.Cu")
		(net "I2C_MUX_3A")
	)
	(segment
		(start 37.07511 -95.123)
		(end 37.07511 -96.5327)
		(width 0.12065)
		(layer "F.Cu")
		(net "I2C_MUX_3A")
	)
	(segment
		(start 37.07511 -94.17939)
		(end 37.07511 -95.123)
		(width 0.12065)
		(layer "F.Cu")
		(net "I2C_MUX_3A")
	)
	(via
		(at 37.07511 -95.123)
		(size 0.7112)
		(drill 0.3556)
		(layers "F.Cu" "B.Cu")
		(net "I2C_MUX_3A")
	)
	(segment
		(start 32.942276 -95.79737)
		(end 33.722056 -95.01759)
		(width 0.12065)
		(layer "F.Cu")
		(net "I2C_MUX_2A")
	)
	(segment
		(start 34.544 -96.774)
		(end 34.544 -97.302066)
		(width 0.12065)
		(layer "F.Cu")
		(net "I2C_MUX_2A")
	)
	(segment
		(start 32.942276 -96.328738)
		(end 34.098738 -96.328738)
		(width 0.12065)
		(layer "F.Cu")
		(net "I2C_MUX_2A")
	)
	(segment
		(start 33.722056 -95.01759)
		(end 33.722056 -94.99219)
		(width 0.12065)
		(layer "F.Cu")
		(net "I2C_MUX_2A")
	)
	(segment
		(start 32.942276 -96.328738)
		(end 32.942276 -95.79737)
		(width 0.12065)
		(layer "F.Cu")
		(net "I2C_MUX_2A")
	)
	(segment
		(start 34.098738 -96.328738)
		(end 34.544 -96.774)
		(width 0.12065)
		(layer "F.Cu")
		(net "I2C_MUX_2A")
	)
	(via
		(at 32.942276 -96.328738)
		(size 0.7112)
		(drill 0.3556)
		(layers "F.Cu" "B.Cu")
		(net "I2C_MUX_2A")
	)
	(segment
		(start 32.4358 -99.6442)
		(end 33.09112 -98.98888)
		(width 0.12065)
		(layer "F.Cu")
		(net "I2C_MUX_1A")
	)
	(segment
		(start 33.278064 -98.801936)
		(end 33.09112 -98.98888)
		(width 0.12065)
		(layer "F.Cu")
		(net "I2C_MUX_1A")
	)
	(segment
		(start 32.1183 -99.6442)
		(end 32.4358 -99.6442)
		(width 0.12065)
		(layer "F.Cu")
		(net "I2C_MUX_1A")
	)
	(segment
		(start 34.544 -98.801936)
		(end 33.278064 -98.801936)
		(width 0.12065)
		(layer "F.Cu")
		(net "I2C_MUX_1A")
	)
	(via
		(at 33.09112 -98.98888)
		(size 0.7112)
		(drill 0.3556)
		(layers "F.Cu" "B.Cu")
		(net "I2C_MUX_1A")
	)
	(segment
		(start 252.767592 -5.867146)
		(end 252.4887 -6.146038)
		(width 0.12065)
		(layer "F.Cu")
		(net "I2C_MAX6654_DAT")
	)
	(segment
		(start 252.39853 -6.146038)
		(end 252.125226 -5.872734)
		(width 0.12065)
		(layer "F.Cu")
		(net "I2C_MAX6654_DAT")
	)
	(segment
		(start 255.207262 -3.481578)
		(end 255.207262 -4.114292)
		(width 0.12065)
		(layer "F.Cu")
		(net "I2C_MAX6654_DAT")
	)
	(segment
		(start 255.207262 -4.114292)
		(end 255.547368 -4.454398)
		(width 0.12065)
		(layer "F.Cu")
		(net "I2C_MAX6654_DAT")
	)
	(segment
		(start 255.547368 -5.27939)
		(end 254.959612 -5.867146)
		(width 0.12065)
		(layer "F.Cu")
		(net "I2C_MAX6654_DAT")
	)
	(segment
		(start 252.4887 -6.146038)
		(end 252.39853 -6.146038)
		(width 0.12065)
		(layer "F.Cu")
		(net "I2C_MAX6654_DAT")
	)
	(segment
		(start 254.959612 -5.867146)
		(end 252.767592 -5.867146)
		(width 0.12065)
		(layer "F.Cu")
		(net "I2C_MAX6654_DAT")
	)
	(segment
		(start 255.547368 -4.454398)
		(end 255.547368 -5.27939)
		(width 0.12065)
		(layer "F.Cu")
		(net "I2C_MAX6654_DAT")
	)
	(segment
		(start 256.477262 -3.481578)
		(end 256.477262 -4.108196)
		(width 0.12065)
		(layer "F.Cu")
		(net "I2C_MAX6654_CLK")
	)
	(segment
		(start 256.477262 -4.108196)
		(end 256.049018 -4.53644)
		(width 0.12065)
		(layer "F.Cu")
		(net "I2C_MAX6654_CLK")
	)
	(segment
		(start 252.975618 -6.368796)
		(end 252.696726 -6.647688)
		(width 0.12065)
		(layer "F.Cu")
		(net "I2C_MAX6654_CLK")
	)
	(segment
		(start 252.696726 -6.647688)
		(end 252.39853 -6.647688)
		(width 0.12065)
		(layer "F.Cu")
		(net "I2C_MAX6654_CLK")
	)
	(segment
		(start 255.167638 -6.368796)
		(end 252.975618 -6.368796)
		(width 0.12065)
		(layer "F.Cu")
		(net "I2C_MAX6654_CLK")
	)
	(segment
		(start 256.049018 -4.53644)
		(end 256.049018 -5.487416)
		(width 0.12065)
		(layer "F.Cu")
		(net "I2C_MAX6654_CLK")
	)
	(segment
		(start 252.39853 -6.647688)
		(end 252.125226 -6.920992)
		(width 0.12065)
		(layer "F.Cu")
		(net "I2C_MAX6654_CLK")
	)
	(segment
		(start 256.049018 -5.487416)
		(end 255.167638 -6.368796)
		(width 0.12065)
		(layer "F.Cu")
		(net "I2C_MAX6654_CLK")
	)
	(segment
		(start 332.259432 -182.268114)
		(end 332.259432 -181.601618)
		(width 0.12065)
		(layer "F.Cu")
		(net "I2C_GPIO_SDA_4")
	)
	(segment
		(start 330.740512 -183.65978)
		(end 330.740512 -184.433718)
		(width 0.12065)
		(layer "F.Cu")
		(net "I2C_GPIO_SDA_4")
	)
	(segment
		(start 330.61275 -183.532018)
		(end 330.740512 -183.65978)
		(width 0.12065)
		(layer "F.Cu")
		(net "I2C_GPIO_SDA_4")
	)
	(segment
		(start 330.61275 -183.532018)
		(end 330.858368 -183.2864)
		(width 0.12065)
		(layer "F.Cu")
		(net "I2C_GPIO_SDA_4")
	)
	(segment
		(start 331.241146 -183.2864)
		(end 332.259432 -182.268114)
		(width 0.12065)
		(layer "F.Cu")
		(net "I2C_GPIO_SDA_4")
	)
	(segment
		(start 330.858368 -183.2864)
		(end 331.241146 -183.2864)
		(width 0.12065)
		(layer "F.Cu")
		(net "I2C_GPIO_SDA_4")
	)
	(via
		(at 330.61275 -183.532018)
		(size 0.7112)
		(drill 0.3556)
		(layers "F.Cu" "B.Cu")
		(net "I2C_GPIO_SDA_4")
	)
	(segment
		(start 217.932 -201.676)
		(end 217.93454 -201.67346)
		(width 0.12065)
		(layer "F.Cu")
		(net "I2C_GPIO_SDA_3")
	)
	(segment
		(start 217.781124 -201.826876)
		(end 217.932 -201.676)
		(width 0.12065)
		(layer "F.Cu")
		(net "I2C_GPIO_SDA_3")
	)
	(segment
		(start 218.458288 -201.67346)
		(end 218.728544 -201.403204)
		(width 0.12065)
		(layer "F.Cu")
		(net "I2C_GPIO_SDA_3")
	)
	(segment
		(start 218.728544 -201.139552)
		(end 219.300044 -200.568052)
		(width 0.12065)
		(layer "F.Cu")
		(net "I2C_GPIO_SDA_3")
	)
	(segment
		(start 219.300044 -200.568052)
		(end 219.300044 -199.770492)
		(width 0.12065)
		(layer "F.Cu")
		(net "I2C_GPIO_SDA_3")
	)
	(segment
		(start 217.781124 -202.602592)
		(end 217.781124 -201.826876)
		(width 0.12065)
		(layer "F.Cu")
		(net "I2C_GPIO_SDA_3")
	)
	(segment
		(start 217.93454 -201.67346)
		(end 218.458288 -201.67346)
		(width 0.12065)
		(layer "F.Cu")
		(net "I2C_GPIO_SDA_3")
	)
	(segment
		(start 218.728544 -201.403204)
		(end 218.728544 -201.139552)
		(width 0.12065)
		(layer "F.Cu")
		(net "I2C_GPIO_SDA_3")
	)
	(via
		(at 217.932 -201.676)
		(size 0.7112)
		(drill 0.3556)
		(layers "F.Cu" "B.Cu")
		(net "I2C_GPIO_SDA_3")
	)
	(segment
		(start 125.635512 -206.501746)
		(end 125.635512 -206.375)
		(width 0.12065)
		(layer "F.Cu")
		(net "I2C_GPIO_SDA_2")
	)
	(segment
		(start 125.224794 -206.912464)
		(end 125.635512 -206.501746)
		(width 0.12065)
		(layer "F.Cu")
		(net "I2C_GPIO_SDA_2")
	)
	(segment
		(start 124.60732 -207.356456)
		(end 125.051312 -206.912464)
		(width 0.12065)
		(layer "F.Cu")
		(net "I2C_GPIO_SDA_2")
	)
	(segment
		(start 123.928124 -208.444592)
		(end 123.928124 -207.579722)
		(width 0.12065)
		(layer "F.Cu")
		(net "I2C_GPIO_SDA_2")
	)
	(segment
		(start 125.447044 -206.186532)
		(end 125.447044 -205.612492)
		(width 0.12065)
		(layer "F.Cu")
		(net "I2C_GPIO_SDA_2")
	)
	(segment
		(start 125.635512 -206.375)
		(end 125.447044 -206.186532)
		(width 0.12065)
		(layer "F.Cu")
		(net "I2C_GPIO_SDA_2")
	)
	(segment
		(start 125.051312 -206.912464)
		(end 125.224794 -206.912464)
		(width 0.12065)
		(layer "F.Cu")
		(net "I2C_GPIO_SDA_2")
	)
	(segment
		(start 124.15139 -207.356456)
		(end 124.60732 -207.356456)
		(width 0.12065)
		(layer "F.Cu")
		(net "I2C_GPIO_SDA_2")
	)
	(segment
		(start 123.928124 -207.579722)
		(end 124.01677 -207.491076)
		(width 0.12065)
		(layer "F.Cu")
		(net "I2C_GPIO_SDA_2")
	)
	(segment
		(start 124.01677 -207.491076)
		(end 124.15139 -207.356456)
		(width 0.12065)
		(layer "F.Cu")
		(net "I2C_GPIO_SDA_2")
	)
	(via
		(at 124.01677 -207.491076)
		(size 0.7112)
		(drill 0.3556)
		(layers "F.Cu" "B.Cu")
		(net "I2C_GPIO_SDA_2")
	)
	(segment
		(start 71.218044 -192.404492)
		(end 71.218044 -193.195956)
		(width 0.12065)
		(layer "F.Cu")
		(net "I2C_GPIO_SDA_1")
	)
	(segment
		(start 71.218044 -193.195956)
		(end 70.866 -193.548)
		(width 0.12065)
		(layer "F.Cu")
		(net "I2C_GPIO_SDA_1")
	)
	(segment
		(start 69.699124 -195.236592)
		(end 69.699124 -193.929)
		(width 0.12065)
		(layer "F.Cu")
		(net "I2C_GPIO_SDA_1")
	)
	(segment
		(start 70.080124 -193.548)
		(end 69.699124 -193.929)
		(width 0.12065)
		(layer "F.Cu")
		(net "I2C_GPIO_SDA_1")
	)
	(segment
		(start 70.866 -193.548)
		(end 70.080124 -193.548)
		(width 0.12065)
		(layer "F.Cu")
		(net "I2C_GPIO_SDA_1")
	)
	(via
		(at 69.699124 -193.929)
		(size 0.7112)
		(drill 0.3556)
		(layers "F.Cu" "B.Cu")
		(net "I2C_GPIO_SDA_1")
	)
	(segment
		(start 332.674214 -182.786528)
		(end 332.450694 -182.786528)
		(width 0.12065)
		(layer "F.Cu")
		(net "I2C_GPIO_SCL_4")
	)
	(segment
		(start 332.909672 -182.55107)
		(end 332.674214 -182.786528)
		(width 0.12065)
		(layer "F.Cu")
		(net "I2C_GPIO_SCL_4")
	)
	(segment
		(start 332.284324 -182.952898)
		(end 332.284324 -183.087264)
		(width 0.12065)
		(layer "F.Cu")
		(net "I2C_GPIO_SCL_4")
	)
	(segment
		(start 331.756512 -183.609488)
		(end 331.8764 -183.4896)
		(width 0.12065)
		(layer "F.Cu")
		(net "I2C_GPIO_SCL_4")
	)
	(segment
		(start 332.909672 -181.601618)
		(end 332.909672 -182.55107)
		(width 0.12065)
		(layer "F.Cu")
		(net "I2C_GPIO_SCL_4")
	)
	(segment
		(start 331.756512 -184.433718)
		(end 331.756512 -183.609488)
		(width 0.12065)
		(layer "F.Cu")
		(net "I2C_GPIO_SCL_4")
	)
	(segment
		(start 331.8764 -183.489346)
		(end 331.882242 -183.489346)
		(width 0.12065)
		(layer "F.Cu")
		(net "I2C_GPIO_SCL_4")
	)
	(segment
		(start 332.450694 -182.786528)
		(end 332.284324 -182.952898)
		(width 0.12065)
		(layer "F.Cu")
		(net "I2C_GPIO_SCL_4")
	)
	(segment
		(start 331.8764 -183.4896)
		(end 331.8764 -183.489346)
		(width 0.12065)
		(layer "F.Cu")
		(net "I2C_GPIO_SCL_4")
	)
	(segment
		(start 332.284324 -183.087264)
		(end 331.882242 -183.489346)
		(width 0.12065)
		(layer "F.Cu")
		(net "I2C_GPIO_SCL_4")
	)
	(via
		(at 331.882242 -183.489346)
		(size 0.7112)
		(drill 0.3556)
		(layers "F.Cu" "B.Cu")
		(net "I2C_GPIO_SCL_4")
	)
	(segment
		(start 218.797124 -202.0443)
		(end 218.797124 -202.602592)
		(width 0.12065)
		(layer "F.Cu")
		(net "I2C_GPIO_SCL_3")
	)
	(segment
		(start 219.950284 -199.770492)
		(end 219.950284 -200.729596)
		(width 0.12065)
		(layer "F.Cu")
		(net "I2C_GPIO_SCL_3")
	)
	(segment
		(start 219.950284 -200.729596)
		(end 219.296996 -201.382884)
		(width 0.12065)
		(layer "F.Cu")
		(net "I2C_GPIO_SCL_3")
	)
	(segment
		(start 219.296996 -201.544428)
		(end 218.797124 -202.0443)
		(width 0.12065)
		(layer "F.Cu")
		(net "I2C_GPIO_SCL_3")
	)
	(segment
		(start 219.296996 -201.382884)
		(end 219.296996 -201.544428)
		(width 0.12065)
		(layer "F.Cu")
		(net "I2C_GPIO_SCL_3")
	)
	(via
		(at 219.296996 -201.382884)
		(size 0.7112)
		(drill 0.3556)
		(layers "F.Cu" "B.Cu")
		(net "I2C_GPIO_SCL_3")
	)
	(segment
		(start 126.097284 -206.186278)
		(end 125.908562 -206.375)
		(width 0.12065)
		(layer "F.Cu")
		(net "I2C_GPIO_SCL_2")
	)
	(segment
		(start 124.944124 -207.823562)
		(end 125.28677 -207.480916)
		(width 0.12065)
		(layer "F.Cu")
		(net "I2C_GPIO_SCL_2")
	)
	(segment
		(start 125.478032 -207.289654)
		(end 125.28677 -207.480916)
		(width 0.12065)
		(layer "F.Cu")
		(net "I2C_GPIO_SCL_2")
	)
	(segment
		(start 125.908562 -206.61503)
		(end 125.478032 -207.04556)
		(width 0.12065)
		(layer "F.Cu")
		(net "I2C_GPIO_SCL_2")
	)
	(segment
		(start 125.908562 -206.375)
		(end 125.908562 -206.61503)
		(width 0.12065)
		(layer "F.Cu")
		(net "I2C_GPIO_SCL_2")
	)
	(segment
		(start 126.097284 -205.612492)
		(end 126.097284 -206.186278)
		(width 0.12065)
		(layer "F.Cu")
		(net "I2C_GPIO_SCL_2")
	)
	(segment
		(start 125.478032 -207.04556)
		(end 125.478032 -207.289654)
		(width 0.12065)
		(layer "F.Cu")
		(net "I2C_GPIO_SCL_2")
	)
	(segment
		(start 124.944124 -208.444592)
		(end 124.944124 -207.823562)
		(width 0.12065)
		(layer "F.Cu")
		(net "I2C_GPIO_SCL_2")
	)
	(via
		(at 125.28677 -207.480916)
		(size 0.7112)
		(drill 0.3556)
		(layers "F.Cu" "B.Cu")
		(net "I2C_GPIO_SCL_2")
	)
	(segment
		(start 71.868284 -192.404492)
		(end 71.868284 -193.053716)
		(width 0.12065)
		(layer "F.Cu")
		(net "I2C_GPIO_SCL_1")
	)
	(segment
		(start 71.628 -193.548)
		(end 70.993 -194.183)
		(width 0.12065)
		(layer "F.Cu")
		(net "I2C_GPIO_SCL_1")
	)
	(segment
		(start 71.628 -193.294)
		(end 71.628 -193.548)
		(width 0.12065)
		(layer "F.Cu")
		(net "I2C_GPIO_SCL_1")
	)
	(segment
		(start 70.715124 -195.236592)
		(end 70.715124 -194.460876)
		(width 0.12065)
		(layer "F.Cu")
		(net "I2C_GPIO_SCL_1")
	)
	(segment
		(start 70.715124 -194.460876)
		(end 70.993 -194.183)
		(width 0.12065)
		(layer "F.Cu")
		(net "I2C_GPIO_SCL_1")
	)
	(segment
		(start 71.868284 -193.053716)
		(end 71.628 -193.294)
		(width 0.12065)
		(layer "F.Cu")
		(net "I2C_GPIO_SCL_1")
	)
	(via
		(at 70.993 -194.183)
		(size 0.7112)
		(drill 0.3556)
		(layers "F.Cu" "B.Cu")
		(net "I2C_GPIO_SCL_1")
	)
	(segment
		(start 9.068562 -185.800238)
		(end 8.7122 -186.1566)
		(width 0.12065)
		(layer "F.Cu")
		(net "HSW_SDA_2")
	)
	(segment
		(start 7.542276 -185.993024)
		(end 7.2517 -186.2836)
		(width 0.12065)
		(layer "F.Cu")
		(net "HSW_SDA_2")
	)
	(segment
		(start 9.967722 -185.800238)
		(end 9.068562 -185.800238)
		(width 0.12065)
		(layer "F.Cu")
		(net "HSW_SDA_2")
	)
	(segment
		(start 8.548624 -185.993024)
		(end 7.542276 -185.993024)
		(width 0.12065)
		(layer "F.Cu")
		(net "HSW_SDA_2")
	)
	(segment
		(start 8.7122 -186.1566)
		(end 8.548624 -185.993024)
		(width 0.12065)
		(layer "F.Cu")
		(net "HSW_SDA_2")
	)
	(segment
		(start 11.3157 -185.414666)
		(end 10.353294 -185.414666)
		(width 0.12065)
		(layer "F.Cu")
		(net "HSW_SDA_2")
	)
	(segment
		(start 10.353294 -185.414666)
		(end 9.967722 -185.800238)
		(width 0.12065)
		(layer "F.Cu")
		(net "HSW_SDA_2")
	)
	(via
		(at 8.7122 -186.1566)
		(size 0.7112)
		(drill 0.3556)
		(layers "F.Cu" "B.Cu")
		(net "HSW_SDA_2")
	)
	(segment
		(start 7.475474 -185.491374)
		(end 7.2517 -185.2676)
		(width 0.12065)
		(layer "F.Cu")
		(net "HSW_SCL_2")
	)
	(segment
		(start 8.847074 -184.871106)
		(end 8.226552 -185.491374)
		(width 0.12065)
		(layer "F.Cu")
		(net "HSW_SCL_2")
	)
	(segment
		(start 8.226552 -185.491374)
		(end 7.475474 -185.491374)
		(width 0.12065)
		(layer "F.Cu")
		(net "HSW_SCL_2")
	)
	(segment
		(start 11.2395 -184.91454)
		(end 10.143744 -184.91454)
		(width 0.12065)
		(layer "F.Cu")
		(net "HSW_SCL_2")
	)
	(segment
		(start 10.143744 -184.91454)
		(end 9.759696 -185.298588)
		(width 0.12065)
		(layer "F.Cu")
		(net "HSW_SCL_2")
	)
	(segment
		(start 9.274556 -185.298588)
		(end 8.847074 -184.871106)
		(width 0.12065)
		(layer "F.Cu")
		(net "HSW_SCL_2")
	)
	(segment
		(start 9.759696 -185.298588)
		(end 9.274556 -185.298588)
		(width 0.12065)
		(layer "F.Cu")
		(net "HSW_SCL_2")
	)
	(via
		(at 8.847074 -184.871106)
		(size 0.7112)
		(drill 0.3556)
		(layers "F.Cu" "B.Cu")
		(net "HSW_SCL_2")
	)
	(segment
		(start 209.413348 -6.54558)
		(end 209.64779 -6.780022)
		(width 0.12065)
		(layer "F.Cu")
		(net "HOST8_RST_N")
	)
	(segment
		(start 209.64779 -6.780022)
		(end 210.564984 -6.780022)
		(width 0.12065)
		(layer "F.Cu")
		(net "HOST8_RST_N")
	)
	(segment
		(start 208.852008 -4.5085)
		(end 209.371438 -5.02793)
		(width 0.12065)
		(layer "F.Cu")
		(net "HOST8_RST_N")
	)
	(segment
		(start 209.371438 -5.02793)
		(end 209.371438 -6.50367)
		(width 0.12065)
		(layer "F.Cu")
		(net "HOST8_RST_N")
	)
	(segment
		(start 211.624418 -6.714236)
		(end 211.624418 -7.4676)
		(width 0.12065)
		(layer "F.Cu")
		(net "HOST8_RST_N")
	)
	(segment
		(start 210.877404 -6.467602)
		(end 211.377784 -6.467602)
		(width 0.12065)
		(layer "F.Cu")
		(net "HOST8_RST_N")
	)
	(segment
		(start 211.377784 -6.467602)
		(end 211.624418 -6.714236)
		(width 0.12065)
		(layer "F.Cu")
		(net "HOST8_RST_N")
	)
	(segment
		(start 210.564984 -6.780022)
		(end 210.877404 -6.467602)
		(width 0.12065)
		(layer "F.Cu")
		(net "HOST8_RST_N")
	)
	(segment
		(start 209.371438 -6.50367)
		(end 209.413348 -6.54558)
		(width 0.12065)
		(layer "F.Cu")
		(net "HOST8_RST_N")
	)
	(via
		(at 209.413348 -6.54558)
		(size 0.508)
		(drill 0.254)
		(layers "F.Cu" "B.Cu")
		(net "HOST8_RST_N")
	)
	(via
		(at 262.522716 -7.674864)
		(size 0.508)
		(drill 0.254)
		(layers "F.Cu" "B.Cu")
		(net "HOST8_RST_N")
	)
	(via
		(at 208.039208 -6.002782)
		(size 0.7112)
		(drill 0.3556)
		(layers "F.Cu" "B.Cu")
		(net "HOST8_RST_N")
	)
	(segment
		(start 208.039208 -6.002782)
		(end 207.899 -5.862574)
		(width 0.12065)
		(layer "B.Cu")
		(net "HOST8_RST_N")
	)
	(segment
		(start 209.22742 -6.731508)
		(end 208.767934 -6.731508)
		(width 0.12065)
		(layer "B.Cu")
		(net "HOST8_RST_N")
	)
	(segment
		(start 265.41349 -6.7564)
		(end 267.0683 -8.41121)
		(width 0.12065)
		(layer "B.Cu")
		(net "HOST8_RST_N")
	)
	(segment
		(start 264.200894 -7.64667)
		(end 265.091164 -6.7564)
		(width 0.12065)
		(layer "B.Cu")
		(net "HOST8_RST_N")
	)
	(segment
		(start 207.899 -5.862574)
		(end 207.899 -4.882134)
		(width 0.12065)
		(layer "B.Cu")
		(net "HOST8_RST_N")
	)
	(segment
		(start 207.899 -4.882134)
		(end 208.293208 -4.487926)
		(width 0.12065)
		(layer "B.Cu")
		(net "HOST8_RST_N")
	)
	(segment
		(start 265.091164 -6.7564)
		(end 265.41349 -6.7564)
		(width 0.12065)
		(layer "B.Cu")
		(net "HOST8_RST_N")
	)
	(segment
		(start 208.293208 -4.487926)
		(end 208.333848 -4.487926)
		(width 0.12065)
		(layer "B.Cu")
		(net "HOST8_RST_N")
	)
	(segment
		(start 262.55091 -7.64667)
		(end 264.200894 -7.64667)
		(width 0.12065)
		(layer "B.Cu")
		(net "HOST8_RST_N")
	)
	(segment
		(start 209.413348 -6.54558)
		(end 209.22742 -6.731508)
		(width 0.12065)
		(layer "B.Cu")
		(net "HOST8_RST_N")
	)
	(segment
		(start 262.522716 -7.674864)
		(end 262.55091 -7.64667)
		(width 0.12065)
		(layer "B.Cu")
		(net "HOST8_RST_N")
	)
	(segment
		(start 208.767934 -6.731508)
		(end 208.039208 -6.002782)
		(width 0.12065)
		(layer "B.Cu")
		(net "HOST8_RST_N")
	)
	(segment
		(start 209.413348 -5.496052)
		(end 209.413348 -6.54558)
		(width 0.127)
		(layer "In5.Cu")
		(net "HOST8_RST_N")
	)
	(segment
		(start 223.149414 -3.670046)
		(end 223.14916 -3.6703)
		(width 0.127)
		(layer "In5.Cu")
		(net "HOST8_RST_N")
	)
	(segment
		(start 262.522716 -7.674864)
		(end 262.438642 -7.758938)
		(width 0.127)
		(layer "In5.Cu")
		(net "HOST8_RST_N")
	)
	(segment
		(start 260.015482 -9.381236)
		(end 259.042662 -8.408416)
		(width 0.127)
		(layer "In5.Cu")
		(net "HOST8_RST_N")
	)
	(segment
		(start 211.2391 -3.6703)
		(end 209.413348 -5.496052)
		(width 0.127)
		(layer "In5.Cu")
		(net "HOST8_RST_N")
	)
	(segment
		(start 243.540026 -5.860034)
		(end 242.43792 -5.860034)
		(width 0.127)
		(layer "In5.Cu")
		(net "HOST8_RST_N")
	)
	(segment
		(start 261.281418 -9.381236)
		(end 260.015482 -9.381236)
		(width 0.127)
		(layer "In5.Cu")
		(net "HOST8_RST_N")
	)
	(segment
		(start 262.438642 -7.758938)
		(end 262.438642 -8.224012)
		(width 0.127)
		(layer "In5.Cu")
		(net "HOST8_RST_N")
	)
	(segment
		(start 259.042662 -8.408416)
		(end 246.088408 -8.408416)
		(width 0.127)
		(layer "In5.Cu")
		(net "HOST8_RST_N")
	)
	(segment
		(start 262.438642 -8.224012)
		(end 261.281418 -9.381236)
		(width 0.127)
		(layer "In5.Cu")
		(net "HOST8_RST_N")
	)
	(segment
		(start 246.088408 -8.408416)
		(end 243.540026 -5.860034)
		(width 0.127)
		(layer "In5.Cu")
		(net "HOST8_RST_N")
	)
	(segment
		(start 242.43792 -5.860034)
		(end 242.369086 -5.7912)
		(width 0.127)
		(layer "In5.Cu")
		(net "HOST8_RST_N")
	)
	(segment
		(start 223.14916 -3.6703)
		(end 211.2391 -3.6703)
		(width 0.127)
		(layer "In5.Cu")
		(net "HOST8_RST_N")
	)
	(segment
		(start 223.464882 -3.670046)
		(end 223.149414 -3.670046)
		(width 0.127)
		(layer "In5.Cu")
		(net "HOST8_RST_N")
	)
	(segment
		(start 225.586036 -5.7912)
		(end 223.464882 -3.670046)
		(width 0.127)
		(layer "In5.Cu")
		(net "HOST8_RST_N")
	)
	(segment
		(start 242.369086 -5.7912)
		(end 225.586036 -5.7912)
		(width 0.127)
		(layer "In5.Cu")
		(net "HOST8_RST_N")
	)
	(segment
		(start 210.789266 -5.877052)
		(end 211.31784 -5.877052)
		(width 0.12065)
		(layer "F.Cu")
		(net "HOST7_RST_N")
	)
	(segment
		(start 211.31784 -5.877052)
		(end 212.024468 -6.58368)
		(width 0.12065)
		(layer "F.Cu")
		(net "HOST7_RST_N")
	)
	(segment
		(start 212.024468 -6.58368)
		(end 212.024468 -7.4676)
		(width 0.12065)
		(layer "F.Cu")
		(net "HOST7_RST_N")
	)
	(segment
		(start 209.868008 -5.766562)
		(end 209.868008 -4.5085)
		(width 0.12065)
		(layer "F.Cu")
		(net "HOST7_RST_N")
	)
	(segment
		(start 210.383882 -6.282436)
		(end 210.789266 -5.877052)
		(width 0.12065)
		(layer "F.Cu")
		(net "HOST7_RST_N")
	)
	(segment
		(start 210.383882 -6.282436)
		(end 209.868008 -5.766562)
		(width 0.12065)
		(layer "F.Cu")
		(net "HOST7_RST_N")
	)
	(via
		(at 209.839814 -5.484876)
		(size 0.7112)
		(drill 0.3556)
		(layers "F.Cu" "B.Cu")
		(net "HOST7_RST_N")
	)
	(via
		(at 265.1887 -7.31901)
		(size 0.508)
		(drill 0.254)
		(layers "F.Cu" "B.Cu")
		(net "HOST7_RST_N")
	)
	(via
		(at 210.383882 -6.282436)
		(size 0.508)
		(drill 0.254)
		(layers "F.Cu" "B.Cu")
		(net "HOST7_RST_N")
	)
	(segment
		(start 265.9253 -8.41121)
		(end 265.9253 -8.05561)
		(width 0.12065)
		(layer "B.Cu")
		(net "HOST7_RST_N")
	)
	(segment
		(start 210.383882 -6.282436)
		(end 210.383882 -6.028944)
		(width 0.12065)
		(layer "B.Cu")
		(net "HOST7_RST_N")
	)
	(segment
		(start 265.9253 -8.05561)
		(end 265.1887 -7.31901)
		(width 0.12065)
		(layer "B.Cu")
		(net "HOST7_RST_N")
	)
	(segment
		(start 209.839814 -5.484876)
		(end 209.841084 -5.483606)
		(width 0.12065)
		(layer "B.Cu")
		(net "HOST7_RST_N")
	)
	(segment
		(start 209.841084 -5.483606)
		(end 209.841084 -4.333748)
		(width 0.12065)
		(layer "B.Cu")
		(net "HOST7_RST_N")
	)
	(segment
		(start 210.383882 -6.028944)
		(end 209.839814 -5.484876)
		(width 0.12065)
		(layer "B.Cu")
		(net "HOST7_RST_N")
	)
	(segment
		(start 209.841084 -4.333748)
		(end 209.839052 -4.331716)
		(width 0.12065)
		(layer "B.Cu")
		(net "HOST7_RST_N")
	)
	(segment
		(start 259.857494 -9.762236)
		(end 261.555484 -9.762236)
		(width 0.127)
		(layer "In5.Cu")
		(net "HOST7_RST_N")
	)
	(segment
		(start 261.555484 -9.762236)
		(end 263.02843 -8.28929)
		(width 0.127)
		(layer "In5.Cu")
		(net "HOST7_RST_N")
	)
	(segment
		(start 263.416288 -7.4422)
		(end 265.06551 -7.4422)
		(width 0.127)
		(layer "In5.Cu")
		(net "HOST7_RST_N")
	)
	(segment
		(start 263.02843 -8.28929)
		(end 263.02843 -7.830058)
		(width 0.127)
		(layer "In5.Cu")
		(net "HOST7_RST_N")
	)
	(segment
		(start 210.383882 -6.282436)
		(end 210.383882 -5.156962)
		(width 0.127)
		(layer "In5.Cu")
		(net "HOST7_RST_N")
	)
	(segment
		(start 244.828314 -8.789416)
		(end 258.884674 -8.789416)
		(width 0.127)
		(layer "In5.Cu")
		(net "HOST7_RST_N")
	)
	(segment
		(start 265.06551 -7.4422)
		(end 265.1887 -7.31901)
		(width 0.127)
		(layer "In5.Cu")
		(net "HOST7_RST_N")
	)
	(segment
		(start 263.02843 -7.830058)
		(end 263.416288 -7.4422)
		(width 0.127)
		(layer "In5.Cu")
		(net "HOST7_RST_N")
	)
	(segment
		(start 225.428048 -6.1722)
		(end 242.211098 -6.1722)
		(width 0.127)
		(layer "In5.Cu")
		(net "HOST7_RST_N")
	)
	(segment
		(start 210.383882 -5.156962)
		(end 211.489544 -4.0513)
		(width 0.127)
		(layer "In5.Cu")
		(net "HOST7_RST_N")
	)
	(segment
		(start 258.884674 -8.789416)
		(end 259.857494 -9.762236)
		(width 0.127)
		(layer "In5.Cu")
		(net "HOST7_RST_N")
	)
	(segment
		(start 242.211098 -6.1722)
		(end 244.828314 -8.789416)
		(width 0.127)
		(layer "In5.Cu")
		(net "HOST7_RST_N")
	)
	(segment
		(start 211.489544 -4.0513)
		(end 223.307148 -4.0513)
		(width 0.127)
		(layer "In5.Cu")
		(net "HOST7_RST_N")
	)
	(segment
		(start 223.307148 -4.0513)
		(end 225.428048 -6.1722)
		(width 0.127)
		(layer "In5.Cu")
		(net "HOST7_RST_N")
	)
	(segment
		(start 211.2518 -5.2832)
		(end 212.424518 -6.455918)
		(width 0.12065)
		(layer "F.Cu")
		(net "HOST6_RST_N")
	)
	(segment
		(start 210.947 -5.2832)
		(end 211.2518 -5.2832)
		(width 0.12065)
		(layer "F.Cu")
		(net "HOST6_RST_N")
	)
	(segment
		(start 210.884008 -5.220208)
		(end 210.947 -5.2832)
		(width 0.12065)
		(layer "F.Cu")
		(net "HOST6_RST_N")
	)
	(segment
		(start 210.884008 -4.5085)
		(end 210.884008 -5.220208)
		(width 0.12065)
		(layer "F.Cu")
		(net "HOST6_RST_N")
	)
	(segment
		(start 212.424518 -6.455918)
		(end 212.424518 -7.4676)
		(width 0.12065)
		(layer "F.Cu")
		(net "HOST6_RST_N")
	)
	(via
		(at 210.947 -5.2832)
		(size 0.508)
		(drill 0.254)
		(layers "F.Cu" "B.Cu")
		(net "HOST6_RST_N")
	)
	(via
		(at 266.56538 -13.652246)
		(size 0.508)
		(drill 0.254)
		(layers "F.Cu" "B.Cu")
		(net "HOST6_RST_N")
	)
	(via
		(at 211.644484 -6.284214)
		(size 0.7112)
		(drill 0.3556)
		(layers "F.Cu" "B.Cu")
		(net "HOST6_RST_N")
	)
	(segment
		(start 211.213954 -4.5085)
		(end 211.42706 -4.721606)
		(width 0.12065)
		(layer "B.Cu")
		(net "HOST6_RST_N")
	)
	(segment
		(start 211.42706 -4.721606)
		(end 211.42706 -5.407406)
		(width 0.12065)
		(layer "B.Cu")
		(net "HOST6_RST_N")
	)
	(segment
		(start 266.692126 -12.190984)
		(end 267.221208 -11.661902)
		(width 0.12065)
		(layer "B.Cu")
		(net "HOST6_RST_N")
	)
	(segment
		(start 211.42706 -5.407406)
		(end 211.652866 -5.633212)
		(width 0.12065)
		(layer "B.Cu")
		(net "HOST6_RST_N")
	)
	(segment
		(start 211.652866 -5.633212)
		(end 211.652866 -6.275832)
		(width 0.12065)
		(layer "B.Cu")
		(net "HOST6_RST_N")
	)
	(segment
		(start 211.112608 -5.985002)
		(end 211.112608 -6.003036)
		(width 0.12065)
		(layer "B.Cu")
		(net "HOST6_RST_N")
	)
	(segment
		(start 210.947 -5.2832)
		(end 210.941412 -5.288788)
		(width 0.12065)
		(layer "B.Cu")
		(net "HOST6_RST_N")
	)
	(segment
		(start 210.941412 -5.813806)
		(end 211.112608 -5.985002)
		(width 0.12065)
		(layer "B.Cu")
		(net "HOST6_RST_N")
	)
	(segment
		(start 267.221208 -11.661902)
		(end 269.135098 -11.661902)
		(width 0.12065)
		(layer "B.Cu")
		(net "HOST6_RST_N")
	)
	(segment
		(start 266.692126 -13.5255)
		(end 266.692126 -12.190984)
		(width 0.12065)
		(layer "B.Cu")
		(net "HOST6_RST_N")
	)
	(segment
		(start 266.56538 -13.652246)
		(end 266.692126 -13.5255)
		(width 0.12065)
		(layer "B.Cu")
		(net "HOST6_RST_N")
	)
	(segment
		(start 211.652866 -6.275832)
		(end 211.644484 -6.284214)
		(width 0.12065)
		(layer "B.Cu")
		(net "HOST6_RST_N")
	)
	(segment
		(start 210.884008 -4.5085)
		(end 211.213954 -4.5085)
		(width 0.12065)
		(layer "B.Cu")
		(net "HOST6_RST_N")
	)
	(segment
		(start 211.112608 -6.003036)
		(end 211.393786 -6.284214)
		(width 0.12065)
		(layer "B.Cu")
		(net "HOST6_RST_N")
	)
	(segment
		(start 211.393786 -6.284214)
		(end 211.644484 -6.284214)
		(width 0.12065)
		(layer "B.Cu")
		(net "HOST6_RST_N")
	)
	(segment
		(start 269.135098 -11.661902)
		(end 269.538958 -11.258042)
		(width 0.12065)
		(layer "B.Cu")
		(net "HOST6_RST_N")
	)
	(segment
		(start 269.538958 -11.258042)
		(end 269.74165 -11.258042)
		(width 0.12065)
		(layer "B.Cu")
		(net "HOST6_RST_N")
	)
	(segment
		(start 210.941412 -5.288788)
		(end 210.941412 -5.813806)
		(width 0.12065)
		(layer "B.Cu")
		(net "HOST6_RST_N")
	)
	(segment
		(start 263.288018 -14.175486)
		(end 266.04214 -14.175486)
		(width 0.127)
		(layer "In5.Cu")
		(net "HOST6_RST_N")
	)
	(segment
		(start 222.30969 -5.27431)
		(end 222.4405 -5.1435)
		(width 0.127)
		(layer "In5.Cu")
		(net "HOST6_RST_N")
	)
	(segment
		(start 225.27006 -6.5532)
		(end 242.05311 -6.5532)
		(width 0.127)
		(layer "In5.Cu")
		(net "HOST6_RST_N")
	)
	(segment
		(start 244.670326 -9.170416)
		(end 258.726686 -9.170416)
		(width 0.127)
		(layer "In5.Cu")
		(net "HOST6_RST_N")
	)
	(segment
		(start 261.980426 -12.867894)
		(end 263.288018 -14.175486)
		(width 0.127)
		(layer "In5.Cu")
		(net "HOST6_RST_N")
	)
	(segment
		(start 210.9978 -5.2832)
		(end 211.8487 -4.4323)
		(width 0.127)
		(layer "In5.Cu")
		(net "HOST6_RST_N")
	)
	(segment
		(start 211.8487 -4.4323)
		(end 219.1385 -4.4323)
		(width 0.127)
		(layer "In5.Cu")
		(net "HOST6_RST_N")
	)
	(segment
		(start 259.765292 -10.209022)
		(end 261.150608 -10.209022)
		(width 0.127)
		(layer "In5.Cu")
		(net "HOST6_RST_N")
	)
	(segment
		(start 261.980426 -11.03884)
		(end 261.980426 -12.867894)
		(width 0.127)
		(layer "In5.Cu")
		(net "HOST6_RST_N")
	)
	(segment
		(start 223.860106 -5.143246)
		(end 225.27006 -6.5532)
		(width 0.127)
		(layer "In5.Cu")
		(net "HOST6_RST_N")
	)
	(segment
		(start 210.947 -5.2832)
		(end 210.9978 -5.2832)
		(width 0.127)
		(layer "In5.Cu")
		(net "HOST6_RST_N")
	)
	(segment
		(start 242.05311 -6.5532)
		(end 244.670326 -9.170416)
		(width 0.127)
		(layer "In5.Cu")
		(net "HOST6_RST_N")
	)
	(segment
		(start 222.4405 -5.1435)
		(end 223.544384 -5.1435)
		(width 0.127)
		(layer "In5.Cu")
		(net "HOST6_RST_N")
	)
	(segment
		(start 219.98051 -5.27431)
		(end 222.30969 -5.27431)
		(width 0.127)
		(layer "In5.Cu")
		(net "HOST6_RST_N")
	)
	(segment
		(start 223.544638 -5.143246)
		(end 223.860106 -5.143246)
		(width 0.127)
		(layer "In5.Cu")
		(net "HOST6_RST_N")
	)
	(segment
		(start 266.04214 -14.175486)
		(end 266.56538 -13.652246)
		(width 0.127)
		(layer "In5.Cu")
		(net "HOST6_RST_N")
	)
	(segment
		(start 261.150608 -10.209022)
		(end 261.980426 -11.03884)
		(width 0.127)
		(layer "In5.Cu")
		(net "HOST6_RST_N")
	)
	(segment
		(start 219.1385 -4.4323)
		(end 219.98051 -5.27431)
		(width 0.127)
		(layer "In5.Cu")
		(net "HOST6_RST_N")
	)
	(segment
		(start 258.726686 -9.170416)
		(end 259.765292 -10.209022)
		(width 0.127)
		(layer "In5.Cu")
		(net "HOST6_RST_N")
	)
	(segment
		(start 223.544384 -5.1435)
		(end 223.544638 -5.143246)
		(width 0.127)
		(layer "In5.Cu")
		(net "HOST6_RST_N")
	)
	(segment
		(start 212.824568 -7.4676)
		(end 212.824568 -6.343904)
		(width 0.12065)
		(layer "F.Cu")
		(net "HOST5_RST_N")
	)
	(segment
		(start 211.900008 -5.220208)
		(end 211.963 -5.2832)
		(width 0.12065)
		(layer "F.Cu")
		(net "HOST5_RST_N")
	)
	(segment
		(start 212.824568 -6.343904)
		(end 211.963 -5.482336)
		(width 0.12065)
		(layer "F.Cu")
		(net "HOST5_RST_N")
	)
	(segment
		(start 211.900008 -4.5085)
		(end 211.900008 -5.220208)
		(width 0.12065)
		(layer "F.Cu")
		(net "HOST5_RST_N")
	)
	(segment
		(start 211.963 -5.482336)
		(end 211.963 -5.2832)
		(width 0.12065)
		(layer "F.Cu")
		(net "HOST5_RST_N")
	)
	(via
		(at 267.396976 -12.305284)
		(size 0.7112)
		(drill 0.3556)
		(layers "F.Cu" "B.Cu")
		(net "HOST5_RST_N")
	)
	(via
		(at 211.963 -5.2832)
		(size 0.508)
		(drill 0.254)
		(layers "F.Cu" "B.Cu")
		(net "HOST5_RST_N")
	)
	(via
		(at 266.642088 -14.543786)
		(size 0.508)
		(drill 0.254)
		(layers "F.Cu" "B.Cu")
		(net "HOST5_RST_N")
	)
	(segment
		(start 267.396976 -12.305284)
		(end 267.076428 -12.625832)
		(width 0.12065)
		(layer "B.Cu")
		(net "HOST5_RST_N")
	)
	(segment
		(start 269.645892 -12.305284)
		(end 269.74165 -12.401042)
		(width 0.12065)
		(layer "B.Cu")
		(net "HOST5_RST_N")
	)
	(segment
		(start 211.900008 -4.5085)
		(end 211.900008 -5.220208)
		(width 0.12065)
		(layer "B.Cu")
		(net "HOST5_RST_N")
	)
	(segment
		(start 267.396976 -12.305284)
		(end 269.645892 -12.305284)
		(width 0.12065)
		(layer "B.Cu")
		(net "HOST5_RST_N")
	)
	(segment
		(start 266.642088 -14.4018)
		(end 266.642088 -14.543786)
		(width 0.12065)
		(layer "B.Cu")
		(net "HOST5_RST_N")
	)
	(segment
		(start 267.076428 -13.96746)
		(end 266.642088 -14.4018)
		(width 0.12065)
		(layer "B.Cu")
		(net "HOST5_RST_N")
	)
	(segment
		(start 211.900008 -5.220208)
		(end 211.963 -5.2832)
		(width 0.12065)
		(layer "B.Cu")
		(net "HOST5_RST_N")
	)
	(segment
		(start 267.076428 -12.625832)
		(end 267.076428 -13.96746)
		(width 0.12065)
		(layer "B.Cu")
		(net "HOST5_RST_N")
	)
	(segment
		(start 223.702372 -5.5245)
		(end 222.598488 -5.5245)
		(width 0.127)
		(layer "In5.Cu")
		(net "HOST5_RST_N")
	)
	(segment
		(start 266.200128 -14.556486)
		(end 263.064752 -14.556486)
		(width 0.127)
		(layer "In5.Cu")
		(net "HOST5_RST_N")
	)
	(segment
		(start 218.9607 -4.8133)
		(end 212.4329 -4.8133)
		(width 0.127)
		(layer "In5.Cu")
		(net "HOST5_RST_N")
	)
	(segment
		(start 260.949186 -10.60069)
		(end 259.617972 -10.60069)
		(width 0.127)
		(layer "In5.Cu")
		(net "HOST5_RST_N")
	)
	(segment
		(start 212.4329 -4.8133)
		(end 211.963 -5.2832)
		(width 0.127)
		(layer "In5.Cu")
		(net "HOST5_RST_N")
	)
	(segment
		(start 222.598488 -5.5245)
		(end 222.467678 -5.65531)
		(width 0.127)
		(layer "In5.Cu")
		(net "HOST5_RST_N")
	)
	(segment
		(start 219.80271 -5.65531)
		(end 218.9607 -4.8133)
		(width 0.127)
		(layer "In5.Cu")
		(net "HOST5_RST_N")
	)
	(segment
		(start 261.599426 -11.25093)
		(end 260.949186 -10.60069)
		(width 0.127)
		(layer "In5.Cu")
		(net "HOST5_RST_N")
	)
	(segment
		(start 225.112072 -6.9342)
		(end 223.702372 -5.5245)
		(width 0.127)
		(layer "In5.Cu")
		(net "HOST5_RST_N")
	)
	(segment
		(start 263.064752 -14.556486)
		(end 261.599426 -13.09116)
		(width 0.127)
		(layer "In5.Cu")
		(net "HOST5_RST_N")
	)
	(segment
		(start 222.467678 -5.65531)
		(end 219.80271 -5.65531)
		(width 0.127)
		(layer "In5.Cu")
		(net "HOST5_RST_N")
	)
	(segment
		(start 258.568698 -9.551416)
		(end 244.512338 -9.551416)
		(width 0.127)
		(layer "In5.Cu")
		(net "HOST5_RST_N")
	)
	(segment
		(start 259.617972 -10.60069)
		(end 258.568698 -9.551416)
		(width 0.127)
		(layer "In5.Cu")
		(net "HOST5_RST_N")
	)
	(segment
		(start 244.512338 -9.551416)
		(end 241.895122 -6.9342)
		(width 0.127)
		(layer "In5.Cu")
		(net "HOST5_RST_N")
	)
	(segment
		(start 266.642088 -14.543786)
		(end 266.212828 -14.543786)
		(width 0.127)
		(layer "In5.Cu")
		(net "HOST5_RST_N")
	)
	(segment
		(start 241.895122 -6.9342)
		(end 225.112072 -6.9342)
		(width 0.127)
		(layer "In5.Cu")
		(net "HOST5_RST_N")
	)
	(segment
		(start 266.212828 -14.543786)
		(end 266.200128 -14.556486)
		(width 0.127)
		(layer "In5.Cu")
		(net "HOST5_RST_N")
	)
	(segment
		(start 261.599426 -13.09116)
		(end 261.599426 -11.25093)
		(width 0.127)
		(layer "In5.Cu")
		(net "HOST5_RST_N")
	)
	(segment
		(start 212.916008 -5.321808)
		(end 212.916008 -5.2832)
		(width 0.12065)
		(layer "F.Cu")
		(net "HOST4_RST_N")
	)
	(segment
		(start 182.564532 -5.651246)
		(end 182.628032 -5.587746)
		(width 0.12065)
		(layer "F.Cu")
		(net "HOST4_RST_N")
	)
	(segment
		(start 182.564532 -6.337808)
		(end 182.564532 -5.651246)
		(width 0.12065)
		(layer "F.Cu")
		(net "HOST4_RST_N")
	)
	(segment
		(start 213.224618 -7.4676)
		(end 213.224618 -5.630418)
		(width 0.12065)
		(layer "F.Cu")
		(net "HOST4_RST_N")
	)
	(segment
		(start 183.999886 -7.267702)
		(end 183.53024 -6.798056)
		(width 0.12065)
		(layer "F.Cu")
		(net "HOST4_RST_N")
	)
	(segment
		(start 213.224618 -5.630418)
		(end 212.916008 -5.321808)
		(width 0.12065)
		(layer "F.Cu")
		(net "HOST4_RST_N")
	)
	(segment
		(start 183.02478 -6.798056)
		(end 182.564532 -6.337808)
		(width 0.12065)
		(layer "F.Cu")
		(net "HOST4_RST_N")
	)
	(segment
		(start 183.53024 -6.798056)
		(end 183.02478 -6.798056)
		(width 0.12065)
		(layer "F.Cu")
		(net "HOST4_RST_N")
	)
	(segment
		(start 212.916008 -4.5085)
		(end 212.916008 -5.2832)
		(width 0.12065)
		(layer "F.Cu")
		(net "HOST4_RST_N")
	)
	(via
		(at 212.916008 -5.2832)
		(size 0.508)
		(drill 0.254)
		(layers "F.Cu" "B.Cu")
		(net "HOST4_RST_N")
	)
	(via
		(at 182.628032 -5.587746)
		(size 0.508)
		(drill 0.254)
		(layers "F.Cu" "B.Cu")
		(net "HOST4_RST_N")
	)
	(via
		(at 213.075774 -6.90753)
		(size 0.7112)
		(drill 0.3556)
		(layers "F.Cu" "B.Cu")
		(net "HOST4_RST_N")
	)
	(segment
		(start 213.051898 -6.883654)
		(end 213.075774 -6.90753)
		(width 0.12065)
		(layer "B.Cu")
		(net "HOST4_RST_N")
	)
	(segment
		(start 213.051898 -5.41909)
		(end 213.051898 -6.883654)
		(width 0.12065)
		(layer "B.Cu")
		(net "HOST4_RST_N")
	)
	(segment
		(start 212.916008 -4.5085)
		(end 212.916008 -5.2832)
		(width 0.12065)
		(layer "B.Cu")
		(net "HOST4_RST_N")
	)
	(segment
		(start 212.916008 -5.2832)
		(end 213.051898 -5.41909)
		(width 0.12065)
		(layer "B.Cu")
		(net "HOST4_RST_N")
	)
	(segment
		(start 197.492366 -6.489446)
		(end 196.433694 -7.548118)
		(width 0.127)
		(layer "In5.Cu")
		(net "HOST4_RST_N")
	)
	(segment
		(start 197.807834 -6.489446)
		(end 197.492366 -6.489446)
		(width 0.127)
		(layer "In5.Cu")
		(net "HOST4_RST_N")
	)
	(segment
		(start 205.217014 -7.01548)
		(end 204.691234 -6.4897)
		(width 0.127)
		(layer "In5.Cu")
		(net "HOST4_RST_N")
	)
	(segment
		(start 183.148478 -5.0673)
		(end 182.628032 -5.587746)
		(width 0.127)
		(layer "In5.Cu")
		(net "HOST4_RST_N")
	)
	(segment
		(start 204.691234 -6.4897)
		(end 197.808088 -6.4897)
		(width 0.127)
		(layer "In5.Cu")
		(net "HOST4_RST_N")
	)
	(segment
		(start 185.878216 -5.0673)
		(end 183.148478 -5.0673)
		(width 0.127)
		(layer "In5.Cu")
		(net "HOST4_RST_N")
	)
	(segment
		(start 196.433694 -7.548118)
		(end 188.359034 -7.548118)
		(width 0.127)
		(layer "In5.Cu")
		(net "HOST4_RST_N")
	)
	(segment
		(start 197.808088 -6.4897)
		(end 197.807834 -6.489446)
		(width 0.127)
		(layer "In5.Cu")
		(net "HOST4_RST_N")
	)
	(segment
		(start 211.183728 -7.01548)
		(end 205.217014 -7.01548)
		(width 0.127)
		(layer "In5.Cu")
		(net "HOST4_RST_N")
	)
	(segment
		(start 188.359034 -7.548118)
		(end 185.878216 -5.0673)
		(width 0.127)
		(layer "In5.Cu")
		(net "HOST4_RST_N")
	)
	(segment
		(start 212.916008 -5.2832)
		(end 211.183728 -7.01548)
		(width 0.127)
		(layer "In5.Cu")
		(net "HOST4_RST_N")
	)
	(segment
		(start 213.623398 -7.4676)
		(end 213.623398 -5.59181)
		(width 0.12065)
		(layer "F.Cu")
		(net "HOST3_RST_N")
	)
	(segment
		(start 213.779608 -5.219192)
		(end 213.779608 -5.2832)
		(width 0.12065)
		(layer "F.Cu")
		(net "HOST3_RST_N")
	)
	(segment
		(start 213.7156 -5.347208)
		(end 213.779608 -5.2832)
		(width 0.12065)
		(layer "F.Cu")
		(net "HOST3_RST_N")
	)
	(segment
		(start 213.7156 -5.499608)
		(end 213.7156 -5.347208)
		(width 0.12065)
		(layer "F.Cu")
		(net "HOST3_RST_N")
	)
	(segment
		(start 213.932008 -5.066792)
		(end 213.779608 -5.219192)
		(width 0.12065)
		(layer "F.Cu")
		(net "HOST3_RST_N")
	)
	(segment
		(start 183.298846 -6.260084)
		(end 183.298846 -4.919726)
		(width 0.12065)
		(layer "F.Cu")
		(net "HOST3_RST_N")
	)
	(segment
		(start 183.36006 -6.321298)
		(end 183.298846 -6.260084)
		(width 0.12065)
		(layer "F.Cu")
		(net "HOST3_RST_N")
	)
	(segment
		(start 183.298846 -4.919726)
		(end 183.0578 -4.67868)
		(width 0.12065)
		(layer "F.Cu")
		(net "HOST3_RST_N")
	)
	(segment
		(start 213.932008 -4.5085)
		(end 213.932008 -5.066792)
		(width 0.12065)
		(layer "F.Cu")
		(net "HOST3_RST_N")
	)
	(segment
		(start 213.623398 -5.59181)
		(end 213.7156 -5.499608)
		(width 0.12065)
		(layer "F.Cu")
		(net "HOST3_RST_N")
	)
	(via
		(at 213.779608 -5.2832)
		(size 0.508)
		(drill 0.254)
		(layers "F.Cu" "B.Cu")
		(net "HOST3_RST_N")
	)
	(via
		(at 214.26043 -6.353048)
		(size 0.7112)
		(drill 0.3556)
		(layers "F.Cu" "B.Cu")
		(net "HOST3_RST_N")
	)
	(via
		(at 183.36006 -6.321298)
		(size 0.508)
		(drill 0.254)
		(layers "F.Cu" "B.Cu")
		(net "HOST3_RST_N")
	)
	(segment
		(start 213.932008 -4.5085)
		(end 213.932008 -5.066792)
		(width 0.12065)
		(layer "B.Cu")
		(net "HOST3_RST_N")
	)
	(segment
		(start 213.932008 -5.066792)
		(end 213.779608 -5.219192)
		(width 0.12065)
		(layer "B.Cu")
		(net "HOST3_RST_N")
	)
	(segment
		(start 213.779608 -5.2832)
		(end 214.26043 -5.764022)
		(width 0.12065)
		(layer "B.Cu")
		(net "HOST3_RST_N")
	)
	(segment
		(start 214.26043 -5.764022)
		(end 214.26043 -6.353048)
		(width 0.12065)
		(layer "B.Cu")
		(net "HOST3_RST_N")
	)
	(segment
		(start 213.779608 -5.219192)
		(end 213.779608 -5.2832)
		(width 0.12065)
		(layer "B.Cu")
		(net "HOST3_RST_N")
	)
	(segment
		(start 197.6501 -6.8707)
		(end 204.533246 -6.8707)
		(width 0.127)
		(layer "In5.Cu")
		(net "HOST3_RST_N")
	)
	(segment
		(start 205.059026 -7.39648)
		(end 211.666328 -7.39648)
		(width 0.127)
		(layer "In5.Cu")
		(net "HOST3_RST_N")
	)
	(segment
		(start 188.201046 -7.929118)
		(end 196.591682 -7.929118)
		(width 0.127)
		(layer "In5.Cu")
		(net "HOST3_RST_N")
	)
	(segment
		(start 183.724042 -5.4483)
		(end 185.720228 -5.4483)
		(width 0.127)
		(layer "In5.Cu")
		(net "HOST3_RST_N")
	)
	(segment
		(start 183.36006 -5.812282)
		(end 183.724042 -5.4483)
		(width 0.127)
		(layer "In5.Cu")
		(net "HOST3_RST_N")
	)
	(segment
		(start 183.36006 -6.321298)
		(end 183.36006 -5.812282)
		(width 0.127)
		(layer "In5.Cu")
		(net "HOST3_RST_N")
	)
	(segment
		(start 196.591682 -7.929118)
		(end 197.6501 -6.8707)
		(width 0.127)
		(layer "In5.Cu")
		(net "HOST3_RST_N")
	)
	(segment
		(start 204.533246 -6.8707)
		(end 205.059026 -7.39648)
		(width 0.127)
		(layer "In5.Cu")
		(net "HOST3_RST_N")
	)
	(segment
		(start 185.720228 -5.4483)
		(end 188.201046 -7.929118)
		(width 0.127)
		(layer "In5.Cu")
		(net "HOST3_RST_N")
	)
	(segment
		(start 211.666328 -7.39648)
		(end 213.779608 -5.2832)
		(width 0.127)
		(layer "In5.Cu")
		(net "HOST3_RST_N")
	)
	(segment
		(start 214.023448 -5.90296)
		(end 214.643208 -5.2832)
		(width 0.12065)
		(layer "F.Cu")
		(net "HOST2_RST_N")
	)
	(segment
		(start 184.229756 -6.286754)
		(end 184.229756 -5.46227)
		(width 0.12065)
		(layer "F.Cu")
		(net "HOST2_RST_N")
	)
	(segment
		(start 184.229756 -5.46227)
		(end 184.10428 -5.336794)
		(width 0.12065)
		(layer "F.Cu")
		(net "HOST2_RST_N")
	)
	(segment
		(start 214.801196 -5.125212)
		(end 214.643208 -5.2832)
		(width 0.12065)
		(layer "F.Cu")
		(net "HOST2_RST_N")
	)
	(segment
		(start 214.801196 -4.99618)
		(end 214.801196 -5.125212)
		(width 0.12065)
		(layer "F.Cu")
		(net "HOST2_RST_N")
	)
	(segment
		(start 214.948008 -4.5085)
		(end 214.948008 -4.849368)
		(width 0.12065)
		(layer "F.Cu")
		(net "HOST2_RST_N")
	)
	(segment
		(start 214.023448 -7.4676)
		(end 214.023448 -5.90296)
		(width 0.12065)
		(layer "F.Cu")
		(net "HOST2_RST_N")
	)
	(segment
		(start 214.948008 -4.849368)
		(end 214.801196 -4.99618)
		(width 0.12065)
		(layer "F.Cu")
		(net "HOST2_RST_N")
	)
	(segment
		(start 184.10428 -5.336794)
		(end 184.10428 -4.69646)
		(width 0.12065)
		(layer "F.Cu")
		(net "HOST2_RST_N")
	)
	(via
		(at 214.643208 -5.2832)
		(size 0.508)
		(drill 0.254)
		(layers "F.Cu" "B.Cu")
		(net "HOST2_RST_N")
	)
	(via
		(at 215.53043 -6.340094)
		(size 0.7112)
		(drill 0.3556)
		(layers "F.Cu" "B.Cu")
		(net "HOST2_RST_N")
	)
	(via
		(at 184.229756 -6.286754)
		(size 0.508)
		(drill 0.254)
		(layers "F.Cu" "B.Cu")
		(net "HOST2_RST_N")
	)
	(segment
		(start 214.948008 -4.5085)
		(end 214.948008 -5.041392)
		(width 0.12065)
		(layer "B.Cu")
		(net "HOST2_RST_N")
	)
	(segment
		(start 214.7062 -5.2832)
		(end 214.643208 -5.2832)
		(width 0.12065)
		(layer "B.Cu")
		(net "HOST2_RST_N")
	)
	(segment
		(start 214.948008 -5.041392)
		(end 214.7062 -5.2832)
		(width 0.12065)
		(layer "B.Cu")
		(net "HOST2_RST_N")
	)
	(segment
		(start 215.523826 -6.340348)
		(end 215.52408 -6.340094)
		(width 0.12065)
		(layer "B.Cu")
		(net "HOST2_RST_N")
	)
	(segment
		(start 214.643208 -5.45973)
		(end 215.523826 -6.340348)
		(width 0.12065)
		(layer "B.Cu")
		(net "HOST2_RST_N")
	)
	(segment
		(start 214.643208 -5.2832)
		(end 214.643208 -5.45973)
		(width 0.12065)
		(layer "B.Cu")
		(net "HOST2_RST_N")
	)
	(segment
		(start 215.52408 -6.340094)
		(end 215.53043 -6.340094)
		(width 0.12065)
		(layer "B.Cu")
		(net "HOST2_RST_N")
	)
	(segment
		(start 184.68721 -5.8293)
		(end 184.229756 -6.286754)
		(width 0.127)
		(layer "In5.Cu")
		(net "HOST2_RST_N")
	)
	(segment
		(start 212.037168 -7.889494)
		(end 210.871562 -7.889494)
		(width 0.127)
		(layer "In5.Cu")
		(net "HOST2_RST_N")
	)
	(segment
		(start 214.643208 -5.2832)
		(end 212.037168 -7.889494)
		(width 0.127)
		(layer "In5.Cu")
		(net "HOST2_RST_N")
	)
	(segment
		(start 188.043058 -8.310118)
		(end 185.56224 -5.8293)
		(width 0.127)
		(layer "In5.Cu")
		(net "HOST2_RST_N")
	)
	(segment
		(start 210.871562 -7.889494)
		(end 210.450938 -8.310118)
		(width 0.127)
		(layer "In5.Cu")
		(net "HOST2_RST_N")
	)
	(segment
		(start 185.56224 -5.8293)
		(end 184.68721 -5.8293)
		(width 0.127)
		(layer "In5.Cu")
		(net "HOST2_RST_N")
	)
	(segment
		(start 210.450938 -8.310118)
		(end 188.043058 -8.310118)
		(width 0.127)
		(layer "In5.Cu")
		(net "HOST2_RST_N")
	)
	(segment
		(start 215.9762 -4.993386)
		(end 215.658954 -5.310632)
		(width 0.12065)
		(layer "F.Cu")
		(net "HOST1_RST_N")
	)
	(segment
		(start 185.15584 -6.087618)
		(end 185.15584 -4.71932)
		(width 0.12065)
		(layer "F.Cu")
		(net "HOST1_RST_N")
	)
	(segment
		(start 185.166 -6.2992)
		(end 185.166 -6.097778)
		(width 0.12065)
		(layer "F.Cu")
		(net "HOST1_RST_N")
	)
	(segment
		(start 185.166 -6.097778)
		(end 185.15584 -6.087618)
		(width 0.12065)
		(layer "F.Cu")
		(net "HOST1_RST_N")
	)
	(segment
		(start 215.9762 -4.5085)
		(end 215.9762 -4.993386)
		(width 0.12065)
		(layer "F.Cu")
		(net "HOST1_RST_N")
	)
	(via
		(at 185.166 -6.2992)
		(size 0.508)
		(drill 0.254)
		(layers "F.Cu" "B.Cu")
		(net "HOST1_RST_N")
	)
	(via
		(at 219.329 -7.112)
		(size 0.7112)
		(drill 0.3556)
		(layers "F.Cu" "B.Cu")
		(net "HOST1_RST_N")
	)
	(via
		(at 215.658954 -5.310632)
		(size 0.508)
		(drill 0.254)
		(layers "F.Cu" "B.Cu")
		(net "HOST1_RST_N")
	)
	(segment
		(start 221.7674 -7.8105)
		(end 221.75724 -7.82066)
		(width 0.12065)
		(layer "B.Cu")
		(net "HOST1_RST_N")
	)
	(segment
		(start 215.658954 -5.310632)
		(end 216.079832 -5.310632)
		(width 0.12065)
		(layer "B.Cu")
		(net "HOST1_RST_N")
	)
	(segment
		(start 219.471494 -7.254494)
		(end 219.329 -7.112)
		(width 0.12065)
		(layer "B.Cu")
		(net "HOST1_RST_N")
	)
	(segment
		(start 218.1352 -5.9182)
		(end 219.329 -7.112)
		(width 0.12065)
		(layer "B.Cu")
		(net "HOST1_RST_N")
	)
	(segment
		(start 216.079832 -5.310632)
		(end 216.6874 -5.9182)
		(width 0.12065)
		(layer "B.Cu")
		(net "HOST1_RST_N")
	)
	(segment
		(start 222.8342 -7.8105)
		(end 221.7674 -7.8105)
		(width 0.12065)
		(layer "B.Cu")
		(net "HOST1_RST_N")
	)
	(segment
		(start 216.6874 -5.9182)
		(end 218.1352 -5.9182)
		(width 0.12065)
		(layer "B.Cu")
		(net "HOST1_RST_N")
	)
	(segment
		(start 221.7674 -7.8105)
		(end 221.211394 -7.254494)
		(width 0.12065)
		(layer "B.Cu")
		(net "HOST1_RST_N")
	)
	(segment
		(start 221.75724 -7.82066)
		(end 221.75724 -9.4869)
		(width 0.12065)
		(layer "B.Cu")
		(net "HOST1_RST_N")
	)
	(segment
		(start 221.211394 -7.254494)
		(end 219.471494 -7.254494)
		(width 0.12065)
		(layer "B.Cu")
		(net "HOST1_RST_N")
	)
	(segment
		(start 211.759292 -9.210294)
		(end 215.658954 -5.310632)
		(width 0.127)
		(layer "In5.Cu")
		(net "HOST1_RST_N")
	)
	(segment
		(start 187.557918 -8.691118)
		(end 210.362292 -8.691118)
		(width 0.127)
		(layer "In5.Cu")
		(net "HOST1_RST_N")
	)
	(segment
		(start 210.881468 -9.210294)
		(end 211.759292 -9.210294)
		(width 0.127)
		(layer "In5.Cu")
		(net "HOST1_RST_N")
	)
	(segment
		(start 210.362292 -8.691118)
		(end 210.881468 -9.210294)
		(width 0.127)
		(layer "In5.Cu")
		(net "HOST1_RST_N")
	)
	(segment
		(start 185.166 -6.2992)
		(end 187.557918 -8.691118)
		(width 0.127)
		(layer "In5.Cu")
		(net "HOST1_RST_N")
	)
	(segment
		(start 36.90493 -123.684792)
		(end 36.505134 -123.284996)
		(width 0.12065)
		(layer "F.Cu")
		(net "HIGH_HEX_3")
	)
	(via
		(at 90.04427 -90.449908)
		(size 0.508)
		(drill 0.254)
		(layers "F.Cu" "B.Cu")
		(net "HIGH_HEX_3")
	)
	(via
		(at 36.505134 -123.284996)
		(size 0.4572)
		(drill 0.2032)
		(layers "F.Cu" "B.Cu")
		(net "HIGH_HEX_3")
	)
	(via
		(at 79.576676 -110.237524)
		(size 0.508)
		(drill 0.254)
		(layers "F.Cu" "B.Cu")
		(net "HIGH_HEX_3")
	)
	(segment
		(start 81.065624 -108.748576)
		(end 79.576676 -110.237524)
		(width 0.12065)
		(layer "B.Cu")
		(net "HIGH_HEX_3")
	)
	(segment
		(start 90.04427 -90.449908)
		(end 90.04427 -91.1098)
		(width 0.12065)
		(layer "B.Cu")
		(net "HIGH_HEX_3")
	)
	(segment
		(start 90.04427 -91.1098)
		(end 87.549736 -93.604334)
		(width 0.12065)
		(layer "B.Cu")
		(net "HIGH_HEX_3")
	)
	(segment
		(start 87.549736 -93.604334)
		(end 87.549736 -98.335592)
		(width 0.12065)
		(layer "B.Cu")
		(net "HIGH_HEX_3")
	)
	(segment
		(start 81.065624 -104.819704)
		(end 81.065624 -108.748576)
		(width 0.12065)
		(layer "B.Cu")
		(net "HIGH_HEX_3")
	)
	(segment
		(start 87.549736 -98.335592)
		(end 81.065624 -104.819704)
		(width 0.12065)
		(layer "B.Cu")
		(net "HIGH_HEX_3")
	)
	(segment
		(start 187.3758 -1.4732)
		(end 186.5249 -2.3241)
		(width 0.127)
		(layer "In2.Cu")
		(net "HIGH_HEX_3")
	)
	(segment
		(start 114.415824 -17.333722)
		(end 96.89719 -34.852356)
		(width 0.127)
		(layer "In2.Cu")
		(net "HIGH_HEX_3")
	)
	(segment
		(start 96.89719 -34.852356)
		(end 96.89719 -47.939706)
		(width 0.127)
		(layer "In2.Cu")
		(net "HIGH_HEX_3")
	)
	(segment
		(start 50.32629 -108.751624)
		(end 51.412648 -109.837982)
		(width 0.127)
		(layer "In2.Cu")
		(net "HIGH_HEX_3")
	)
	(segment
		(start 35.784282 -113.574322)
		(end 35.784282 -111.252)
		(width 0.127)
		(layer "In2.Cu")
		(net "HIGH_HEX_3")
	)
	(segment
		(start 99.5426 -71.625968)
		(end 99.542346 -74.544174)
		(width 0.127)
		(layer "In2.Cu")
		(net "HIGH_HEX_3")
	)
	(segment
		(start 125.16358 -10.070846)
		(end 122.069352 -10.070846)
		(width 0.127)
		(layer "In2.Cu")
		(net "HIGH_HEX_3")
	)
	(segment
		(start 79.027528 -109.837728)
		(end 79.4258 -110.236)
		(width 0.127)
		(layer "In2.Cu")
		(net "HIGH_HEX_3")
	)
	(segment
		(start 226.464622 -5.087112)
		(end 223.91751 -2.54)
		(width 0.127)
		(layer "In2.Cu")
		(net "HIGH_HEX_3")
	)
	(segment
		(start 177.406046 -2.772156)
		(end 132.466334 -2.772156)
		(width 0.127)
		(layer "In2.Cu")
		(net "HIGH_HEX_3")
	)
	(segment
		(start 237.549944 -1.500632)
		(end 238.375444 -2.326132)
		(width 0.127)
		(layer "In2.Cu")
		(net "HIGH_HEX_3")
	)
	(segment
		(start 237.377224 -4.83997)
		(end 233.289094 -4.83997)
		(width 0.127)
		(layer "In2.Cu")
		(net "HIGH_HEX_3")
	)
	(segment
		(start 180.1495 -2.241296)
		(end 177.936906 -2.241296)
		(width 0.127)
		(layer "In2.Cu")
		(net "HIGH_HEX_3")
	)
	(segment
		(start 189.490858 -2.11074)
		(end 188.24321 -2.11074)
		(width 0.127)
		(layer "In2.Cu")
		(net "HIGH_HEX_3")
	)
	(segment
		(start 96.89719 -47.939706)
		(end 99.5426 -50.585116)
		(width 0.127)
		(layer "In2.Cu")
		(net "HIGH_HEX_3")
	)
	(segment
		(start 98.086418 -76.782422)
		(end 97.1677 -77.701394)
		(width 0.127)
		(layer "In2.Cu")
		(net "HIGH_HEX_3")
	)
	(segment
		(start 223.91751 -2.54)
		(end 223.125538 -2.54)
		(width 0.127)
		(layer "In2.Cu")
		(net "HIGH_HEX_3")
	)
	(segment
		(start 186.5249 -2.3241)
		(end 181.422548 -2.3241)
		(width 0.127)
		(layer "In2.Cu")
		(net "HIGH_HEX_3")
	)
	(segment
		(start 79.4258 -110.236)
		(end 79.575152 -110.236)
		(width 0.127)
		(layer "In2.Cu")
		(net "HIGH_HEX_3")
	)
	(segment
		(start 35.90163 -119.182388)
		(end 36.223448 -118.86057)
		(width 0.127)
		(layer "In2.Cu")
		(net "HIGH_HEX_3")
	)
	(segment
		(start 35.784282 -111.252)
		(end 38.284658 -108.751624)
		(width 0.127)
		(layer "In2.Cu")
		(net "HIGH_HEX_3")
	)
	(segment
		(start 99.542346 -75.325986)
		(end 98.086418 -76.782422)
		(width 0.127)
		(layer "In2.Cu")
		(net "HIGH_HEX_3")
	)
	(segment
		(start 79.575152 -110.236)
		(end 79.576676 -110.237524)
		(width 0.127)
		(layer "In2.Cu")
		(net "HIGH_HEX_3")
	)
	(segment
		(start 238.375444 -2.326132)
		(end 238.375444 -3.84175)
		(width 0.127)
		(layer "In2.Cu")
		(net "HIGH_HEX_3")
	)
	(segment
		(start 233.289094 -4.83997)
		(end 233.041952 -5.087112)
		(width 0.127)
		(layer "In2.Cu")
		(net "HIGH_HEX_3")
	)
	(segment
		(start 116.7257 -15.414498)
		(end 116.7257 -16.019018)
		(width 0.127)
		(layer "In2.Cu")
		(net "HIGH_HEX_3")
	)
	(segment
		(start 203.1238 -3.747008)
		(end 203.1238 -4.623054)
		(width 0.127)
		(layer "In2.Cu")
		(net "HIGH_HEX_3")
	)
	(segment
		(start 188.24321 -2.11074)
		(end 187.60567 -1.4732)
		(width 0.127)
		(layer "In2.Cu")
		(net "HIGH_HEX_3")
	)
	(segment
		(start 93.486478 -83.540854)
		(end 93.486224 -83.5406)
		(width 0.127)
		(layer "In2.Cu")
		(net "HIGH_HEX_3")
	)
	(segment
		(start 99.5426 -50.585116)
		(end 99.5426 -71.625968)
		(width 0.127)
		(layer "In2.Cu")
		(net "HIGH_HEX_3")
	)
	(segment
		(start 116.7257 -16.019018)
		(end 115.410996 -17.333722)
		(width 0.127)
		(layer "In2.Cu")
		(net "HIGH_HEX_3")
	)
	(segment
		(start 51.412648 -109.837982)
		(end 51.728116 -109.837982)
		(width 0.127)
		(layer "In2.Cu")
		(net "HIGH_HEX_3")
	)
	(segment
		(start 36.327334 -122.992134)
		(end 35.90163 -122.56643)
		(width 0.127)
		(layer "In2.Cu")
		(net "HIGH_HEX_3")
	)
	(segment
		(start 36.327334 -123.107196)
		(end 36.327334 -122.992134)
		(width 0.127)
		(layer "In2.Cu")
		(net "HIGH_HEX_3")
	)
	(segment
		(start 180.47462 -2.566416)
		(end 180.1495 -2.241296)
		(width 0.127)
		(layer "In2.Cu")
		(net "HIGH_HEX_3")
	)
	(segment
		(start 93.486224 -83.5406)
		(end 93.242384 -83.5406)
		(width 0.127)
		(layer "In2.Cu")
		(net "HIGH_HEX_3")
	)
	(segment
		(start 203.1238 -4.623054)
		(end 202.666854 -5.08)
		(width 0.127)
		(layer "In2.Cu")
		(net "HIGH_HEX_3")
	)
	(segment
		(start 223.125538 -2.54)
		(end 220.1926 0.392938)
		(width 0.127)
		(layer "In2.Cu")
		(net "HIGH_HEX_3")
	)
	(segment
		(start 189.704218 -2.3241)
		(end 189.490858 -2.11074)
		(width 0.127)
		(layer "In2.Cu")
		(net "HIGH_HEX_3")
	)
	(segment
		(start 196.85 -3.1242)
		(end 192.626488 -3.1242)
		(width 0.127)
		(layer "In2.Cu")
		(net "HIGH_HEX_3")
	)
	(segment
		(start 220.1926 0.392938)
		(end 207.263746 0.392938)
		(width 0.127)
		(layer "In2.Cu")
		(net "HIGH_HEX_3")
	)
	(segment
		(start 36.223448 -114.013488)
		(end 35.784282 -113.574322)
		(width 0.127)
		(layer "In2.Cu")
		(net "HIGH_HEX_3")
	)
	(segment
		(start 181.180232 -2.566416)
		(end 180.47462 -2.566416)
		(width 0.127)
		(layer "In2.Cu")
		(net "HIGH_HEX_3")
	)
	(segment
		(start 192.626488 -3.1242)
		(end 191.826388 -2.3241)
		(width 0.127)
		(layer "In2.Cu")
		(net "HIGH_HEX_3")
	)
	(segment
		(start 238.375444 -3.84175)
		(end 237.377224 -4.83997)
		(width 0.127)
		(layer "In2.Cu")
		(net "HIGH_HEX_3")
	)
	(segment
		(start 187.60567 -1.4732)
		(end 187.3758 -1.4732)
		(width 0.127)
		(layer "In2.Cu")
		(net "HIGH_HEX_3")
	)
	(segment
		(start 38.284658 -108.751624)
		(end 50.32629 -108.751624)
		(width 0.127)
		(layer "In2.Cu")
		(net "HIGH_HEX_3")
	)
	(segment
		(start 96.9264 -80.4164)
		(end 93.801946 -83.540854)
		(width 0.127)
		(layer "In2.Cu")
		(net "HIGH_HEX_3")
	)
	(segment
		(start 202.666854 -5.08)
		(end 198.8058 -5.08)
		(width 0.127)
		(layer "In2.Cu")
		(net "HIGH_HEX_3")
	)
	(segment
		(start 51.728116 -109.837982)
		(end 51.72837 -109.837728)
		(width 0.127)
		(layer "In2.Cu")
		(net "HIGH_HEX_3")
	)
	(segment
		(start 132.466334 -2.772156)
		(end 125.16358 -10.070846)
		(width 0.127)
		(layer "In2.Cu")
		(net "HIGH_HEX_3")
	)
	(segment
		(start 191.826388 -2.3241)
		(end 189.704218 -2.3241)
		(width 0.127)
		(layer "In2.Cu")
		(net "HIGH_HEX_3")
	)
	(segment
		(start 96.9264 -77.942948)
		(end 96.9264 -80.4164)
		(width 0.127)
		(layer "In2.Cu")
		(net "HIGH_HEX_3")
	)
	(segment
		(start 93.801946 -83.540854)
		(end 93.486478 -83.540854)
		(width 0.127)
		(layer "In2.Cu")
		(net "HIGH_HEX_3")
	)
	(segment
		(start 198.8058 -5.08)
		(end 196.85 -3.1242)
		(width 0.127)
		(layer "In2.Cu")
		(net "HIGH_HEX_3")
	)
	(segment
		(start 90.04427 -86.738714)
		(end 90.04427 -90.449908)
		(width 0.127)
		(layer "In2.Cu")
		(net "HIGH_HEX_3")
	)
	(segment
		(start 177.936906 -2.241296)
		(end 177.406046 -2.772156)
		(width 0.127)
		(layer "In2.Cu")
		(net "HIGH_HEX_3")
	)
	(segment
		(start 36.223448 -118.86057)
		(end 36.223448 -114.013488)
		(width 0.127)
		(layer "In2.Cu")
		(net "HIGH_HEX_3")
	)
	(segment
		(start 233.041952 -5.087112)
		(end 226.464622 -5.087112)
		(width 0.127)
		(layer "In2.Cu")
		(net "HIGH_HEX_3")
	)
	(segment
		(start 51.72837 -109.837728)
		(end 79.027528 -109.837728)
		(width 0.127)
		(layer "In2.Cu")
		(net "HIGH_HEX_3")
	)
	(segment
		(start 181.422548 -2.3241)
		(end 181.180232 -2.566416)
		(width 0.127)
		(layer "In2.Cu")
		(net "HIGH_HEX_3")
	)
	(segment
		(start 93.242384 -83.5406)
		(end 90.04427 -86.738714)
		(width 0.127)
		(layer "In2.Cu")
		(net "HIGH_HEX_3")
	)
	(segment
		(start 122.069352 -10.070846)
		(end 116.7257 -15.414498)
		(width 0.127)
		(layer "In2.Cu")
		(net "HIGH_HEX_3")
	)
	(segment
		(start 115.410996 -17.333722)
		(end 114.415824 -17.333722)
		(width 0.127)
		(layer "In2.Cu")
		(net "HIGH_HEX_3")
	)
	(segment
		(start 207.263746 0.392938)
		(end 203.1238 -3.747008)
		(width 0.127)
		(layer "In2.Cu")
		(net "HIGH_HEX_3")
	)
	(segment
		(start 99.542346 -74.544174)
		(end 99.542346 -75.325986)
		(width 0.127)
		(layer "In2.Cu")
		(net "HIGH_HEX_3")
	)
	(segment
		(start 36.505134 -123.284996)
		(end 36.327334 -123.107196)
		(width 0.127)
		(layer "In2.Cu")
		(net "HIGH_HEX_3")
	)
	(segment
		(start 97.1677 -77.701394)
		(end 96.9264 -77.942948)
		(width 0.127)
		(layer "In2.Cu")
		(net "HIGH_HEX_3")
	)
	(segment
		(start 35.90163 -122.56643)
		(end 35.90163 -119.182388)
		(width 0.127)
		(layer "In2.Cu")
		(net "HIGH_HEX_3")
	)
	(segment
		(start 36.90493 -124.484892)
		(end 36.505134 -124.085096)
		(width 0.12065)
		(layer "F.Cu")
		(net "HIGH_HEX_2")
	)
	(via
		(at 79.5782 -109.119162)
		(size 0.508)
		(drill 0.254)
		(layers "F.Cu" "B.Cu")
		(net "HIGH_HEX_2")
	)
	(via
		(at 36.505134 -124.085096)
		(size 0.4572)
		(drill 0.2032)
		(layers "F.Cu" "B.Cu")
		(net "HIGH_HEX_2")
	)
	(via
		(at 89.408762 -91.085162)
		(size 0.508)
		(drill 0.254)
		(layers "F.Cu" "B.Cu")
		(net "HIGH_HEX_2")
	)
	(segment
		(start 87.187786 -93.306138)
		(end 87.187786 -98.185478)
		(width 0.12065)
		(layer "B.Cu")
		(net "HIGH_HEX_2")
	)
	(segment
		(start 89.408762 -91.085162)
		(end 87.187786 -93.306138)
		(width 0.12065)
		(layer "B.Cu")
		(net "HIGH_HEX_2")
	)
	(segment
		(start 80.703674 -104.66959)
		(end 80.703674 -107.993688)
		(width 0.12065)
		(layer "B.Cu")
		(net "HIGH_HEX_2")
	)
	(segment
		(start 80.703674 -107.993688)
		(end 79.5782 -109.119162)
		(width 0.12065)
		(layer "B.Cu")
		(net "HIGH_HEX_2")
	)
	(segment
		(start 87.187786 -98.185478)
		(end 80.703674 -104.66959)
		(width 0.12065)
		(layer "B.Cu")
		(net "HIGH_HEX_2")
	)
	(segment
		(start 79.240634 -109.456728)
		(end 51.570382 -109.456728)
		(width 0.127)
		(layer "In2.Cu")
		(net "HIGH_HEX_2")
	)
	(segment
		(start 99.1616 -50.743104)
		(end 99.1616 -71.625714)
		(width 0.127)
		(layer "In2.Cu")
		(net "HIGH_HEX_2")
	)
	(segment
		(start 223.283526 -2.159)
		(end 220.350588 0.773938)
		(width 0.127)
		(layer "In2.Cu")
		(net "HIGH_HEX_2")
	)
	(segment
		(start 187.763658 -1.0922)
		(end 187.071 -1.0922)
		(width 0.127)
		(layer "In2.Cu")
		(net "HIGH_HEX_2")
	)
	(segment
		(start 224.282 -2.159)
		(end 223.283526 -2.159)
		(width 0.127)
		(layer "In2.Cu")
		(net "HIGH_HEX_2")
	)
	(segment
		(start 34.840926 -112.76203)
		(end 35.355276 -113.27638)
		(width 0.127)
		(layer "In2.Cu")
		(net "HIGH_HEX_2")
	)
	(segment
		(start 132.308346 -2.391156)
		(end 125.005592 -9.689846)
		(width 0.127)
		(layer "In2.Cu")
		(net "HIGH_HEX_2")
	)
	(segment
		(start 96.51619 -48.097694)
		(end 99.1616 -50.743104)
		(width 0.127)
		(layer "In2.Cu")
		(net "HIGH_HEX_2")
	)
	(segment
		(start 89.408762 -86.835234)
		(end 89.408762 -91.085162)
		(width 0.127)
		(layer "In2.Cu")
		(net "HIGH_HEX_2")
	)
	(segment
		(start 181.26456 -1.9431)
		(end 181.022244 -2.185416)
		(width 0.127)
		(layer "In2.Cu")
		(net "HIGH_HEX_2")
	)
	(segment
		(start 96.5454 -77.785214)
		(end 96.5454 -80.258412)
		(width 0.127)
		(layer "In2.Cu")
		(net "HIGH_HEX_2")
	)
	(segment
		(start 35.355276 -113.27638)
		(end 35.355276 -113.784888)
		(width 0.127)
		(layer "In2.Cu")
		(net "HIGH_HEX_2")
	)
	(segment
		(start 51.570382 -109.456728)
		(end 50.484278 -108.370624)
		(width 0.127)
		(layer "In2.Cu")
		(net "HIGH_HEX_2")
	)
	(segment
		(start 35.403282 -110.981236)
		(end 34.840926 -111.543592)
		(width 0.127)
		(layer "In2.Cu")
		(net "HIGH_HEX_2")
	)
	(segment
		(start 236.590586 -4.45897)
		(end 233.131106 -4.45897)
		(width 0.127)
		(layer "In2.Cu")
		(net "HIGH_HEX_2")
	)
	(segment
		(start 181.022244 -2.185416)
		(end 180.632608 -2.185416)
		(width 0.127)
		(layer "In2.Cu")
		(net "HIGH_HEX_2")
	)
	(segment
		(start 35.67303 -122.69597)
		(end 36.098734 -123.121674)
		(width 0.127)
		(layer "In2.Cu")
		(net "HIGH_HEX_2")
	)
	(segment
		(start 50.484278 -108.370624)
		(end 38.009576 -108.370624)
		(width 0.127)
		(layer "In2.Cu")
		(net "HIGH_HEX_2")
	)
	(segment
		(start 177.779172 -1.860042)
		(end 177.248058 -2.391156)
		(width 0.127)
		(layer "In2.Cu")
		(net "HIGH_HEX_2")
	)
	(segment
		(start 180.632608 -2.185416)
		(end 180.307488 -1.860296)
		(width 0.127)
		(layer "In2.Cu")
		(net "HIGH_HEX_2")
	)
	(segment
		(start 177.248058 -2.391156)
		(end 132.308346 -2.391156)
		(width 0.127)
		(layer "In2.Cu")
		(net "HIGH_HEX_2")
	)
	(segment
		(start 96.999298 -77.3303)
		(end 96.786446 -77.543406)
		(width 0.127)
		(layer "In2.Cu")
		(net "HIGH_HEX_2")
	)
	(segment
		(start 93.084396 -83.1596)
		(end 89.408762 -86.835234)
		(width 0.127)
		(layer "In2.Cu")
		(net "HIGH_HEX_2")
	)
	(segment
		(start 186.2201 -1.9431)
		(end 181.26456 -1.9431)
		(width 0.127)
		(layer "In2.Cu")
		(net "HIGH_HEX_2")
	)
	(segment
		(start 187.071 -1.0922)
		(end 186.2201 -1.9431)
		(width 0.127)
		(layer "In2.Cu")
		(net "HIGH_HEX_2")
	)
	(segment
		(start 36.098734 -123.678696)
		(end 36.505134 -124.085096)
		(width 0.127)
		(layer "In2.Cu")
		(net "HIGH_HEX_2")
	)
	(segment
		(start 96.5454 -80.258412)
		(end 93.644212 -83.1596)
		(width 0.127)
		(layer "In2.Cu")
		(net "HIGH_HEX_2")
	)
	(segment
		(start 35.403282 -110.976918)
		(end 35.403282 -110.981236)
		(width 0.127)
		(layer "In2.Cu")
		(net "HIGH_HEX_2")
	)
	(segment
		(start 35.67303 -114.102642)
		(end 35.67303 -122.69597)
		(width 0.127)
		(layer "In2.Cu")
		(net "HIGH_HEX_2")
	)
	(segment
		(start 96.51619 -34.694368)
		(end 96.51619 -48.097694)
		(width 0.127)
		(layer "In2.Cu")
		(net "HIGH_HEX_2")
	)
	(segment
		(start 93.644212 -83.1596)
		(end 93.084396 -83.1596)
		(width 0.127)
		(layer "In2.Cu")
		(net "HIGH_HEX_2")
	)
	(segment
		(start 180.307488 -1.860296)
		(end 178.094894 -1.860296)
		(width 0.127)
		(layer "In2.Cu")
		(net "HIGH_HEX_2")
	)
	(segment
		(start 79.5782 -109.119162)
		(end 79.240634 -109.456728)
		(width 0.127)
		(layer "In2.Cu")
		(net "HIGH_HEX_2")
	)
	(segment
		(start 193.984118 -2.7178)
		(end 192.995804 -1.729486)
		(width 0.127)
		(layer "In2.Cu")
		(net "HIGH_HEX_2")
	)
	(segment
		(start 233.131106 -4.45897)
		(end 232.883964 -4.706112)
		(width 0.127)
		(layer "In2.Cu")
		(net "HIGH_HEX_2")
	)
	(segment
		(start 96.786446 -77.543406)
		(end 96.5454 -77.785214)
		(width 0.127)
		(layer "In2.Cu")
		(net "HIGH_HEX_2")
	)
	(segment
		(start 36.098734 -123.121674)
		(end 36.098734 -123.678696)
		(width 0.127)
		(layer "In2.Cu")
		(net "HIGH_HEX_2")
	)
	(segment
		(start 237.549944 -3.499612)
		(end 236.590586 -4.45897)
		(width 0.127)
		(layer "In2.Cu")
		(net "HIGH_HEX_2")
	)
	(segment
		(start 121.520712 -9.689846)
		(end 96.51619 -34.694368)
		(width 0.127)
		(layer "In2.Cu")
		(net "HIGH_HEX_2")
	)
	(segment
		(start 34.840926 -111.543592)
		(end 34.840926 -112.76203)
		(width 0.127)
		(layer "In2.Cu")
		(net "HIGH_HEX_2")
	)
	(segment
		(start 178.09464 -1.860042)
		(end 177.779172 -1.860042)
		(width 0.127)
		(layer "In2.Cu")
		(net "HIGH_HEX_2")
	)
	(segment
		(start 192.995804 -1.729486)
		(end 188.400944 -1.729486)
		(width 0.127)
		(layer "In2.Cu")
		(net "HIGH_HEX_2")
	)
	(segment
		(start 226.829112 -4.706112)
		(end 224.282 -2.159)
		(width 0.127)
		(layer "In2.Cu")
		(net "HIGH_HEX_2")
	)
	(segment
		(start 125.005592 -9.689846)
		(end 121.520712 -9.689846)
		(width 0.127)
		(layer "In2.Cu")
		(net "HIGH_HEX_2")
	)
	(segment
		(start 207.105758 0.773938)
		(end 203.61402 -2.7178)
		(width 0.127)
		(layer "In2.Cu")
		(net "HIGH_HEX_2")
	)
	(segment
		(start 99.1616 -71.625714)
		(end 99.161346 -74.54392)
		(width 0.127)
		(layer "In2.Cu")
		(net "HIGH_HEX_2")
	)
	(segment
		(start 203.61402 -2.7178)
		(end 193.984118 -2.7178)
		(width 0.127)
		(layer "In2.Cu")
		(net "HIGH_HEX_2")
	)
	(segment
		(start 220.350588 0.773938)
		(end 207.105758 0.773938)
		(width 0.127)
		(layer "In2.Cu")
		(net "HIGH_HEX_2")
	)
	(segment
		(start 232.883964 -4.706112)
		(end 226.829112 -4.706112)
		(width 0.127)
		(layer "In2.Cu")
		(net "HIGH_HEX_2")
	)
	(segment
		(start 188.400944 -1.729486)
		(end 187.763658 -1.0922)
		(width 0.127)
		(layer "In2.Cu")
		(net "HIGH_HEX_2")
	)
	(segment
		(start 35.355276 -113.784888)
		(end 35.67303 -114.102642)
		(width 0.127)
		(layer "In2.Cu")
		(net "HIGH_HEX_2")
	)
	(segment
		(start 99.161346 -74.54392)
		(end 99.161346 -75.167998)
		(width 0.127)
		(layer "In2.Cu")
		(net "HIGH_HEX_2")
	)
	(segment
		(start 38.009576 -108.370624)
		(end 35.403282 -110.976918)
		(width 0.127)
		(layer "In2.Cu")
		(net "HIGH_HEX_2")
	)
	(segment
		(start 178.094894 -1.860296)
		(end 178.09464 -1.860042)
		(width 0.127)
		(layer "In2.Cu")
		(net "HIGH_HEX_2")
	)
	(segment
		(start 99.161346 -75.167998)
		(end 96.999298 -77.3303)
		(width 0.127)
		(layer "In2.Cu")
		(net "HIGH_HEX_2")
	)
	(segment
		(start 36.90493 -125.284992)
		(end 36.505134 -124.885196)
		(width 0.12065)
		(layer "F.Cu")
		(net "HIGH_HEX_1")
	)
	(via
		(at 79.629 -112.014)
		(size 0.508)
		(drill 0.254)
		(layers "F.Cu" "B.Cu")
		(net "HIGH_HEX_1")
	)
	(via
		(at 91.288362 -89.205562)
		(size 0.508)
		(drill 0.254)
		(layers "F.Cu" "B.Cu")
		(net "HIGH_HEX_1")
	)
	(via
		(at 36.505134 -124.885196)
		(size 0.4572)
		(drill 0.2032)
		(layers "F.Cu" "B.Cu")
		(net "HIGH_HEX_1")
	)
	(segment
		(start 88.273636 -98.63582)
		(end 81.789524 -105.119932)
		(width 0.12065)
		(layer "B.Cu")
		(net "HIGH_HEX_1")
	)
	(segment
		(start 88.273636 -93.904562)
		(end 88.273636 -98.63582)
		(width 0.12065)
		(layer "B.Cu")
		(net "HIGH_HEX_1")
	)
	(segment
		(start 91.288362 -89.205562)
		(end 91.288362 -90.889836)
		(width 0.12065)
		(layer "B.Cu")
		(net "HIGH_HEX_1")
	)
	(segment
		(start 81.789524 -105.119932)
		(end 81.789524 -109.853476)
		(width 0.12065)
		(layer "B.Cu")
		(net "HIGH_HEX_1")
	)
	(segment
		(start 81.789524 -109.853476)
		(end 79.629 -112.014)
		(width 0.12065)
		(layer "B.Cu")
		(net "HIGH_HEX_1")
	)
	(segment
		(start 91.288362 -90.889836)
		(end 88.273636 -93.904562)
		(width 0.12065)
		(layer "B.Cu")
		(net "HIGH_HEX_1")
	)
	(segment
		(start 191.6811 -6.9088)
		(end 192.99174 -6.9088)
		(width 0.127)
		(layer "In2.Cu")
		(net "HIGH_HEX_1")
	)
	(segment
		(start 208.929224 -3.4417)
		(end 223.741234 -3.4417)
		(width 0.127)
		(layer "In2.Cu")
		(net "HIGH_HEX_1")
	)
	(segment
		(start 181.921912 -5.05841)
		(end 182.243476 -4.736846)
		(width 0.127)
		(layer "In2.Cu")
		(net "HIGH_HEX_1")
	)
	(segment
		(start 42.798746 -124.748544)
		(end 41.468548 -126.078742)
		(width 0.127)
		(layer "In2.Cu")
		(net "HIGH_HEX_1")
	)
	(segment
		(start 36.505134 -125.442472)
		(end 36.505134 -124.885196)
		(width 0.127)
		(layer "In2.Cu")
		(net "HIGH_HEX_1")
	)
	(segment
		(start 54.965092 -110.980728)
		(end 54.042818 -111.903002)
		(width 0.127)
		(layer "In2.Cu")
		(net "HIGH_HEX_1")
	)
	(segment
		(start 182.243476 -4.736846)
		(end 185.731404 -4.736846)
		(width 0.127)
		(layer "In2.Cu")
		(net "HIGH_HEX_1")
	)
	(segment
		(start 115.20551 -19.238722)
		(end 119.412258 -19.238722)
		(width 0.127)
		(layer "In2.Cu")
		(net "HIGH_HEX_1")
	)
	(segment
		(start 98.8314 -78.732634)
		(end 101.447346 -76.115672)
		(width 0.127)
		(layer "In2.Cu")
		(net "HIGH_HEX_1")
	)
	(segment
		(start 41.468548 -126.078742)
		(end 37.141404 -126.078742)
		(width 0.127)
		(layer "In2.Cu")
		(net "HIGH_HEX_1")
	)
	(segment
		(start 98.80219 -47.15002)
		(end 98.80219 -35.642042)
		(width 0.127)
		(layer "In2.Cu")
		(net "HIGH_HEX_1")
	)
	(segment
		(start 223.741234 -3.4417)
		(end 226.148646 -5.849112)
		(width 0.127)
		(layer "In2.Cu")
		(net "HIGH_HEX_1")
	)
	(segment
		(start 135.177022 -5.05841)
		(end 181.921912 -5.05841)
		(width 0.127)
		(layer "In2.Cu")
		(net "HIGH_HEX_1")
	)
	(segment
		(start 37.141404 -126.078742)
		(end 36.505134 -125.442472)
		(width 0.127)
		(layer "In2.Cu")
		(net "HIGH_HEX_1")
	)
	(segment
		(start 135.176768 -5.058156)
		(end 135.177022 -5.05841)
		(width 0.127)
		(layer "In2.Cu")
		(net "HIGH_HEX_1")
	)
	(segment
		(start 101.447346 -76.115672)
		(end 101.447346 -74.54519)
		(width 0.127)
		(layer "In2.Cu")
		(net "HIGH_HEX_1")
	)
	(segment
		(start 65.149476 -110.980728)
		(end 54.965092 -110.980728)
		(width 0.127)
		(layer "In2.Cu")
		(net "HIGH_HEX_1")
	)
	(segment
		(start 204.446124 -7.9248)
		(end 208.929224 -3.4417)
		(width 0.127)
		(layer "In2.Cu")
		(net "HIGH_HEX_1")
	)
	(segment
		(start 192.99174 -6.9088)
		(end 194.00774 -7.9248)
		(width 0.127)
		(layer "In2.Cu")
		(net "HIGH_HEX_1")
	)
	(segment
		(start 188.043058 -4.736592)
		(end 190.215012 -6.907784)
		(width 0.127)
		(layer "In2.Cu")
		(net "HIGH_HEX_1")
	)
	(segment
		(start 194.00774 -7.9248)
		(end 204.446124 -7.9248)
		(width 0.127)
		(layer "In2.Cu")
		(net "HIGH_HEX_1")
	)
	(segment
		(start 133.59638 -5.059426)
		(end 133.59765 -5.058156)
		(width 0.127)
		(layer "In2.Cu")
		(net "HIGH_HEX_1")
	)
	(segment
		(start 91.288362 -89.205562)
		(end 91.446096 -89.205562)
		(width 0.127)
		(layer "In2.Cu")
		(net "HIGH_HEX_1")
	)
	(segment
		(start 240.375694 -2.326132)
		(end 239.550194 -1.500632)
		(width 0.127)
		(layer "In2.Cu")
		(net "HIGH_HEX_1")
	)
	(segment
		(start 101.447346 -74.54519)
		(end 101.4476 -71.626984)
		(width 0.127)
		(layer "In2.Cu")
		(net "HIGH_HEX_1")
	)
	(segment
		(start 42.798746 -119.142256)
		(end 42.798746 -124.748544)
		(width 0.127)
		(layer "In2.Cu")
		(net "HIGH_HEX_1")
	)
	(segment
		(start 67.631818 -111.2393)
		(end 66.971418 -111.8997)
		(width 0.127)
		(layer "In2.Cu")
		(net "HIGH_HEX_1")
	)
	(segment
		(start 50.038 -111.903002)
		(end 42.798746 -119.142256)
		(width 0.127)
		(layer "In2.Cu")
		(net "HIGH_HEX_1")
	)
	(segment
		(start 78.8543 -111.2393)
		(end 67.631818 -111.2393)
		(width 0.127)
		(layer "In2.Cu")
		(net "HIGH_HEX_1")
	)
	(segment
		(start 101.4476 -49.79543)
		(end 98.80219 -47.15002)
		(width 0.127)
		(layer "In2.Cu")
		(net "HIGH_HEX_1")
	)
	(segment
		(start 238.615474 -5.60197)
		(end 240.375694 -3.84175)
		(width 0.127)
		(layer "In2.Cu")
		(net "HIGH_HEX_1")
	)
	(segment
		(start 66.971418 -111.8997)
		(end 66.068448 -111.8997)
		(width 0.127)
		(layer "In2.Cu")
		(net "HIGH_HEX_1")
	)
	(segment
		(start 119.412258 -19.238722)
		(end 133.59638 -5.059426)
		(width 0.127)
		(layer "In2.Cu")
		(net "HIGH_HEX_1")
	)
	(segment
		(start 233.357928 -5.849112)
		(end 233.60507 -5.60197)
		(width 0.127)
		(layer "In2.Cu")
		(net "HIGH_HEX_1")
	)
	(segment
		(start 66.068448 -111.8997)
		(end 65.149476 -110.980728)
		(width 0.127)
		(layer "In2.Cu")
		(net "HIGH_HEX_1")
	)
	(segment
		(start 191.680084 -6.907784)
		(end 191.6811 -6.9088)
		(width 0.127)
		(layer "In2.Cu")
		(net "HIGH_HEX_1")
	)
	(segment
		(start 91.446096 -89.205562)
		(end 98.8314 -81.820258)
		(width 0.127)
		(layer "In2.Cu")
		(net "HIGH_HEX_1")
	)
	(segment
		(start 54.042818 -111.903002)
		(end 50.038 -111.903002)
		(width 0.127)
		(layer "In2.Cu")
		(net "HIGH_HEX_1")
	)
	(segment
		(start 190.215012 -6.907784)
		(end 191.680084 -6.907784)
		(width 0.127)
		(layer "In2.Cu")
		(net "HIGH_HEX_1")
	)
	(segment
		(start 233.60507 -5.60197)
		(end 238.615474 -5.60197)
		(width 0.127)
		(layer "In2.Cu")
		(net "HIGH_HEX_1")
	)
	(segment
		(start 226.148646 -5.849112)
		(end 233.357928 -5.849112)
		(width 0.127)
		(layer "In2.Cu")
		(net "HIGH_HEX_1")
	)
	(segment
		(start 185.731404 -4.736846)
		(end 186.047126 -4.736592)
		(width 0.127)
		(layer "In2.Cu")
		(net "HIGH_HEX_1")
	)
	(segment
		(start 186.047126 -4.736592)
		(end 188.043058 -4.736592)
		(width 0.127)
		(layer "In2.Cu")
		(net "HIGH_HEX_1")
	)
	(segment
		(start 79.629 -112.014)
		(end 78.8543 -111.2393)
		(width 0.127)
		(layer "In2.Cu")
		(net "HIGH_HEX_1")
	)
	(segment
		(start 98.8314 -81.820258)
		(end 98.8314 -78.732634)
		(width 0.127)
		(layer "In2.Cu")
		(net "HIGH_HEX_1")
	)
	(segment
		(start 240.375694 -3.84175)
		(end 240.375694 -2.326132)
		(width 0.127)
		(layer "In2.Cu")
		(net "HIGH_HEX_1")
	)
	(segment
		(start 101.4476 -71.626984)
		(end 101.4476 -49.79543)
		(width 0.127)
		(layer "In2.Cu")
		(net "HIGH_HEX_1")
	)
	(segment
		(start 98.80219 -35.642042)
		(end 115.20551 -19.238722)
		(width 0.127)
		(layer "In2.Cu")
		(net "HIGH_HEX_1")
	)
	(segment
		(start 133.59765 -5.058156)
		(end 135.176768 -5.058156)
		(width 0.127)
		(layer "In2.Cu")
		(net "HIGH_HEX_1")
	)
	(segment
		(start 36.10483 -122.084846)
		(end 36.10483 -121.80697)
		(width 0.12065)
		(layer "F.Cu")
		(net "HIGH_HEX_0")
	)
	(segment
		(start 36.460938 -121.450862)
		(end 36.460938 -121.405904)
		(width 0.12065)
		(layer "F.Cu")
		(net "HIGH_HEX_0")
	)
	(segment
		(start 36.10483 -121.80697)
		(end 36.460938 -121.450862)
		(width 0.12065)
		(layer "F.Cu")
		(net "HIGH_HEX_0")
	)
	(via
		(at 79.629 -111.0996)
		(size 0.508)
		(drill 0.254)
		(layers "F.Cu" "B.Cu")
		(net "HIGH_HEX_0")
	)
	(via
		(at 36.460938 -121.405904)
		(size 0.508)
		(drill 0.254)
		(layers "F.Cu" "B.Cu")
		(net "HIGH_HEX_0")
	)
	(via
		(at 90.666062 -89.827862)
		(size 0.508)
		(drill 0.254)
		(layers "F.Cu" "B.Cu")
		(net "HIGH_HEX_0")
	)
	(segment
		(start 81.427574 -104.969818)
		(end 81.427574 -109.301026)
		(width 0.12065)
		(layer "B.Cu")
		(net "HIGH_HEX_0")
	)
	(segment
		(start 81.427574 -109.301026)
		(end 79.629 -111.0996)
		(width 0.12065)
		(layer "B.Cu")
		(net "HIGH_HEX_0")
	)
	(segment
		(start 90.666062 -91.000072)
		(end 87.911686 -93.754448)
		(width 0.12065)
		(layer "B.Cu")
		(net "HIGH_HEX_0")
	)
	(segment
		(start 87.911686 -93.754448)
		(end 87.911686 -98.485706)
		(width 0.12065)
		(layer "B.Cu")
		(net "HIGH_HEX_0")
	)
	(segment
		(start 87.911686 -98.485706)
		(end 81.427574 -104.969818)
		(width 0.12065)
		(layer "B.Cu")
		(net "HIGH_HEX_0")
	)
	(segment
		(start 90.666062 -89.827862)
		(end 90.666062 -91.000072)
		(width 0.12065)
		(layer "B.Cu")
		(net "HIGH_HEX_0")
	)
	(segment
		(start 98.4504 -78.574646)
		(end 98.4504 -81.378552)
		(width 0.127)
		(layer "In2.Cu")
		(net "HIGH_HEX_0")
	)
	(segment
		(start 78.417928 -110.218728)
		(end 51.886358 -110.218728)
		(width 0.127)
		(layer "In2.Cu")
		(net "HIGH_HEX_0")
	)
	(segment
		(start 133.439662 -4.677156)
		(end 133.439154 -4.677664)
		(width 0.127)
		(layer "In2.Cu")
		(net "HIGH_HEX_0")
	)
	(segment
		(start 185.573162 -4.355846)
		(end 182.085488 -4.355846)
		(width 0.127)
		(layer "In2.Cu")
		(net "HIGH_HEX_0")
	)
	(segment
		(start 36.165282 -113.416334)
		(end 36.604448 -113.8555)
		(width 0.127)
		(layer "In2.Cu")
		(net "HIGH_HEX_0")
	)
	(segment
		(start 51.570636 -110.218982)
		(end 51.570382 -110.219236)
		(width 0.127)
		(layer "In2.Cu")
		(net "HIGH_HEX_0")
	)
	(segment
		(start 51.254914 -110.219236)
		(end 50.168302 -109.132624)
		(width 0.127)
		(layer "In2.Cu")
		(net "HIGH_HEX_0")
	)
	(segment
		(start 135.334756 -4.677156)
		(end 133.439662 -4.677156)
		(width 0.127)
		(layer "In2.Cu")
		(net "HIGH_HEX_0")
	)
	(segment
		(start 190.372746 -6.52653)
		(end 189.224412 -5.378704)
		(width 0.127)
		(layer "In2.Cu")
		(net "HIGH_HEX_0")
	)
	(segment
		(start 115.047522 -18.857722)
		(end 98.42119 -35.484054)
		(width 0.127)
		(layer "In2.Cu")
		(net "HIGH_HEX_0")
	)
	(segment
		(start 98.4504 -81.378552)
		(end 90.666062 -89.163144)
		(width 0.127)
		(layer "In2.Cu")
		(net "HIGH_HEX_0")
	)
	(segment
		(start 79.2988 -111.0996)
		(end 78.417928 -110.218728)
		(width 0.127)
		(layer "In2.Cu")
		(net "HIGH_HEX_0")
	)
	(segment
		(start 122.044714 -15.143988)
		(end 122.044714 -15.957804)
		(width 0.127)
		(layer "In2.Cu")
		(net "HIGH_HEX_0")
	)
	(segment
		(start 191.897 -6.5278)
		(end 191.89573 -6.52653)
		(width 0.127)
		(layer "In2.Cu")
		(net "HIGH_HEX_0")
	)
	(segment
		(start 98.42119 -35.484054)
		(end 98.42119 -47.308008)
		(width 0.127)
		(layer "In2.Cu")
		(net "HIGH_HEX_0")
	)
	(segment
		(start 193.327782 -6.705854)
		(end 193.149728 -6.5278)
		(width 0.127)
		(layer "In2.Cu")
		(net "HIGH_HEX_0")
	)
	(segment
		(start 135.33501 -4.67741)
		(end 135.334756 -4.677156)
		(width 0.127)
		(layer "In2.Cu")
		(net "HIGH_HEX_0")
	)
	(segment
		(start 90.666062 -89.163144)
		(end 90.666062 -89.827862)
		(width 0.127)
		(layer "In2.Cu")
		(net "HIGH_HEX_0")
	)
	(segment
		(start 189.224412 -5.378704)
		(end 188.2013 -4.355592)
		(width 0.127)
		(layer "In2.Cu")
		(net "HIGH_HEX_0")
	)
	(segment
		(start 237.828836 -5.22097)
		(end 233.447082 -5.22097)
		(width 0.127)
		(layer "In2.Cu")
		(net "HIGH_HEX_0")
	)
	(segment
		(start 133.439154 -4.677664)
		(end 123.668028 -14.444218)
		(width 0.127)
		(layer "In2.Cu")
		(net "HIGH_HEX_0")
	)
	(segment
		(start 101.066346 -74.544936)
		(end 101.066346 -75.957684)
		(width 0.127)
		(layer "In2.Cu")
		(net "HIGH_HEX_0")
	)
	(segment
		(start 226.306634 -5.468112)
		(end 223.899222 -3.0607)
		(width 0.127)
		(layer "In2.Cu")
		(net "HIGH_HEX_0")
	)
	(segment
		(start 101.0666 -71.62673)
		(end 101.066346 -74.544936)
		(width 0.127)
		(layer "In2.Cu")
		(net "HIGH_HEX_0")
	)
	(segment
		(start 191.89573 -6.52653)
		(end 190.372746 -6.52653)
		(width 0.127)
		(layer "In2.Cu")
		(net "HIGH_HEX_0")
	)
	(segment
		(start 36.604448 -113.8555)
		(end 36.604448 -121.262394)
		(width 0.127)
		(layer "In2.Cu")
		(net "HIGH_HEX_0")
	)
	(segment
		(start 181.763924 -4.67741)
		(end 135.33501 -4.67741)
		(width 0.127)
		(layer "In2.Cu")
		(net "HIGH_HEX_0")
	)
	(segment
		(start 36.604448 -121.262394)
		(end 36.460938 -121.405904)
		(width 0.127)
		(layer "In2.Cu")
		(net "HIGH_HEX_0")
	)
	(segment
		(start 101.066346 -75.957684)
		(end 98.4504 -78.574646)
		(width 0.127)
		(layer "In2.Cu")
		(net "HIGH_HEX_0")
	)
	(segment
		(start 51.886104 -110.218982)
		(end 51.570636 -110.218982)
		(width 0.127)
		(layer "In2.Cu")
		(net "HIGH_HEX_0")
	)
	(segment
		(start 79.629 -111.0996)
		(end 79.2988 -111.0996)
		(width 0.127)
		(layer "In2.Cu")
		(net "HIGH_HEX_0")
	)
	(segment
		(start 239.550194 -3.499612)
		(end 237.828836 -5.22097)
		(width 0.127)
		(layer "In2.Cu")
		(net "HIGH_HEX_0")
	)
	(segment
		(start 188.2013 -4.355592)
		(end 185.573416 -4.355592)
		(width 0.127)
		(layer "In2.Cu")
		(net "HIGH_HEX_0")
	)
	(segment
		(start 233.447082 -5.22097)
		(end 233.19994 -5.468112)
		(width 0.127)
		(layer "In2.Cu")
		(net "HIGH_HEX_0")
	)
	(segment
		(start 98.42119 -47.308008)
		(end 101.0666 -49.953418)
		(width 0.127)
		(layer "In2.Cu")
		(net "HIGH_HEX_0")
	)
	(segment
		(start 205.0796 -6.705854)
		(end 193.327782 -6.705854)
		(width 0.127)
		(layer "In2.Cu")
		(net "HIGH_HEX_0")
	)
	(segment
		(start 185.573416 -4.355592)
		(end 185.573162 -4.355846)
		(width 0.127)
		(layer "In2.Cu")
		(net "HIGH_HEX_0")
	)
	(segment
		(start 51.570382 -110.219236)
		(end 51.254914 -110.219236)
		(width 0.127)
		(layer "In2.Cu")
		(net "HIGH_HEX_0")
	)
	(segment
		(start 50.168302 -109.132624)
		(end 38.715188 -109.132624)
		(width 0.127)
		(layer "In2.Cu")
		(net "HIGH_HEX_0")
	)
	(segment
		(start 123.668028 -14.444218)
		(end 122.744484 -14.444218)
		(width 0.127)
		(layer "In2.Cu")
		(net "HIGH_HEX_0")
	)
	(segment
		(start 122.744484 -14.444218)
		(end 122.044714 -15.143988)
		(width 0.127)
		(layer "In2.Cu")
		(net "HIGH_HEX_0")
	)
	(segment
		(start 36.165282 -111.68253)
		(end 36.165282 -113.416334)
		(width 0.127)
		(layer "In2.Cu")
		(net "HIGH_HEX_0")
	)
	(segment
		(start 193.149728 -6.5278)
		(end 191.897 -6.5278)
		(width 0.127)
		(layer "In2.Cu")
		(net "HIGH_HEX_0")
	)
	(segment
		(start 233.19994 -5.468112)
		(end 226.306634 -5.468112)
		(width 0.127)
		(layer "In2.Cu")
		(net "HIGH_HEX_0")
	)
	(segment
		(start 122.044714 -15.957804)
		(end 119.144796 -18.857722)
		(width 0.127)
		(layer "In2.Cu")
		(net "HIGH_HEX_0")
	)
	(segment
		(start 119.144796 -18.857722)
		(end 115.047522 -18.857722)
		(width 0.127)
		(layer "In2.Cu")
		(net "HIGH_HEX_0")
	)
	(segment
		(start 223.899222 -3.0607)
		(end 208.724754 -3.0607)
		(width 0.127)
		(layer "In2.Cu")
		(net "HIGH_HEX_0")
	)
	(segment
		(start 208.724754 -3.0607)
		(end 205.0796 -6.705854)
		(width 0.127)
		(layer "In2.Cu")
		(net "HIGH_HEX_0")
	)
	(segment
		(start 101.0666 -49.953418)
		(end 101.0666 -71.62673)
		(width 0.127)
		(layer "In2.Cu")
		(net "HIGH_HEX_0")
	)
	(segment
		(start 182.085488 -4.355846)
		(end 181.763924 -4.67741)
		(width 0.127)
		(layer "In2.Cu")
		(net "HIGH_HEX_0")
	)
	(segment
		(start 51.886358 -110.218728)
		(end 51.886104 -110.218982)
		(width 0.127)
		(layer "In2.Cu")
		(net "HIGH_HEX_0")
	)
	(segment
		(start 38.715188 -109.132624)
		(end 36.165282 -111.68253)
		(width 0.127)
		(layer "In2.Cu")
		(net "HIGH_HEX_0")
	)
	(segment
		(start 192.1129 -6.6548)
		(end 191.781684 -6.6548)
		(width 0.12065)
		(layer "F.Cu")
		(net "HB_OUT_R")
	)
	(segment
		(start 191.161924 -7.27456)
		(end 190.4365 -7.27456)
		(width 0.12065)
		(layer "F.Cu")
		(net "HB_OUT_R")
	)
	(segment
		(start 191.781684 -6.6548)
		(end 191.161924 -7.27456)
		(width 0.12065)
		(layer "F.Cu")
		(net "HB_OUT_R")
	)
	(segment
		(start 186.094116 -3.556)
		(end 185.029094 -2.490978)
		(width 0.12065)
		(layer "F.Cu")
		(net "HB_OUT_BMC")
	)
	(segment
		(start 186.1947 -3.556)
		(end 186.094116 -3.556)
		(width 0.12065)
		(layer "F.Cu")
		(net "HB_OUT_BMC")
	)
	(segment
		(start 66.415666 -84.87156)
		(end 66.415666 -83.872832)
		(width 0.12065)
		(layer "F.Cu")
		(net "HB_OUT_BMC")
	)
	(segment
		(start 67.36969 -82.918808)
		(end 72.835008 -82.918808)
		(width 0.12065)
		(layer "F.Cu")
		(net "HB_OUT_BMC")
	)
	(segment
		(start 48.133 -143.5608)
		(end 48.133 -144.1958)
		(width 0.12065)
		(layer "F.Cu")
		(net "HB_OUT_BMC")
	)
	(segment
		(start 66.415666 -83.872832)
		(end 66.819272 -83.469226)
		(width 0.12065)
		(layer "F.Cu")
		(net "HB_OUT_BMC")
	)
	(segment
		(start 185.029094 -1.078484)
		(end 185.199528 -0.90805)
		(width 0.12065)
		(layer "F.Cu")
		(net "HB_OUT_BMC")
	)
	(segment
		(start 44.904914 -138.884914)
		(end 44.904914 -139.192)
		(width 0.12065)
		(layer "F.Cu")
		(net "HB_OUT_BMC")
	)
	(segment
		(start 66.819272 -83.469226)
		(end 67.36969 -82.918808)
		(width 0.12065)
		(layer "F.Cu")
		(net "HB_OUT_BMC")
	)
	(segment
		(start 72.923908 -83.007708)
		(end 72.9488 -83.007708)
		(width 0.12065)
		(layer "F.Cu")
		(net "HB_OUT_BMC")
	)
	(segment
		(start 72.835008 -82.918808)
		(end 72.923908 -83.007708)
		(width 0.12065)
		(layer "F.Cu")
		(net "HB_OUT_BMC")
	)
	(segment
		(start 47.47895 -142.90675)
		(end 48.133 -143.5608)
		(width 0.12065)
		(layer "F.Cu")
		(net "HB_OUT_BMC")
	)
	(segment
		(start 48.133 -144.1958)
		(end 48.133 -144.9705)
		(width 0.12065)
		(layer "F.Cu")
		(net "HB_OUT_BMC")
	)
	(segment
		(start 185.029094 -2.490978)
		(end 185.029094 -1.078484)
		(width 0.12065)
		(layer "F.Cu")
		(net "HB_OUT_BMC")
	)
	(segment
		(start 44.904914 -139.192)
		(end 47.47895 -141.766036)
		(width 0.12065)
		(layer "F.Cu")
		(net "HB_OUT_BMC")
	)
	(segment
		(start 47.47895 -141.766036)
		(end 47.47895 -142.90675)
		(width 0.12065)
		(layer "F.Cu")
		(net "HB_OUT_BMC")
	)
	(via
		(at 48.133 -144.1958)
		(size 0.508)
		(drill 0.254)
		(layers "F.Cu" "B.Cu")
		(net "HB_OUT_BMC")
	)
	(via
		(at 185.199528 -0.90805)
		(size 0.508)
		(drill 0.254)
		(layers "F.Cu" "B.Cu")
		(net "HB_OUT_BMC")
	)
	(via
		(at 66.819272 -83.469226)
		(size 0.7112)
		(drill 0.3556)
		(layers "F.Cu" "B.Cu")
		(net "HB_OUT_BMC")
	)
	(via
		(at 72.9488 -83.007708)
		(size 0.508)
		(drill 0.254)
		(layers "F.Cu" "B.Cu")
		(net "HB_OUT_BMC")
	)
	(via
		(at 71.118476 -140.917676)
		(size 0.508)
		(drill 0.254)
		(layers "F.Cu" "B.Cu")
		(net "HB_OUT_BMC")
	)
	(segment
		(start 131.99237 -1.629156)
		(end 124.689616 -8.927846)
		(width 0.127)
		(layer "In2.Cu")
		(net "HB_OUT_BMC")
	)
	(segment
		(start 84.868512 -85.344254)
		(end 75.532234 -85.344254)
		(width 0.127)
		(layer "In2.Cu")
		(net "HB_OUT_BMC")
	)
	(segment
		(start 177.959766 -0.601472)
		(end 176.932082 -1.629156)
		(width 0.127)
		(layer "In2.Cu")
		(net "HB_OUT_BMC")
	)
	(segment
		(start 53.065934 -143.49603)
		(end 52.600606 -143.030702)
		(width 0.127)
		(layer "In2.Cu")
		(net "HB_OUT_BMC")
	)
	(segment
		(start 92.60205 -82.397092)
		(end 87.815674 -82.397092)
		(width 0.127)
		(layer "In2.Cu")
		(net "HB_OUT_BMC")
	)
	(segment
		(start 178.275234 -0.601472)
		(end 177.959766 -0.601472)
		(width 0.127)
		(layer "In2.Cu")
		(net "HB_OUT_BMC")
	)
	(segment
		(start 95.75419 -34.341308)
		(end 95.75419 -48.41367)
		(width 0.127)
		(layer "In2.Cu")
		(net "HB_OUT_BMC")
	)
	(segment
		(start 48.133 -143.047212)
		(end 48.133 -144.1958)
		(width 0.127)
		(layer "In2.Cu")
		(net "HB_OUT_BMC")
	)
	(segment
		(start 184.559702 -0.90805)
		(end 184.253378 -0.601726)
		(width 0.127)
		(layer "In2.Cu")
		(net "HB_OUT_BMC")
	)
	(segment
		(start 176.932082 -1.629156)
		(end 131.99237 -1.629156)
		(width 0.127)
		(layer "In2.Cu")
		(net "HB_OUT_BMC")
	)
	(segment
		(start 75.532234 -85.344254)
		(end 73.195688 -83.007708)
		(width 0.127)
		(layer "In2.Cu")
		(net "HB_OUT_BMC")
	)
	(segment
		(start 98.29673 -74.954384)
		(end 96.459802 -76.791312)
		(width 0.127)
		(layer "In2.Cu")
		(net "HB_OUT_BMC")
	)
	(segment
		(start 73.195688 -83.007708)
		(end 72.9488 -83.007708)
		(width 0.127)
		(layer "In2.Cu")
		(net "HB_OUT_BMC")
	)
	(segment
		(start 96.353376 -76.897992)
		(end 96.024446 -77.227176)
		(width 0.127)
		(layer "In2.Cu")
		(net "HB_OUT_BMC")
	)
	(segment
		(start 93.234002 -82.397092)
		(end 93.233748 -82.397346)
		(width 0.127)
		(layer "In2.Cu")
		(net "HB_OUT_BMC")
	)
	(segment
		(start 95.7834 -77.470254)
		(end 95.7834 -79.942436)
		(width 0.127)
		(layer "In2.Cu")
		(net "HB_OUT_BMC")
	)
	(segment
		(start 92.602304 -82.397346)
		(end 92.60205 -82.397092)
		(width 0.127)
		(layer "In2.Cu")
		(net "HB_OUT_BMC")
	)
	(segment
		(start 185.199528 -0.90805)
		(end 184.559702 -0.90805)
		(width 0.127)
		(layer "In2.Cu")
		(net "HB_OUT_BMC")
	)
	(segment
		(start 93.328744 -82.397092)
		(end 93.234002 -82.397092)
		(width 0.127)
		(layer "In2.Cu")
		(net "HB_OUT_BMC")
	)
	(segment
		(start 95.7834 -79.942436)
		(end 93.328744 -82.397092)
		(width 0.127)
		(layer "In2.Cu")
		(net "HB_OUT_BMC")
	)
	(segment
		(start 50.988468 -143.030702)
		(end 50.46345 -142.505684)
		(width 0.127)
		(layer "In2.Cu")
		(net "HB_OUT_BMC")
	)
	(segment
		(start 68.540122 -143.49603)
		(end 53.065934 -143.49603)
		(width 0.127)
		(layer "In2.Cu")
		(net "HB_OUT_BMC")
	)
	(segment
		(start 124.689616 -8.927846)
		(end 121.167652 -8.927846)
		(width 0.127)
		(layer "In2.Cu")
		(net "HB_OUT_BMC")
	)
	(segment
		(start 178.275488 -0.601726)
		(end 178.275234 -0.601472)
		(width 0.127)
		(layer "In2.Cu")
		(net "HB_OUT_BMC")
	)
	(segment
		(start 48.674528 -142.505684)
		(end 48.133 -143.047212)
		(width 0.127)
		(layer "In2.Cu")
		(net "HB_OUT_BMC")
	)
	(segment
		(start 96.024192 -77.228446)
		(end 95.7834 -77.470254)
		(width 0.127)
		(layer "In2.Cu")
		(net "HB_OUT_BMC")
	)
	(segment
		(start 98.29673 -50.95621)
		(end 98.29673 -74.954384)
		(width 0.127)
		(layer "In2.Cu")
		(net "HB_OUT_BMC")
	)
	(segment
		(start 96.024192 -77.22743)
		(end 96.024192 -77.228446)
		(width 0.127)
		(layer "In2.Cu")
		(net "HB_OUT_BMC")
	)
	(segment
		(start 121.167652 -8.927846)
		(end 95.75419 -34.341308)
		(width 0.127)
		(layer "In2.Cu")
		(net "HB_OUT_BMC")
	)
	(segment
		(start 96.024446 -77.227176)
		(end 96.024192 -77.22743)
		(width 0.127)
		(layer "In2.Cu")
		(net "HB_OUT_BMC")
	)
	(segment
		(start 184.253378 -0.601726)
		(end 178.275488 -0.601726)
		(width 0.127)
		(layer "In2.Cu")
		(net "HB_OUT_BMC")
	)
	(segment
		(start 95.75419 -48.41367)
		(end 98.29673 -50.95621)
		(width 0.127)
		(layer "In2.Cu")
		(net "HB_OUT_BMC")
	)
	(segment
		(start 96.459802 -76.791312)
		(end 96.353376 -76.897992)
		(width 0.127)
		(layer "In2.Cu")
		(net "HB_OUT_BMC")
	)
	(segment
		(start 52.600606 -143.030702)
		(end 50.988468 -143.030702)
		(width 0.127)
		(layer "In2.Cu")
		(net "HB_OUT_BMC")
	)
	(segment
		(start 87.815674 -82.397092)
		(end 84.868512 -85.344254)
		(width 0.127)
		(layer "In2.Cu")
		(net "HB_OUT_BMC")
	)
	(segment
		(start 50.46345 -142.505684)
		(end 48.674528 -142.505684)
		(width 0.127)
		(layer "In2.Cu")
		(net "HB_OUT_BMC")
	)
	(segment
		(start 93.233748 -82.397346)
		(end 92.602304 -82.397346)
		(width 0.127)
		(layer "In2.Cu")
		(net "HB_OUT_BMC")
	)
	(segment
		(start 71.118476 -140.917676)
		(end 68.540122 -143.49603)
		(width 0.127)
		(layer "In2.Cu")
		(net "HB_OUT_BMC")
	)
	(segment
		(start 72.9488 -91.42349)
		(end 72.9488 -83.007708)
		(width 0.127)
		(layer "In5.Cu")
		(net "HB_OUT_BMC")
	)
	(segment
		(start 72.182228 -128.633728)
		(end 72.182228 -126.19736)
		(width 0.127)
		(layer "In5.Cu")
		(net "HB_OUT_BMC")
	)
	(segment
		(start 70.7009 -140.5001)
		(end 70.7009 -130.115056)
		(width 0.127)
		(layer "In5.Cu")
		(net "HB_OUT_BMC")
	)
	(segment
		(start 74.0664 -92.54109)
		(end 72.9488 -91.42349)
		(width 0.127)
		(layer "In5.Cu")
		(net "HB_OUT_BMC")
	)
	(segment
		(start 72.182228 -126.19736)
		(end 74.0664 -124.313188)
		(width 0.127)
		(layer "In5.Cu")
		(net "HB_OUT_BMC")
	)
	(segment
		(start 70.7009 -130.115056)
		(end 72.182228 -128.633728)
		(width 0.127)
		(layer "In5.Cu")
		(net "HB_OUT_BMC")
	)
	(segment
		(start 71.118476 -140.917676)
		(end 70.7009 -140.5001)
		(width 0.127)
		(layer "In5.Cu")
		(net "HB_OUT_BMC")
	)
	(segment
		(start 74.0664 -124.313188)
		(end 74.0664 -92.54109)
		(width 0.127)
		(layer "In5.Cu")
		(net "HB_OUT_BMC")
	)
	(segment
		(start 68.638166 -90.77706)
		(end 67.749166 -90.77706)
		(width 0.12065)
		(layer "F.Cu")
		(net "HB_OUT")
	)
	(segment
		(start 345.441016 -42.697908)
		(end 345.218512 -42.475404)
		(width 0.12065)
		(layer "F.Cu")
		(net "HB_OUT")
	)
	(segment
		(start 192.0748 -5.08)
		(end 193.0019 -6.0071)
		(width 0.12065)
		(layer "F.Cu")
		(net "HB_OUT")
	)
	(segment
		(start 73.22058 -92.77096)
		(end 69.774308 -92.77096)
		(width 0.12065)
		(layer "F.Cu")
		(net "HB_OUT")
	)
	(segment
		(start 190.520828 1.025144)
		(end 190.520828 -2.050288)
		(width 0.12065)
		(layer "F.Cu")
		(net "HB_OUT")
	)
	(segment
		(start 65.3288 -91.172538)
		(end 65.3288 -89.90584)
		(width 0.12065)
		(layer "F.Cu")
		(net "HB_OUT")
	)
	(segment
		(start 67.61226 -90.77706)
		(end 67.749166 -90.77706)
		(width 0.12065)
		(layer "F.Cu")
		(net "HB_OUT")
	)
	(segment
		(start 346.244672 -42.697908)
		(end 345.441016 -42.697908)
		(width 0.12065)
		(layer "F.Cu")
		(net "HB_OUT")
	)
	(segment
		(start 66.74104 -89.90584)
		(end 67.61226 -90.77706)
		(width 0.12065)
		(layer "F.Cu")
		(net "HB_OUT")
	)
	(segment
		(start 66.927222 -92.77096)
		(end 65.3288 -91.172538)
		(width 0.12065)
		(layer "F.Cu")
		(net "HB_OUT")
	)
	(segment
		(start 190.520828 -2.050288)
		(end 192.0748 -3.60426)
		(width 0.12065)
		(layer "F.Cu")
		(net "HB_OUT")
	)
	(segment
		(start 192.0748 -3.60426)
		(end 192.0748 -5.08)
		(width 0.12065)
		(layer "F.Cu")
		(net "HB_OUT")
	)
	(segment
		(start 193.0019 -6.0071)
		(end 193.0019 -6.6548)
		(width 0.12065)
		(layer "F.Cu")
		(net "HB_OUT")
	)
	(segment
		(start 69.774308 -92.77096)
		(end 66.927222 -92.77096)
		(width 0.12065)
		(layer "F.Cu")
		(net "HB_OUT")
	)
	(segment
		(start 69.336666 -90.07856)
		(end 68.638166 -90.77706)
		(width 0.12065)
		(layer "F.Cu")
		(net "HB_OUT")
	)
	(segment
		(start 65.3288 -89.90584)
		(end 66.74104 -89.90584)
		(width 0.12065)
		(layer "F.Cu")
		(net "HB_OUT")
	)
	(segment
		(start 189.567566 1.978406)
		(end 190.520828 1.025144)
		(width 0.12065)
		(layer "F.Cu")
		(net "HB_OUT")
	)
	(via
		(at 345.218512 -42.475404)
		(size 0.508)
		(drill 0.254)
		(layers "F.Cu" "B.Cu")
		(net "HB_OUT")
	)
	(via
		(at 69.774308 -92.77096)
		(size 0.7112)
		(drill 0.3556)
		(layers "F.Cu" "B.Cu")
		(net "HB_OUT")
	)
	(via
		(at 78.08595 -78.698852)
		(size 0.508)
		(drill 0.254)
		(layers "F.Cu" "B.Cu")
		(net "HB_OUT")
	)
	(via
		(at 73.22058 -92.77096)
		(size 0.508)
		(drill 0.254)
		(layers "F.Cu" "B.Cu")
		(net "HB_OUT")
	)
	(via
		(at 58.801 -177.546)
		(size 0.508)
		(drill 0.254)
		(layers "F.Cu" "B.Cu")
		(net "HB_OUT")
	)
	(via
		(at 189.567566 1.978406)
		(size 0.508)
		(drill 0.254)
		(layers "F.Cu" "B.Cu")
		(net "HB_OUT")
	)
	(segment
		(start 73.22058 -92.77096)
		(end 73.4822 -92.50934)
		(width 0.12065)
		(layer "B.Cu")
		(net "HB_OUT")
	)
	(segment
		(start 41.80205 -223.466914)
		(end 41.80205 -214.77605)
		(width 0.12065)
		(layer "B.Cu")
		(net "HB_OUT")
	)
	(segment
		(start 41.801796 -214.775796)
		(end 41.801796 -212.156294)
		(width 0.12065)
		(layer "B.Cu")
		(net "HB_OUT")
	)
	(segment
		(start 42.099992 -225.92538)
		(end 42.099992 -223.764856)
		(width 0.12065)
		(layer "B.Cu")
		(net "HB_OUT")
	)
	(segment
		(start 78.08595 -80.575912)
		(end 78.08595 -78.698852)
		(width 0.12065)
		(layer "B.Cu")
		(net "HB_OUT")
	)
	(segment
		(start 41.801796 -212.156294)
		(end 47.83709 -206.121)
		(width 0.12065)
		(layer "B.Cu")
		(net "HB_OUT")
	)
	(segment
		(start 59.83605 -200.25995)
		(end 59.83605 -178.58105)
		(width 0.12065)
		(layer "B.Cu")
		(net "HB_OUT")
	)
	(segment
		(start 47.83709 -206.121)
		(end 53.975 -206.121)
		(width 0.12065)
		(layer "B.Cu")
		(net "HB_OUT")
	)
	(segment
		(start 41.80205 -214.77605)
		(end 41.801796 -214.775796)
		(width 0.12065)
		(layer "B.Cu")
		(net "HB_OUT")
	)
	(segment
		(start 73.4822 -92.50934)
		(end 73.4822 -85.179662)
		(width 0.12065)
		(layer "B.Cu")
		(net "HB_OUT")
	)
	(segment
		(start 42.099992 -223.764856)
		(end 41.80205 -223.466914)
		(width 0.12065)
		(layer "B.Cu")
		(net "HB_OUT")
	)
	(segment
		(start 73.4822 -85.179662)
		(end 78.08595 -80.575912)
		(width 0.12065)
		(layer "B.Cu")
		(net "HB_OUT")
	)
	(segment
		(start 53.975 -206.121)
		(end 59.83605 -200.25995)
		(width 0.12065)
		(layer "B.Cu")
		(net "HB_OUT")
	)
	(segment
		(start 59.83605 -178.58105)
		(end 58.801 -177.546)
		(width 0.12065)
		(layer "B.Cu")
		(net "HB_OUT")
	)
	(segment
		(start 344.64371 -43.050206)
		(end 344.015314 -43.050206)
		(width 0.127)
		(layer "In2.Cu")
		(net "HB_OUT")
	)
	(segment
		(start 345.218512 -42.475404)
		(end 344.64371 -43.050206)
		(width 0.127)
		(layer "In2.Cu")
		(net "HB_OUT")
	)
	(segment
		(start 189.959742 2.370582)
		(end 189.567566 1.978406)
		(width 0.127)
		(layer "In2.Cu")
		(net "HB_OUT")
	)
	(segment
		(start 340.083394 -41.76522)
		(end 337.391248 -39.073074)
		(width 0.127)
		(layer "In2.Cu")
		(net "HB_OUT")
	)
	(segment
		(start 271.91208 0.4826)
		(end 261.196582 0.4826)
		(width 0.127)
		(layer "In2.Cu")
		(net "HB_OUT")
	)
	(segment
		(start 257.69443 -3.019552)
		(end 247.54967 -3.019552)
		(width 0.127)
		(layer "In2.Cu")
		(net "HB_OUT")
	)
	(segment
		(start 333.375 -6.891274)
		(end 323.885306 2.59842)
		(width 0.127)
		(layer "In2.Cu")
		(net "HB_OUT")
	)
	(segment
		(start 94.6912 -52.427886)
		(end 94.6912 -64.164718)
		(width 0.127)
		(layer "In2.Cu")
		(net "HB_OUT")
	)
	(segment
		(start 272.293334 0.8636)
		(end 271.91208 0.4826)
		(width 0.127)
		(layer "In2.Cu")
		(net "HB_OUT")
	)
	(segment
		(start 189.567566 1.978406)
		(end 189.149482 2.39649)
		(width 0.127)
		(layer "In2.Cu")
		(net "HB_OUT")
	)
	(segment
		(start 189.149482 2.39649)
		(end 129.36093 2.39649)
		(width 0.127)
		(layer "In2.Cu")
		(net "HB_OUT")
	)
	(segment
		(start 197.146418 2.370582)
		(end 189.959742 2.370582)
		(width 0.127)
		(layer "In2.Cu")
		(net "HB_OUT")
	)
	(segment
		(start 241.47018 3.059938)
		(end 205.164182 3.059938)
		(width 0.127)
		(layer "In2.Cu")
		(net "HB_OUT")
	)
	(segment
		(start 92.96019 -33.087818)
		(end 92.96019 -50.696876)
		(width 0.127)
		(layer "In2.Cu")
		(net "HB_OUT")
	)
	(segment
		(start 323.885306 2.59842)
		(end 274.028154 2.59842)
		(width 0.127)
		(layer "In2.Cu")
		(net "HB_OUT")
	)
	(segment
		(start 343.994232 -43.029378)
		(end 343.13368 -43.029378)
		(width 0.127)
		(layer "In2.Cu")
		(net "HB_OUT")
	)
	(segment
		(start 247.54967 -3.019552)
		(end 241.47018 3.059938)
		(width 0.127)
		(layer "In2.Cu")
		(net "HB_OUT")
	)
	(segment
		(start 120.165622 -5.882386)
		(end 92.96019 -33.087818)
		(width 0.127)
		(layer "In2.Cu")
		(net "HB_OUT")
	)
	(segment
		(start 79.03464 -77.750162)
		(end 78.08595 -78.698852)
		(width 0.127)
		(layer "In2.Cu")
		(net "HB_OUT")
	)
	(segment
		(start 92.96019 -50.696876)
		(end 94.6912 -52.427886)
		(width 0.127)
		(layer "In2.Cu")
		(net "HB_OUT")
	)
	(segment
		(start 334.608932 -39.073074)
		(end 333.79664 -38.260782)
		(width 0.127)
		(layer "In2.Cu")
		(net "HB_OUT")
	)
	(segment
		(start 341.869522 -41.76522)
		(end 340.083394 -41.76522)
		(width 0.127)
		(layer "In2.Cu")
		(net "HB_OUT")
	)
	(segment
		(start 129.36093 2.39649)
		(end 121.082054 -5.882386)
		(width 0.127)
		(layer "In2.Cu")
		(net "HB_OUT")
	)
	(segment
		(start 333.79664 -38.260782)
		(end 333.375 -37.839396)
		(width 0.127)
		(layer "In2.Cu")
		(net "HB_OUT")
	)
	(segment
		(start 201.888344 -0.2159)
		(end 199.7329 -0.2159)
		(width 0.127)
		(layer "In2.Cu")
		(net "HB_OUT")
	)
	(segment
		(start 333.375 -37.839396)
		(end 333.375 -6.891274)
		(width 0.127)
		(layer "In2.Cu")
		(net "HB_OUT")
	)
	(segment
		(start 121.082054 -5.882386)
		(end 120.165622 -5.882386)
		(width 0.127)
		(layer "In2.Cu")
		(net "HB_OUT")
	)
	(segment
		(start 94.6912 -64.164718)
		(end 81.105756 -77.750162)
		(width 0.127)
		(layer "In2.Cu")
		(net "HB_OUT")
	)
	(segment
		(start 344.015314 -43.050206)
		(end 343.994232 -43.029378)
		(width 0.127)
		(layer "In2.Cu")
		(net "HB_OUT")
	)
	(segment
		(start 274.028154 2.59842)
		(end 272.293334 0.8636)
		(width 0.127)
		(layer "In2.Cu")
		(net "HB_OUT")
	)
	(segment
		(start 343.13368 -43.029378)
		(end 341.869522 -41.76522)
		(width 0.127)
		(layer "In2.Cu")
		(net "HB_OUT")
	)
	(segment
		(start 199.7329 -0.2159)
		(end 197.146418 2.370582)
		(width 0.127)
		(layer "In2.Cu")
		(net "HB_OUT")
	)
	(segment
		(start 81.105756 -77.750162)
		(end 79.03464 -77.750162)
		(width 0.127)
		(layer "In2.Cu")
		(net "HB_OUT")
	)
	(segment
		(start 261.196582 0.4826)
		(end 257.69443 -3.019552)
		(width 0.127)
		(layer "In2.Cu")
		(net "HB_OUT")
	)
	(segment
		(start 337.391248 -39.073074)
		(end 334.608932 -39.073074)
		(width 0.127)
		(layer "In2.Cu")
		(net "HB_OUT")
	)
	(segment
		(start 205.164182 3.059938)
		(end 201.888344 -0.2159)
		(width 0.127)
		(layer "In2.Cu")
		(net "HB_OUT")
	)
	(segment
		(start 73.6854 -124.098812)
		(end 71.801228 -125.982984)
		(width 0.127)
		(layer "In5.Cu")
		(net "HB_OUT")
	)
	(segment
		(start 70.1421 -130.134868)
		(end 70.1421 -132.745988)
		(width 0.127)
		(layer "In5.Cu")
		(net "HB_OUT")
	)
	(segment
		(start 71.801228 -125.982984)
		(end 71.801228 -128.47574)
		(width 0.127)
		(layer "In5.Cu")
		(net "HB_OUT")
	)
	(segment
		(start 70.1421 -132.745988)
		(end 63.598552 -139.289536)
		(width 0.127)
		(layer "In5.Cu")
		(net "HB_OUT")
	)
	(segment
		(start 73.22058 -92.77096)
		(end 73.6854 -93.23578)
		(width 0.127)
		(layer "In5.Cu")
		(net "HB_OUT")
	)
	(segment
		(start 62.103 -147.725892)
		(end 62.103 -174.244)
		(width 0.127)
		(layer "In5.Cu")
		(net "HB_OUT")
	)
	(segment
		(start 71.801228 -128.47574)
		(end 70.1421 -130.134868)
		(width 0.127)
		(layer "In5.Cu")
		(net "HB_OUT")
	)
	(segment
		(start 73.6854 -93.23578)
		(end 73.6854 -124.098812)
		(width 0.127)
		(layer "In5.Cu")
		(net "HB_OUT")
	)
	(segment
		(start 62.103 -174.244)
		(end 58.801 -177.546)
		(width 0.127)
		(layer "In5.Cu")
		(net "HB_OUT")
	)
	(segment
		(start 63.598552 -139.289536)
		(end 63.598552 -146.23034)
		(width 0.127)
		(layer "In5.Cu")
		(net "HB_OUT")
	)
	(segment
		(start 63.598552 -146.23034)
		(end 62.103 -147.725892)
		(width 0.127)
		(layer "In5.Cu")
		(net "HB_OUT")
	)
	(segment
		(start 70.70344 -87.28456)
		(end 69.400166 -87.28456)
		(width 0.12065)
		(layer "F.Cu")
		(net "HB_A_OUT")
	)
	(segment
		(start 67.749166 -89.88806)
		(end 67.749166 -88.74506)
		(width 0.12065)
		(layer "F.Cu")
		(net "HB_A_OUT")
	)
	(segment
		(start 71.97344 -86.01456)
		(end 70.70344 -87.28456)
		(width 0.12065)
		(layer "F.Cu")
		(net "HB_A_OUT")
	)
	(segment
		(start 74.480166 -86.01456)
		(end 71.97344 -86.01456)
		(width 0.12065)
		(layer "F.Cu")
		(net "HB_A_OUT")
	)
	(segment
		(start 68.381626 -88.1126)
		(end 67.749166 -88.74506)
		(width 0.12065)
		(layer "F.Cu")
		(net "HB_A_OUT")
	)
	(segment
		(start 69.088 -88.1126)
		(end 68.381626 -88.1126)
		(width 0.12065)
		(layer "F.Cu")
		(net "HB_A_OUT")
	)
	(segment
		(start 77.429106 -86.487254)
		(end 76.2762 -86.487254)
		(width 0.12065)
		(layer "F.Cu")
		(net "HB_A_OUT")
	)
	(segment
		(start 76.2762 -86.487254)
		(end 75.819 -86.487254)
		(width 0.12065)
		(layer "F.Cu")
		(net "HB_A_OUT")
	)
	(segment
		(start 69.400166 -87.800434)
		(end 69.088 -88.1126)
		(width 0.12065)
		(layer "F.Cu")
		(net "HB_A_OUT")
	)
	(segment
		(start 75.819 -86.487254)
		(end 75.346306 -86.01456)
		(width 0.12065)
		(layer "F.Cu")
		(net "HB_A_OUT")
	)
	(segment
		(start 69.400166 -87.28456)
		(end 69.400166 -87.800434)
		(width 0.12065)
		(layer "F.Cu")
		(net "HB_A_OUT")
	)
	(segment
		(start 75.346306 -86.01456)
		(end 74.480166 -86.01456)
		(width 0.12065)
		(layer "F.Cu")
		(net "HB_A_OUT")
	)
	(via
		(at 76.2762 -86.487254)
		(size 0.7112)
		(drill 0.3556)
		(layers "F.Cu" "B.Cu")
		(net "HB_A_OUT")
	)
	(segment
		(start 71.7042 -84.1502)
		(end 67.7164 -84.1502)
		(width 0.12065)
		(layer "F.Cu")
		(net "HB_A_IN")
	)
	(segment
		(start 74.480166 -83.47456)
		(end 72.37984 -83.47456)
		(width 0.12065)
		(layer "F.Cu")
		(net "HB_A_IN")
	)
	(segment
		(start 67.7164 -84.1502)
		(end 67.304666 -84.561934)
		(width 0.12065)
		(layer "F.Cu")
		(net "HB_A_IN")
	)
	(segment
		(start 76.021184 -83.109816)
		(end 75.65644 -83.47456)
		(width 0.12065)
		(layer "F.Cu")
		(net "HB_A_IN")
	)
	(segment
		(start 69.400166 -86.01456)
		(end 67.304666 -86.01456)
		(width 0.12065)
		(layer "F.Cu")
		(net "HB_A_IN")
	)
	(segment
		(start 75.65644 -83.47456)
		(end 74.480166 -83.47456)
		(width 0.12065)
		(layer "F.Cu")
		(net "HB_A_IN")
	)
	(segment
		(start 72.37984 -83.47456)
		(end 71.7042 -84.1502)
		(width 0.12065)
		(layer "F.Cu")
		(net "HB_A_IN")
	)
	(segment
		(start 67.304666 -84.87156)
		(end 67.304666 -86.01456)
		(width 0.12065)
		(layer "F.Cu")
		(net "HB_A_IN")
	)
	(segment
		(start 76.275946 -82.855054)
		(end 76.021184 -83.109816)
		(width 0.12065)
		(layer "F.Cu")
		(net "HB_A_IN")
	)
	(segment
		(start 67.304666 -84.561934)
		(end 67.304666 -84.87156)
		(width 0.12065)
		(layer "F.Cu")
		(net "HB_A_IN")
	)
	(segment
		(start 77.378306 -82.855054)
		(end 76.275946 -82.855054)
		(width 0.12065)
		(layer "F.Cu")
		(net "HB_A_IN")
	)
	(via
		(at 76.021184 -83.109816)
		(size 0.7112)
		(drill 0.3556)
		(layers "F.Cu" "B.Cu")
		(net "HB_A_IN")
	)
	(segment
		(start 23.657052 -138.084052)
		(end 23.6474 -138.084052)
		(width 0.12065)
		(layer "F.Cu")
		(net "GPIOR5_R")
	)
	(segment
		(start 22.1107 -137.4394)
		(end 21.3995 -136.7282)
		(width 0.12065)
		(layer "F.Cu")
		(net "GPIOR5_R")
	)
	(segment
		(start 22.5806 -137.4394)
		(end 22.1107 -137.4394)
		(width 0.12065)
		(layer "F.Cu")
		(net "GPIOR5_R")
	)
	(segment
		(start 23.2156 -138.0744)
		(end 22.5806 -137.4394)
		(width 0.12065)
		(layer "F.Cu")
		(net "GPIOR5_R")
	)
	(segment
		(start 23.637748 -138.0744)
		(end 23.2156 -138.0744)
		(width 0.12065)
		(layer "F.Cu")
		(net "GPIOR5_R")
	)
	(segment
		(start 23.828248 -138.255248)
		(end 23.657052 -138.084052)
		(width 0.12065)
		(layer "F.Cu")
		(net "GPIOR5_R")
	)
	(segment
		(start 29.704792 -136.484868)
		(end 29.083 -136.484868)
		(width 0.12065)
		(layer "F.Cu")
		(net "GPIOR5_R")
	)
	(segment
		(start 29.083 -136.484868)
		(end 27.31262 -138.255248)
		(width 0.12065)
		(layer "F.Cu")
		(net "GPIOR5_R")
	)
	(segment
		(start 23.6474 -138.084052)
		(end 23.637748 -138.0744)
		(width 0.12065)
		(layer "F.Cu")
		(net "GPIOR5_R")
	)
	(segment
		(start 27.31262 -138.255248)
		(end 23.828248 -138.255248)
		(width 0.12065)
		(layer "F.Cu")
		(net "GPIOR5_R")
	)
	(via
		(at 23.6474 -138.084052)
		(size 0.7112)
		(drill 0.3556)
		(layers "F.Cu" "B.Cu")
		(net "GPIOR5_R")
	)
	(segment
		(start 26.832814 -137.547096)
		(end 27.357324 -137.547096)
		(width 0.12065)
		(layer "F.Cu")
		(net "GPIOR4_BMC_INT_N_R")
	)
	(segment
		(start 21.3995 -135.7122)
		(end 22.352 -136.6647)
		(width 0.12065)
		(layer "F.Cu")
		(net "GPIOR4_BMC_INT_N_R")
	)
	(segment
		(start 22.352 -136.779)
		(end 22.606 -136.779)
		(width 0.12065)
		(layer "F.Cu")
		(net "GPIOR4_BMC_INT_N_R")
	)
	(segment
		(start 27.357324 -137.547096)
		(end 27.38882 -137.5156)
		(width 0.12065)
		(layer "F.Cu")
		(net "GPIOR4_BMC_INT_N_R")
	)
	(segment
		(start 22.352 -136.6647)
		(end 22.352 -136.779)
		(width 0.12065)
		(layer "F.Cu")
		(net "GPIOR4_BMC_INT_N_R")
	)
	(segment
		(start 24.70658 -137.677144)
		(end 24.745696 -137.677144)
		(width 0.12065)
		(layer "F.Cu")
		(net "GPIOR4_BMC_INT_N_R")
	)
	(segment
		(start 24.545036 -137.5156)
		(end 24.70658 -137.677144)
		(width 0.12065)
		(layer "F.Cu")
		(net "GPIOR4_BMC_INT_N_R")
	)
	(segment
		(start 27.5336 -137.5156)
		(end 28.9814 -136.0678)
		(width 0.12065)
		(layer "F.Cu")
		(net "GPIOR4_BMC_INT_N_R")
	)
	(segment
		(start 30.12186 -136.0678)
		(end 30.504892 -135.684768)
		(width 0.12065)
		(layer "F.Cu")
		(net "GPIOR4_BMC_INT_N_R")
	)
	(segment
		(start 25.619964 -137.686796)
		(end 26.693114 -137.686796)
		(width 0.12065)
		(layer "F.Cu")
		(net "GPIOR4_BMC_INT_N_R")
	)
	(segment
		(start 27.38882 -137.5156)
		(end 27.5336 -137.5156)
		(width 0.12065)
		(layer "F.Cu")
		(net "GPIOR4_BMC_INT_N_R")
	)
	(segment
		(start 28.9814 -136.0678)
		(end 30.12186 -136.0678)
		(width 0.12065)
		(layer "F.Cu")
		(net "GPIOR4_BMC_INT_N_R")
	)
	(segment
		(start 25.423114 -137.883646)
		(end 25.619964 -137.686796)
		(width 0.12065)
		(layer "F.Cu")
		(net "GPIOR4_BMC_INT_N_R")
	)
	(segment
		(start 24.745696 -137.677144)
		(end 24.952198 -137.883646)
		(width 0.12065)
		(layer "F.Cu")
		(net "GPIOR4_BMC_INT_N_R")
	)
	(segment
		(start 24.952198 -137.883646)
		(end 25.423114 -137.883646)
		(width 0.12065)
		(layer "F.Cu")
		(net "GPIOR4_BMC_INT_N_R")
	)
	(segment
		(start 22.606 -136.779)
		(end 23.3426 -137.5156)
		(width 0.12065)
		(layer "F.Cu")
		(net "GPIOR4_BMC_INT_N_R")
	)
	(segment
		(start 23.3426 -137.5156)
		(end 24.545036 -137.5156)
		(width 0.12065)
		(layer "F.Cu")
		(net "GPIOR4_BMC_INT_N_R")
	)
	(segment
		(start 26.693114 -137.686796)
		(end 26.832814 -137.547096)
		(width 0.12065)
		(layer "F.Cu")
		(net "GPIOR4_BMC_INT_N_R")
	)
	(via
		(at 22.352 -136.779)
		(size 0.7112)
		(drill 0.3556)
		(layers "F.Cu" "B.Cu")
		(net "GPIOR4_BMC_INT_N_R")
	)
	(segment
		(start 32.104838 -134.884922)
		(end 31.705042 -135.284718)
		(width 0.12065)
		(layer "F.Cu")
		(net "GPIOR3_R")
	)
	(via
		(at 22.422612 -139.408662)
		(size 0.7112)
		(drill 0.3556)
		(layers "F.Cu" "B.Cu")
		(net "GPIOR3_R")
	)
	(via
		(at 31.705042 -135.284718)
		(size 0.4572)
		(drill 0.2032)
		(layers "F.Cu" "B.Cu")
		(net "GPIOR3_R")
	)
	(segment
		(start 31.295848 -135.693912)
		(end 31.705042 -135.284718)
		(width 0.12065)
		(layer "B.Cu")
		(net "GPIOR3_R")
	)
	(segment
		(start 23.368254 -140.318998)
		(end 23.368254 -140.332968)
		(width 0.12065)
		(layer "B.Cu")
		(net "GPIOR3_R")
	)
	(segment
		(start 26.905204 -139.154154)
		(end 29.078936 -136.980422)
		(width 0.12065)
		(layer "B.Cu")
		(net "GPIOR3_R")
	)
	(segment
		(start 29.078936 -136.980422)
		(end 29.456634 -136.980422)
		(width 0.12065)
		(layer "B.Cu")
		(net "GPIOR3_R")
	)
	(segment
		(start 23.368254 -140.332968)
		(end 25.966166 -140.332968)
		(width 0.12065)
		(layer "B.Cu")
		(net "GPIOR3_R")
	)
	(segment
		(start 25.966166 -140.332968)
		(end 26.905204 -139.39393)
		(width 0.12065)
		(layer "B.Cu")
		(net "GPIOR3_R")
	)
	(segment
		(start 26.905204 -139.39393)
		(end 26.905204 -139.154154)
		(width 0.12065)
		(layer "B.Cu")
		(net "GPIOR3_R")
	)
	(segment
		(start 22.788118 -139.774168)
		(end 22.823424 -139.774168)
		(width 0.12065)
		(layer "B.Cu")
		(net "GPIOR3_R")
	)
	(segment
		(start 21.3995 -138.811)
		(end 21.82495 -138.811)
		(width 0.12065)
		(layer "B.Cu")
		(net "GPIOR3_R")
	)
	(segment
		(start 22.422612 -139.408662)
		(end 22.788118 -139.774168)
		(width 0.12065)
		(layer "B.Cu")
		(net "GPIOR3_R")
	)
	(segment
		(start 22.823424 -139.774168)
		(end 23.368254 -140.318998)
		(width 0.12065)
		(layer "B.Cu")
		(net "GPIOR3_R")
	)
	(segment
		(start 29.456634 -136.980422)
		(end 30.743144 -135.693912)
		(width 0.12065)
		(layer "B.Cu")
		(net "GPIOR3_R")
	)
	(segment
		(start 30.743144 -135.693912)
		(end 31.295848 -135.693912)
		(width 0.12065)
		(layer "B.Cu")
		(net "GPIOR3_R")
	)
	(segment
		(start 21.82495 -138.811)
		(end 22.422612 -139.408662)
		(width 0.12065)
		(layer "B.Cu")
		(net "GPIOR3_R")
	)
	(segment
		(start 28.741878 -137.63371)
		(end 28.751022 -137.63371)
		(width 0.12065)
		(layer "F.Cu")
		(net "GPIOR2_R")
	)
	(segment
		(start 25.267412 -139.277852)
		(end 25.566116 -138.979148)
		(width 0.12065)
		(layer "F.Cu")
		(net "GPIOR2_R")
	)
	(segment
		(start 28.751022 -137.63371)
		(end 29.099764 -137.284968)
		(width 0.12065)
		(layer "F.Cu")
		(net "GPIOR2_R")
	)
	(segment
		(start 24.894032 -139.277852)
		(end 25.267412 -139.277852)
		(width 0.12065)
		(layer "F.Cu")
		(net "GPIOR2_R")
	)
	(segment
		(start 27.39644 -138.979148)
		(end 28.741878 -137.63371)
		(width 0.12065)
		(layer "F.Cu")
		(net "GPIOR2_R")
	)
	(segment
		(start 23.11781 -139.51839)
		(end 22.15769 -139.51839)
		(width 0.12065)
		(layer "F.Cu")
		(net "GPIOR2_R")
	)
	(segment
		(start 24.894032 -139.303252)
		(end 24.894032 -139.277852)
		(width 0.12065)
		(layer "F.Cu")
		(net "GPIOR2_R")
	)
	(segment
		(start 22.15769 -139.51839)
		(end 21.3995 -138.7602)
		(width 0.12065)
		(layer "F.Cu")
		(net "GPIOR2_R")
	)
	(segment
		(start 23.358348 -139.277852)
		(end 23.11781 -139.51839)
		(width 0.12065)
		(layer "F.Cu")
		(net "GPIOR2_R")
	)
	(segment
		(start 29.099764 -137.284968)
		(end 29.704792 -137.284968)
		(width 0.12065)
		(layer "F.Cu")
		(net "GPIOR2_R")
	)
	(segment
		(start 25.566116 -138.979148)
		(end 27.39644 -138.979148)
		(width 0.12065)
		(layer "F.Cu")
		(net "GPIOR2_R")
	)
	(segment
		(start 24.894032 -139.277852)
		(end 23.358348 -139.277852)
		(width 0.12065)
		(layer "F.Cu")
		(net "GPIOR2_R")
	)
	(via
		(at 24.894032 -139.303252)
		(size 0.7112)
		(drill 0.3556)
		(layers "F.Cu" "B.Cu")
		(net "GPIOR2_R")
	)
	(segment
		(start 23.174198 -138.949938)
		(end 23.389336 -138.7348)
		(width 0.12065)
		(layer "F.Cu")
		(net "GPIOR1_R")
	)
	(segment
		(start 30.13456 -136.8552)
		(end 30.504892 -136.484868)
		(width 0.12065)
		(layer "F.Cu")
		(net "GPIOR1_R")
	)
	(segment
		(start 27.443938 -138.617198)
		(end 28.649676 -137.41146)
		(width 0.12065)
		(layer "F.Cu")
		(net "GPIOR1_R")
	)
	(segment
		(start 28.649676 -137.41146)
		(end 28.65882 -137.41146)
		(width 0.12065)
		(layer "F.Cu")
		(net "GPIOR1_R")
	)
	(segment
		(start 22.536658 -138.881358)
		(end 22.536658 -138.949938)
		(width 0.12065)
		(layer "F.Cu")
		(net "GPIOR1_R")
	)
	(segment
		(start 22.536658 -138.949938)
		(end 23.174198 -138.949938)
		(width 0.12065)
		(layer "F.Cu")
		(net "GPIOR1_R")
	)
	(segment
		(start 25.416002 -138.617198)
		(end 27.443938 -138.617198)
		(width 0.12065)
		(layer "F.Cu")
		(net "GPIOR1_R")
	)
	(segment
		(start 21.3995 -137.7442)
		(end 22.536658 -138.881358)
		(width 0.12065)
		(layer "F.Cu")
		(net "GPIOR1_R")
	)
	(segment
		(start 23.389336 -138.7348)
		(end 25.2984 -138.7348)
		(width 0.12065)
		(layer "F.Cu")
		(net "GPIOR1_R")
	)
	(segment
		(start 28.65882 -137.41146)
		(end 29.21508 -136.8552)
		(width 0.12065)
		(layer "F.Cu")
		(net "GPIOR1_R")
	)
	(segment
		(start 25.2984 -138.7348)
		(end 25.416002 -138.617198)
		(width 0.12065)
		(layer "F.Cu")
		(net "GPIOR1_R")
	)
	(segment
		(start 29.21508 -136.8552)
		(end 30.13456 -136.8552)
		(width 0.12065)
		(layer "F.Cu")
		(net "GPIOR1_R")
	)
	(via
		(at 22.536658 -138.949938)
		(size 0.7112)
		(drill 0.3556)
		(layers "F.Cu" "B.Cu")
		(net "GPIOR1_R")
	)
	(segment
		(start 43.8912 -118.704106)
		(end 43.027346 -119.56796)
		(width 0.12065)
		(layer "F.Cu")
		(net "GPIOH2_R")
	)
	(segment
		(start 41.339516 -121.25579)
		(end 41.339516 -122.519694)
		(width 0.12065)
		(layer "F.Cu")
		(net "GPIOH2_R")
	)
	(segment
		(start 43.8912 -117.1575)
		(end 43.8912 -118.704106)
		(width 0.12065)
		(layer "F.Cu")
		(net "GPIOH2_R")
	)
	(segment
		(start 43.027346 -119.56796)
		(end 41.339516 -121.25579)
		(width 0.12065)
		(layer "F.Cu")
		(net "GPIOH2_R")
	)
	(segment
		(start 41.339516 -122.519694)
		(end 41.704768 -122.884946)
		(width 0.12065)
		(layer "F.Cu")
		(net "GPIOH2_R")
	)
	(via
		(at 43.027346 -119.56796)
		(size 0.7112)
		(drill 0.3556)
		(layers "F.Cu" "B.Cu")
		(net "GPIOH2_R")
	)
	(segment
		(start 45.549312 -116.2685)
		(end 45.618146 -116.199666)
		(width 0.12065)
		(layer "F.Cu")
		(net "GPIOH2")
	)
	(segment
		(start 43.8912 -116.2685)
		(end 45.549312 -116.2685)
		(width 0.12065)
		(layer "F.Cu")
		(net "GPIOH2")
	)
	(segment
		(start 40.904922 -121.111518)
		(end 42.29481 -119.72163)
		(width 0.12065)
		(layer "F.Cu")
		(net "GPIOH0")
	)
	(segment
		(start 40.904922 -122.084846)
		(end 40.904922 -121.111518)
		(width 0.12065)
		(layer "F.Cu")
		(net "GPIOH0")
	)
	(segment
		(start 42.29481 -119.72163)
		(end 42.29481 -119.241062)
		(width 0.12065)
		(layer "F.Cu")
		(net "GPIOH0")
	)
	(segment
		(start 42.29481 -119.241062)
		(end 43.228768 -118.307104)
		(width 0.12065)
		(layer "F.Cu")
		(net "GPIOH0")
	)
	(segment
		(start 248.59996 -34.99993)
		(end 249.099832 -34.500058)
		(width 0.12065)
		(layer "F.Cu")
		(net "GPIO109_R")
	)
	(via
		(at 249.099832 -34.500058)
		(size 0.4572)
		(drill 0.2032)
		(layers "F.Cu" "B.Cu")
		(net "GPIO109_R")
	)
	(segment
		(start 249.599958 -33.999932)
		(end 249.099832 -34.500058)
		(width 0.12065)
		(layer "B.Cu")
		(net "GPIO109_R")
	)
	(segment
		(start 248.59996 -39.99992)
		(end 249.099832 -39.500048)
		(width 0.12065)
		(layer "F.Cu")
		(net "GPIO108_R")
	)
	(via
		(at 249.099832 -39.500048)
		(size 0.4572)
		(drill 0.2032)
		(layers "F.Cu" "B.Cu")
		(net "GPIO108_R")
	)
	(segment
		(start 249.099832 -39.511224)
		(end 249.099832 -39.500048)
		(width 0.12065)
		(layer "B.Cu")
		(net "GPIO108_R")
	)
	(segment
		(start 249.588528 -39.99992)
		(end 249.099832 -39.511224)
		(width 0.12065)
		(layer "B.Cu")
		(net "GPIO108_R")
	)
	(segment
		(start 248.59996 -40.999918)
		(end 249.099832 -40.500046)
		(width 0.12065)
		(layer "F.Cu")
		(net "GPIO107_R")
	)
	(via
		(at 249.099832 -40.500046)
		(size 0.4572)
		(drill 0.2032)
		(layers "F.Cu" "B.Cu")
		(net "GPIO107_R")
	)
	(segment
		(start 248.59996 -40.999918)
		(end 249.099832 -40.500046)
		(width 0.12065)
		(layer "B.Cu")
		(net "GPIO107_R")
	)
	(segment
		(start 18.25498 -65.30848)
		(end 18.82648 -65.30848)
		(width 0.508)
		(layer "F.Cu")
		(net "GND")
	)
	(segment
		(start 239.599978 -31.999936)
		(end 239.100106 -31.500064)
		(width 0.4572)
		(layer "F.Cu")
		(net "GND")
	)
	(segment
		(start 125.978412 -210.142074)
		(end 125.978412 -209.341974)
		(width 0.508)
		(layer "F.Cu")
		(net "GND")
	)
	(segment
		(start 63.427102 -133.5405)
		(end 63.4238 -133.537198)
		(width 0.508)
		(layer "F.Cu")
		(net "GND")
	)
	(segment
		(start 318.900048 -225.54438)
		(end 318.900048 -223.482154)
		(width 0.508)
		(layer "F.Cu")
		(net "GND")
	)
	(segment
		(start 23.05812 -69.35343)
		(end 23.05812 -69.5452)
		(width 0.508)
		(layer "F.Cu")
		(net "GND")
	)
	(segment
		(start 241.599974 -57.999884)
		(end 242.099846 -58.499756)
		(width 0.4572)
		(layer "F.Cu")
		(net "GND")
	)
	(segment
		(start 250.599956 -58.999882)
		(end 251.099828 -59.499754)
		(width 0.4572)
		(layer "F.Cu")
		(net "GND")
	)
	(segment
		(start 234.599988 -45.999908)
		(end 234.100116 -45.500036)
		(width 0.4572)
		(layer "F.Cu")
		(net "GND")
	)
	(segment
		(start 9.779 -67.5386)
		(end 8.9916 -66.7512)
		(width 0.508)
		(layer "F.Cu")
		(net "GND")
	)
	(segment
		(start 251.599954 -63.999872)
		(end 252.099826 -64.499744)
		(width 0.4572)
		(layer "F.Cu")
		(net "GND")
	)
	(segment
		(start 35.571938 -97.801938)
		(end 36.322 -98.552)
		(width 0.3048)
		(layer "F.Cu")
		(net "GND")
	)
	(segment
		(start 9.779 -72.2249)
		(end 8.9281 -72.2249)
		(width 0.508)
		(layer "F.Cu")
		(net "GND")
	)
	(segment
		(start 49.149 -184.15)
		(end 48.26 -184.15)
		(width 0.508)
		(layer "F.Cu")
		(net "GND")
	)
	(segment
		(start 340.500208 -225.54438)
		(end 340.500208 -223.482408)
		(width 0.508)
		(layer "F.Cu")
		(net "GND")
	)
	(segment
		(start 153.45918 -84.85886)
		(end 153.45918 -85.8266)
		(width 0.508)
		(layer "F.Cu")
		(net "GND")
	)
	(segment
		(start 22.422104 -62.999874)
		(end 22.422104 -59.1058)
		(width 1.016)
		(layer "F.Cu")
		(net "GND")
	)
	(segment
		(start 226.600004 -62.999874)
		(end 226.100132 -63.499746)
		(width 0.4572)
		(layer "F.Cu")
		(net "GND")
	)
	(segment
		(start 137.700004 -223.538796)
		(end 138.176 -223.0628)
		(width 0.508)
		(layer "F.Cu")
		(net "GND")
	)
	(segment
		(start 230.6955 -11.43)
		(end 231.648 -11.43)
		(width 0.508)
		(layer "F.Cu")
		(net "GND")
	)
	(segment
		(start 240.599976 -56.999886)
		(end 241.099848 -57.499758)
		(width 0.4572)
		(layer "F.Cu")
		(net "GND")
	)
	(segment
		(start 233.59999 -57.999884)
		(end 233.100118 -58.499756)
		(width 0.4572)
		(layer "F.Cu")
		(net "GND")
	)
	(segment
		(start 247.599962 -54.99989)
		(end 248.099834 -55.499762)
		(width 0.4572)
		(layer "F.Cu")
		(net "GND")
	)
	(segment
		(start 209.4103 -17.21485)
		(end 211.10575 -17.21485)
		(width 0.508)
		(layer "F.Cu")
		(net "GND")
	)
	(segment
		(start 332.7908 -186.1312)
		(end 332.7654 -186.1566)
		(width 0.508)
		(layer "F.Cu")
		(net "GND")
	)
	(segment
		(start 12.1666 -52.0446)
		(end 12.1666 -52.836318)
		(width 0.508)
		(layer "F.Cu")
		(net "GND")
	)
	(segment
		(start 68.326 -129.14376)
		(end 68.326 -128.260348)
		(width 0.4064)
		(layer "F.Cu")
		(net "GND")
	)
	(segment
		(start 249.599958 -49.9999)
		(end 250.09983 -50.499772)
		(width 0.4572)
		(layer "F.Cu")
		(net "GND")
	)
	(segment
		(start 49.149 -192.913)
		(end 49.149 -191.897)
		(width 0.508)
		(layer "F.Cu")
		(net "GND")
	)
	(segment
		(start 249.599958 -32.999934)
		(end 250.09983 -32.500062)
		(width 0.4572)
		(layer "F.Cu")
		(net "GND")
	)
	(segment
		(start 225.600006 -31.999936)
		(end 225.100134 -31.500064)
		(width 0.4572)
		(layer "F.Cu")
		(net "GND")
	)
	(segment
		(start 79.883 -182.499)
		(end 79.375 -181.991)
		(width 0.508)
		(layer "F.Cu")
		(net "GND")
	)
	(segment
		(start 8.9916 -66.7512)
		(end 7.2136 -66.7512)
		(width 0.508)
		(layer "F.Cu")
		(net "GND")
	)
	(segment
		(start 20.8661 -50.6476)
		(end 20.6121 -50.6476)
		(width 0.508)
		(layer "F.Cu")
		(net "GND")
	)
	(segment
		(start 256.599944 -57.999884)
		(end 257.099816 -58.499756)
		(width 0.4572)
		(layer "F.Cu")
		(net "GND")
	)
	(segment
		(start 196.100192 -225.54438)
		(end 196.100192 -223.482154)
		(width 0.508)
		(layer "F.Cu")
		(net "GND")
	)
	(segment
		(start 248.59996 -50.999898)
		(end 249.099832 -51.49977)
		(width 0.4572)
		(layer "F.Cu")
		(net "GND")
	)
	(segment
		(start 37.704776 -125.284992)
		(end 37.30498 -124.885196)
		(width 0.3556)
		(layer "F.Cu")
		(net "GND")
	)
	(segment
		(start 158.294578 -89.326466)
		(end 157.240478 -89.326466)
		(width 0.3048)
		(layer "F.Cu")
		(net "GND")
	)
	(segment
		(start 192.900046 -225.54438)
		(end 192.900046 -223.482154)
		(width 0.508)
		(layer "F.Cu")
		(net "GND")
	)
	(segment
		(start 230.599996 -62.999874)
		(end 230.100124 -63.499746)
		(width 0.4572)
		(layer "F.Cu")
		(net "GND")
	)
	(segment
		(start 234.599988 -55.999888)
		(end 234.100116 -56.49976)
		(width 0.4572)
		(layer "F.Cu")
		(net "GND")
	)
	(segment
		(start 62.611 -132.3975)
		(end 63.4238 -132.3975)
		(width 0.508)
		(layer "F.Cu")
		(net "GND")
	)
	(segment
		(start 229.5525 -92.202)
		(end 229.6922 -92.202)
		(width 0.508)
		(layer "F.Cu")
		(net "GND")
	)
	(segment
		(start 153.283412 -93.017848)
		(end 153.283412 -94.279212)
		(width 0.508)
		(layer "F.Cu")
		(net "GND")
	)
	(segment
		(start 119.4308 -98.7552)
		(end 118.5418 -98.7552)
		(width 0.508)
		(layer "F.Cu")
		(net "GND")
	)
	(segment
		(start 284.63875 -57.15)
		(end 285.496 -57.15)
		(width 0.508)
		(layer "F.Cu")
		(net "GND")
	)
	(segment
		(start 231.599994 -61.999876)
		(end 231.100122 -62.499748)
		(width 0.4572)
		(layer "F.Cu")
		(net "GND")
	)
	(segment
		(start 314.900056 -225.54438)
		(end 314.900056 -223.482154)
		(width 0.508)
		(layer "F.Cu")
		(net "GND")
	)
	(segment
		(start 47.700184 -223.645984)
		(end 47.117 -223.0628)
		(width 0.508)
		(layer "F.Cu")
		(net "GND")
	)
	(segment
		(start 137.034778 -81.844642)
		(end 137.0203 -81.830164)
		(width 0.508)
		(layer "F.Cu")
		(net "GND")
	)
	(segment
		(start 165.6715 -95.6564)
		(end 165.6715 -96.4565)
		(width 0.508)
		(layer "F.Cu")
		(net "GND")
	)
	(segment
		(start 37.273992 -106.757724)
		(end 38.209474 -106.757724)
		(width 0.508)
		(layer "F.Cu")
		(net "GND")
	)
	(segment
		(start 253.59995 -31.999936)
		(end 254.099822 -31.500064)
		(width 0.4572)
		(layer "F.Cu")
		(net "GND")
	)
	(segment
		(start 251.196094 -3.59664)
		(end 250.27001 -3.59664)
		(width 0.508)
		(layer "F.Cu")
		(net "GND")
	)
	(segment
		(start 39.705026 -128.885188)
		(end 39.30523 -129.284984)
		(width 0.3556)
		(layer "F.Cu")
		(net "GND")
	)
	(segment
		(start 231.599994 -48.999902)
		(end 231.100122 -49.499774)
		(width 0.4572)
		(layer "F.Cu")
		(net "GND")
	)
	(segment
		(start 237.599982 -62.999874)
		(end 237.10011 -63.499746)
		(width 0.4572)
		(layer "F.Cu")
		(net "GND")
	)
	(segment
		(start 317.428372 -35.859466)
		(end 317.42888 -35.859974)
		(width 0.508)
		(layer "F.Cu")
		(net "GND")
	)
	(segment
		(start 222.600012 -61.999876)
		(end 222.10014 -62.499748)
		(width 0.4572)
		(layer "F.Cu")
		(net "GND")
	)
	(segment
		(start 195.300092 -223.482154)
		(end 194.900042 -223.082104)
		(width 0.508)
		(layer "F.Cu")
		(net "GND")
	)
	(segment
		(start 335.70037 -37.657786)
		(end 336.651092 -37.657786)
		(width 0.508)
		(layer "F.Cu")
		(net "GND")
	)
	(segment
		(start 7.9756 -52.0446)
		(end 7.9756 -53.13426)
		(width 0.508)
		(layer "F.Cu")
		(net "GND")
	)
	(segment
		(start 242.599972 -45.999908)
		(end 243.099844 -45.500036)
		(width 0.4572)
		(layer "F.Cu")
		(net "GND")
	)
	(segment
		(start 152.14981 -88.54821)
		(end 151.590756 -88.54821)
		(width 0.3048)
		(layer "F.Cu")
		(net "GND")
	)
	(segment
		(start 251.599954 -32.999934)
		(end 252.099826 -32.500062)
		(width 0.4572)
		(layer "F.Cu")
		(net "GND")
	)
	(segment
		(start 63.4492 -90.71102)
		(end 63.22822 -90.932)
		(width 0.4064)
		(layer "F.Cu")
		(net "GND")
	)
	(segment
		(start 27.5336 -97.845118)
		(end 27.547062 -97.831656)
		(width 0.508)
		(layer "F.Cu")
		(net "GND")
	)
	(segment
		(start 71.724012 -196.959474)
		(end 71.749412 -196.934074)
		(width 0.508)
		(layer "F.Cu")
		(net "GND")
	)
	(segment
		(start 255.599946 -56.999886)
		(end 256.099818 -57.499758)
		(width 0.4572)
		(layer "F.Cu")
		(net "GND")
	)
	(segment
		(start 238.59998 -43.999912)
		(end 238.100108 -43.50004)
		(width 0.4572)
		(layer "F.Cu")
		(net "GND")
	)
	(segment
		(start 227.600002 -53.999892)
		(end 227.10013 -54.499764)
		(width 0.4572)
		(layer "F.Cu")
		(net "GND")
	)
	(segment
		(start 219.831412 -204.300074)
		(end 219.806012 -204.325474)
		(width 0.508)
		(layer "F.Cu")
		(net "GND")
	)
	(segment
		(start 53.300122 -223.482408)
		(end 52.899818 -223.082104)
		(width 0.508)
		(layer "F.Cu")
		(net "GND")
	)
	(segment
		(start 235.599986 -48.999902)
		(end 235.100114 -49.499774)
		(width 0.4572)
		(layer "F.Cu")
		(net "GND")
	)
	(segment
		(start 321.300094 -223.482154)
		(end 320.900044 -223.082104)
		(width 0.508)
		(layer "F.Cu")
		(net "GND")
	)
	(segment
		(start 221.360238 -7.874762)
		(end 220.844872 -7.874762)
		(width 0.508)
		(layer "F.Cu")
		(net "GND")
	)
	(segment
		(start 248.59996 -48.999902)
		(end 249.099832 -49.499774)
		(width 0.4572)
		(layer "F.Cu")
		(net "GND")
	)
	(segment
		(start 246.599964 -43.999912)
		(end 247.099836 -43.50004)
		(width 0.4572)
		(layer "F.Cu")
		(net "GND")
	)
	(segment
		(start 16.058388 -183.0324)
		(end 16.637 -182.453788)
		(width 0.508)
		(layer "F.Cu")
		(net "GND")
	)
	(segment
		(start 255.599946 -54.99989)
		(end 256.099818 -55.499762)
		(width 0.4572)
		(layer "F.Cu")
		(net "GND")
	)
	(segment
		(start 36.90493 -128.484884)
		(end 36.90493 -128.485138)
		(width 0.3556)
		(layer "F.Cu")
		(net "GND")
	)
	(segment
		(start 156.100018 -225.54438)
		(end 156.100018 -223.482154)
		(width 0.508)
		(layer "F.Cu")
		(net "GND")
	)
	(segment
		(start 228.6 -51.999896)
		(end 228.100128 -52.499768)
		(width 0.4572)
		(layer "F.Cu")
		(net "GND")
	)
	(segment
		(start 28.2956 -183.3372)
		(end 28.2956 -182.4482)
		(width 0.508)
		(layer "F.Cu")
		(net "GND")
	)
	(segment
		(start 43.304714 -131.685284)
		(end 43.70451 -132.08508)
		(width 0.3556)
		(layer "F.Cu")
		(net "GND")
	)
	(segment
		(start 256.599944 -44.99991)
		(end 257.099816 -44.500038)
		(width 0.4572)
		(layer "F.Cu")
		(net "GND")
	)
	(segment
		(start 23.0759 -120.2055)
		(end 23.495 -120.2055)
		(width 0.508)
		(layer "F.Cu")
		(net "GND")
	)
	(segment
		(start 37.704776 -128.484884)
		(end 38.504876 -129.284984)
		(width 0.3556)
		(layer "F.Cu")
		(net "GND")
	)
	(segment
		(start 185.700162 -225.54438)
		(end 185.700162 -223.482408)
		(width 0.508)
		(layer "F.Cu")
		(net "GND")
	)
	(segment
		(start 255.599946 -31.999936)
		(end 256.099818 -31.500064)
		(width 0.4572)
		(layer "F.Cu")
		(net "GND")
	)
	(segment
		(start 6.3627 -182.9816)
		(end 6.3627 -182.0926)
		(width 0.508)
		(layer "F.Cu")
		(net "GND")
	)
	(segment
		(start 314.900056 -223.482154)
		(end 314.500006 -223.082104)
		(width 0.508)
		(layer "F.Cu")
		(net "GND")
	)
	(segment
		(start 336.8294 -187.995306)
		(end 336.971894 -188.1378)
		(width 0.508)
		(layer "F.Cu")
		(net "GND")
	)
	(segment
		(start 20.6121 -50.6476)
		(end 19.8247 -49.8602)
		(width 0.508)
		(layer "F.Cu")
		(net "GND")
	)
	(segment
		(start 236.599984 -58.999882)
		(end 236.100112 -59.499754)
		(width 0.4572)
		(layer "F.Cu")
		(net "GND")
	)
	(segment
		(start 160.031938 -93.968062)
		(end 159.893 -94.107)
		(width 0.3048)
		(layer "F.Cu")
		(net "GND")
	)
	(segment
		(start 75.625452 -149.52091)
		(end 76.454 -149.52091)
		(width 0.508)
		(layer "F.Cu")
		(net "GND")
	)
	(segment
		(start 37.768022 -150.779988)
		(end 37.768022 -150.783036)
		(width 0.3048)
		(layer "F.Cu")
		(net "GND")
	)
	(segment
		(start 6.223 -93.1926)
		(end 5.8166 -92.7862)
		(width 0.508)
		(layer "F.Cu")
		(net "GND")
	)
	(segment
		(start 42.037 -146.939)
		(end 42.037 -149.710902)
		(width 0.508)
		(layer "F.Cu")
		(net "GND")
	)
	(segment
		(start 229.599998 -47.999904)
		(end 229.100126 -48.499776)
		(width 0.4572)
		(layer "F.Cu")
		(net "GND")
	)
	(segment
		(start 64.07658 -147.670774)
		(end 63.530226 -147.670774)
		(width 0.508)
		(layer "F.Cu")
		(net "GND")
	)
	(segment
		(start 38.180264 -163.546536)
		(end 38.203886 -163.546536)
		(width 0.508)
		(layer "F.Cu")
		(net "GND")
	)
	(segment
		(start 32.341312 -62.999874)
		(end 32.34182 -62.999366)
		(width 1.016)
		(layer "F.Cu")
		(net "GND")
	)
	(segment
		(start 22.987 -145.7706)
		(end 23.561548 -145.196052)
		(width 0.508)
		(layer "F.Cu")
		(net "GND")
	)
	(segment
		(start 224.600008 -48.999902)
		(end 224.100136 -49.499774)
		(width 0.4572)
		(layer "F.Cu")
		(net "GND")
	)
	(segment
		(start 225.600006 -41.999916)
		(end 225.100134 -41.500044)
		(width 0.4572)
		(layer "F.Cu")
		(net "GND")
	)
	(segment
		(start 202.50023 -223.4819)
		(end 202.900026 -223.082104)
		(width 0.508)
		(layer "F.Cu")
		(net "GND")
	)
	(segment
		(start 237.599982 -57.999884)
		(end 237.10011 -58.499756)
		(width 0.4572)
		(layer "F.Cu")
		(net "GND")
	)
	(segment
		(start 23.517352 -104.331262)
		(end 23.51532 -104.333294)
		(width 0.4064)
		(layer "F.Cu")
		(net "GND")
	)
	(segment
		(start 257.867912 -11.641582)
		(end 257.670554 -11.444224)
		(width 0.508)
		(layer "F.Cu")
		(net "GND")
	)
	(segment
		(start 191.9478 -25.0952)
		(end 191.389 -24.5364)
		(width 0.508)
		(layer "F.Cu")
		(net "GND")
	)
	(segment
		(start 28.642056 -65.294764)
		(end 28.642056 -67.111372)
		(width 0.508)
		(layer "F.Cu")
		(net "GND")
	)
	(segment
		(start 248.59996 -42.999914)
		(end 249.099832 -42.500042)
		(width 0.4572)
		(layer "F.Cu")
		(net "GND")
	)
	(segment
		(start 218.885008 -3.302)
		(end 218.885008 -3.6195)
		(width 0.508)
		(layer "F.Cu")
		(net "GND")
	)
	(segment
		(start 256.599944 -48.999902)
		(end 257.099816 -49.499774)
		(width 0.4572)
		(layer "F.Cu")
		(net "GND")
	)
	(segment
		(start 251.599954 -51.999896)
		(end 252.099826 -52.499768)
		(width 0.4572)
		(layer "F.Cu")
		(net "GND")
	)
	(segment
		(start 226.600004 -32.999934)
		(end 226.100132 -32.500062)
		(width 0.4572)
		(layer "F.Cu")
		(net "GND")
	)
	(segment
		(start 79.308706 -82.855054)
		(end 80.37068 -83.917028)
		(width 0.508)
		(layer "F.Cu")
		(net "GND")
	)
	(segment
		(start 218.8845 -10.16)
		(end 218.059 -10.16)
		(width 0.508)
		(layer "F.Cu")
		(net "GND")
	)
	(segment
		(start 111.700056 -225.54438)
		(end 111.700056 -223.482154)
		(width 0.508)
		(layer "F.Cu")
		(net "GND")
	)
	(segment
		(start 11.7983 -80.6704)
		(end 12.3063 -81.1784)
		(width 0.508)
		(layer "F.Cu")
		(net "GND")
	)
	(segment
		(start 18.4785 -142.24)
		(end 18.06067 -142.24)
		(width 0.508)
		(layer "F.Cu")
		(net "GND")
	)
	(segment
		(start 143.300196 -225.54438)
		(end 143.300196 -223.482408)
		(width 0.508)
		(layer "F.Cu")
		(net "GND")
	)
	(segment
		(start 240.599976 -47.999904)
		(end 241.599974 -48.999902)
		(width 0.4572)
		(layer "F.Cu")
		(net "GND")
	)
	(segment
		(start 11.8999 -99.4029)
		(end 11.8999 -100.1776)
		(width 0.508)
		(layer "F.Cu")
		(net "GND")
	)
	(segment
		(start 165.672516 -86.384384)
		(end 165.672516 -85.433662)
		(width 0.508)
		(layer "F.Cu")
		(net "GND")
	)
	(segment
		(start 233.59999 -46.999906)
		(end 233.100118 -46.500034)
		(width 0.4572)
		(layer "F.Cu")
		(net "GND")
	)
	(segment
		(start 231.599994 -45.999908)
		(end 231.100122 -45.500036)
		(width 0.4572)
		(layer "F.Cu")
		(net "GND")
	)
	(segment
		(start 162.031934 -93.832934)
		(end 162.433 -94.234)
		(width 0.3048)
		(layer "F.Cu")
		(net "GND")
	)
	(segment
		(start 217.700098 -225.54438)
		(end 217.700098 -223.338898)
		(width 0.508)
		(layer "F.Cu")
		(net "GND")
	)
	(segment
		(start 81.300066 -225.54438)
		(end 81.300066 -223.482408)
		(width 0.508)
		(layer "F.Cu")
		(net "GND")
	)
	(segment
		(start 75.568048 -120.74144)
		(end 77.07376 -120.74144)
		(width 0.3048)
		(layer "F.Cu")
		(net "GND")
	)
	(segment
		(start 271.731486 -3.376168)
		(end 271.477486 -3.376168)
		(width 0.508)
		(layer "F.Cu")
		(net "GND")
	)
	(segment
		(start 240.599976 -61.999876)
		(end 241.099848 -62.499748)
		(width 0.4572)
		(layer "F.Cu")
		(net "GND")
	)
	(segment
		(start 257.599942 -60.999878)
		(end 258.099814 -61.49975)
		(width 0.4572)
		(layer "F.Cu")
		(net "GND")
	)
	(segment
		(start 5.4356 -86.614)
		(end 5.4356 -83.2866)
		(width 0.508)
		(layer "F.Cu")
		(net "GND")
	)
	(segment
		(start 229.599998 -45.999908)
		(end 229.100126 -45.500036)
		(width 0.4572)
		(layer "F.Cu")
		(net "GND")
	)
	(segment
		(start 56.1594 -131.6609)
		(end 56.134 -131.6355)
		(width 0.508)
		(layer "F.Cu")
		(net "GND")
	)
	(segment
		(start 241.599974 -54.99989)
		(end 242.099846 -55.499762)
		(width 0.4572)
		(layer "F.Cu")
		(net "GND")
	)
	(segment
		(start 334.01 -71.6915)
		(end 335.026 -71.6915)
		(width 0.508)
		(layer "F.Cu")
		(net "GND")
	)
	(segment
		(start 243.59997 -48.999902)
		(end 244.099842 -49.499774)
		(width 0.4572)
		(layer "F.Cu")
		(net "GND")
	)
	(segment
		(start 150.930356 -89.20861)
		(end 150.930356 -94.110302)
		(width 0.3048)
		(layer "F.Cu")
		(net "GND")
	)
	(segment
		(start 255.599946 -50.999898)
		(end 256.099818 -51.49977)
		(width 0.4572)
		(layer "F.Cu")
		(net "GND")
	)
	(segment
		(start 87.700104 -225.54438)
		(end 87.700104 -223.482408)
		(width 0.508)
		(layer "F.Cu")
		(net "GND")
	)
	(segment
		(start 318.900048 -223.482154)
		(end 319.300098 -223.082104)
		(width 0.508)
		(layer "F.Cu")
		(net "GND")
	)
	(segment
		(start 168.099994 -225.54438)
		(end 168.099994 -223.482154)
		(width 0.508)
		(layer "F.Cu")
		(net "GND")
	)
	(segment
		(start 238.59998 -49.9999)
		(end 238.100108 -50.499772)
		(width 0.4572)
		(layer "F.Cu")
		(net "GND")
	)
	(segment
		(start 217.043 -11.6205)
		(end 216.230708 -11.6205)
		(width 0.508)
		(layer "F.Cu")
		(net "GND")
	)
	(segment
		(start 231.599994 -51.999896)
		(end 231.100122 -52.499768)
		(width 0.4572)
		(layer "F.Cu")
		(net "GND")
	)
	(segment
		(start 240.599976 -54.99989)
		(end 241.099848 -55.499762)
		(width 0.4572)
		(layer "F.Cu")
		(net "GND")
	)
	(segment
		(start 250.599956 -42.999914)
		(end 251.099828 -42.500042)
		(width 0.4572)
		(layer "F.Cu")
		(net "GND")
	)
	(segment
		(start 37.30498 -129.685034)
		(end 37.704776 -130.08483)
		(width 0.3556)
		(layer "F.Cu")
		(net "GND")
	)
	(segment
		(start 43.304714 -131.684776)
		(end 43.304714 -131.685284)
		(width 0.3556)
		(layer "F.Cu")
		(net "GND")
	)
	(segment
		(start 50.900076 -223.482154)
		(end 51.300126 -223.082104)
		(width 0.508)
		(layer "F.Cu")
		(net "GND")
	)
	(segment
		(start 32.96793 -149.979888)
		(end 33.367726 -149.580092)
		(width 0.3556)
		(layer "F.Cu")
		(net "GND")
	)
	(segment
		(start 137.034778 -84.986622)
		(end 137.034778 -84.019898)
		(width 0.508)
		(layer "F.Cu")
		(net "GND")
	)
	(segment
		(start 252.599952 -51.999896)
		(end 253.099824 -52.499768)
		(width 0.4572)
		(layer "F.Cu")
		(net "GND")
	)
	(segment
		(start 66.275966 -87.775034)
		(end 65.717166 -87.775034)
		(width 0.4064)
		(layer "F.Cu")
		(net "GND")
	)
	(segment
		(start 272.822162 -11.426952)
		(end 272.742152 -11.346942)
		(width 0.508)
		(layer "F.Cu")
		(net "GND")
	)
	(segment
		(start 114.945414 -38.927786)
		(end 114.935 -38.9382)
		(width 0.508)
		(layer "F.Cu")
		(net "GND")
	)
	(segment
		(start 140.90015 -225.54438)
		(end 140.90015 -223.482154)
		(width 0.508)
		(layer "F.Cu")
		(net "GND")
	)
	(segment
		(start 198.500238 -225.54438)
		(end 198.500238 -223.482408)
		(width 0.508)
		(layer "F.Cu")
		(net "GND")
	)
	(segment
		(start 154.813 -90.711782)
		(end 154.813 -91.622118)
		(width 0.508)
		(layer "F.Cu")
		(net "GND")
	)
	(segment
		(start 235.599986 -54.99989)
		(end 235.100114 -55.499762)
		(width 0.4572)
		(layer "F.Cu")
		(net "GND")
	)
	(segment
		(start 162.031934 -93.063822)
		(end 162.031934 -93.832934)
		(width 0.3048)
		(layer "F.Cu")
		(net "GND")
	)
	(segment
		(start 22.987 -149.098)
		(end 22.987 -147.3454)
		(width 0.508)
		(layer "F.Cu")
		(net "GND")
	)
	(segment
		(start 311.700164 -223.482408)
		(end 311.29986 -223.082104)
		(width 0.508)
		(layer "F.Cu")
		(net "GND")
	)
	(segment
		(start 229.599998 -52.999894)
		(end 229.100126 -53.499766)
		(width 0.4572)
		(layer "F.Cu")
		(net "GND")
	)
	(segment
		(start 38.568122 -157.179772)
		(end 38.967918 -156.779976)
		(width 0.3556)
		(layer "F.Cu")
		(net "GND")
	)
	(segment
		(start 38.904926 -132.084826)
		(end 38.904926 -132.08508)
		(width 0.3556)
		(layer "F.Cu")
		(net "GND")
	)
	(segment
		(start 245.599966 -46.999906)
		(end 246.099838 -46.500034)
		(width 0.4572)
		(layer "F.Cu")
		(net "GND")
	)
	(segment
		(start 255.599946 -38.999922)
		(end 256.099818 -38.50005)
		(width 0.4572)
		(layer "F.Cu")
		(net "GND")
	)
	(segment
		(start 191.7954 -27.7622)
		(end 191.389 -28.1686)
		(width 0.508)
		(layer "F.Cu")
		(net "GND")
	)
	(segment
		(start 248.59996 -31.999936)
		(end 249.099832 -31.500064)
		(width 0.4572)
		(layer "F.Cu")
		(net "GND")
	)
	(segment
		(start 116.577872 -34.882328)
		(end 116.1796 -35.2806)
		(width 0.508)
		(layer "F.Cu")
		(net "GND")
	)
	(segment
		(start 253.59995 -46.999906)
		(end 254.099822 -46.500034)
		(width 0.4572)
		(layer "F.Cu")
		(net "GND")
	)
	(segment
		(start 265.7348 -6.223)
		(end 265.797792 -6.285992)
		(width 0.508)
		(layer "F.Cu")
		(net "GND")
	)
	(segment
		(start 78.90002 -223.53778)
		(end 79.375 -223.0628)
		(width 0.508)
		(layer "F.Cu")
		(net "GND")
	)
	(segment
		(start 16.637 -182.453788)
		(end 16.637 -182.2196)
		(width 0.508)
		(layer "F.Cu")
		(net "GND")
	)
	(segment
		(start 177.299874 -223.832674)
		(end 177.299874 -223.082104)
		(width 0.508)
		(layer "F.Cu")
		(net "GND")
	)
	(segment
		(start 235.5215 -7.9883)
		(end 235.5215 -6.92658)
		(width 0.508)
		(layer "F.Cu")
		(net "GND")
	)
	(segment
		(start 35.365436 -156.379926)
		(end 34.965894 -155.980384)
		(width 0.3556)
		(layer "F.Cu")
		(net "GND")
	)
	(segment
		(start 63.242698 -133.5405)
		(end 62.611 -133.5405)
		(width 0.508)
		(layer "F.Cu")
		(net "GND")
	)
	(segment
		(start 38.904926 -132.08508)
		(end 39.304722 -132.484876)
		(width 0.3556)
		(layer "F.Cu")
		(net "GND")
	)
	(segment
		(start 46.068234 -152.002744)
		(end 46.068234 -152.815544)
		(width 0.508)
		(layer "F.Cu")
		(net "GND")
	)
	(segment
		(start 288.500058 -223.482154)
		(end 288.100008 -223.082104)
		(width 0.508)
		(layer "F.Cu")
		(net "GND")
	)
	(segment
		(start 201.70013 -223.482408)
		(end 201.299826 -223.082104)
		(width 0.508)
		(layer "F.Cu")
		(net "GND")
	)
	(segment
		(start 153.700226 -225.54438)
		(end 153.700226 -223.4819)
		(width 0.508)
		(layer "F.Cu")
		(net "GND")
	)
	(segment
		(start 49.657 -150.0505)
		(end 49.9364 -150.0505)
		(width 0.508)
		(layer "F.Cu")
		(net "GND")
	)
	(segment
		(start 234.599988 -43.999912)
		(end 234.100116 -43.50004)
		(width 0.4572)
		(layer "F.Cu")
		(net "GND")
	)
	(segment
		(start 19.115024 -94.056962)
		(end 18.986246 -94.18574)
		(width 0.508)
		(layer "F.Cu")
		(net "GND")
	)
	(segment
		(start 134.1374 -195.9737)
		(end 134.1374 -194.8942)
		(width 0.508)
		(layer "F.Cu")
		(net "GND")
	)
	(segment
		(start 230.599996 -52.999894)
		(end 230.100124 -53.499766)
		(width 0.4572)
		(layer "F.Cu")
		(net "GND")
	)
	(segment
		(start 223.60001 -60.999878)
		(end 223.100138 -61.49975)
		(width 0.4572)
		(layer "F.Cu")
		(net "GND")
	)
	(segment
		(start 38.1 -224.116646)
		(end 38.1 -225.54438)
		(width 0.508)
		(layer "F.Cu")
		(net "GND")
	)
	(segment
		(start 142.692374 -87.11692)
		(end 142.692374 -87.955374)
		(width 0.508)
		(layer "F.Cu")
		(net "GND")
	)
	(segment
		(start 177.700178 -224.232978)
		(end 177.299874 -223.832674)
		(width 0.508)
		(layer "F.Cu")
		(net "GND")
	)
	(segment
		(start 30.862016 -62.999874)
		(end 32.341312 -62.999874)
		(width 1.016)
		(layer "F.Cu")
		(net "GND")
	)
	(segment
		(start 239.599978 -35.999928)
		(end 239.100106 -35.500056)
		(width 0.4572)
		(layer "F.Cu")
		(net "GND")
	)
	(segment
		(start 33.6296 -187.5282)
		(end 34.6456 -187.5282)
		(width 0.508)
		(layer "F.Cu")
		(net "GND")
	)
	(segment
		(start 226.390454 -3.334258)
		(end 226.390454 -2.82575)
		(width 0.508)
		(layer "F.Cu")
		(net "GND")
	)
	(segment
		(start 121.75744 -22.79904)
		(end 121.8438 -22.8854)
		(width 0.3048)
		(layer "F.Cu")
		(net "GND")
	)
	(segment
		(start 241.599974 -48.999902)
		(end 242.099846 -49.499774)
		(width 0.4572)
		(layer "F.Cu")
		(net "GND")
	)
	(segment
		(start 238.59998 -54.99989)
		(end 238.100108 -55.499762)
		(width 0.4572)
		(layer "F.Cu")
		(net "GND")
	)
	(segment
		(start 256.599944 -35.999928)
		(end 257.099816 -35.500056)
		(width 0.4572)
		(layer "F.Cu")
		(net "GND")
	)
	(segment
		(start 194.4243 -31.8262)
		(end 194.0306 -31.8262)
		(width 0.508)
		(layer "F.Cu")
		(net "GND")
	)
	(segment
		(start 31.367984 -157.179772)
		(end 31.76778 -156.779976)
		(width 0.3556)
		(layer "F.Cu")
		(net "GND")
	)
	(segment
		(start 252.355604 -11.735562)
		(end 252.068584 -11.448542)
		(width 0.508)
		(layer "F.Cu")
		(net "GND")
	)
	(segment
		(start 40.9448 -190.2206)
		(end 40.0558 -190.2206)
		(width 0.508)
		(layer "F.Cu")
		(net "GND")
	)
	(segment
		(start 56.134 -131.6355)
		(end 55.6387 -131.6355)
		(width 0.508)
		(layer "F.Cu")
		(net "GND")
	)
	(segment
		(start 183.09336 -13.76426)
		(end 183.09336 -14.32306)
		(width 0.508)
		(layer "F.Cu")
		(net "GND")
	)
	(segment
		(start 91.700096 -225.54438)
		(end 91.700096 -223.482154)
		(width 0.508)
		(layer "F.Cu")
		(net "GND")
	)
	(segment
		(start 26.9748 -149.479)
		(end 26.5176 -149.9362)
		(width 0.508)
		(layer "F.Cu")
		(net "GND")
	)
	(segment
		(start 226.600004 -59.99988)
		(end 226.100132 -60.499752)
		(width 0.4572)
		(layer "F.Cu")
		(net "GND")
	)
	(segment
		(start 224.4344 -187.9092)
		(end 224.4344 -188.4172)
		(width 0.508)
		(layer "F.Cu")
		(net "GND")
	)
	(segment
		(start 286.100012 -223.482154)
		(end 286.500062 -223.082104)
		(width 0.508)
		(layer "F.Cu")
		(net "GND")
	)
	(segment
		(start 194.9831 -6.6548)
		(end 195.4784 -6.6548)
		(width 0.508)
		(layer "F.Cu")
		(net "GND")
	)
	(segment
		(start 225.600006 -34.99993)
		(end 225.100134 -34.500058)
		(width 0.4572)
		(layer "F.Cu")
		(net "GND")
	)
	(segment
		(start 23.517352 -103.02621)
		(end 23.517352 -104.331262)
		(width 0.4064)
		(layer "F.Cu")
		(net "GND")
	)
	(segment
		(start 40.967914 -150.779988)
		(end 41.36771 -151.179784)
		(width 0.3556)
		(layer "F.Cu")
		(net "GND")
	)
	(segment
		(start 124.848112 -40.422068)
		(end 124.848112 -40.672512)
		(width 0.508)
		(layer "F.Cu")
		(net "GND")
	)
	(segment
		(start 248.59996 -52.999894)
		(end 249.099832 -53.499766)
		(width 0.4572)
		(layer "F.Cu")
		(net "GND")
	)
	(segment
		(start 229.599998 -44.99991)
		(end 229.100126 -44.500038)
		(width 0.4572)
		(layer "F.Cu")
		(net "GND")
	)
	(segment
		(start 251.599954 -47.999904)
		(end 252.099826 -48.499776)
		(width 0.4572)
		(layer "F.Cu")
		(net "GND")
	)
	(segment
		(start 230.599996 -48.999902)
		(end 230.100124 -49.499774)
		(width 0.4572)
		(layer "F.Cu")
		(net "GND")
	)
	(segment
		(start 186.500008 -225.54438)
		(end 186.500008 -223.482154)
		(width 0.508)
		(layer "F.Cu")
		(net "GND")
	)
	(segment
		(start 24.186642 -98.794316)
		(end 24.186642 -97.968816)
		(width 0.508)
		(layer "F.Cu")
		(net "GND")
	)
	(segment
		(start 266.433808 -6.285992)
		(end 266.68349 -6.535674)
		(width 0.508)
		(layer "F.Cu")
		(net "GND")
	)
	(segment
		(start 41.767506 -150.779988)
		(end 41.36771 -151.179784)
		(width 0.3556)
		(layer "F.Cu")
		(net "GND")
	)
	(segment
		(start 242.599972 -63.999872)
		(end 243.099844 -64.499744)
		(width 0.4572)
		(layer "F.Cu")
		(net "GND")
	)
	(segment
		(start 28.2956 -187.5282)
		(end 28.2956 -188.4172)
		(width 0.508)
		(layer "F.Cu")
		(net "GND")
	)
	(segment
		(start 28.524454 -162.734244)
		(end 29.603954 -163.813744)
		(width 0.508)
		(layer "F.Cu")
		(net "GND")
	)
	(segment
		(start 37.211 -223.901)
		(end 37.300154 -223.990154)
		(width 0.508)
		(layer "F.Cu")
		(net "GND")
	)
	(segment
		(start 195.4276 -27.3431)
		(end 195.4276 -28.4226)
		(width 0.508)
		(layer "F.Cu")
		(net "GND")
	)
	(segment
		(start 208.100168 -225.54438)
		(end 208.100168 -223.242632)
		(width 0.508)
		(layer "F.Cu")
		(net "GND")
	)
	(segment
		(start 223.60001 -63.999872)
		(end 223.100138 -64.499744)
		(width 0.4572)
		(layer "F.Cu")
		(net "GND")
	)
	(segment
		(start 272.742152 -11.346942)
		(end 271.966182 -11.346942)
		(width 0.508)
		(layer "F.Cu")
		(net "GND")
	)
	(segment
		(start 318.100202 -225.54438)
		(end 318.100202 -223.482408)
		(width 0.508)
		(layer "F.Cu")
		(net "GND")
	)
	(segment
		(start 149.700234 -225.54438)
		(end 149.700234 -223.482408)
		(width 0.508)
		(layer "F.Cu")
		(net "GND")
	)
	(segment
		(start 77.0382 -196.1007)
		(end 77.0382 -196.342)
		(width 0.508)
		(layer "F.Cu")
		(net "GND")
	)
	(segment
		(start 38.904926 -131.28498)
		(end 39.304722 -131.684776)
		(width 0.3556)
		(layer "F.Cu")
		(net "GND")
	)
	(segment
		(start 5.5372 -46.8249)
		(end 5.5372 -47.7774)
		(width 0.508)
		(layer "F.Cu")
		(net "GND")
	)
	(segment
		(start 230.599996 -31.999936)
		(end 230.100124 -31.500064)
		(width 0.4572)
		(layer "F.Cu")
		(net "GND")
	)
	(segment
		(start 225.600006 -40.999918)
		(end 225.100134 -40.500046)
		(width 0.4572)
		(layer "F.Cu")
		(net "GND")
	)
	(segment
		(start 54.5465 -134.4295)
		(end 55.245 -134.4295)
		(width 0.508)
		(layer "F.Cu")
		(net "GND")
	)
	(segment
		(start 25.019 -151.9555)
		(end 25.7175 -151.9555)
		(width 0.508)
		(layer "F.Cu")
		(net "GND")
	)
	(segment
		(start 29.048456 -32.079946)
		(end 29.048456 -31.001716)
		(width 0.508)
		(layer "F.Cu")
		(net "GND")
	)
	(segment
		(start 328.835512 -185.322718)
		(end 328.835512 -186.182)
		(width 0.508)
		(layer "F.Cu")
		(net "GND")
	)
	(segment
		(start 135.579866 -85.592666)
		(end 133.438138 -85.592666)
		(width 0.508)
		(layer "F.Cu")
		(net "GND")
	)
	(segment
		(start 240.599976 -60.999878)
		(end 241.099848 -61.49975)
		(width 0.4572)
		(layer "F.Cu")
		(net "GND")
	)
	(segment
		(start 247.599962 -50.999898)
		(end 248.099834 -51.49977)
		(width 0.4572)
		(layer "F.Cu")
		(net "GND")
	)
	(segment
		(start 69.30009 -225.54438)
		(end 69.30009 -223.482154)
		(width 0.508)
		(layer "F.Cu")
		(net "GND")
	)
	(segment
		(start 155.194 -87.9094)
		(end 156.972 -87.9094)
		(width 0.508)
		(layer "F.Cu")
		(net "GND")
	)
	(segment
		(start 327.700132 -223.482408)
		(end 327.299828 -223.082104)
		(width 0.508)
		(layer "F.Cu")
		(net "GND")
	)
	(segment
		(start 131.949444 -199.973692)
		(end 131.949444 -199.647556)
		(width 0.3048)
		(layer "F.Cu")
		(net "GND")
	)
	(segment
		(start 46.355 -180.0225)
		(end 46.355 -179.197)
		(width 0.508)
		(layer "F.Cu")
		(net "GND")
	)
	(segment
		(start 94.100142 -223.069658)
		(end 94.107 -223.0628)
		(width 0.508)
		(layer "F.Cu")
		(net "GND")
	)
	(segment
		(start 152.7556 -88.5698)
		(end 153.472388 -89.286588)
		(width 0.3048)
		(layer "F.Cu")
		(net "GND")
	)
	(segment
		(start 36.90493 -130.08483)
		(end 37.30498 -130.48488)
		(width 0.3556)
		(layer "F.Cu")
		(net "GND")
	)
	(segment
		(start 25.7175 -151.9555)
		(end 25.908 -152.146)
		(width 0.508)
		(layer "F.Cu")
		(net "GND")
	)
	(segment
		(start 37.704776 -131.684776)
		(end 37.30498 -131.28498)
		(width 0.3556)
		(layer "F.Cu")
		(net "GND")
	)
	(segment
		(start 229.599998 -42.999914)
		(end 229.100126 -42.500042)
		(width 0.4572)
		(layer "F.Cu")
		(net "GND")
	)
	(segment
		(start 16.9418 -181.229)
		(end 16.637 -181.5338)
		(width 0.508)
		(layer "F.Cu")
		(net "GND")
	)
	(segment
		(start 264.07745 -4.784598)
		(end 265.43127 -4.784598)
		(width 0.508)
		(layer "F.Cu")
		(net "GND")
	)
	(segment
		(start 300.500034 -223.482154)
		(end 300.099984 -223.082104)
		(width 0.508)
		(layer "F.Cu")
		(net "GND")
	)
	(segment
		(start 248.59996 -55.999888)
		(end 249.099832 -56.49976)
		(width 0.4572)
		(layer "F.Cu")
		(net "GND")
	)
	(segment
		(start 227.584 -1.5875)
		(end 227.5459 -1.5875)
		(width 0.508)
		(layer "F.Cu")
		(net "GND")
	)
	(segment
		(start 242.599972 -41.999916)
		(end 243.099844 -41.500044)
		(width 0.4572)
		(layer "F.Cu")
		(net "GND")
	)
	(segment
		(start 28.321 -116.2685)
		(end 28.321 -115.4938)
		(width 0.508)
		(layer "F.Cu")
		(net "GND")
	)
	(segment
		(start 294.900096 -223.482408)
		(end 294.499792 -223.082104)
		(width 0.508)
		(layer "F.Cu")
		(net "GND")
	)
	(segment
		(start 211.224368 -12.009374)
		(end 211.429854 -11.803888)
		(width 0.2032)
		(layer "F.Cu")
		(net "GND")
	)
	(segment
		(start 20.574 -147.066)
		(end 20.574 -147.8915)
		(width 0.508)
		(layer "F.Cu")
		(net "GND")
	)
	(segment
		(start 249.599958 -42.999914)
		(end 250.09983 -42.500042)
		(width 0.4572)
		(layer "F.Cu")
		(net "GND")
	)
	(segment
		(start 19.1643 -176.3141)
		(end 19.4183 -176.5681)
		(width 0.508)
		(layer "F.Cu")
		(net "GND")
	)
	(segment
		(start 247.599962 -52.999894)
		(end 248.099834 -53.499766)
		(width 0.4572)
		(layer "F.Cu")
		(net "GND")
	)
	(segment
		(start 139.885674 -95.27032)
		(end 139.885674 -96.588326)
		(width 0.508)
		(layer "F.Cu")
		(net "GND")
	)
	(segment
		(start 230.599996 -43.999912)
		(end 230.100124 -43.50004)
		(width 0.4572)
		(layer "F.Cu")
		(net "GND")
	)
	(segment
		(start 54.256178 -35.09645)
		(end 55.55615 -35.09645)
		(width 0.508)
		(layer "F.Cu")
		(net "GND")
	)
	(segment
		(start 157.240478 -89.326466)
		(end 156.77007 -88.856058)
		(width 0.3048)
		(layer "F.Cu")
		(net "GND")
	)
	(segment
		(start 177.700178 -225.54438)
		(end 177.700178 -224.232978)
		(width 0.508)
		(layer "F.Cu")
		(net "GND")
	)
	(segment
		(start 234.599988 -57.999884)
		(end 234.100116 -58.499756)
		(width 0.4572)
		(layer "F.Cu")
		(net "GND")
	)
	(segment
		(start 244.599968 -43.999912)
		(end 245.09984 -43.50004)
		(width 0.4572)
		(layer "F.Cu")
		(net "GND")
	)
	(segment
		(start 275.700236 -223.482408)
		(end 275.299932 -223.082104)
		(width 0.508)
		(layer "F.Cu")
		(net "GND")
	)
	(segment
		(start 249.599958 -61.999876)
		(end 250.09983 -62.499748)
		(width 0.4572)
		(layer "F.Cu")
		(net "GND")
	)
	(segment
		(start 75.623166 -91.03106)
		(end 75.623166 -92.093034)
		(width 0.508)
		(layer "F.Cu")
		(net "GND")
	)
	(segment
		(start 156.900118 -223.482154)
		(end 157.300168 -223.082104)
		(width 0.508)
		(layer "F.Cu")
		(net "GND")
	)
	(segment
		(start 250.599956 -54.99989)
		(end 251.099828 -55.499762)
		(width 0.4572)
		(layer "F.Cu")
		(net "GND")
	)
	(segment
		(start 192.4939 -24.0538)
		(end 191.8716 -24.0538)
		(width 0.508)
		(layer "F.Cu")
		(net "GND")
	)
	(segment
		(start 264.215372 -8.16356)
		(end 264.234676 -8.182864)
		(width 0.508)
		(layer "F.Cu")
		(net "GND")
	)
	(segment
		(start 171.30014 -225.54438)
		(end 171.30014 -223.482408)
		(width 0.508)
		(layer "F.Cu")
		(net "GND")
	)
	(segment
		(start 227.9904 -190.1317)
		(end 228.853746 -190.1317)
		(width 0.508)
		(layer "F.Cu")
		(net "GND")
	)
	(segment
		(start 249.599958 -62.999874)
		(end 250.09983 -63.499746)
		(width 0.4572)
		(layer "F.Cu")
		(net "GND")
	)
	(segment
		(start 231.599994 -41.999916)
		(end 231.100122 -41.500044)
		(width 0.4572)
		(layer "F.Cu")
		(net "GND")
	)
	(segment
		(start 159.131 -94.742)
		(end 159.131 -94.620334)
		(width 0.508)
		(layer "F.Cu")
		(net "GND")
	)
	(segment
		(start 232.599992 -49.9999)
		(end 232.10012 -50.499772)
		(width 0.4572)
		(layer "F.Cu")
		(net "GND")
	)
	(segment
		(start 256.599944 -46.999906)
		(end 257.099816 -46.500034)
		(width 0.4572)
		(layer "F.Cu")
		(net "GND")
	)
	(segment
		(start 40.33393 -103.1875)
		(end 40.3352 -103.18877)
		(width 0.508)
		(layer "F.Cu")
		(net "GND")
	)
	(segment
		(start 54.590188 -131.8006)
		(end 54.818788 -132.0292)
		(width 0.508)
		(layer "F.Cu")
		(net "GND")
	)
	(segment
		(start 235.599986 -52.999894)
		(end 235.100114 -53.499766)
		(width 0.4572)
		(layer "F.Cu")
		(net "GND")
	)
	(segment
		(start 40.104822 -128.485392)
		(end 40.104822 -128.484884)
		(width 0.3556)
		(layer "F.Cu")
		(net "GND")
	)
	(segment
		(start 232.599992 -57.999884)
		(end 232.10012 -58.499756)
		(width 0.4572)
		(layer "F.Cu")
		(net "GND")
	)
	(segment
		(start 331.97038 -33.38449)
		(end 331.97038 -33.1978)
		(width 0.508)
		(layer "F.Cu")
		(net "GND")
	)
	(segment
		(start 255.599946 -34.99993)
		(end 256.099818 -34.500058)
		(width 0.4572)
		(layer "F.Cu")
		(net "GND")
	)
	(segment
		(start 146.500088 -225.54438)
		(end 146.500088 -223.482154)
		(width 0.508)
		(layer "F.Cu")
		(net "GND")
	)
	(segment
		(start 45.300138 -223.482408)
		(end 44.899834 -223.082104)
		(width 0.508)
		(layer "F.Cu")
		(net "GND")
	)
	(segment
		(start 232.599992 -43.999912)
		(end 232.10012 -43.50004)
		(width 0.4572)
		(layer "F.Cu")
		(net "GND")
	)
	(segment
		(start 258.59994 -64.99987)
		(end 259.099812 -65.499742)
		(width 0.4572)
		(layer "F.Cu")
		(net "GND")
	)
	(segment
		(start 236.599984 -49.9999)
		(end 236.100112 -50.499772)
		(width 0.4572)
		(layer "F.Cu")
		(net "GND")
	)
	(segment
		(start 216.230708 -11.6205)
		(end 216.2302 -11.619992)
		(width 0.508)
		(layer "F.Cu")
		(net "GND")
	)
	(segment
		(start 4.572 -68.9864)
		(end 4.572 -67.3354)
		(width 0.508)
		(layer "F.Cu")
		(net "GND")
	)
	(segment
		(start 81.0641 -136.7282)
		(end 81.5086 -136.7282)
		(width 0.508)
		(layer "F.Cu")
		(net "GND")
	)
	(segment
		(start 294.900096 -225.54438)
		(end 294.900096 -223.482408)
		(width 0.508)
		(layer "F.Cu")
		(net "GND")
	)
	(segment
		(start 132.715 -198.882)
		(end 132.715 -198.635874)
		(width 0.3048)
		(layer "F.Cu")
		(net "GND")
	)
	(segment
		(start 22.733 -119.507)
		(end 22.733 -119.8626)
		(width 0.508)
		(layer "F.Cu")
		(net "GND")
	)
	(segment
		(start 243.59997 -59.99988)
		(end 244.099842 -60.499752)
		(width 0.4572)
		(layer "F.Cu")
		(net "GND")
	)
	(segment
		(start 20.5105 -141.859)
		(end 20.3835 -141.986)
		(width 0.508)
		(layer "F.Cu")
		(net "GND")
	)
	(segment
		(start 152.900126 -223.482408)
		(end 152.499822 -223.082104)
		(width 0.508)
		(layer "F.Cu")
		(net "GND")
	)
	(segment
		(start 100.50018 -225.54438)
		(end 100.50018 -223.4819)
		(width 0.508)
		(layer "F.Cu")
		(net "GND")
	)
	(segment
		(start 259.743702 -3.737102)
		(end 259.743702 -4.419092)
		(width 0.508)
		(layer "F.Cu")
		(net "GND")
	)
	(segment
		(start 36.90493 -131.684776)
		(end 36.905184 -131.684776)
		(width 0.3556)
		(layer "F.Cu")
		(net "GND")
	)
	(segment
		(start 218.8845 -8.128)
		(end 218.059 -8.128)
		(width 0.508)
		(layer "F.Cu")
		(net "GND")
	)
	(segment
		(start 38.904926 -129.685034)
		(end 38.504876 -129.284984)
		(width 0.3556)
		(layer "F.Cu")
		(net "GND")
	)
	(segment
		(start 127.0254 -209.3341)
		(end 125.986286 -209.3341)
		(width 0.508)
		(layer "F.Cu")
		(net "GND")
	)
	(segment
		(start 12.4714 -82.138012)
		(end 12.4714 -83.3882)
		(width 0.508)
		(layer "F.Cu")
		(net "GND")
	)
	(segment
		(start 191.8716 -28.6512)
		(end 191.389 -28.1686)
		(width 0.508)
		(layer "F.Cu")
		(net "GND")
	)
	(segment
		(start 18.796 -142.5575)
		(end 18.4785 -142.24)
		(width 0.508)
		(layer "F.Cu")
		(net "GND")
	)
	(segment
		(start 22.23897 -142.51559)
		(end 21.81606 -142.9385)
		(width 0.508)
		(layer "F.Cu")
		(net "GND")
	)
	(segment
		(start 13.8684 -82.5881)
		(end 13.8684 -83.4644)
		(width 0.508)
		(layer "F.Cu")
		(net "GND")
	)
	(segment
		(start 117.3226 -16.6243)
		(end 117.3226 -15.8242)
		(width 0.508)
		(layer "F.Cu")
		(net "GND")
	)
	(segment
		(start 148.682456 -59.198256)
		(end 148.682456 -59.174126)
		(width 0.508)
		(layer "F.Cu")
		(net "GND")
	)
	(segment
		(start 88.500204 -223.4819)
		(end 88.9 -223.082104)
		(width 0.508)
		(layer "F.Cu")
		(net "GND")
	)
	(segment
		(start 225.600006 -36.999926)
		(end 225.100134 -36.500054)
		(width 0.4572)
		(layer "F.Cu")
		(net "GND")
	)
	(segment
		(start 8.0137 -176.59985)
		(end 6.88975 -176.59985)
		(width 0.508)
		(layer "F.Cu")
		(net "GND")
	)
	(segment
		(start 63.545974 -21.231606)
		(end 65.473326 -21.231606)
		(width 0.508)
		(layer "F.Cu")
		(net "GND")
	)
	(segment
		(start 12.5222 -88.0618)
		(end 12.322048 -88.261952)
		(width 0.508)
		(layer "F.Cu")
		(net "GND")
	)
	(segment
		(start 71.102982 -130.44424)
		(end 71.310246 -130.236976)
		(width 0.4064)
		(layer "F.Cu")
		(net "GND")
	)
	(segment
		(start 245.599966 -50.999898)
		(end 246.099838 -51.49977)
		(width 0.4572)
		(layer "F.Cu")
		(net "GND")
	)
	(segment
		(start 44.504864 -132.084826)
		(end 44.104814 -131.684776)
		(width 0.3556)
		(layer "F.Cu")
		(net "GND")
	)
	(segment
		(start 257.599942 -63.999872)
		(end 258.099814 -64.499744)
		(width 0.4572)
		(layer "F.Cu")
		(net "GND")
	)
	(segment
		(start 249.599958 -57.999884)
		(end 250.09983 -58.499756)
		(width 0.4572)
		(layer "F.Cu")
		(net "GND")
	)
	(segment
		(start 237.599982 -40.999918)
		(end 237.10011 -40.500046)
		(width 0.4572)
		(layer "F.Cu")
		(net "GND")
	)
	(segment
		(start 253.59995 -37.999924)
		(end 254.099822 -37.500052)
		(width 0.4572)
		(layer "F.Cu")
		(net "GND")
	)
	(segment
		(start 241.599974 -31.999936)
		(end 242.099846 -31.500064)
		(width 0.4572)
		(layer "F.Cu")
		(net "GND")
	)
	(segment
		(start 334.900016 -225.54438)
		(end 334.900016 -223.482154)
		(width 0.508)
		(layer "F.Cu")
		(net "GND")
	)
	(segment
		(start 301.300134 -225.54438)
		(end 301.300134 -223.482154)
		(width 0.508)
		(layer "F.Cu")
		(net "GND")
	)
	(segment
		(start 249.599958 -53.999892)
		(end 250.09983 -54.499764)
		(width 0.4572)
		(layer "F.Cu")
		(net "GND")
	)
	(segment
		(start 246.599964 -49.9999)
		(end 247.099836 -50.499772)
		(width 0.4572)
		(layer "F.Cu")
		(net "GND")
	)
	(segment
		(start 21.3614 -52.669694)
		(end 20.999704 -53.03139)
		(width 0.508)
		(layer "F.Cu")
		(net "GND")
	)
	(segment
		(start 201.70013 -225.54438)
		(end 201.70013 -223.482408)
		(width 0.508)
		(layer "F.Cu")
		(net "GND")
	)
	(segment
		(start 219.0115 -12.319)
		(end 218.5924 -12.319)
		(width 0.508)
		(layer "F.Cu")
		(net "GND")
	)
	(segment
		(start 245.599966 -59.99988)
		(end 246.099838 -60.499752)
		(width 0.4572)
		(layer "F.Cu")
		(net "GND")
	)
	(segment
		(start 189.700154 -223.482154)
		(end 190.100204 -223.082104)
		(width 0.508)
		(layer "F.Cu")
		(net "GND")
	)
	(segment
		(start 11.825732 -67.921632)
		(end 12.2936 -68.3895)
		(width 0.508)
		(layer "F.Cu")
		(net "GND")
	)
	(segment
		(start 83.821524 -83.29041)
		(end 83.627214 -83.48472)
		(width 0.3048)
		(layer "F.Cu")
		(net "GND")
	)
	(segment
		(start 230.1875 -85.0265)
		(end 231.013 -85.852)
		(width 0.508)
		(layer "F.Cu")
		(net "GND")
	)
	(segment
		(start 224.600008 -46.999906)
		(end 225.600006 -47.999904)
		(width 0.4572)
		(layer "F.Cu")
		(net "GND")
	)
	(segment
		(start 287.55975 -58.1025)
		(end 288.4805 -58.1025)
		(width 0.508)
		(layer "F.Cu")
		(net "GND")
	)
	(segment
		(start 135.254746 -80.160114)
		(end 131.117086 -80.160114)
		(width 0.508)
		(layer "F.Cu")
		(net "GND")
	)
	(segment
		(start 246.599964 -63.999872)
		(end 247.099836 -64.499744)
		(width 0.4572)
		(layer "F.Cu")
		(net "GND")
	)
	(segment
		(start 162.031934 -88.088978)
		(end 162.031934 -87.396066)
		(width 0.3048)
		(layer "F.Cu")
		(net "GND")
	)
	(segment
		(start 116.456206 -53.591206)
		(end 115.7732 -52.9082)
		(width 0.508)
		(layer "F.Cu")
		(net "GND")
	)
	(segment
		(start 25.629616 -104.131872)
		(end 25.634696 -104.131872)
		(width 0.4064)
		(layer "F.Cu")
		(net "GND")
	)
	(segment
		(start 244.599968 -47.999904)
		(end 245.09984 -48.499776)
		(width 0.4572)
		(layer "F.Cu")
		(net "GND")
	)
	(segment
		(start 234.599988 -41.999916)
		(end 234.100116 -41.500044)
		(width 0.4572)
		(layer "F.Cu")
		(net "GND")
	)
	(segment
		(start 38.568122 -151.579834)
		(end 38.568376 -151.579834)
		(width 0.3556)
		(layer "F.Cu")
		(net "GND")
	)
	(segment
		(start 236.599984 -51.999896)
		(end 236.100112 -52.499768)
		(width 0.4572)
		(layer "F.Cu")
		(net "GND")
	)
	(segment
		(start 64.389 -133.5405)
		(end 63.427102 -133.5405)
		(width 0.508)
		(layer "F.Cu")
		(net "GND")
	)
	(segment
		(start 35.687 -223.901)
		(end 35.699954 -223.913954)
		(width 0.508)
		(layer "F.Cu")
		(net "GND")
	)
	(segment
		(start 229.997 -85.0265)
		(end 230.1875 -85.0265)
		(width 0.508)
		(layer "F.Cu")
		(net "GND")
	)
	(segment
		(start 230.8606 -88.1634)
		(end 230.8098 -88.2142)
		(width 0.508)
		(layer "F.Cu")
		(net "GND")
	)
	(segment
		(start 215.300052 -223.482154)
		(end 215.700102 -223.082104)
		(width 0.508)
		(layer "F.Cu")
		(net "GND")
	)
	(segment
		(start 289.300158 -225.54438)
		(end 289.300158 -223.482154)
		(width 0.508)
		(layer "F.Cu")
		(net "GND")
	)
	(segment
		(start 123.5329 -97.06356)
		(end 124.93244 -97.06356)
		(width 0.381)
		(layer "F.Cu")
		(net "GND")
	)
	(segment
		(start 26.289 -116.2685)
		(end 27.305 -116.2685)
		(width 0.508)
		(layer "F.Cu")
		(net "GND")
	)
	(segment
		(start 33.782 -116.2685)
		(end 33.782 -115.4938)
		(width 0.508)
		(layer "F.Cu")
		(net "GND")
	)
	(segment
		(start 233.59999 -44.99991)
		(end 233.100118 -44.500038)
		(width 0.4572)
		(layer "F.Cu")
		(net "GND")
	)
	(segment
		(start 156.900118 -225.54438)
		(end 156.900118 -223.482154)
		(width 0.508)
		(layer "F.Cu")
		(net "GND")
	)
	(segment
		(start 72.8726 -179.4002)
		(end 72.517 -179.0446)
		(width 0.508)
		(layer "F.Cu")
		(net "GND")
	)
	(segment
		(start 9.779 -74.7014)
		(end 9.271 -75.2094)
		(width 0.508)
		(layer "F.Cu")
		(net "GND")
	)
	(segment
		(start 16.637 -181.5338)
		(end 16.637 -182.2196)
		(width 0.508)
		(layer "F.Cu")
		(net "GND")
	)
	(segment
		(start 239.599978 -54.99989)
		(end 239.100106 -55.499762)
		(width 0.4572)
		(layer "F.Cu")
		(net "GND")
	)
	(segment
		(start 11.395964 -97.613978)
		(end 11.395964 -98.898964)
		(width 0.508)
		(layer "F.Cu")
		(net "GND")
	)
	(segment
		(start 162.031934 -87.396066)
		(end 162.433 -86.995)
		(width 0.3048)
		(layer "F.Cu")
		(net "GND")
	)
	(segment
		(start 303.515522 -223.29775)
		(end 303.299876 -223.082104)
		(width 0.508)
		(layer "F.Cu")
		(net "GND")
	)
	(segment
		(start 38.568122 -156.379926)
		(end 38.168326 -155.98013)
		(width 0.3556)
		(layer "F.Cu")
		(net "GND")
	)
	(segment
		(start 319.405 -100.0125)
		(end 319.405 -100.838)
		(width 0.508)
		(layer "F.Cu")
		(net "GND")
	)
	(segment
		(start 211.224368 -13.1064)
		(end 211.224368 -12.009374)
		(width 0.2032)
		(layer "F.Cu")
		(net "GND")
	)
	(segment
		(start 175.300132 -225.54438)
		(end 175.300132 -223.482154)
		(width 0.508)
		(layer "F.Cu")
		(net "GND")
	)
	(segment
		(start 242.599972 -31.999936)
		(end 243.099844 -31.500064)
		(width 0.4572)
		(layer "F.Cu")
		(net "GND")
	)
	(segment
		(start 235.599986 -59.99988)
		(end 235.100114 -60.499752)
		(width 0.4572)
		(layer "F.Cu")
		(net "GND")
	)
	(segment
		(start 222.25 -7.874)
		(end 221.361 -7.874)
		(width 0.508)
		(layer "F.Cu")
		(net "GND")
	)
	(segment
		(start 196.504052 -20.35556)
		(end 197.24116 -20.35556)
		(width 0.3556)
		(layer "F.Cu")
		(net "GND")
	)
	(segment
		(start 335.915508 -33.153858)
		(end 335.62163 -32.85998)
		(width 0.508)
		(layer "F.Cu")
		(net "GND")
	)
	(segment
		(start 5.1562 -66.7512)
		(end 7.2136 -66.7512)
		(width 0.508)
		(layer "F.Cu")
		(net "GND")
	)
	(segment
		(start 22.81555 -174.7266)
		(end 22.81555 -175.99025)
		(width 0.508)
		(layer "F.Cu")
		(net "GND")
	)
	(segment
		(start 122.023124 -209.333592)
		(end 122.023124 -210.192874)
		(width 0.508)
		(layer "F.Cu")
		(net "GND")
	)
	(segment
		(start 7.874 -105.7148)
		(end 7.874 -104.821736)
		(width 0.508)
		(layer "F.Cu")
		(net "GND")
	)
	(segment
		(start 227.600002 -63.999872)
		(end 227.10013 -64.499744)
		(width 0.4572)
		(layer "F.Cu")
		(net "GND")
	)
	(segment
		(start 225.600006 -52.999894)
		(end 225.100134 -53.499766)
		(width 0.4572)
		(layer "F.Cu")
		(net "GND")
	)
	(segment
		(start 125.5649 -42.164)
		(end 125.5649 -41.4909)
		(width 0.508)
		(layer "F.Cu")
		(net "GND")
	)
	(segment
		(start 67.794124 -196.125592)
		(end 67.794124 -196.984874)
		(width 0.508)
		(layer "F.Cu")
		(net "GND")
	)
	(segment
		(start 202.50023 -225.54438)
		(end 202.50023 -223.4819)
		(width 0.508)
		(layer "F.Cu")
		(net "GND")
	)
	(segment
		(start 237.599982 -35.999928)
		(end 237.10011 -35.500056)
		(width 0.4572)
		(layer "F.Cu")
		(net "GND")
	)
	(segment
		(start 253.59995 -55.999888)
		(end 254.099822 -56.49976)
		(width 0.4572)
		(layer "F.Cu")
		(net "GND")
	)
	(segment
		(start 40.9448 -184.8866)
		(end 40.9448 -183.8706)
		(width 0.508)
		(layer "F.Cu")
		(net "GND")
	)
	(segment
		(start 41.768014 -150.779988)
		(end 41.767506 -150.779988)
		(width 0.3556)
		(layer "F.Cu")
		(net "GND")
	)
	(segment
		(start 156.100018 -223.482154)
		(end 155.699968 -223.082104)
		(width 0.508)
		(layer "F.Cu")
		(net "GND")
	)
	(segment
		(start 259.16382 -8.898128)
		(end 260.013958 -8.898128)
		(width 0.508)
		(layer "F.Cu")
		(net "GND")
	)
	(segment
		(start 251.599954 -43.999912)
		(end 252.099826 -43.50004)
		(width 0.4572)
		(layer "F.Cu")
		(net "GND")
	)
	(segment
		(start 36.10483 -130.08483)
		(end 36.90493 -130.88493)
		(width 0.3556)
		(layer "F.Cu")
		(net "GND")
	)
	(segment
		(start 246.599964 -47.999904)
		(end 247.099836 -48.499776)
		(width 0.4572)
		(layer "F.Cu")
		(net "GND")
	)
	(segment
		(start 32.96793 -157.179772)
		(end 33.367726 -156.779976)
		(width 0.3556)
		(layer "F.Cu")
		(net "GND")
	)
	(segment
		(start 256.011934 -10.05459)
		(end 255.522476 -10.544048)
		(width 0.508)
		(layer "F.Cu")
		(net "GND")
	)
	(segment
		(start 230.599996 -51.999896)
		(end 230.100124 -52.499768)
		(width 0.4572)
		(layer "F.Cu")
		(net "GND")
	)
	(segment
		(start 55.107078 -144.27708)
		(end 54.934612 -144.104614)
		(width 0.508)
		(layer "F.Cu")
		(net "GND")
	)
	(segment
		(start 85.379814 -83.29041)
		(end 83.821524 -83.29041)
		(width 0.3048)
		(layer "F.Cu")
		(net "GND")
	)
	(segment
		(start 172.10024 -225.54438)
		(end 172.10024 -223.4819)
		(width 0.508)
		(layer "F.Cu")
		(net "GND")
	)
	(segment
		(start 139.885674 -96.588326)
		(end 139.7 -96.774)
		(width 0.508)
		(layer "F.Cu")
		(net "GND")
	)
	(segment
		(start 158.334202 -58.002932)
		(end 158.334202 -57.177432)
		(width 0.508)
		(layer "F.Cu")
		(net "GND")
	)
	(segment
		(start 311.700164 -225.54438)
		(end 311.700164 -223.482408)
		(width 0.508)
		(layer "F.Cu")
		(net "GND")
	)
	(segment
		(start 56.515 -130.4925)
		(end 55.6387 -130.4925)
		(width 0.508)
		(layer "F.Cu")
		(net "GND")
	)
	(segment
		(start 243.59997 -55.999888)
		(end 244.099842 -56.49976)
		(width 0.4572)
		(layer "F.Cu")
		(net "GND")
	)
	(segment
		(start 15.042134 -184.1881)
		(end 15.042134 -183.3753)
		(width 0.3048)
		(layer "F.Cu")
		(net "GND")
	)
	(segment
		(start 233.59999 -62.999874)
		(end 233.100118 -63.499746)
		(width 0.4572)
		(layer "F.Cu")
		(net "GND")
	)
	(segment
		(start 10.0584 -80.6704)
		(end 11.7983 -80.6704)
		(width 0.508)
		(layer "F.Cu")
		(net "GND")
	)
	(segment
		(start 187.022232 1.895348)
		(end 186.279028 1.152144)
		(width 0.508)
		(layer "F.Cu")
		(net "GND")
	)
	(segment
		(start 242.824 -23.6855)
		(end 242.824 -24.638)
		(width 0.508)
		(layer "F.Cu")
		(net "GND")
	)
	(segment
		(start 79.0575 -56.3626)
		(end 79.007208 -56.312308)
		(width 0.508)
		(layer "F.Cu")
		(net "GND")
	)
	(segment
		(start 49.9364 -150.0505)
		(end 50.4444 -149.5425)
		(width 0.508)
		(layer "F.Cu")
		(net "GND")
	)
	(segment
		(start 278.900128 -225.54438)
		(end 278.900128 -223.482408)
		(width 0.508)
		(layer "F.Cu")
		(net "GND")
	)
	(segment
		(start 5.08 -75.2094)
		(end 4.572 -74.7014)
		(width 0.508)
		(layer "F.Cu")
		(net "GND")
	)
	(segment
		(start 45.31741 -113.454688)
		(end 44.728892 -112.86617)
		(width 0.508)
		(layer "F.Cu")
		(net "GND")
	)
	(segment
		(start 249.599958 -34.99993)
		(end 250.09983 -34.500058)
		(width 0.4572)
		(layer "F.Cu")
		(net "GND")
	)
	(segment
		(start 236.599984 -41.999916)
		(end 236.100112 -41.500044)
		(width 0.4572)
		(layer "F.Cu")
		(net "GND")
	)
	(segment
		(start 225.600006 -43.999912)
		(end 225.100134 -43.50004)
		(width 0.4572)
		(layer "F.Cu")
		(net "GND")
	)
	(segment
		(start 230.6955 -12.319)
		(end 230.5685 -12.446)
		(width 0.508)
		(layer "F.Cu")
		(net "GND")
	)
	(segment
		(start 63.545974 -16.151606)
		(end 65.494154 -16.151606)
		(width 0.508)
		(layer "F.Cu")
		(net "GND")
	)
	(segment
		(start 227.600002 -42.999914)
		(end 227.10013 -42.500042)
		(width 0.4572)
		(layer "F.Cu")
		(net "GND")
	)
	(segment
		(start 252.599952 -62.999874)
		(end 253.099824 -63.499746)
		(width 0.4572)
		(layer "F.Cu")
		(net "GND")
	)
	(segment
		(start 18.034 -142.21333)
		(end 17.9832 -142.21333)
		(width 0.508)
		(layer "F.Cu")
		(net "GND")
	)
	(segment
		(start 251.599954 -45.999908)
		(end 252.099826 -45.500036)
		(width 0.4572)
		(layer "F.Cu")
		(net "GND")
	)
	(segment
		(start 134.5438 -211.1756)
		(end 135.5852 -212.217)
		(width 0.508)
		(layer "F.Cu")
		(net "GND")
	)
	(segment
		(start 224.600008 -37.999924)
		(end 224.100136 -37.500052)
		(width 0.4572)
		(layer "F.Cu")
		(net "GND")
	)
	(segment
		(start 26.533094 -145.21561)
		(end 26.9748 -145.657316)
		(width 0.508)
		(layer "F.Cu")
		(net "GND")
	)
	(segment
		(start 32.224726 -146.75358)
		(end 32.232346 -146.7612)
		(width 0.381)
		(layer "F.Cu")
		(net "GND")
	)
	(segment
		(start 23.561548 -145.196052)
		(end 24.194008 -145.196052)
		(width 0.508)
		(layer "F.Cu")
		(net "GND")
	)
	(segment
		(start 237.599982 -46.999906)
		(end 237.10011 -46.500034)
		(width 0.4572)
		(layer "F.Cu")
		(net "GND")
	)
	(segment
		(start 29.768038 -157.179772)
		(end 30.167834 -156.779976)
		(width 0.3556)
		(layer "F.Cu")
		(net "GND")
	)
	(segment
		(start 246.599964 -41.999916)
		(end 247.099836 -41.500044)
		(width 0.4572)
		(layer "F.Cu")
		(net "GND")
	)
	(segment
		(start 334.900016 -223.482154)
		(end 335.300066 -223.082104)
		(width 0.508)
		(layer "F.Cu")
		(net "GND")
	)
	(segment
		(start 233.59999 -56.999886)
		(end 233.100118 -57.499758)
		(width 0.4572)
		(layer "F.Cu")
		(net "GND")
	)
	(segment
		(start 39.5478 -103.1875)
		(end 40.33393 -103.1875)
		(width 0.508)
		(layer "F.Cu")
		(net "GND")
	)
	(segment
		(start 163.1188 -223.0374)
		(end 163.1188 -222.9866)
		(width 0.508)
		(layer "F.Cu")
		(net "GND")
	)
	(segment
		(start 272.311622 -3.956304)
		(end 271.731486 -3.376168)
		(width 0.508)
		(layer "F.Cu")
		(net "GND")
	)
	(segment
		(start 25.6286 -49.3141)
		(end 25.7429 -49.4284)
		(width 0.508)
		(layer "F.Cu")
		(net "GND")
	)
	(segment
		(start 350.918272 -45.867066)
		(end 350.798384 -45.986954)
		(width 0.508)
		(layer "F.Cu")
		(net "GND")
	)
	(segment
		(start 11.284204 -67.921632)
		(end 11.825732 -67.921632)
		(width 0.508)
		(layer "F.Cu")
		(net "GND")
	)
	(segment
		(start 251.599954 -56.999886)
		(end 252.099826 -57.499758)
		(width 0.4572)
		(layer "F.Cu")
		(net "GND")
	)
	(segment
		(start 26.289 -115.4938)
		(end 26.289 -116.2685)
		(width 0.508)
		(layer "F.Cu")
		(net "GND")
	)
	(segment
		(start 230.5685 -12.446)
		(end 230.5685 -13.1445)
		(width 0.508)
		(layer "F.Cu")
		(net "GND")
	)
	(segment
		(start 37.30498 -122.48515)
		(end 37.704776 -122.884946)
		(width 0.3556)
		(layer "F.Cu")
		(net "GND")
	)
	(segment
		(start 253.59995 -35.999928)
		(end 254.099822 -35.500056)
		(width 0.4572)
		(layer "F.Cu")
		(net "GND")
	)
	(segment
		(start 25.6286 -45.1739)
		(end 25.6286 -44.1452)
		(width 0.508)
		(layer "F.Cu")
		(net "GND")
	)
	(segment
		(start 163.269422 -90.326464)
		(end 164.308536 -90.326464)
		(width 0.3048)
		(layer "F.Cu")
		(net "GND")
	)
	(segment
		(start 106.899964 -223.482154)
		(end 107.300014 -223.082104)
		(width 0.508)
		(layer "F.Cu")
		(net "GND")
	)
	(segment
		(start 233.59999 -32.999934)
		(end 233.100118 -32.500062)
		(width 0.4572)
		(layer "F.Cu")
		(net "GND")
	)
	(segment
		(start 248.59996 -51.999896)
		(end 249.099832 -52.499768)
		(width 0.4572)
		(layer "F.Cu")
		(net "GND")
	)
	(segment
		(start 70.86727 -129.794)
		(end 71.310246 -130.236976)
		(width 0.4064)
		(layer "F.Cu")
		(net "GND")
	)
	(segment
		(start 36.90493 -122.084846)
		(end 36.90493 -122.0851)
		(width 0.3556)
		(layer "F.Cu")
		(net "GND")
	)
	(segment
		(start 224.600008 -59.99988)
		(end 224.100136 -60.499752)
		(width 0.4572)
		(layer "F.Cu")
		(net "GND")
	)
	(segment
		(start 249.599958 -43.999912)
		(end 250.09983 -43.50004)
		(width 0.4572)
		(layer "F.Cu")
		(net "GND")
	)
	(segment
		(start 69.400166 -83.47456)
		(end 67.8942 -83.47456)
		(width 0.508)
		(layer "F.Cu")
		(net "GND")
	)
	(segment
		(start 45.1358 -190.2206)
		(end 46.0248 -190.2206)
		(width 0.508)
		(layer "F.Cu")
		(net "GND")
	)
	(segment
		(start 226.75723 -2.37617)
		(end 226.75723 -2.458974)
		(width 0.508)
		(layer "F.Cu")
		(net "GND")
	)
	(segment
		(start 242.599972 -60.999878)
		(end 243.099844 -61.49975)
		(width 0.4572)
		(layer "F.Cu")
		(net "GND")
	)
	(segment
		(start 135.769604 -63.223902)
		(end 135.769604 -61.905134)
		(width 0.508)
		(layer "F.Cu")
		(net "GND")
	)
	(segment
		(start 250.599956 -53.999892)
		(end 251.099828 -54.499764)
		(width 0.4572)
		(layer "F.Cu")
		(net "GND")
	)
	(segment
		(start 11.183366 -69.233288)
		(end 11.2014 -69.233288)
		(width 0.508)
		(layer "F.Cu")
		(net "GND")
	)
	(segment
		(start 225.600006 -47.999904)
		(end 225.100134 -48.499776)
		(width 0.4572)
		(layer "F.Cu")
		(net "GND")
	)
	(segment
		(start 229.599998 -58.999882)
		(end 229.100126 -59.499754)
		(width 0.4572)
		(layer "F.Cu")
		(net "GND")
	)
	(segment
		(start 266.100052 -225.54438)
		(end 266.100052 -223.482154)
		(width 0.508)
		(layer "F.Cu")
		(net "GND")
	)
	(segment
		(start 24.194008 -146.402552)
		(end 24.194008 -145.196052)
		(width 0.508)
		(layer "F.Cu")
		(net "GND")
	)
	(segment
		(start 83.525868 -75.1586)
		(end 83.745832 -74.938636)
		(width 0.508)
		(layer "F.Cu")
		(net "GND")
	)
	(segment
		(start 232.599992 -63.999872)
		(end 232.10012 -64.499744)
		(width 0.4572)
		(layer "F.Cu")
		(net "GND")
	)
	(segment
		(start 255.599946 -59.99988)
		(end 256.099818 -60.499752)
		(width 0.4572)
		(layer "F.Cu")
		(net "GND")
	)
	(segment
		(start 152.900126 -225.54438)
		(end 152.900126 -223.482408)
		(width 0.508)
		(layer "F.Cu")
		(net "GND")
	)
	(segment
		(start 239.599978 -52.999894)
		(end 238.59998 -53.999892)
		(width 0.4572)
		(layer "F.Cu")
		(net "GND")
	)
	(segment
		(start 250.599956 -44.99991)
		(end 251.099828 -44.500038)
		(width 0.4572)
		(layer "F.Cu")
		(net "GND")
	)
	(segment
		(start 20.2184 -101.3968)
		(end 20.546314 -101.3968)
		(width 0.508)
		(layer "F.Cu")
		(net "GND")
	)
	(segment
		(start 49.9364 -152.8445)
		(end 50.4444 -152.3365)
		(width 0.508)
		(layer "F.Cu")
		(net "GND")
	)
	(segment
		(start 256.599944 -32.999934)
		(end 257.099816 -32.500062)
		(width 0.4572)
		(layer "F.Cu")
		(net "GND")
	)
	(segment
		(start 54.356 -134.62)
		(end 54.5465 -134.4295)
		(width 0.508)
		(layer "F.Cu")
		(net "GND")
	)
	(segment
		(start 154.5463 -87.4268)
		(end 154.7114 -87.4268)
		(width 0.508)
		(layer "F.Cu")
		(net "GND")
	)
	(segment
		(start 251.599954 -42.999914)
		(end 252.099826 -42.500042)
		(width 0.4572)
		(layer "F.Cu")
		(net "GND")
	)
	(segment
		(start 237.599982 -50.999898)
		(end 237.10011 -51.49977)
		(width 0.4572)
		(layer "F.Cu")
		(net "GND")
	)
	(segment
		(start 257.599942 -59.99988)
		(end 258.099814 -60.499752)
		(width 0.4572)
		(layer "F.Cu")
		(net "GND")
	)
	(segment
		(start 240.599976 -63.999872)
		(end 241.099848 -64.499744)
		(width 0.4572)
		(layer "F.Cu")
		(net "GND")
	)
	(segment
		(start 225.600006 -63.999872)
		(end 225.100134 -64.499744)
		(width 0.4572)
		(layer "F.Cu")
		(net "GND")
	)
	(segment
		(start 30.061154 -145.970244)
		(end 30.886654 -145.970244)
		(width 0.508)
		(layer "F.Cu")
		(net "GND")
	)
	(segment
		(start 36.10483 -129.284984)
		(end 36.105084 -129.284984)
		(width 0.3556)
		(layer "F.Cu")
		(net "GND")
	)
	(segment
		(start 19.654774 -128.651)
		(end 19.662902 -128.642872)
		(width 0.508)
		(layer "F.Cu")
		(net "GND")
	)
	(segment
		(start 248.59996 -58.999882)
		(end 249.099832 -59.499754)
		(width 0.4572)
		(layer "F.Cu")
		(net "GND")
	)
	(segment
		(start 38.862 -55.753)
		(end 38.862 -57.15)
		(width 0.508)
		(layer "F.Cu")
		(net "GND")
	)
	(segment
		(start 15.39494 -96.94291)
		(end 15.39494 -95.833184)
		(width 0.508)
		(layer "F.Cu")
		(net "GND")
	)
	(segment
		(start 229.599998 -54.99989)
		(end 229.100126 -55.499762)
		(width 0.4572)
		(layer "F.Cu")
		(net "GND")
	)
	(segment
		(start 256.599944 -51.999896)
		(end 257.099816 -52.499768)
		(width 0.4572)
		(layer "F.Cu")
		(net "GND")
	)
	(segment
		(start 117.5258 -94.6277)
		(end 117.5258 -93.8022)
		(width 0.508)
		(layer "F.Cu")
		(net "GND")
	)
	(segment
		(start 241.935 -18.942558)
		(end 241.935 -19.0754)
		(width 0.508)
		(layer "F.Cu")
		(net "GND")
	)
	(segment
		(start 125.986286 -209.3341)
		(end 125.978412 -209.341974)
		(width 0.508)
		(layer "F.Cu")
		(net "GND")
	)
	(segment
		(start 70.6247 -161.2646)
		(end 71.5518 -161.2646)
		(width 0.508)
		(layer "F.Cu")
		(net "GND")
	)
	(segment
		(start 38.504876 -130.88493)
		(end 38.10508 -130.485134)
		(width 0.3556)
		(layer "F.Cu")
		(net "GND")
	)
	(segment
		(start 38.104826 -131.28498)
		(end 38.10508 -131.28498)
		(width 0.3556)
		(layer "F.Cu")
		(net "GND")
	)
	(segment
		(start 57.300114 -223.482154)
		(end 57.700164 -223.082104)
		(width 0.508)
		(layer "F.Cu")
		(net "GND")
	)
	(segment
		(start 35.699954 -223.913954)
		(end 35.699954 -225.54438)
		(width 0.508)
		(layer "F.Cu")
		(net "GND")
	)
	(segment
		(start 236.599984 -43.999912)
		(end 236.100112 -43.50004)
		(width 0.4572)
		(layer "F.Cu")
		(net "GND")
	)
	(segment
		(start 225.600006 -38.999922)
		(end 225.100134 -38.50005)
		(width 0.4572)
		(layer "F.Cu")
		(net "GND")
	)
	(segment
		(start 69.922644 -128.115568)
		(end 70.2056 -127.832612)
		(width 0.4064)
		(layer "F.Cu")
		(net "GND")
	)
	(segment
		(start 247.599962 -58.999882)
		(end 248.099834 -59.499754)
		(width 0.4572)
		(layer "F.Cu")
		(net "GND")
	)
	(segment
		(start 26.5176 -78.8035)
		(end 26.5176 -77.9145)
		(width 0.508)
		(layer "F.Cu")
		(net "GND")
	)
	(segment
		(start 239.599978 -46.999906)
		(end 238.59998 -45.999908)
		(width 0.4572)
		(layer "F.Cu")
		(net "GND")
	)
	(segment
		(start 88.500204 -225.54438)
		(end 88.500204 -223.4819)
		(width 0.508)
		(layer "F.Cu")
		(net "GND")
	)
	(segment
		(start 318.516 -100.0125)
		(end 318.516 -100.838)
		(width 0.508)
		(layer "F.Cu")
		(net "GND")
	)
	(segment
		(start 20.447 -142.9385)
		(end 19.6215 -142.9385)
		(width 0.508)
		(layer "F.Cu")
		(net "GND")
	)
	(segment
		(start 192.4939 -25.0952)
		(end 191.9478 -25.0952)
		(width 0.508)
		(layer "F.Cu")
		(net "GND")
	)
	(segment
		(start 234.599988 -54.99989)
		(end 234.100116 -55.499762)
		(width 0.4572)
		(layer "F.Cu")
		(net "GND")
	)
	(segment
		(start 83.290664 -83.48472)
		(end 83.627214 -83.48472)
		(width 0.508)
		(layer "F.Cu")
		(net "GND")
	)
	(segment
		(start 227.600002 -46.999906)
		(end 227.10013 -46.500034)
		(width 0.4572)
		(layer "F.Cu")
		(net "GND")
	)
	(segment
		(start 52.1208 -49.8729)
		(end 52.1208 -48.966882)
		(width 0.508)
		(layer "F.Cu")
		(net "GND")
	)
	(segment
		(start 248.59996 -49.9999)
		(end 249.099832 -50.499772)
		(width 0.4572)
		(layer "F.Cu")
		(net "GND")
	)
	(segment
		(start 215.876124 -203.491592)
		(end 215.876124 -204.350874)
		(width 0.508)
		(layer "F.Cu")
		(net "GND")
	)
	(segment
		(start 225.600006 -60.999878)
		(end 225.100134 -61.49975)
		(width 0.4572)
		(layer "F.Cu")
		(net "GND")
	)
	(segment
		(start 56.500014 -223.482154)
		(end 56.099964 -223.082104)
		(width 0.508)
		(layer "F.Cu")
		(net "GND")
	)
	(segment
		(start 193.6115 -12.28725)
		(end 193.6115 -11.3411)
		(width 0.508)
		(layer "F.Cu")
		(net "GND")
	)
	(segment
		(start 217.8812 -3.067812)
		(end 217.8812 -3.504692)
		(width 0.508)
		(layer "F.Cu")
		(net "GND")
	)
	(segment
		(start 239.395 -7.6454)
		(end 239.708436 -7.6454)
		(width 0.508)
		(layer "F.Cu")
		(net "GND")
	)
	(segment
		(start 37.211 -200.0885)
		(end 37.211 -199.263)
		(width 0.508)
		(layer "F.Cu")
		(net "GND")
	)
	(segment
		(start 240.599976 -64.99987)
		(end 241.099848 -65.499742)
		(width 0.4572)
		(layer "F.Cu")
		(net "GND")
	)
	(segment
		(start 64.893698 -130.163316)
		(end 64.893698 -130.23088)
		(width 0.508)
		(layer "F.Cu")
		(net "GND")
	)
	(segment
		(start 232.599992 -42.999914)
		(end 232.10012 -42.500042)
		(width 0.4572)
		(layer "F.Cu")
		(net "GND")
	)
	(segment
		(start 35.988498 -103.386636)
		(end 35.988498 -102.74681)
		(width 0.508)
		(layer "F.Cu")
		(net "GND")
	)
	(segment
		(start 54.1655 -120.9675)
		(end 54.864 -120.269)
		(width 0.508)
		(layer "F.Cu")
		(net "GND")
	)
	(segment
		(start 38.167056 -163.559744)
		(end 38.180264 -163.546536)
		(width 0.508)
		(layer "F.Cu")
		(net "GND")
	)
	(segment
		(start 84.499958 -223.482154)
		(end 84.099908 -223.082104)
		(width 0.508)
		(layer "F.Cu")
		(net "GND")
	)
	(segment
		(start 237.599982 -54.99989)
		(end 237.10011 -55.499762)
		(width 0.4572)
		(layer "F.Cu")
		(net "GND")
	)
	(segment
		(start 137.0203 -81.830164)
		(end 137.0203 -81.0641)
		(width 0.508)
		(layer "F.Cu")
		(net "GND")
	)
	(segment
		(start 45.300138 -225.54438)
		(end 45.300138 -223.482408)
		(width 0.508)
		(layer "F.Cu")
		(net "GND")
	)
	(segment
		(start 40.576754 -146.021044)
		(end 41.119044 -146.021044)
		(width 0.508)
		(layer "F.Cu")
		(net "GND")
	)
	(segment
		(start 99.70008 -223.482408)
		(end 99.299776 -223.082104)
		(width 0.508)
		(layer "F.Cu")
		(net "GND")
	)
	(segment
		(start 65.3288 -88.1634)
		(end 65.3288 -88.60536)
		(width 0.4064)
		(layer "F.Cu")
		(net "GND")
	)
	(segment
		(start 49.788572 -49.661572)
		(end 49.788572 -49.861724)
		(width 0.508)
		(layer "F.Cu")
		(net "GND")
	)
	(segment
		(start 230.886 -89.916)
		(end 230.886 -89.8144)
		(width 0.508)
		(layer "F.Cu")
		(net "GND")
	)
	(segment
		(start 257.599942 -41.999916)
		(end 258.099814 -41.500044)
		(width 0.4572)
		(layer "F.Cu")
		(net "GND")
	)
	(segment
		(start 238.59998 -53.999892)
		(end 238.100108 -54.499764)
		(width 0.4572)
		(layer "F.Cu")
		(net "GND")
	)
	(segment
		(start 13.569188 -90.008456)
		(end 13.569188 -89.702132)
		(width 0.508)
		(layer "F.Cu")
		(net "GND")
	)
	(segment
		(start 123.6218 -98.7552)
		(end 124.5108 -98.7552)
		(width 0.508)
		(layer "F.Cu")
		(net "GND")
	)
	(segment
		(start 230.599996 -44.99991)
		(end 230.100124 -44.500038)
		(width 0.4572)
		(layer "F.Cu")
		(net "GND")
	)
	(segment
		(start 36.500054 -223.952054)
		(end 36.500054 -225.54438)
		(width 0.508)
		(layer "F.Cu")
		(net "GND")
	)
	(segment
		(start 20.546314 -101.3968)
		(end 20.574 -101.369114)
		(width 0.508)
		(layer "F.Cu")
		(net "GND")
	)
	(segment
		(start 252.355604 -13.156692)
		(end 252.355604 -11.735562)
		(width 0.508)
		(layer "F.Cu")
		(net "GND")
	)
	(segment
		(start 18.1483 -146.8882)
		(end 18.1356 -146.8882)
		(width 0.508)
		(layer "F.Cu")
		(net "GND")
	)
	(segment
		(start 63.246 -133.537198)
		(end 63.242698 -133.5405)
		(width 0.508)
		(layer "F.Cu")
		(net "GND")
	)
	(segment
		(start 232.599992 -51.999896)
		(end 232.10012 -52.499768)
		(width 0.4572)
		(layer "F.Cu")
		(net "GND")
	)
	(segment
		(start 15.39494 -95.833184)
		(end 15.696946 -95.531178)
		(width 0.508)
		(layer "F.Cu")
		(net "GND")
	)
	(segment
		(start 37.292026 -161.70148)
		(end 38.17112 -161.70148)
		(width 0.508)
		(layer "F.Cu")
		(net "GND")
	)
	(segment
		(start 229.599998 -48.999902)
		(end 229.100126 -49.499774)
		(width 0.4572)
		(layer "F.Cu")
		(net "GND")
	)
	(segment
		(start 224.600008 -42.999914)
		(end 224.100136 -42.500042)
		(width 0.4572)
		(layer "F.Cu")
		(net "GND")
	)
	(segment
		(start 250.599956 -55.999888)
		(end 251.099828 -56.49976)
		(width 0.4572)
		(layer "F.Cu")
		(net "GND")
	)
	(segment
		(start 315.700156 -223.482154)
		(end 316.100206 -223.082104)
		(width 0.508)
		(layer "F.Cu")
		(net "GND")
	)
	(segment
		(start 242.599972 -51.999896)
		(end 243.099844 -52.499768)
		(width 0.4572)
		(layer "F.Cu")
		(net "GND")
	)
	(segment
		(start 31.705042 -137.685018)
		(end 32.104838 -138.084814)
		(width 0.3556)
		(layer "F.Cu")
		(net "GND")
	)
	(segment
		(start 214.500206 -223.482408)
		(end 214.099902 -223.082104)
		(width 0.508)
		(layer "F.Cu")
		(net "GND")
	)
	(segment
		(start 27.3177 -51.6382)
		(end 26.9748 -51.6382)
		(width 0.508)
		(layer "F.Cu")
		(net "GND")
	)
	(segment
		(start 238.59998 -31.999936)
		(end 238.100108 -31.500064)
		(width 0.4572)
		(layer "F.Cu")
		(net "GND")
	)
	(segment
		(start 338.761832 -175.962818)
		(end 339.707982 -175.962818)
		(width 0.3048)
		(layer "F.Cu")
		(net "GND")
	)
	(segment
		(start 159.385 -95.4659)
		(end 159.385 -94.996)
		(width 0.508)
		(layer "F.Cu")
		(net "GND")
	)
	(segment
		(start 250.599956 -43.999912)
		(end 251.099828 -43.50004)
		(width 0.4572)
		(layer "F.Cu")
		(net "GND")
	)
	(segment
		(start 32.104838 -137.284968)
		(end 32.104838 -137.285222)
		(width 0.3556)
		(layer "F.Cu")
		(net "GND")
	)
	(segment
		(start 231.599994 -54.99989)
		(end 231.100122 -55.499762)
		(width 0.4572)
		(layer "F.Cu")
		(net "GND")
	)
	(segment
		(start 331.4192 -207.8736)
		(end 331.4192 -206.2226)
		(width 0.508)
		(layer "F.Cu")
		(net "GND")
	)
	(segment
		(start 247.599962 -46.999906)
		(end 248.099834 -46.500034)
		(width 0.4572)
		(layer "F.Cu")
		(net "GND")
	)
	(segment
		(start 246.599964 -54.99989)
		(end 247.099836 -55.499762)
		(width 0.4572)
		(layer "F.Cu")
		(net "GND")
	)
	(segment
		(start 151.770588 -90.674952)
		(end 151.770588 -89.464388)
		(width 0.508)
		(layer "F.Cu")
		(net "GND")
	)
	(segment
		(start 31.367984 -150.779988)
		(end 30.968188 -150.380192)
		(width 0.3556)
		(layer "F.Cu")
		(net "GND")
	)
	(segment
		(start 40.967914 -155.579826)
		(end 41.36771 -155.18003)
		(width 0.3556)
		(layer "F.Cu")
		(net "GND")
	)
	(segment
		(start 241.599974 -55.999888)
		(end 242.099846 -56.49976)
		(width 0.4572)
		(layer "F.Cu")
		(net "GND")
	)
	(segment
		(start 17.930114 -92.239846)
		(end 17.930114 -91.264486)
		(width 0.508)
		(layer "F.Cu")
		(net "GND")
	)
	(segment
		(start 192.3923 -28.6512)
		(end 191.8716 -28.6512)
		(width 0.508)
		(layer "F.Cu")
		(net "GND")
	)
	(segment
		(start 39.116 -198.882)
		(end 39.116 -197.866)
		(width 0.508)
		(layer "F.Cu")
		(net "GND")
	)
	(segment
		(start 36.10483 -130.88493)
		(end 36.105084 -130.88493)
		(width 0.3556)
		(layer "F.Cu")
		(net "GND")
	)
	(segment
		(start 37.30498 -131.284726)
		(end 37.30498 -131.28498)
		(width 0.3556)
		(layer "F.Cu")
		(net "GND")
	)
	(segment
		(start 249.599958 -56.999886)
		(end 250.09983 -57.499758)
		(width 0.4572)
		(layer "F.Cu")
		(net "GND")
	)
	(segment
		(start 71.700136 -225.54438)
		(end 71.700136 -224.303336)
		(width 0.508)
		(layer "F.Cu")
		(net "GND")
	)
	(segment
		(start 237.599982 -48.999902)
		(end 237.10011 -49.499774)
		(width 0.4572)
		(layer "F.Cu")
		(net "GND")
	)
	(segment
		(start 38.07968 -162.66668)
		(end 38.1 -162.687)
		(width 0.508)
		(layer "F.Cu")
		(net "GND")
	)
	(segment
		(start 76.108306 -84.493354)
		(end 76.898246 -84.493354)
		(width 0.508)
		(layer "F.Cu")
		(net "GND")
	)
	(segment
		(start 249.599958 -46.999906)
		(end 250.09983 -46.500034)
		(width 0.4572)
		(layer "F.Cu")
		(net "GND")
	)
	(segment
		(start 25.0571 -50.080164)
		(end 24.532336 -49.5554)
		(width 0.508)
		(layer "F.Cu")
		(net "GND")
	)
	(segment
		(start 234.599988 -49.9999)
		(end 234.100116 -50.499772)
		(width 0.4572)
		(layer "F.Cu")
		(net "GND")
	)
	(segment
		(start 241.599974 -50.999898)
		(end 242.099846 -51.49977)
		(width 0.4572)
		(layer "F.Cu")
		(net "GND")
	)
	(segment
		(start 62.900052 -223.4819)
		(end 63.299848 -223.082104)
		(width 0.508)
		(layer "F.Cu")
		(net "GND")
	)
	(segment
		(start 21.3614 -52.0192)
		(end 21.3614 -52.669694)
		(width 0.508)
		(layer "F.Cu")
		(net "GND")
	)
	(segment
		(start 53.2511 -182.45836)
		(end 54.65064 -182.45836)
		(width 0.381)
		(layer "F.Cu")
		(net "GND")
	)
	(segment
		(start 327.908412 -47.288958)
		(end 327.88098 -47.31639)
		(width 0.508)
		(layer "F.Cu")
		(net "GND")
	)
	(segment
		(start 94.100142 -225.54438)
		(end 94.100142 -223.069658)
		(width 0.508)
		(layer "F.Cu")
		(net "GND")
	)
	(segment
		(start 5.4356 -81.4832)
		(end 6.2484 -80.6704)
		(width 0.508)
		(layer "F.Cu")
		(net "GND")
	)
	(segment
		(start 32.505142 -137.685018)
		(end 32.904938 -138.084814)
		(width 0.3556)
		(layer "F.Cu")
		(net "GND")
	)
	(segment
		(start 22.7076 -119.4816)
		(end 22.733 -119.507)
		(width 0.508)
		(layer "F.Cu")
		(net "GND")
	)
	(segment
		(start 243.59997 -50.999898)
		(end 244.099842 -51.49977)
		(width 0.4572)
		(layer "F.Cu")
		(net "GND")
	)
	(segment
		(start 235.599986 -62.999874)
		(end 235.100114 -63.499746)
		(width 0.4572)
		(layer "F.Cu")
		(net "GND")
	)
	(segment
		(start 272.311622 -4.1656)
		(end 272.311622 -3.956304)
		(width 0.508)
		(layer "F.Cu")
		(net "GND")
	)
	(segment
		(start 26.9748 -51.6382)
		(end 26.3398 -51.0032)
		(width 0.508)
		(layer "F.Cu")
		(net "GND")
	)
	(segment
		(start 247.599962 -62.999874)
		(end 248.099834 -63.499746)
		(width 0.4572)
		(layer "F.Cu")
		(net "GND")
	)
	(segment
		(start 72.005952 -150.66391)
		(end 73.36409 -150.66391)
		(width 0.508)
		(layer "F.Cu")
		(net "GND")
	)
	(segment
		(start 229.5525 -86.7664)
		(end 230.1494 -86.7664)
		(width 0.508)
		(layer "F.Cu")
		(net "GND")
	)
	(segment
		(start 249.599958 -64.99987)
		(end 250.09983 -65.499742)
		(width 0.4572)
		(layer "F.Cu")
		(net "GND")
	)
	(segment
		(start 37.287454 -164.702744)
		(end 38.217856 -164.702744)
		(width 0.508)
		(layer "F.Cu")
		(net "GND")
	)
	(segment
		(start 50.099976 -223.482154)
		(end 49.699926 -223.082104)
		(width 0.508)
		(layer "F.Cu")
		(net "GND")
	)
	(segment
		(start 232.599992 -58.999882)
		(end 232.10012 -59.499754)
		(width 0.4572)
		(layer "F.Cu")
		(net "GND")
	)
	(segment
		(start 102.899972 -225.54438)
		(end 102.899972 -223.482154)
		(width 0.508)
		(layer "F.Cu")
		(net "GND")
	)
	(segment
		(start 38.10508 -130.485134)
		(end 37.704776 -130.08483)
		(width 0.3556)
		(layer "F.Cu")
		(net "GND")
	)
	(segment
		(start 37.193474 -113.066068)
		(end 37.12591 -112.998504)
		(width 0.508)
		(layer "F.Cu")
		(net "GND")
	)
	(segment
		(start 253.59995 -32.999934)
		(end 254.099822 -32.500062)
		(width 0.4572)
		(layer "F.Cu")
		(net "GND")
	)
	(segment
		(start 119.4308 -93.4212)
		(end 119.4308 -92.4052)
		(width 0.508)
		(layer "F.Cu")
		(net "GND")
	)
	(segment
		(start 259.6642 -3.5306)
		(end 259.6642 -3.6576)
		(width 0.508)
		(layer "F.Cu")
		(net "GND")
	)
	(segment
		(start 128.404112 -40.422068)
		(end 128.404112 -41.750488)
		(width 0.508)
		(layer "F.Cu")
		(net "GND")
	)
	(segment
		(start 341.300054 -225.54438)
		(end 341.300054 -223.482154)
		(width 0.508)
		(layer "F.Cu")
		(net "GND")
	)
	(segment
		(start 49.149 -178.816)
		(end 49.149 -177.8)
		(width 0.508)
		(layer "F.Cu")
		(net "GND")
	)
	(segment
		(start 336.653886 -37.66058)
		(end 336.658966 -37.66058)
		(width 0.508)
		(layer "F.Cu")
		(net "GND")
	)
	(segment
		(start 231.599994 -44.99991)
		(end 231.100122 -44.500038)
		(width 0.4572)
		(layer "F.Cu")
		(net "GND")
	)
	(segment
		(start 251.599954 -58.999882)
		(end 252.099826 -59.499754)
		(width 0.4572)
		(layer "F.Cu")
		(net "GND")
	)
	(segment
		(start 140.90015 -223.482154)
		(end 141.3002 -223.082104)
		(width 0.508)
		(layer "F.Cu")
		(net "GND")
	)
	(segment
		(start 70.2056 -127.832612)
		(end 70.2056 -127.34544)
		(width 0.4064)
		(layer "F.Cu")
		(net "GND")
	)
	(segment
		(start 254.599948 -41.999916)
		(end 255.09982 -41.500044)
		(width 0.4572)
		(layer "F.Cu")
		(net "GND")
	)
	(segment
		(start 192.900046 -223.482154)
		(end 193.300096 -223.082104)
		(width 0.508)
		(layer "F.Cu")
		(net "GND")
	)
	(segment
		(start 32.904938 -135.684768)
		(end 32.505142 -135.284972)
		(width 0.3556)
		(layer "F.Cu")
		(net "GND")
	)
	(segment
		(start 59.871102 -18.691606)
		(end 57.792874 -18.691606)
		(width 0.508)
		(layer "F.Cu")
		(net "GND")
	)
	(segment
		(start 156.3116 -93.726)
		(end 157.2768 -93.726)
		(width 0.3048)
		(layer "F.Cu")
		(net "GND")
	)
	(segment
		(start 231.599994 -62.999874)
		(end 231.100122 -63.499746)
		(width 0.4572)
		(layer "F.Cu")
		(net "GND")
	)
	(segment
		(start 15.042134 -183.3753)
		(end 15.385034 -183.0324)
		(width 0.3048)
		(layer "F.Cu")
		(net "GND")
	)
	(segment
		(start 77.720444 -186.185556)
		(end 78.570074 -185.335926)
		(width 0.3048)
		(layer "F.Cu")
		(net "GND")
	)
	(segment
		(start 129.1717 -47.371)
		(end 130.2004 -47.371)
		(width 0.508)
		(layer "F.Cu")
		(net "GND")
	)
	(segment
		(start 255.599946 -45.999908)
		(end 256.099818 -45.500036)
		(width 0.4572)
		(layer "F.Cu")
		(net "GND")
	)
	(segment
		(start 258.59994 -61.999876)
		(end 259.099812 -62.499748)
		(width 0.4572)
		(layer "F.Cu")
		(net "GND")
	)
	(segment
		(start 244.599968 -54.99989)
		(end 245.09984 -55.499762)
		(width 0.4572)
		(layer "F.Cu")
		(net "GND")
	)
	(segment
		(start 240.599976 -58.999882)
		(end 241.099848 -59.499754)
		(width 0.4572)
		(layer "F.Cu")
		(net "GND")
	)
	(segment
		(start 252.068584 -11.448542)
		(end 252.068584 -11.444224)
		(width 0.508)
		(layer "F.Cu")
		(net "GND")
	)
	(segment
		(start 81.4578 -135.763)
		(end 81.0895 -135.763)
		(width 0.508)
		(layer "F.Cu")
		(net "GND")
	)
	(segment
		(start 37.30498 -131.28498)
		(end 36.90493 -130.88493)
		(width 0.3556)
		(layer "F.Cu")
		(net "GND")
	)
	(segment
		(start 249.599958 -37.999924)
		(end 250.09983 -37.500052)
		(width 0.4572)
		(layer "F.Cu")
		(net "GND")
	)
	(segment
		(start 68.49999 -223.482154)
		(end 68.09994 -223.082104)
		(width 0.508)
		(layer "F.Cu")
		(net "GND")
	)
	(segment
		(start 37.30498 -132.084826)
		(end 37.30498 -132.08508)
		(width 0.3556)
		(layer "F.Cu")
		(net "GND")
	)
	(segment
		(start 18.3642 -65.4177)
		(end 18.25498 -65.30848)
		(width 0.508)
		(layer "F.Cu")
		(net "GND")
	)
	(segment
		(start 224.600008 -55.999888)
		(end 224.100136 -56.49976)
		(width 0.4572)
		(layer "F.Cu")
		(net "GND")
	)
	(segment
		(start 225.15068 -206.059024)
		(end 224.824798 -206.384906)
		(width 0.508)
		(layer "F.Cu")
		(net "GND")
	)
	(segment
		(start 230.599996 -40.999918)
		(end 230.100124 -40.500046)
		(width 0.4572)
		(layer "F.Cu")
		(net "GND")
	)
	(segment
		(start 242.599972 -53.999892)
		(end 243.099844 -54.499764)
		(width 0.4572)
		(layer "F.Cu")
		(net "GND")
	)
	(segment
		(start 70.2056 -130.44424)
		(end 71.102982 -130.44424)
		(width 0.4064)
		(layer "F.Cu")
		(net "GND")
	)
	(segment
		(start 240.164874 -7.188962)
		(end 240.164874 -6.444996)
		(width 0.508)
		(layer "F.Cu")
		(net "GND")
	)
	(segment
		(start 27.554936 -88.487758)
		(end 26.897584 -89.14511)
		(width 0.3048)
		(layer "F.Cu")
		(net "GND")
	)
	(segment
		(start 23.792688 -68.618862)
		(end 23.05812 -69.35343)
		(width 0.508)
		(layer "F.Cu")
		(net "GND")
	)
	(segment
		(start 69.699124 -182.790592)
		(end 69.699124 -182.015892)
		(width 0.508)
		(layer "F.Cu")
		(net "GND")
	)
	(segment
		(start 312.50001 -225.54438)
		(end 312.50001 -223.482154)
		(width 0.508)
		(layer "F.Cu")
		(net "GND")
	)
	(segment
		(start 240.599976 -51.999896)
		(end 241.099848 -52.499768)
		(width 0.4572)
		(layer "F.Cu")
		(net "GND")
	)
	(segment
		(start 57.15 -131.6609)
		(end 56.1594 -131.6609)
		(width 0.508)
		(layer "F.Cu")
		(net "GND")
	)
	(segment
		(start 26.5176 -77.9145)
		(end 26.5049 -77.9018)
		(width 0.508)
		(layer "F.Cu")
		(net "GND")
	)
	(segment
		(start 198.500238 -223.482408)
		(end 198.099934 -223.082104)
		(width 0.508)
		(layer "F.Cu")
		(net "GND")
	)
	(segment
		(start 50.7365 -147.447)
		(end 50.038 -148.1455)
		(width 0.508)
		(layer "F.Cu")
		(net "GND")
	)
	(segment
		(start 241.599974 -42.999914)
		(end 242.099846 -42.500042)
		(width 0.4572)
		(layer "F.Cu")
		(net "GND")
	)
	(segment
		(start 137.527284 -56.530748)
		(end 137.69848 -56.359552)
		(width 0.508)
		(layer "F.Cu")
		(net "GND")
	)
	(segment
		(start 246.599964 -53.999892)
		(end 247.099836 -54.499764)
		(width 0.4572)
		(layer "F.Cu")
		(net "GND")
	)
	(segment
		(start 38.10508 -130.484626)
		(end 38.10508 -130.485134)
		(width 0.3556)
		(layer "F.Cu")
		(net "GND")
	)
	(segment
		(start 170.181524 -52.055268)
		(end 170.181524 -53.251608)
		(width 0.508)
		(layer "F.Cu")
		(net "GND")
	)
	(segment
		(start 37.704776 -130.88493)
		(end 38.104572 -130.485134)
		(width 0.3556)
		(layer "F.Cu")
		(net "GND")
	)
	(segment
		(start 39.704772 -131.28498)
		(end 39.705026 -131.28498)
		(width 0.3556)
		(layer "F.Cu")
		(net "GND")
	)
	(segment
		(start 231.599994 -58.999882)
		(end 231.100122 -59.499754)
		(width 0.4572)
		(layer "F.Cu")
		(net "GND")
	)
	(segment
		(start 228.732588 -4.245864)
		(end 229.21976 -4.245864)
		(width 0.508)
		(layer "F.Cu")
		(net "GND")
	)
	(segment
		(start 147.300188 -225.54438)
		(end 147.300188 -223.482154)
		(width 0.508)
		(layer "F.Cu")
		(net "GND")
	)
	(segment
		(start 230.6955 -10.414)
		(end 231.648 -10.414)
		(width 0.508)
		(layer "F.Cu")
		(net "GND")
	)
	(segment
		(start 38.904926 -129.68478)
		(end 38.904926 -129.685034)
		(width 0.3556)
		(layer "F.Cu")
		(net "GND")
	)
	(segment
		(start 19.28241 -96.187006)
		(end 19.282918 -96.186498)
		(width 0.508)
		(layer "F.Cu")
		(net "GND")
	)
	(segment
		(start 21.3868 -149.9362)
		(end 20.828 -150.495)
		(width 0.508)
		(layer "F.Cu")
		(net "GND")
	)
	(segment
		(start 77.0382 -196.342)
		(end 76.3524 -197.0278)
		(width 0.508)
		(layer "F.Cu")
		(net "GND")
	)
	(segment
		(start 249.599958 -58.999882)
		(end 250.09983 -59.499754)
		(width 0.4572)
		(layer "F.Cu")
		(net "GND")
	)
	(segment
		(start 318.100202 -223.482408)
		(end 317.699898 -223.082104)
		(width 0.508)
		(layer "F.Cu")
		(net "GND")
	)
	(segment
		(start 255.599946 -43.999912)
		(end 256.099818 -43.50004)
		(width 0.4572)
		(layer "F.Cu")
		(net "GND")
	)
	(segment
		(start 78.90002 -225.54438)
		(end 78.90002 -223.53778)
		(width 0.508)
		(layer "F.Cu")
		(net "GND")
	)
	(segment
		(start 162.500056 -225.54438)
		(end 162.500056 -223.656144)
		(width 0.508)
		(layer "F.Cu")
		(net "GND")
	)
	(segment
		(start 18.502376 -96.187006)
		(end 19.28241 -96.187006)
		(width 0.508)
		(layer "F.Cu")
		(net "GND")
	)
	(segment
		(start 137.69848 -56.359552)
		(end 137.69848 -55.51297)
		(width 0.508)
		(layer "F.Cu")
		(net "GND")
	)
	(segment
		(start 227.600002 -32.999934)
		(end 227.10013 -32.500062)
		(width 0.4572)
		(layer "F.Cu")
		(net "GND")
	)
	(segment
		(start 29.704792 -124.484892)
		(end 29.7053 -124.484892)
		(width 0.3556)
		(layer "F.Cu")
		(net "GND")
	)
	(segment
		(start 241.096292 -18.10385)
		(end 241.935 -18.942558)
		(width 0.508)
		(layer "F.Cu")
		(net "GND")
	)
	(segment
		(start 232.599992 -47.999904)
		(end 232.10012 -48.499776)
		(width 0.4572)
		(layer "F.Cu")
		(net "GND")
	)
	(segment
		(start 325.300086 -223.482154)
		(end 325.700136 -223.082104)
		(width 0.508)
		(layer "F.Cu")
		(net "GND")
	)
	(segment
		(start 102.899972 -223.482154)
		(end 102.499922 -223.082104)
		(width 0.508)
		(layer "F.Cu")
		(net "GND")
	)
	(segment
		(start 246.599964 -56.999886)
		(end 247.099836 -57.499758)
		(width 0.4572)
		(layer "F.Cu")
		(net "GND")
	)
	(segment
		(start 28.918154 -145.970244)
		(end 30.061154 -145.970244)
		(width 0.508)
		(layer "F.Cu")
		(net "GND")
	)
	(segment
		(start 250.599956 -52.999894)
		(end 251.099828 -53.499766)
		(width 0.4572)
		(layer "F.Cu")
		(net "GND")
	)
	(segment
		(start 256.599944 -37.999924)
		(end 257.099816 -37.500052)
		(width 0.4572)
		(layer "F.Cu")
		(net "GND")
	)
	(segment
		(start 243.59997 -32.999934)
		(end 244.099842 -32.500062)
		(width 0.4572)
		(layer "F.Cu")
		(net "GND")
	)
	(segment
		(start 350.798384 -45.986954)
		(end 350.05264 -45.986954)
		(width 0.508)
		(layer "F.Cu")
		(net "GND")
	)
	(segment
		(start 4.572 -68.9864)
		(end 4.572 -73.5076)
		(width 0.508)
		(layer "F.Cu")
		(net "GND")
	)
	(segment
		(start 75.625452 -146.85391)
		(end 76.41209 -146.85391)
		(width 0.508)
		(layer "F.Cu")
		(net "GND")
	)
	(segment
		(start 266.68349 -6.535674)
		(end 266.68349 -7.2644)
		(width 0.508)
		(layer "F.Cu")
		(net "GND")
	)
	(segment
		(start 109.30001 -225.54438)
		(end 109.30001 -223.4819)
		(width 0.508)
		(layer "F.Cu")
		(net "GND")
	)
	(segment
		(start 247.599962 -32.999934)
		(end 248.099834 -32.500062)
		(width 0.4572)
		(layer "F.Cu")
		(net "GND")
	)
	(segment
		(start 19.618452 -109.347)
		(end 19.776186 -109.189266)
		(width 0.508)
		(layer "F.Cu")
		(net "GND")
	)
	(segment
		(start 38.504876 -131.684776)
		(end 38.904926 -132.084826)
		(width 0.3556)
		(layer "F.Cu")
		(net "GND")
	)
	(segment
		(start 225.600006 -32.999934)
		(end 225.100134 -32.500062)
		(width 0.4572)
		(layer "F.Cu")
		(net "GND")
	)
	(segment
		(start 106.100118 -223.482408)
		(end 105.699814 -223.082104)
		(width 0.508)
		(layer "F.Cu")
		(net "GND")
	)
	(segment
		(start 140.8176 -86.1949)
		(end 140.8176 -85.3186)
		(width 0.508)
		(layer "F.Cu")
		(net "GND")
	)
	(segment
		(start 133.453886 -81.480914)
		(end 133.288786 -81.480914)
		(width 0.508)
		(layer "F.Cu")
		(net "GND")
	)
	(segment
		(start 258.59994 -60.999878)
		(end 259.099812 -61.49975)
		(width 0.4572)
		(layer "F.Cu")
		(net "GND")
	)
	(segment
		(start 144.100042 -225.54438)
		(end 144.100042 -223.482154)
		(width 0.508)
		(layer "F.Cu")
		(net "GND")
	)
	(segment
		(start 235.599986 -46.999906)
		(end 235.100114 -46.500034)
		(width 0.4572)
		(layer "F.Cu")
		(net "GND")
	)
	(segment
		(start 57.589166 -36.832794)
		(end 57.589166 -36.664646)
		(width 0.508)
		(layer "F.Cu")
		(net "GND")
	)
	(segment
		(start 189.8015 -12.28725)
		(end 189.8015 -11.3157)
		(width 0.508)
		(layer "F.Cu")
		(net "GND")
	)
	(segment
		(start 253.59995 -44.99991)
		(end 254.099822 -44.500038)
		(width 0.4572)
		(layer "F.Cu")
		(net "GND")
	)
	(segment
		(start 7.956296 -104.73944)
		(end 7.956296 -104.3432)
		(width 0.508)
		(layer "F.Cu")
		(net "GND")
	)
	(segment
		(start 212.10016 -225.54438)
		(end 212.10016 -223.482154)
		(width 0.508)
		(layer "F.Cu")
		(net "GND")
	)
	(segment
		(start 156.972 -87.9094)
		(end 157.14472 -88.08212)
		(width 0.508)
		(layer "F.Cu")
		(net "GND")
	)
	(segment
		(start 337.300062 -223.482154)
		(end 336.900012 -223.082104)
		(width 0.508)
		(layer "F.Cu")
		(net "GND")
	)
	(segment
		(start 191.201802 -9.814052)
		(end 190.4365 -9.04875)
		(width 0.3556)
		(layer "F.Cu")
		(net "GND")
	)
	(segment
		(start 187.022232 1.900682)
		(end 187.022232 1.895348)
		(width 0.508)
		(layer "F.Cu")
		(net "GND")
	)
	(segment
		(start 273.30019 -223.482154)
		(end 273.70024 -223.082104)
		(width 0.508)
		(layer "F.Cu")
		(net "GND")
	)
	(segment
		(start 253.59995 -60.999878)
		(end 254.099822 -61.49975)
		(width 0.4572)
		(layer "F.Cu")
		(net "GND")
	)
	(segment
		(start 256.599944 -55.999888)
		(end 257.099816 -56.49976)
		(width 0.4572)
		(layer "F.Cu")
		(net "GND")
	)
	(segment
		(start 159.893 -94.107)
		(end 159.893 -94.234)
		(width 0.3048)
		(layer "F.Cu")
		(net "GND")
	)
	(segment
		(start 40.0177 -101.3714)
		(end 40.0177 -102.1588)
		(width 0.508)
		(layer "F.Cu")
		(net "GND")
	)
	(segment
		(start 254.599948 -59.99988)
		(end 255.09982 -60.499752)
		(width 0.4572)
		(layer "F.Cu")
		(net "GND")
	)
	(segment
		(start 121.5136 -16.6243)
		(end 121.5136 -15.8242)
		(width 0.508)
		(layer "F.Cu")
		(net "GND")
	)
	(segment
		(start 42.037 -150.511002)
		(end 41.768014 -150.779988)
		(width 0.3556)
		(layer "F.Cu")
		(net "GND")
	)
	(segment
		(start 256.599944 -39.99992)
		(end 257.099816 -39.500048)
		(width 0.4572)
		(layer "F.Cu")
		(net "GND")
	)
	(segment
		(start 53.34 -178.816)
		(end 53.34 -177.8)
		(width 0.508)
		(layer "F.Cu")
		(net "GND")
	)
	(segment
		(start 221.2086 -205.4479)
		(end 221.2086 -206.274416)
		(width 0.508)
		(layer "F.Cu")
		(net "GND")
	)
	(segment
		(start 54.989222 -150.96236)
		(end 54.88686 -150.859998)
		(width 0.3556)
		(layer "F.Cu")
		(net "GND")
	)
	(segment
		(start 238.59998 -47.999904)
		(end 238.100108 -48.499776)
		(width 0.4572)
		(layer "F.Cu")
		(net "GND")
	)
	(segment
		(start 27.3558 -174.7266)
		(end 27.4193 -174.6631)
		(width 0.508)
		(layer "F.Cu")
		(net "GND")
	)
	(segment
		(start 26.9748 -145.657316)
		(end 26.9748 -149.479)
		(width 0.508)
		(layer "F.Cu")
		(net "GND")
	)
	(segment
		(start 140.3985 -35.7632)
		(end 139.8905 -35.2552)
		(width 0.508)
		(layer "F.Cu")
		(net "GND")
	)
	(segment
		(start 234.599988 -56.999886)
		(end 234.100116 -57.499758)
		(width 0.4572)
		(layer "F.Cu")
		(net "GND")
	)
	(segment
		(start 37.30498 -130.485134)
		(end 37.704776 -130.88493)
		(width 0.3556)
		(layer "F.Cu")
		(net "GND")
	)
	(segment
		(start 229.599998 -43.999912)
		(end 229.100126 -43.50004)
		(width 0.4572)
		(layer "F.Cu")
		(net "GND")
	)
	(segment
		(start 249.599958 -54.99989)
		(end 250.09983 -55.499762)
		(width 0.4572)
		(layer "F.Cu")
		(net "GND")
	)
	(segment
		(start 37.287454 -163.559744)
		(end 38.167056 -163.559744)
		(width 0.508)
		(layer "F.Cu")
		(net "GND")
	)
	(segment
		(start 234.599988 -47.999904)
		(end 234.100116 -48.499776)
		(width 0.4572)
		(layer "F.Cu")
		(net "GND")
	)
	(segment
		(start 123.928124 -195.998592)
		(end 123.928124 -195.223892)
		(width 0.508)
		(layer "F.Cu")
		(net "GND")
	)
	(segment
		(start 253.59995 -53.999892)
		(end 254.099822 -54.499764)
		(width 0.4572)
		(layer "F.Cu")
		(net "GND")
	)
	(segment
		(start 125.953012 -210.167474)
		(end 125.978412 -210.142074)
		(width 0.508)
		(layer "F.Cu")
		(net "GND")
	)
	(segment
		(start 211.429854 -11.803888)
		(end 211.429854 -11.833098)
		(width 0.2032)
		(layer "F.Cu")
		(net "GND")
	)
	(segment
		(start 330.740512 -171.987718)
		(end 330.740512 -171.213018)
		(width 0.508)
		(layer "F.Cu")
		(net "GND")
	)
	(segment
		(start 29.98724 -187.4393)
		(end 29.98724 -188.83884)
		(width 0.381)
		(layer "F.Cu")
		(net "GND")
	)
	(segment
		(start 15.385034 -183.0324)
		(end 16.058388 -183.0324)
		(width 0.3048)
		(layer "F.Cu")
		(net "GND")
	)
	(segment
		(start 65.300098 -225.54438)
		(end 65.300098 -223.482408)
		(width 0.508)
		(layer "F.Cu")
		(net "GND")
	)
	(segment
		(start 196.4817 -35.0393)
		(end 196.5706 -35.1282)
		(width 0.508)
		(layer "F.Cu")
		(net "GND")
	)
	(segment
		(start 12.3063 -81.972912)
		(end 12.4714 -82.138012)
		(width 0.508)
		(layer "F.Cu")
		(net "GND")
	)
	(segment
		(start 218.797124 -190.156592)
		(end 218.797124 -189.364874)
		(width 0.508)
		(layer "F.Cu")
		(net "GND")
	)
	(segment
		(start 217.700098 -223.338898)
		(end 217.424 -223.0628)
		(width 0.508)
		(layer "F.Cu")
		(net "GND")
	)
	(segment
		(start 246.599964 -55.999888)
		(end 247.099836 -56.49976)
		(width 0.4572)
		(layer "F.Cu")
		(net "GND")
	)
	(segment
		(start 229.599998 -50.999898)
		(end 229.100126 -51.49977)
		(width 0.4572)
		(layer "F.Cu")
		(net "GND")
	)
	(segment
		(start 159.300164 -223.482408)
		(end 158.89986 -223.082104)
		(width 0.508)
		(layer "F.Cu")
		(net "GND")
	)
	(segment
		(start 312.50001 -223.482154)
		(end 312.90006 -223.082104)
		(width 0.508)
		(layer "F.Cu")
		(net "GND")
	)
	(segment
		(start 46.355 -194.1195)
		(end 46.355 -193.294)
		(width 0.508)
		(layer "F.Cu")
		(net "GND")
	)
	(segment
		(start 339.707982 -175.962818)
		(end 339.9028 -175.768)
		(width 0.3048)
		(layer "F.Cu")
		(net "GND")
	)
	(segment
		(start 227.400612 -193.858388)
		(end 227.400612 -192.75679)
		(width 0.3048)
		(layer "F.Cu")
		(net "GND")
	)
	(segment
		(start 224.824798 -206.384906)
		(end 224.824798 -207.407002)
		(width 0.508)
		(layer "F.Cu")
		(net "GND")
	)
	(segment
		(start 46.904656 -131.284726)
		(end 46.50486 -130.88493)
		(width 0.3556)
		(layer "F.Cu")
		(net "GND")
	)
	(segment
		(start 229.599998 -56.999886)
		(end 229.100126 -57.499758)
		(width 0.4572)
		(layer "F.Cu")
		(net "GND")
	)
	(segment
		(start 12.1666 -52.836318)
		(end 11.87704 -53.125878)
		(width 0.508)
		(layer "F.Cu")
		(net "GND")
	)
	(segment
		(start 14.5288 -176.2887)
		(end 15.4051 -176.2887)
		(width 0.508)
		(layer "F.Cu")
		(net "GND")
	)
	(segment
		(start 121.75744 -21.4884)
		(end 121.75744 -22.79904)
		(width 0.3048)
		(layer "F.Cu")
		(net "GND")
	)
	(segment
		(start 153.472388 -89.286588)
		(end 154.005788 -89.286588)
		(width 0.3048)
		(layer "F.Cu")
		(net "GND")
	)
	(segment
		(start 85.300058 -225.54438)
		(end 85.300058 -223.482154)
		(width 0.508)
		(layer "F.Cu")
		(net "GND")
	)
	(segment
		(start 246.599964 -45.999908)
		(end 247.099836 -45.500036)
		(width 0.4572)
		(layer "F.Cu")
		(net "GND")
	)
	(segment
		(start 45.70476 -130.88493)
		(end 46.50486 -130.88493)
		(width 0.3556)
		(layer "F.Cu")
		(net "GND")
	)
	(segment
		(start 272.32356 -4.08178)
		(end 272.32356 -4.177538)
		(width 0.508)
		(layer "F.Cu")
		(net "GND")
	)
	(segment
		(start 191.8716 -24.0538)
		(end 191.389 -24.5364)
		(width 0.508)
		(layer "F.Cu")
		(net "GND")
	)
	(segment
		(start 26.746962 -106.552238)
		(end 25.009348 -106.552238)
		(width 0.508)
		(layer "F.Cu")
		(net "GND")
	)
	(segment
		(start 17.930114 -90.103706)
		(end 17.930622 -90.103198)
		(width 0.508)
		(layer "F.Cu")
		(net "GND")
	)
	(segment
		(start 230.599996 -29.99994)
		(end 230.100124 -29.500068)
		(width 0.4572)
		(layer "F.Cu")
		(net "GND")
	)
	(segment
		(start 116.05514 -38.927786)
		(end 114.945414 -38.927786)
		(width 0.508)
		(layer "F.Cu")
		(net "GND")
	)
	(segment
		(start 193.6496 -32.2072)
		(end 193.6496 -32.4104)
		(width 0.508)
		(layer "F.Cu")
		(net "GND")
	)
	(segment
		(start 18.214086 -152.854914)
		(end 17.907 -153.162)
		(width 0.4064)
		(layer "F.Cu")
		(net "GND")
	)
	(segment
		(start 165.700202 -223.478598)
		(end 166.116 -223.0628)
		(width 0.508)
		(layer "F.Cu")
		(net "GND")
	)
	(segment
		(start 246.599964 -58.999882)
		(end 247.099836 -59.499754)
		(width 0.4572)
		(layer "F.Cu")
		(net "GND")
	)
	(segment
		(start 226.7966 -14.71549)
		(end 226.7966 -13.972032)
		(width 0.508)
		(layer "F.Cu")
		(net "GND")
	)
	(segment
		(start 11.2014 -69.233288)
		(end 11.2014 -69.2404)
		(width 0.508)
		(layer "F.Cu")
		(net "GND")
	)
	(segment
		(start 36.505134 -132.08508)
		(end 36.105338 -132.484876)
		(width 0.3556)
		(layer "F.Cu")
		(net "GND")
	)
	(segment
		(start 214.500206 -225.54438)
		(end 214.500206 -223.482408)
		(width 0.508)
		(layer "F.Cu")
		(net "GND")
	)
	(segment
		(start 338.100162 -225.54438)
		(end 338.100162 -223.482154)
		(width 0.508)
		(layer "F.Cu")
		(net "GND")
	)
	(segment
		(start 233.59999 -55.999888)
		(end 233.100118 -56.49976)
		(width 0.4572)
		(layer "F.Cu")
		(net "GND")
	)
	(segment
		(start 45.492416 -113.454688)
		(end 45.31741 -113.454688)
		(width 0.508)
		(layer "F.Cu")
		(net "GND")
	)
	(segment
		(start 43.2181 -202.52436)
		(end 44.61764 -202.52436)
		(width 0.381)
		(layer "F.Cu")
		(net "GND")
	)
	(segment
		(start 332.7908 -185.3311)
		(end 332.7908 -186.1312)
		(width 0.508)
		(layer "F.Cu")
		(net "GND")
	)
	(segment
		(start 258.59994 -63.999872)
		(end 259.099812 -64.499744)
		(width 0.4572)
		(layer "F.Cu")
		(net "GND")
	)
	(segment
		(start 82.814414 -83.637628)
		(end 83.137756 -83.637628)
		(width 0.508)
		(layer "F.Cu")
		(net "GND")
	)
	(segment
		(start 143.300196 -223.482408)
		(end 142.899892 -223.082104)
		(width 0.508)
		(layer "F.Cu")
		(net "GND")
	)
	(segment
		(start 195.4784 -6.6548)
		(end 195.9864 -6.1468)
		(width 0.508)
		(layer "F.Cu")
		(net "GND")
	)
	(segment
		(start 57.300114 -225.54438)
		(end 57.300114 -223.482154)
		(width 0.508)
		(layer "F.Cu")
		(net "GND")
	)
	(segment
		(start 203.0984 -27.0002)
		(end 202.6412 -26.543)
		(width 0.508)
		(layer "F.Cu")
		(net "GND")
	)
	(segment
		(start 196.100192 -223.482154)
		(end 196.500242 -223.082104)
		(width 0.508)
		(layer "F.Cu")
		(net "GND")
	)
	(segment
		(start 46.50486 -131.684522)
		(end 46.904656 -131.284726)
		(width 0.3556)
		(layer "F.Cu")
		(net "GND")
	)
	(segment
		(start 239.4839 -18.10385)
		(end 241.096292 -18.10385)
		(width 0.508)
		(layer "F.Cu")
		(net "GND")
	)
	(segment
		(start 227.600002 -60.999878)
		(end 227.10013 -61.49975)
		(width 0.4572)
		(layer "F.Cu")
		(net "GND")
	)
	(segment
		(start 259.6642 -3.6576)
		(end 259.743702 -3.737102)
		(width 0.508)
		(layer "F.Cu")
		(net "GND")
	)
	(segment
		(start 344.678 -68.961)
		(end 344.847164 -69.130164)
		(width 0.508)
		(layer "F.Cu")
		(net "GND")
	)
	(segment
		(start 165.5826 -207.645)
		(end 165.989 -208.0514)
		(width 0.508)
		(layer "F.Cu")
		(net "GND")
	)
	(segment
		(start 335.026 -71.6915)
		(end 335.8515 -71.6915)
		(width 0.508)
		(layer "F.Cu")
		(net "GND")
	)
	(segment
		(start 247.599962 -55.999888)
		(end 248.099834 -56.49976)
		(width 0.4572)
		(layer "F.Cu")
		(net "GND")
	)
	(segment
		(start 229.599998 -49.9999)
		(end 229.100126 -50.499772)
		(width 0.4572)
		(layer "F.Cu")
		(net "GND")
	)
	(segment
		(start 253.59995 -51.999896)
		(end 254.099822 -52.499768)
		(width 0.4572)
		(layer "F.Cu")
		(net "GND")
	)
	(segment
		(start 20.1295 -182.7022)
		(end 20.1295 -181.8767)
		(width 0.508)
		(layer "F.Cu")
		(net "GND")
	)
	(segment
		(start 54.1655 -131.445)
		(end 54.5211 -131.8006)
		(width 0.508)
		(layer "F.Cu")
		(net "GND")
	)
	(segment
		(start 253.59995 -42.999914)
		(end 254.099822 -42.500042)
		(width 0.4572)
		(layer "F.Cu")
		(net "GND")
	)
	(segment
		(start 45.0469 -188.52896)
		(end 46.44644 -188.52896)
		(width 0.381)
		(layer "F.Cu")
		(net "GND")
	)
	(segment
		(start 187.6679 -5.1562)
		(end 186.8424 -5.1562)
		(width 0.508)
		(layer "F.Cu")
		(net "GND")
	)
	(segment
		(start 159.300164 -225.54438)
		(end 159.300164 -223.482408)
		(width 0.508)
		(layer "F.Cu")
		(net "GND")
	)
	(segment
		(start 18.235676 -95.920306)
		(end 18.502376 -96.187006)
		(width 0.508)
		(layer "F.Cu")
		(net "GND")
	)
	(segment
		(start 59.70016 -225.54438)
		(end 59.70016 -223.482408)
		(width 0.508)
		(layer "F.Cu")
		(net "GND")
	)
	(segment
		(start 230.599996 -50.999898)
		(end 230.100124 -51.49977)
		(width 0.4572)
		(layer "F.Cu")
		(net "GND")
	)
	(segment
		(start 39.304722 -129.284984)
		(end 38.904926 -129.68478)
		(width 0.3556)
		(layer "F.Cu")
		(net "GND")
	)
	(segment
		(start 12.4714 -83.3882)
		(end 12.4714 -88.011)
		(width 0.508)
		(layer "F.Cu")
		(net "GND")
	)
	(segment
		(start 37.30498 -130.48488)
		(end 37.30498 -130.485134)
		(width 0.3556)
		(layer "F.Cu")
		(net "GND")
	)
	(segment
		(start 231.599994 -65.999868)
		(end 231.100122 -66.49974)
		(width 0.4572)
		(layer "F.Cu")
		(net "GND")
	)
	(segment
		(start 292.50005 -225.54438)
		(end 292.50005 -223.482154)
		(width 0.508)
		(layer "F.Cu")
		(net "GND")
	)
	(segment
		(start 205.700122 -223.482154)
		(end 206.100172 -223.082104)
		(width 0.508)
		(layer "F.Cu")
		(net "GND")
	)
	(segment
		(start 229.21976 -4.245864)
		(end 229.682548 -3.783076)
		(width 0.508)
		(layer "F.Cu")
		(net "GND")
	)
	(segment
		(start 39.367968 -151.579834)
		(end 38.968172 -151.180038)
		(width 0.3556)
		(layer "F.Cu")
		(net "GND")
	)
	(segment
		(start 32.2072 -92.075)
		(end 31.575756 -91.443556)
		(width 0.508)
		(layer "F.Cu")
		(net "GND")
	)
	(segment
		(start 267.92809 -10.258044)
		(end 267.8811 -10.305034)
		(width 0.508)
		(layer "F.Cu")
		(net "GND")
	)
	(segment
		(start 205.700122 -225.54438)
		(end 205.700122 -223.482154)
		(width 0.508)
		(layer "F.Cu")
		(net "GND")
	)
	(segment
		(start 258.59994 -62.999874)
		(end 259.099812 -63.499746)
		(width 0.4572)
		(layer "F.Cu")
		(net "GND")
	)
	(segment
		(start 5.4356 -92.4052)
		(end 5.4356 -89.916)
		(width 0.508)
		(layer "F.Cu")
		(net "GND")
	)
	(segment
		(start 67.649344 -126.6952)
		(end 67.314826 -126.360682)
		(width 0.4064)
		(layer "F.Cu")
		(net "GND")
	)
	(segment
		(start 150.50008 -225.54438)
		(end 150.50008 -223.482154)
		(width 0.508)
		(layer "F.Cu")
		(net "GND")
	)
	(segment
		(start 245.599966 -62.999874)
		(end 246.099838 -63.499746)
		(width 0.4572)
		(layer "F.Cu")
		(net "GND")
	)
	(segment
		(start 154.94 -95.0976)
		(end 156.3116 -93.726)
		(width 0.3048)
		(layer "F.Cu")
		(net "GND")
	)
	(segment
		(start 166.625524 -54.100476)
		(end 166.497 -54.229)
		(width 0.508)
		(layer "F.Cu")
		(net "GND")
	)
	(segment
		(start 38.217856 -164.702744)
		(end 38.2524 -164.6682)
		(width 0.508)
		(layer "F.Cu")
		(net "GND")
	)
	(segment
		(start 79.375 -181.991)
		(end 79.375 -180.9496)
		(width 0.508)
		(layer "F.Cu")
		(net "GND")
	)
	(segment
		(start 247.599962 -56.999886)
		(end 248.099834 -57.499758)
		(width 0.4572)
		(layer "F.Cu")
		(net "GND")
	)
	(segment
		(start 185.700162 -223.482408)
		(end 185.299858 -223.082104)
		(width 0.508)
		(layer "F.Cu")
		(net "GND")
	)
	(segment
		(start 70.715124 -182.790592)
		(end 70.715124 -181.998874)
		(width 0.508)
		(layer "F.Cu")
		(net "GND")
	)
	(segment
		(start 229.599998 -40.999918)
		(end 229.100126 -40.500046)
		(width 0.4572)
		(layer "F.Cu")
		(net "GND")
	)
	(segment
		(start 263.700006 -225.54438)
		(end 263.700006 -223.482154)
		(width 0.508)
		(layer "F.Cu")
		(net "GND")
	)
	(segment
		(start 42.037 -149.710902)
		(end 42.037 -150.511002)
		(width 0.3556)
		(layer "F.Cu")
		(net "GND")
	)
	(segment
		(start 5.8166 -92.7862)
		(end 5.4356 -92.4052)
		(width 0.508)
		(layer "F.Cu")
		(net "GND")
	)
	(segment
		(start 18.214086 -152.26538)
		(end 18.214086 -152.854914)
		(width 0.4064)
		(layer "F.Cu")
		(net "GND")
	)
	(segment
		(start 248.59996 -54.99989)
		(end 249.099832 -55.499762)
		(width 0.4572)
		(layer "F.Cu")
		(net "GND")
	)
	(segment
		(start 22.987 -147.3454)
		(end 22.987 -145.7706)
		(width 0.508)
		(layer "F.Cu")
		(net "GND")
	)
	(segment
		(start 173.737524 -52.055268)
		(end 173.737524 -53.230272)
		(width 0.508)
		(layer "F.Cu")
		(net "GND")
	)
	(segment
		(start 258.59994 -32.999934)
		(end 259.099812 -32.500062)
		(width 0.4572)
		(layer "F.Cu")
		(net "GND")
	)
	(segment
		(start 65.717166 -87.775034)
		(end 65.3288 -88.1634)
		(width 0.4064)
		(layer "F.Cu")
		(net "GND")
	)
	(segment
		(start 160.031938 -93.063822)
		(end 160.031938 -93.968062)
		(width 0.3048)
		(layer "F.Cu")
		(net "GND")
	)
	(segment
		(start 225.15068 -205.29042)
		(end 225.15068 -206.059024)
		(width 0.508)
		(layer "F.Cu")
		(net "GND")
	)
	(segment
		(start 234.599988 -58.999882)
		(end 234.100116 -59.499754)
		(width 0.4572)
		(layer "F.Cu")
		(net "GND")
	)
	(segment
		(start 222.600012 -41.999916)
		(end 222.10014 -41.500044)
		(width 0.4572)
		(layer "F.Cu")
		(net "GND")
	)
	(segment
		(start 250.599956 -45.999908)
		(end 251.099828 -45.500036)
		(width 0.4572)
		(layer "F.Cu")
		(net "GND")
	)
	(segment
		(start 20.3835 -141.986)
		(end 19.6596 -141.986)
		(width 0.508)
		(layer "F.Cu")
		(net "GND")
	)
	(segment
		(start 186.8424 -5.1562)
		(end 186.737244 -5.261356)
		(width 0.508)
		(layer "F.Cu")
		(net "GND")
	)
	(segment
		(start 344.847164 -69.721984)
		(end 345.09837 -69.97319)
		(width 0.508)
		(layer "F.Cu")
		(net "GND")
	)
	(segment
		(start 239.599978 -42.999914)
		(end 239.100106 -42.500042)
		(width 0.4572)
		(layer "F.Cu")
		(net "GND")
	)
	(segment
		(start 34.0741 -67.1322)
		(end 34.06648 -67.13982)
		(width 0.508)
		(layer "F.Cu")
		(net "GND")
	)
	(segment
		(start 85.300058 -223.482154)
		(end 85.700108 -223.082104)
		(width 0.508)
		(layer "F.Cu")
		(net "GND")
	)
	(segment
		(start 239.599978 -29.99994)
		(end 239.100106 -29.500068)
		(width 0.4572)
		(layer "F.Cu")
		(net "GND")
	)
	(segment
		(start 38.10508 -129.685034)
		(end 38.504876 -130.08483)
		(width 0.3556)
		(layer "F.Cu")
		(net "GND")
	)
	(segment
		(start 193.9544 -32.8676)
		(end 194.4243 -32.8676)
		(width 0.508)
		(layer "F.Cu")
		(net "GND")
	)
	(segment
		(start 193.6496 -32.4104)
		(end 193.6496 -32.5628)
		(width 0.508)
		(layer "F.Cu")
		(net "GND")
	)
	(segment
		(start 226.390454 -2.82575)
		(end 226.75723 -2.458974)
		(width 0.508)
		(layer "F.Cu")
		(net "GND")
	)
	(segment
		(start 224.600008 -51.999896)
		(end 224.100136 -52.499768)
		(width 0.4572)
		(layer "F.Cu")
		(net "GND")
	)
	(segment
		(start 8.0137 -81.5848)
		(end 8.8392 -81.5848)
		(width 0.508)
		(layer "F.Cu")
		(net "GND")
	)
	(segment
		(start 11.2014 -69.2404)
		(end 11.0744 -69.2404)
		(width 0.508)
		(layer "F.Cu")
		(net "GND")
	)
	(segment
		(start 37.193474 -114.307112)
		(end 37.193474 -113.066068)
		(width 0.508)
		(layer "F.Cu")
		(net "GND")
	)
	(segment
		(start 11.0744 -69.2404)
		(end 9.779 -67.945)
		(width 0.508)
		(layer "F.Cu")
		(net "GND")
	)
	(segment
		(start 231.599994 -57.999884)
		(end 231.100122 -58.499756)
		(width 0.4572)
		(layer "F.Cu")
		(net "GND")
	)
	(segment
		(start 55.245 -134.4295)
		(end 56.134 -134.4295)
		(width 0.508)
		(layer "F.Cu")
		(net "GND")
	)
	(segment
		(start 283.87675 -57.912)
		(end 284.63875 -57.15)
		(width 0.508)
		(layer "F.Cu")
		(net "GND")
	)
	(segment
		(start 212.10016 -223.482154)
		(end 212.50021 -223.082104)
		(width 0.508)
		(layer "F.Cu")
		(net "GND")
	)
	(segment
		(start 263.700006 -223.482154)
		(end 264.100056 -223.082104)
		(width 0.508)
		(layer "F.Cu")
		(net "GND")
	)
	(segment
		(start 150.930356 -94.110302)
		(end 151.917654 -95.0976)
		(width 0.3048)
		(layer "F.Cu")
		(net "GND")
	)
	(segment
		(start 244.599968 -51.999896)
		(end 245.09984 -52.499768)
		(width 0.4572)
		(layer "F.Cu")
		(net "GND")
	)
	(segment
		(start 10.988548 -88.977978)
		(end 10.988548 -90.693748)
		(width 0.508)
		(layer "F.Cu")
		(net "GND")
	)
	(segment
		(start 239.599978 -62.999874)
		(end 239.100106 -63.499746)
		(width 0.4572)
		(layer "F.Cu")
		(net "GND")
	)
	(segment
		(start 221.7039 -0.635)
		(end 220.3704 -0.635)
		(width 0.3048)
		(layer "F.Cu")
		(net "GND")
	)
	(segment
		(start 256.599944 -42.999914)
		(end 257.099816 -42.500042)
		(width 0.4572)
		(layer "F.Cu")
		(net "GND")
	)
	(segment
		(start 14.5288 -176.2887)
		(end 13.92555 -176.2887)
		(width 0.508)
		(layer "F.Cu")
		(net "GND")
	)
	(segment
		(start 233.59999 -48.999902)
		(end 233.100118 -49.499774)
		(width 0.4572)
		(layer "F.Cu")
		(net "GND")
	)
	(segment
		(start 231.599994 -32.999934)
		(end 231.100122 -32.500062)
		(width 0.4572)
		(layer "F.Cu")
		(net "GND")
	)
	(segment
		(start 34.900108 -223.925892)
		(end 34.900108 -225.54438)
		(width 0.508)
		(layer "F.Cu")
		(net "GND")
	)
	(segment
		(start 168.900094 -225.54438)
		(end 168.900094 -223.482154)
		(width 0.508)
		(layer "F.Cu")
		(net "GND")
	)
	(segment
		(start 55.8038 -119.935498)
		(end 55.819802 -119.935498)
		(width 0.508)
		(layer "F.Cu")
		(net "GND")
	)
	(segment
		(start 230.8606 -87.4776)
		(end 230.8606 -88.1634)
		(width 0.508)
		(layer "F.Cu")
		(net "GND")
	)
	(segment
		(start 324.50024 -225.54438)
		(end 324.50024 -223.482408)
		(width 0.508)
		(layer "F.Cu")
		(net "GND")
	)
	(segment
		(start 252.599952 -32.999934)
		(end 253.099824 -32.500062)
		(width 0.4572)
		(layer "F.Cu")
		(net "GND")
	)
	(segment
		(start 315.700156 -225.54438)
		(end 315.700156 -223.482154)
		(width 0.508)
		(layer "F.Cu")
		(net "GND")
	)
	(segment
		(start 239.599978 -40.999918)
		(end 239.100106 -40.500046)
		(width 0.4572)
		(layer "F.Cu")
		(net "GND")
	)
	(segment
		(start 257.867912 -12.473686)
		(end 257.867912 -11.641582)
		(width 0.508)
		(layer "F.Cu")
		(net "GND")
	)
	(segment
		(start 34.52622 -79.048356)
		(end 35.378644 -79.048356)
		(width 0.508)
		(layer "F.Cu")
		(net "GND")
	)
	(segment
		(start 231.599994 -37.999924)
		(end 231.100122 -37.500052)
		(width 0.4572)
		(layer "F.Cu")
		(net "GND")
	)
	(segment
		(start 117.954806 -82.34934)
		(end 117.954806 -81.66354)
		(width 0.508)
		(layer "F.Cu")
		(net "GND")
	)
	(segment
		(start 218.2622 -2.5146)
		(end 218.6432 -2.8956)
		(width 0.508)
		(layer "F.Cu")
		(net "GND")
	)
	(segment
		(start 279.700228 -223.4819)
		(end 280.100024 -223.082104)
		(width 0.508)
		(layer "F.Cu")
		(net "GND")
	)
	(segment
		(start 21.6535 -151.24176)
		(end 20.56384 -151.24176)
		(width 0.3556)
		(layer "F.Cu")
		(net "GND")
	)
	(segment
		(start 26.510488 -96.178624)
		(end 27.4828 -96.178624)
		(width 0.508)
		(layer "F.Cu")
		(net "GND")
	)
	(segment
		(start 111.700056 -223.482154)
		(end 111.300006 -223.082104)
		(width 0.508)
		(layer "F.Cu")
		(net "GND")
	)
	(segment
		(start 234.599988 -31.999936)
		(end 234.100116 -31.500064)
		(width 0.4572)
		(layer "F.Cu")
		(net "GND")
	)
	(segment
		(start 217.781124 -190.156592)
		(end 217.781124 -189.381892)
		(width 0.508)
		(layer "F.Cu")
		(net "GND")
	)
	(segment
		(start 282.90012 -225.54438)
		(end 282.90012 -223.482154)
		(width 0.508)
		(layer "F.Cu")
		(net "GND")
	)
	(segment
		(start 39.705026 -128.885188)
		(end 40.104822 -128.485392)
		(width 0.3556)
		(layer "F.Cu")
		(net "GND")
	)
	(segment
		(start 66.100198 -223.4819)
		(end 66.499994 -223.082104)
		(width 0.508)
		(layer "F.Cu")
		(net "GND")
	)
	(segment
		(start 192.1002 -225.54438)
		(end 192.1002 -223.482408)
		(width 0.508)
		(layer "F.Cu")
		(net "GND")
	)
	(segment
		(start 197.24116 -20.35556)
		(end 198.501 -21.6154)
		(width 0.3556)
		(layer "F.Cu")
		(net "GND")
	)
	(segment
		(start 44.504864 -132.084826)
		(end 44.104814 -132.484876)
		(width 0.3556)
		(layer "F.Cu")
		(net "GND")
	)
	(segment
		(start 317.42888 -35.859974)
		(end 318.203072 -35.859974)
		(width 0.508)
		(layer "F.Cu")
		(net "GND")
	)
	(segment
		(start 91.700096 -223.482154)
		(end 92.100146 -223.082104)
		(width 0.508)
		(layer "F.Cu")
		(net "GND")
	)
	(segment
		(start 84.499958 -225.54438)
		(end 84.499958 -223.482154)
		(width 0.508)
		(layer "F.Cu")
		(net "GND")
	)
	(segment
		(start 243.59997 -52.999894)
		(end 244.099842 -53.499766)
		(width 0.4572)
		(layer "F.Cu")
		(net "GND")
	)
	(segment
		(start 300.500034 -225.54438)
		(end 300.500034 -223.482154)
		(width 0.508)
		(layer "F.Cu")
		(net "GND")
	)
	(segment
		(start 333.039974 -46.237906)
		(end 333.039974 -47.383192)
		(width 0.508)
		(layer "F.Cu")
		(net "GND")
	)
	(segment
		(start 43.307 -198.882)
		(end 43.307 -197.866)
		(width 0.508)
		(layer "F.Cu")
		(net "GND")
	)
	(segment
		(start 282.90012 -223.482154)
		(end 283.30017 -223.082104)
		(width 0.508)
		(layer "F.Cu")
		(net "GND")
	)
	(segment
		(start 186.737244 -5.825744)
		(end 186.737244 -5.261356)
		(width 0.508)
		(layer "F.Cu")
		(net "GND")
	)
	(segment
		(start 12.4714 -88.011)
		(end 12.5222 -88.0618)
		(width 0.508)
		(layer "F.Cu")
		(net "GND")
	)
	(segment
		(start 31.575756 -91.443556)
		(end 30.936946 -91.443556)
		(width 0.508)
		(layer "F.Cu")
		(net "GND")
	)
	(segment
		(start 70.2056 -129.794)
		(end 70.86727 -129.794)
		(width 0.4064)
		(layer "F.Cu")
		(net "GND")
	)
	(segment
		(start 238.59998 -45.999908)
		(end 238.100108 -45.500036)
		(width 0.4572)
		(layer "F.Cu")
		(net "GND")
	)
	(segment
		(start 36.90493 -131.684776)
		(end 37.30498 -132.084826)
		(width 0.3556)
		(layer "F.Cu")
		(net "GND")
	)
	(segment
		(start 79.883 -182.8165)
		(end 79.883 -182.499)
		(width 0.508)
		(layer "F.Cu")
		(net "GND")
	)
	(segment
		(start 252.627638 -13.428726)
		(end 252.355604 -13.156692)
		(width 0.508)
		(layer "F.Cu")
		(net "GND")
	)
	(segment
		(start 243.59997 -57.999884)
		(end 244.099842 -58.499756)
		(width 0.4572)
		(layer "F.Cu")
		(net "GND")
	)
	(segment
		(start 249.599958 -60.999878)
		(end 250.09983 -61.49975)
		(width 0.4572)
		(layer "F.Cu")
		(net "GND")
	)
	(segment
		(start 45.1358 -184.8866)
		(end 45.1358 -183.8706)
		(width 0.508)
		(layer "F.Cu")
		(net "GND")
	)
	(segment
		(start 255.522476 -10.544048)
		(end 255.314704 -10.544048)
		(width 0.508)
		(layer "F.Cu")
		(net "GND")
	)
	(segment
		(start 269.300198 -223.482408)
		(end 268.899894 -223.082104)
		(width 0.508)
		(layer "F.Cu")
		(net "GND")
	)
	(segment
		(start 240.599976 -62.999874)
		(end 241.099848 -63.499746)
		(width 0.4572)
		(layer "F.Cu")
		(net "GND")
	)
	(segment
		(start 231.599994 -50.999898)
		(end 231.100122 -51.49977)
		(width 0.4572)
		(layer "F.Cu")
		(net "GND")
	)
	(segment
		(start 37.704776 -130.88493)
		(end 38.104826 -131.28498)
		(width 0.3556)
		(layer "F.Cu")
		(net "GND")
	)
	(segment
		(start 116.6368 -94.6277)
		(end 116.6368 -93.8022)
		(width 0.508)
		(layer "F.Cu")
		(net "GND")
	)
	(segment
		(start 246.599964 -31.999936)
		(end 247.099836 -31.500064)
		(width 0.4572)
		(layer "F.Cu")
		(net "GND")
	)
	(segment
		(start 211.624418 -12.027662)
		(end 211.624418 -13.1064)
		(width 0.2032)
		(layer "F.Cu")
		(net "GND")
	)
	(segment
		(start 245.599966 -55.999888)
		(end 246.099838 -56.49976)
		(width 0.4572)
		(layer "F.Cu")
		(net "GND")
	)
	(segment
		(start 151.590756 -88.54821)
		(end 150.930356 -89.20861)
		(width 0.3048)
		(layer "F.Cu")
		(net "GND")
	)
	(segment
		(start 231.599994 -56.999886)
		(end 231.100122 -57.499758)
		(width 0.4572)
		(layer "F.Cu")
		(net "GND")
	)
	(segment
		(start 252.433836 -11.809476)
		(end 253.04242 -11.809476)
		(width 0.508)
		(layer "F.Cu")
		(net "GND")
	)
	(segment
		(start 152.1714 -88.5698)
		(end 152.7556 -88.5698)
		(width 0.3048)
		(layer "F.Cu")
		(net "GND")
	)
	(segment
		(start 333.060548 -46.217332)
		(end 333.039974 -46.237906)
		(width 0.508)
		(layer "F.Cu")
		(net "GND")
	)
	(segment
		(start 227.600002 -35.999928)
		(end 227.10013 -35.500056)
		(width 0.4572)
		(layer "F.Cu")
		(net "GND")
	)
	(segment
		(start 90.899996 -225.54438)
		(end 90.899996 -223.482154)
		(width 0.508)
		(layer "F.Cu")
		(net "GND")
	)
	(segment
		(start 249.599958 -41.999916)
		(end 250.09983 -41.500044)
		(width 0.4572)
		(layer "F.Cu")
		(net "GND")
	)
	(segment
		(start 244.599968 -49.9999)
		(end 245.09984 -50.499772)
		(width 0.4572)
		(layer "F.Cu")
		(net "GND")
	)
	(segment
		(start 37.94252 -46.007274)
		(end 37.94252 -44.70654)
		(width 0.508)
		(layer "F.Cu")
		(net "GND")
	)
	(segment
		(start 241.599974 -44.99991)
		(end 242.099846 -44.500038)
		(width 0.4572)
		(layer "F.Cu")
		(net "GND")
	)
	(segment
		(start 116.604034 -31.061914)
		(end 115.537234 -31.061914)
		(width 0.508)
		(layer "F.Cu")
		(net "GND")
	)
	(segment
		(start 223.2152 -13.4239)
		(end 223.2152 -12.5984)
		(width 0.508)
		(layer "F.Cu")
		(net "GND")
	)
	(segment
		(start 230.599996 -42.999914)
		(end 230.100124 -42.500042)
		(width 0.4572)
		(layer "F.Cu")
		(net "GND")
	)
	(segment
		(start 241.599974 -59.99988)
		(end 242.099846 -60.499752)
		(width 0.4572)
		(layer "F.Cu")
		(net "GND")
	)
	(segment
		(start 239.599978 -57.999884)
		(end 239.100106 -58.499756)
		(width 0.4572)
		(layer "F.Cu")
		(net "GND")
	)
	(segment
		(start 343.7001 -223.3549)
		(end 343.4588 -223.1136)
		(width 0.508)
		(layer "F.Cu")
		(net "GND")
	)
	(segment
		(start 9.779 -69.4055)
		(end 8.9281 -69.4055)
		(width 0.508)
		(layer "F.Cu")
		(net "GND")
	)
	(segment
		(start 226.600004 -41.999916)
		(end 226.100132 -41.500044)
		(width 0.4572)
		(layer "F.Cu")
		(net "GND")
	)
	(segment
		(start 36.90493 -132.484876)
		(end 36.505134 -132.08508)
		(width 0.3556)
		(layer "F.Cu")
		(net "GND")
	)
	(segment
		(start 188.900054 -223.482154)
		(end 188.500004 -223.082104)
		(width 0.508)
		(layer "F.Cu")
		(net "GND")
	)
	(segment
		(start 18.796 -146.2405)
		(end 18.1483 -146.8882)
		(width 0.508)
		(layer "F.Cu")
		(net "GND")
	)
	(segment
		(start 36.971224 -151.579834)
		(end 36.967922 -151.579834)
		(width 0.3556)
		(layer "F.Cu")
		(net "GND")
	)
	(segment
		(start 282.10002 -223.482154)
		(end 281.69997 -223.082104)
		(width 0.508)
		(layer "F.Cu")
		(net "GND")
	)
	(segment
		(start 109.30001 -223.4819)
		(end 109.699806 -223.082104)
		(width 0.508)
		(layer "F.Cu")
		(net "GND")
	)
	(segment
		(start 38.504876 -128.485138)
		(end 39.304722 -129.284984)
		(width 0.3556)
		(layer "F.Cu")
		(net "GND")
	)
	(segment
		(start 254.599948 -32.999934)
		(end 255.09982 -32.500062)
		(width 0.4572)
		(layer "F.Cu")
		(net "GND")
	)
	(segment
		(start 59.70016 -223.482408)
		(end 59.299856 -223.082104)
		(width 0.508)
		(layer "F.Cu")
		(net "GND")
	)
	(segment
		(start 248.59996 -57.999884)
		(end 249.099832 -58.499756)
		(width 0.4572)
		(layer "F.Cu")
		(net "GND")
	)
	(segment
		(start 235.599986 -57.999884)
		(end 235.100114 -58.499756)
		(width 0.4572)
		(layer "F.Cu")
		(net "GND")
	)
	(segment
		(start 234.599988 -63.999872)
		(end 234.100116 -64.499744)
		(width 0.4572)
		(layer "F.Cu")
		(net "GND")
	)
	(segment
		(start 32.6898 -146.7612)
		(end 33.40862 -146.04238)
		(width 0.381)
		(layer "F.Cu")
		(net "GND")
	)
	(segment
		(start 303.70018 -225.54438)
		(end 303.70018 -224.22358)
		(width 0.508)
		(layer "F.Cu")
		(net "GND")
	)
	(segment
		(start 128.391158 -75.05446)
		(end 127.474218 -75.05446)
		(width 0.508)
		(layer "F.Cu")
		(net "GND")
	)
	(segment
		(start 225.600006 -56.999886)
		(end 225.100134 -57.499758)
		(width 0.4572)
		(layer "F.Cu")
		(net "GND")
	)
	(segment
		(start 20.2819 -173.2026)
		(end 19.2532 -173.2026)
		(width 0.508)
		(layer "F.Cu")
		(net "GND")
	)
	(segment
		(start 241.599974 -52.999894)
		(end 242.099846 -53.499766)
		(width 0.4572)
		(layer "F.Cu")
		(net "GND")
	)
	(segment
		(start 341.300054 -223.482154)
		(end 341.700104 -223.082104)
		(width 0.508)
		(layer "F.Cu")
		(net "GND")
	)
	(segment
		(start 331.97038 -33.1978)
		(end 330.644246 -31.871666)
		(width 0.508)
		(layer "F.Cu")
		(net "GND")
	)
	(segment
		(start 251.599954 -53.999892)
		(end 252.099826 -54.499764)
		(width 0.4572)
		(layer "F.Cu")
		(net "GND")
	)
	(segment
		(start 240.599976 -43.999912)
		(end 241.099848 -43.50004)
		(width 0.4572)
		(layer "F.Cu")
		(net "GND")
	)
	(segment
		(start 245.599966 -40.999918)
		(end 246.099838 -40.500046)
		(width 0.4572)
		(layer "F.Cu")
		(net "GND")
	)
	(segment
		(start 234.599988 -51.999896)
		(end 234.100116 -52.499768)
		(width 0.4572)
		(layer "F.Cu")
		(net "GND")
	)
	(segment
		(start 47.244 -180.0225)
		(end 47.244 -179.197)
		(width 0.508)
		(layer "F.Cu")
		(net "GND")
	)
	(segment
		(start 117.19433 -34.882328)
		(end 116.577872 -34.882328)
		(width 0.508)
		(layer "F.Cu")
		(net "GND")
	)
	(segment
		(start 14.33449 -107.20451)
		(end 14.6812 -106.8578)
		(width 0.3048)
		(layer "F.Cu")
		(net "GND")
	)
	(segment
		(start 253.59995 -48.999902)
		(end 254.099822 -49.499774)
		(width 0.4572)
		(layer "F.Cu")
		(net "GND")
	)
	(segment
		(start 245.599966 -44.99991)
		(end 246.099838 -44.500038)
		(width 0.4572)
		(layer "F.Cu")
		(net "GND")
	)
	(segment
		(start 4.572 -74.7014)
		(end 4.572 -73.5076)
		(width 0.508)
		(layer "F.Cu")
		(net "GND")
	)
	(segment
		(start 71.766938 -196.1515)
		(end 71.749412 -196.133974)
		(width 0.508)
		(layer "F.Cu")
		(net "GND")
	)
	(segment
		(start 26.4287 -32.60852)
		(end 26.416 -32.59582)
		(width 0.508)
		(layer "F.Cu")
		(net "GND")
	)
	(segment
		(start 7.874 -104.821736)
		(end 7.956296 -104.73944)
		(width 0.508)
		(layer "F.Cu")
		(net "GND")
	)
	(segment
		(start 21.81606 -142.9385)
		(end 21.336 -142.9385)
		(width 0.508)
		(layer "F.Cu")
		(net "GND")
	)
	(segment
		(start 57.404 -130.4925)
		(end 56.515 -130.4925)
		(width 0.508)
		(layer "F.Cu")
		(net "GND")
	)
	(segment
		(start 208.100168 -223.242632)
		(end 208.28 -223.0628)
		(width 0.508)
		(layer "F.Cu")
		(net "GND")
	)
	(segment
		(start 233.59999 -58.999882)
		(end 233.100118 -59.499754)
		(width 0.4572)
		(layer "F.Cu")
		(net "GND")
	)
	(segment
		(start 20.3581 -145.8595)
		(end 19.6596 -146.558)
		(width 0.508)
		(layer "F.Cu")
		(net "GND")
	)
	(segment
		(start 232.599992 -31.999936)
		(end 232.10012 -31.500064)
		(width 0.4572)
		(layer "F.Cu")
		(net "GND")
	)
	(segment
		(start 83.525868 -76.210668)
		(end 83.525868 -75.1586)
		(width 0.508)
		(layer "F.Cu")
		(net "GND")
	)
	(segment
		(start 147.300188 -223.482154)
		(end 147.700238 -223.082104)
		(width 0.508)
		(layer "F.Cu")
		(net "GND")
	)
	(segment
		(start 63.545974 -18.691606)
		(end 65.572386 -18.691606)
		(width 0.508)
		(layer "F.Cu")
		(net "GND")
	)
	(segment
		(start 140.4112 -35.7632)
		(end 140.3985 -35.7632)
		(width 0.508)
		(layer "F.Cu")
		(net "GND")
	)
	(segment
		(start 41.362122 -156.785564)
		(end 41.371774 -156.785564)
		(width 0.3556)
		(layer "F.Cu")
		(net "GND")
	)
	(segment
		(start 249.599958 -44.99991)
		(end 250.09983 -44.500038)
		(width 0.4572)
		(layer "F.Cu")
		(net "GND")
	)
	(segment
		(start 5.4356 -83.2866)
		(end 5.4356 -81.4832)
		(width 0.508)
		(layer "F.Cu")
		(net "GND")
	)
	(segment
		(start 37.768022 -150.783036)
		(end 37.374322 -151.176736)
		(width 0.3048)
		(layer "F.Cu")
		(net "GND")
	)
	(segment
		(start 231.599994 -52.999894)
		(end 231.100122 -53.499766)
		(width 0.4572)
		(layer "F.Cu")
		(net "GND")
	)
	(segment
		(start 53.300122 -225.54438)
		(end 53.300122 -223.482408)
		(width 0.508)
		(layer "F.Cu")
		(net "GND")
	)
	(segment
		(start 298.100242 -225.54438)
		(end 298.100242 -223.0628)
		(width 0.508)
		(layer "F.Cu")
		(net "GND")
	)
	(segment
		(start 34.100008 -224.217992)
		(end 34.100008 -225.54438)
		(width 0.508)
		(layer "F.Cu")
		(net "GND")
	)
	(segment
		(start 11.256772 -67.8942)
		(end 11.284204 -67.921632)
		(width 0.508)
		(layer "F.Cu")
		(net "GND")
	)
	(segment
		(start 339.9028 -175.768)
		(end 339.9028 -175.2092)
		(width 0.3048)
		(layer "F.Cu")
		(net "GND")
	)
	(segment
		(start 53.34 -198.247)
		(end 54.229 -198.247)
		(width 0.508)
		(layer "F.Cu")
		(net "GND")
	)
	(segment
		(start 186.500008 -223.482154)
		(end 186.900058 -223.082104)
		(width 0.508)
		(layer "F.Cu")
		(net "GND")
	)
	(segment
		(start 323.469 -100.0125)
		(end 323.469 -100.838)
		(width 0.508)
		(layer "F.Cu")
		(net "GND")
	)
	(segment
		(start 236.599984 -56.999886)
		(end 236.100112 -57.499758)
		(width 0.4572)
		(layer "F.Cu")
		(net "GND")
	)
	(segment
		(start 222.600012 -59.99988)
		(end 222.10014 -60.499752)
		(width 0.4572)
		(layer "F.Cu")
		(net "GND")
	)
	(segment
		(start 257.670554 -11.444224)
		(end 258.537202 -11.444224)
		(width 0.508)
		(layer "F.Cu")
		(net "GND")
	)
	(segment
		(start 222.600012 -64.99987)
		(end 222.10014 -65.499742)
		(width 0.4572)
		(layer "F.Cu")
		(net "GND")
	)
	(segment
		(start 225.802444 -194.131692)
		(end 227.127308 -194.131692)
		(width 0.3048)
		(layer "F.Cu")
		(net "GND")
	)
	(segment
		(start 250.599956 -51.999896)
		(end 251.099828 -52.499768)
		(width 0.4572)
		(layer "F.Cu")
		(net "GND")
	)
	(segment
		(start 43.307 -204.216)
		(end 44.196 -204.216)
		(width 0.508)
		(layer "F.Cu")
		(net "GND")
	)
	(segment
		(start 230.1494 -86.7664)
		(end 230.8606 -87.4776)
		(width 0.508)
		(layer "F.Cu")
		(net "GND")
	)
	(segment
		(start 24.395684 -107.165902)
		(end 24.395684 -107.51312)
		(width 0.508)
		(layer "F.Cu")
		(net "GND")
	)
	(segment
		(start 250.599956 -29.99994)
		(end 251.099828 -29.500068)
		(width 0.4572)
		(layer "F.Cu")
		(net "GND")
	)
	(segment
		(start 165.5826 -206.883)
		(end 165.5826 -207.645)
		(width 0.508)
		(layer "F.Cu")
		(net "GND")
	)
	(segment
		(start 266.046966 -4.168902)
		(end 266.046966 -3.868166)
		(width 0.508)
		(layer "F.Cu")
		(net "GND")
	)
	(segment
		(start 223.60001 -31.999936)
		(end 223.100138 -31.500064)
		(width 0.4572)
		(layer "F.Cu")
		(net "GND")
	)
	(segment
		(start 171.30014 -223.482408)
		(end 170.899836 -223.082104)
		(width 0.508)
		(layer "F.Cu")
		(net "GND")
	)
	(segment
		(start 6.6802 -80.6704)
		(end 10.0584 -80.6704)
		(width 0.508)
		(layer "F.Cu")
		(net "GND")
	)
	(segment
		(start 168.099994 -223.482154)
		(end 167.699944 -223.082104)
		(width 0.508)
		(layer "F.Cu")
		(net "GND")
	)
	(segment
		(start 249.599958 -45.999908)
		(end 250.09983 -45.500036)
		(width 0.4572)
		(layer "F.Cu")
		(net "GND")
	)
	(segment
		(start 29.7053 -124.484892)
		(end 30.105096 -124.884688)
		(width 0.3556)
		(layer "F.Cu")
		(net "GND")
	)
	(segment
		(start 234.599988 -37.999924)
		(end 234.100116 -37.500052)
		(width 0.4572)
		(layer "F.Cu")
		(net "GND")
	)
	(segment
		(start 39.304722 -130.08483)
		(end 38.904926 -129.685034)
		(width 0.3556)
		(layer "F.Cu")
		(net "GND")
	)
	(segment
		(start 38.904926 -130.485134)
		(end 39.304722 -130.88493)
		(width 0.3556)
		(layer "F.Cu")
		(net "GND")
	)
	(segment
		(start 227.600002 -51.999896)
		(end 227.10013 -52.499768)
		(width 0.4572)
		(layer "F.Cu")
		(net "GND")
	)
	(segment
		(start 231.599994 -42.999914)
		(end 231.100122 -42.500042)
		(width 0.4572)
		(layer "F.Cu")
		(net "GND")
	)
	(segment
		(start 158.243778 -92.759022)
		(end 157.8102 -93.1926)
		(width 0.3048)
		(layer "F.Cu")
		(net "GND")
	)
	(segment
		(start 17.930114 -91.264486)
		(end 17.930114 -90.103706)
		(width 0.508)
		(layer "F.Cu")
		(net "GND")
	)
	(segment
		(start 231.599994 -63.999872)
		(end 231.100122 -64.499744)
		(width 0.4572)
		(layer "F.Cu")
		(net "GND")
	)
	(segment
		(start 303.70018 -224.22358)
		(end 303.515522 -224.038922)
		(width 0.508)
		(layer "F.Cu")
		(net "GND")
	)
	(segment
		(start 38.904926 -130.48488)
		(end 38.904926 -130.485134)
		(width 0.3556)
		(layer "F.Cu")
		(net "GND")
	)
	(segment
		(start 253.59995 -63.999872)
		(end 254.099822 -64.499744)
		(width 0.4572)
		(layer "F.Cu")
		(net "GND")
	)
	(segment
		(start 81.5086 -136.7282)
		(end 81.9658 -136.271)
		(width 0.508)
		(layer "F.Cu")
		(net "GND")
	)
	(segment
		(start 125.5649 -41.4909)
		(end 125.6792 -41.3766)
		(width 0.508)
		(layer "F.Cu")
		(net "GND")
	)
	(segment
		(start 149.700234 -223.482408)
		(end 149.29993 -223.082104)
		(width 0.508)
		(layer "F.Cu")
		(net "GND")
	)
	(segment
		(start 90.899996 -223.482154)
		(end 90.499946 -223.082104)
		(width 0.508)
		(layer "F.Cu")
		(net "GND")
	)
	(segment
		(start 9.779 -67.945)
		(end 9.779 -67.5386)
		(width 0.508)
		(layer "F.Cu")
		(net "GND")
	)
	(segment
		(start 229.599998 -31.999936)
		(end 229.100126 -31.500064)
		(width 0.4572)
		(layer "F.Cu")
		(net "GND")
	)
	(segment
		(start 32.568134 -156.779976)
		(end 32.96793 -157.179772)
		(width 0.3556)
		(layer "F.Cu")
		(net "GND")
	)
	(segment
		(start 340.500208 -223.482408)
		(end 340.099904 -223.082104)
		(width 0.508)
		(layer "F.Cu")
		(net "GND")
	)
	(segment
		(start 41.119044 -146.021044)
		(end 42.037 -146.939)
		(width 0.508)
		(layer "F.Cu")
		(net "GND")
	)
	(segment
		(start 39.304722 -130.08483)
		(end 40.104822 -130.88493)
		(width 0.3556)
		(layer "F.Cu")
		(net "GND")
	)
	(segment
		(start 5.5626 -49.7459)
		(end 5.5626 -50.7238)
		(width 0.508)
		(layer "F.Cu")
		(net "GND")
	)
	(segment
		(start 39.704772 -129.685034)
		(end 39.705026 -129.685034)
		(width 0.3556)
		(layer "F.Cu")
		(net "GND")
	)
	(segment
		(start 227.600002 -44.99991)
		(end 227.10013 -44.500038)
		(width 0.4572)
		(layer "F.Cu")
		(net "GND")
	)
	(segment
		(start 222.600012 -60.999878)
		(end 222.10014 -61.49975)
		(width 0.4572)
		(layer "F.Cu")
		(net "GND")
	)
	(segment
		(start 283.87675 -58.1025)
		(end 283.87675 -57.912)
		(width 0.508)
		(layer "F.Cu")
		(net "GND")
	)
	(segment
		(start 242.599972 -47.999904)
		(end 243.099844 -48.499776)
		(width 0.4572)
		(layer "F.Cu")
		(net "GND")
	)
	(segment
		(start 55.470298 -120.269)
		(end 55.8038 -119.935498)
		(width 0.508)
		(layer "F.Cu")
		(net "GND")
	)
	(segment
		(start 236.599984 -53.999892)
		(end 236.100112 -54.499764)
		(width 0.4572)
		(layer "F.Cu")
		(net "GND")
	)
	(segment
		(start 329.1078 -90.2462)
		(end 329.565 -89.789)
		(width 0.3048)
		(layer "F.Cu")
		(net "GND")
	)
	(segment
		(start 17.907 -153.162)
		(end 17.591532 -153.162)
		(width 0.4064)
		(layer "F.Cu")
		(net "GND")
	)
	(segment
		(start 230.599996 -58.999882)
		(end 230.100124 -59.499754)
		(width 0.4572)
		(layer "F.Cu")
		(net "GND")
	)
	(segment
		(start 255.599946 -32.999934)
		(end 256.099818 -32.500062)
		(width 0.4572)
		(layer "F.Cu")
		(net "GND")
	)
	(segment
		(start 29.768038 -150.779988)
		(end 30.167834 -151.179784)
		(width 0.3556)
		(layer "F.Cu")
		(net "GND")
	)
	(segment
		(start 230.599996 -49.9999)
		(end 230.100124 -50.499772)
		(width 0.4572)
		(layer "F.Cu")
		(net "GND")
	)
	(segment
		(start 36.90493 -129.284984)
		(end 37.30498 -129.685034)
		(width 0.3556)
		(layer "F.Cu")
		(net "GND")
	)
	(segment
		(start 232.599992 -44.99991)
		(end 232.10012 -44.500038)
		(width 0.4572)
		(layer "F.Cu")
		(net "GND")
	)
	(segment
		(start 22.733 -119.8626)
		(end 23.0759 -120.2055)
		(width 0.508)
		(layer "F.Cu")
		(net "GND")
	)
	(segment
		(start 331.756512 -171.987718)
		(end 331.756512 -171.196)
		(width 0.508)
		(layer "F.Cu")
		(net "GND")
	)
	(segment
		(start 222.0722 -4.79425)
		(end 222.0722 -3.98145)
		(width 0.508)
		(layer "F.Cu")
		(net "GND")
	)
	(segment
		(start 20.701 -161.0995)
		(end 19.8882 -161.0995)
		(width 0.508)
		(layer "F.Cu")
		(net "GND")
	)
	(segment
		(start 336.51063 -33.153858)
		(end 335.915508 -33.153858)
		(width 0.508)
		(layer "F.Cu")
		(net "GND")
	)
	(segment
		(start 227.600002 -31.999936)
		(end 227.10013 -31.500064)
		(width 0.4572)
		(layer "F.Cu")
		(net "GND")
	)
	(segment
		(start 278.900128 -223.482408)
		(end 278.499824 -223.082104)
		(width 0.508)
		(layer "F.Cu")
		(net "GND")
	)
	(segment
		(start 250.599956 -56.999886)
		(end 251.099828 -57.499758)
		(width 0.4572)
		(layer "F.Cu")
		(net "GND")
	)
	(segment
		(start 250.599956 -32.999934)
		(end 251.099828 -32.500062)
		(width 0.4572)
		(layer "F.Cu")
		(net "GND")
	)
	(segment
		(start 44.904914 -131.684776)
		(end 44.504864 -132.084826)
		(width 0.3556)
		(layer "F.Cu")
		(net "GND")
	)
	(segment
		(start 336.651092 -37.657786)
		(end 336.653886 -37.66058)
		(width 0.508)
		(layer "F.Cu")
		(net "GND")
	)
	(segment
		(start 251.599954 -52.999894)
		(end 252.099826 -53.499766)
		(width 0.4572)
		(layer "F.Cu")
		(net "GND")
	)
	(segment
		(start 241.599974 -34.99993)
		(end 242.099846 -34.500058)
		(width 0.4572)
		(layer "F.Cu")
		(net "GND")
	)
	(segment
		(start 40.104822 -129.284984)
		(end 39.705026 -128.885188)
		(width 0.3556)
		(layer "F.Cu")
		(net "GND")
	)
	(segment
		(start 56.500014 -225.54438)
		(end 56.500014 -223.482154)
		(width 0.508)
		(layer "F.Cu")
		(net "GND")
	)
	(segment
		(start 54.818788 -132.0292)
		(end 55.245 -132.0292)
		(width 0.508)
		(layer "F.Cu")
		(net "GND")
	)
	(segment
		(start 78.189836 -62.212728)
		(end 78.189836 -60.443364)
		(width 0.508)
		(layer "F.Cu")
		(net "GND")
	)
	(segment
		(start 257.599942 -50.999898)
		(end 258.099814 -51.49977)
		(width 0.4572)
		(layer "F.Cu")
		(net "GND")
	)
	(segment
		(start 244.599968 -41.999916)
		(end 245.09984 -41.500044)
		(width 0.4572)
		(layer "F.Cu")
		(net "GND")
	)
	(segment
		(start 235.599986 -40.999918)
		(end 235.100114 -40.500046)
		(width 0.4572)
		(layer "F.Cu")
		(net "GND")
	)
	(segment
		(start 131.117086 -80.160114)
		(end 130.0734 -81.2038)
		(width 0.508)
		(layer "F.Cu")
		(net "GND")
	)
	(segment
		(start 77.720444 -186.765692)
		(end 77.720444 -186.185556)
		(width 0.3048)
		(layer "F.Cu")
		(net "GND")
	)
	(segment
		(start 196.4817 -34.3408)
		(end 196.4817 -35.0393)
		(width 0.508)
		(layer "F.Cu")
		(net "GND")
	)
	(segment
		(start 36.977574 -150.779988)
		(end 37.374322 -151.176736)
		(width 0.3048)
		(layer "F.Cu")
		(net "GND")
	)
	(segment
		(start 38.104826 -129.685034)
		(end 38.10508 -129.685034)
		(width 0.3556)
		(layer "F.Cu")
		(net "GND")
	)
	(segment
		(start 32.105092 -137.284968)
		(end 32.505142 -137.685018)
		(width 0.3556)
		(layer "F.Cu")
		(net "GND")
	)
	(segment
		(start 34.925 -223.901)
		(end 34.900108 -223.925892)
		(width 0.508)
		(layer "F.Cu")
		(net "GND")
	)
	(segment
		(start 32.4231 -180.5432)
		(end 33.2486 -180.5432)
		(width 0.508)
		(layer "F.Cu")
		(net "GND")
	)
	(segment
		(start 159.131 -94.620334)
		(end 159.120332 -94.620334)
		(width 0.508)
		(layer "F.Cu")
		(net "GND")
	)
	(segment
		(start 242.599972 -54.99989)
		(end 243.099844 -55.499762)
		(width 0.4572)
		(layer "F.Cu")
		(net "GND")
	)
	(segment
		(start 37.292026 -162.66668)
		(end 38.07968 -162.66668)
		(width 0.508)
		(layer "F.Cu")
		(net "GND")
	)
	(segment
		(start 165.6715 -96.4565)
		(end 165.862 -96.647)
		(width 0.508)
		(layer "F.Cu")
		(net "GND")
	)
	(segment
		(start 97.300034 -223.482154)
		(end 97.700084 -223.082104)
		(width 0.508)
		(layer "F.Cu")
		(net "GND")
	)
	(segment
		(start 160.10001 -223.482154)
		(end 160.50006 -223.082104)
		(width 0.508)
		(layer "F.Cu")
		(net "GND")
	)
	(segment
		(start 189.8015 -11.3157)
		(end 189.738 -11.2522)
		(width 0.508)
		(layer "F.Cu")
		(net "GND")
	)
	(segment
		(start 222.600012 -50.999898)
		(end 222.10014 -51.49977)
		(width 0.4572)
		(layer "F.Cu")
		(net "GND")
	)
	(segment
		(start 13.92555 -176.2887)
		(end 13.8938 -176.32045)
		(width 0.508)
		(layer "F.Cu")
		(net "GND")
	)
	(segment
		(start 244.599968 -53.999892)
		(end 245.09984 -54.499764)
		(width 0.4572)
		(layer "F.Cu")
		(net "GND")
	)
	(segment
		(start 35.367976 -156.379926)
		(end 35.365436 -156.379926)
		(width 0.3556)
		(layer "F.Cu")
		(net "GND")
	)
	(segment
		(start 244.599968 -56.999886)
		(end 245.09984 -57.499758)
		(width 0.4572)
		(layer "F.Cu")
		(net "GND")
	)
	(segment
		(start 343.7001 -225.54438)
		(end 343.7001 -223.3549)
		(width 0.508)
		(layer "F.Cu")
		(net "GND")
	)
	(segment
		(start 230.599996 -30.999938)
		(end 230.100124 -30.500066)
		(width 0.4572)
		(layer "F.Cu")
		(net "GND")
	)
	(segment
		(start 337.300062 -225.54438)
		(end 337.300062 -223.482154)
		(width 0.508)
		(layer "F.Cu")
		(net "GND")
	)
	(segment
		(start 250.599956 -57.999884)
		(end 251.099828 -58.499756)
		(width 0.4572)
		(layer "F.Cu")
		(net "GND")
	)
	(segment
		(start 11.395964 -98.898964)
		(end 11.8999 -99.4029)
		(width 0.508)
		(layer "F.Cu")
		(net "GND")
	)
	(segment
		(start 39.0398 -186.0931)
		(end 39.0398 -185.2676)
		(width 0.508)
		(layer "F.Cu")
		(net "GND")
	)
	(segment
		(start 273.072606 -3.57378)
		(end 272.83156 -3.57378)
		(width 0.508)
		(layer "F.Cu")
		(net "GND")
	)
	(segment
		(start 6.2484 -80.6704)
		(end 6.6802 -80.6704)
		(width 0.508)
		(layer "F.Cu")
		(net "GND")
	)
	(segment
		(start 272.50009 -225.54438)
		(end 272.50009 -223.482154)
		(width 0.508)
		(layer "F.Cu")
		(net "GND")
	)
	(segment
		(start 231.599994 -34.99993)
		(end 231.100122 -34.500058)
		(width 0.4572)
		(layer "F.Cu")
		(net "GND")
	)
	(segment
		(start 244.599968 -45.999908)
		(end 245.09984 -45.500036)
		(width 0.4572)
		(layer "F.Cu")
		(net "GND")
	)
	(segment
		(start 17.1704 -84.0359)
		(end 17.1704 -84.6582)
		(width 0.381)
		(layer "F.Cu")
		(net "GND")
	)
	(segment
		(start 247.599962 -57.999884)
		(end 248.099834 -58.499756)
		(width 0.4572)
		(layer "F.Cu")
		(net "GND")
	)
	(segment
		(start 158.242 -96.3549)
		(end 158.242 -97.155)
		(width 0.508)
		(layer "F.Cu")
		(net "GND")
	)
	(segment
		(start 224.824798 -207.407002)
		(end 224.832418 -207.414622)
		(width 0.508)
		(layer "F.Cu")
		(net "GND")
	)
	(segment
		(start 219.831412 -203.499974)
		(end 219.831412 -204.300074)
		(width 0.508)
		(layer "F.Cu")
		(net "GND")
	)
	(segment
		(start 61.3537 -163.4236)
		(end 60.4774 -163.4236)
		(width 0.508)
		(layer "F.Cu")
		(net "GND")
	)
	(segment
		(start 36.505134 -132.084572)
		(end 36.90493 -131.684776)
		(width 0.3556)
		(layer "F.Cu")
		(net "GND")
	)
	(segment
		(start 232.599992 -54.99989)
		(end 232.10012 -55.499762)
		(width 0.4572)
		(layer "F.Cu")
		(net "GND")
	)
	(segment
		(start 260.013958 -8.898128)
		(end 260.17982 -8.732266)
		(width 0.508)
		(layer "F.Cu")
		(net "GND")
	)
	(segment
		(start 238.59998 -51.999896)
		(end 238.100108 -52.499768)
		(width 0.4572)
		(layer "F.Cu")
		(net "GND")
	)
	(segment
		(start 250.599956 -48.999902)
		(end 251.099828 -49.499774)
		(width 0.4572)
		(layer "F.Cu")
		(net "GND")
	)
	(segment
		(start 239.599978 -55.999888)
		(end 239.100106 -56.49976)
		(width 0.4572)
		(layer "F.Cu")
		(net "GND")
	)
	(segment
		(start 255.599946 -58.999882)
		(end 256.099818 -59.499754)
		(width 0.4572)
		(layer "F.Cu")
		(net "GND")
	)
	(segment
		(start 254.599948 -50.999898)
		(end 255.09982 -51.49977)
		(width 0.4572)
		(layer "F.Cu")
		(net "GND")
	)
	(segment
		(start 72.460358 -126.8603)
		(end 72.689974 -126.630684)
		(width 0.4064)
		(layer "F.Cu")
		(net "GND")
	)
	(segment
		(start 24.394922 -110.285022)
		(end 23.559008 -110.285022)
		(width 0.508)
		(layer "F.Cu")
		(net "GND")
	)
	(segment
		(start 32.4231 -181.4322)
		(end 33.2486 -181.4322)
		(width 0.508)
		(layer "F.Cu")
		(net "GND")
	)
	(segment
		(start 243.59997 -42.999914)
		(end 244.099842 -42.500042)
		(width 0.4572)
		(layer "F.Cu")
		(net "GND")
	)
	(segment
		(start 245.599966 -35.999928)
		(end 246.099838 -35.500056)
		(width 0.4572)
		(layer "F.Cu")
		(net "GND")
	)
	(segment
		(start 218.6432 -3.060192)
		(end 218.885008 -3.302)
		(width 0.508)
		(layer "F.Cu")
		(net "GND")
	)
	(segment
		(start 157.318202 -58.002932)
		(end 157.318202 -57.177432)
		(width 0.508)
		(layer "F.Cu")
		(net "GND")
	)
	(segment
		(start 201.1172 -7.4549)
		(end 200.2917 -7.4549)
		(width 0.508)
		(layer "F.Cu")
		(net "GND")
	)
	(segment
		(start 30.105096 -124.884688)
		(end 30.504892 -124.484892)
		(width 0.3556)
		(layer "F.Cu")
		(net "GND")
	)
	(segment
		(start 36.322 -87.0966)
		(end 36.745418 -86.673182)
		(width 0.508)
		(layer "F.Cu")
		(net "GND")
	)
	(segment
		(start 230.599996 -55.999888)
		(end 230.100124 -56.49976)
		(width 0.4572)
		(layer "F.Cu")
		(net "GND")
	)
	(segment
		(start 327.700132 -225.54438)
		(end 327.700132 -223.482408)
		(width 0.508)
		(layer "F.Cu")
		(net "GND")
	)
	(segment
		(start 63.4238 -133.537198)
		(end 63.246 -133.537198)
		(width 0.508)
		(layer "F.Cu")
		(net "GND")
	)
	(segment
		(start 258.59994 -41.999916)
		(end 259.099812 -41.500044)
		(width 0.4572)
		(layer "F.Cu")
		(net "GND")
	)
	(segment
		(start 250.599956 -31.999936)
		(end 251.099828 -31.500064)
		(width 0.4572)
		(layer "F.Cu")
		(net "GND")
	)
	(segment
		(start 66.415666 -86.01456)
		(end 65.36436 -86.01456)
		(width 0.508)
		(layer "F.Cu")
		(net "GND")
	)
	(segment
		(start 225.600006 -50.999898)
		(end 225.100134 -51.49977)
		(width 0.4572)
		(layer "F.Cu")
		(net "GND")
	)
	(segment
		(start 156.67101 -88.856058)
		(end 156.643324 -88.828372)
		(width 0.3048)
		(layer "F.Cu")
		(net "GND")
	)
	(segment
		(start 217.316812 -2.5146)
		(end 217.327988 -2.5146)
		(width 0.508)
		(layer "F.Cu")
		(net "GND")
	)
	(segment
		(start 224.600008 -53.999892)
		(end 224.100136 -54.499764)
		(width 0.4572)
		(layer "F.Cu")
		(net "GND")
	)
	(segment
		(start 266.100052 -223.482154)
		(end 265.700002 -223.082104)
		(width 0.508)
		(layer "F.Cu")
		(net "GND")
	)
	(segment
		(start 224.600008 -33.999932)
		(end 224.100136 -33.50006)
		(width 0.4572)
		(layer "F.Cu")
		(net "GND")
	)
	(segment
		(start 217.294206 -2.491994)
		(end 217.316812 -2.5146)
		(width 0.508)
		(layer "F.Cu")
		(net "GND")
	)
	(segment
		(start 265.797792 -6.285992)
		(end 266.433808 -6.285992)
		(width 0.508)
		(layer "F.Cu")
		(net "GND")
	)
	(segment
		(start 298.6278 -207.645)
		(end 298.4246 -207.8482)
		(width 0.508)
		(layer "F.Cu")
		(net "GND")
	)
	(segment
		(start 233.59999 -52.999894)
		(end 233.100118 -53.499766)
		(width 0.4572)
		(layer "F.Cu")
		(net "GND")
	)
	(segment
		(start 26.897584 -89.14511)
		(end 26.897584 -90.663776)
		(width 0.3048)
		(layer "F.Cu")
		(net "GND")
	)
	(segment
		(start 228.981 -82.55)
		(end 230.505 -82.55)
		(width 0.3048)
		(layer "F.Cu")
		(net "GND")
	)
	(segment
		(start 48.518572 -49.861724)
		(end 48.518572 -49.601628)
		(width 0.508)
		(layer "F.Cu")
		(net "GND")
	)
	(segment
		(start 241.599974 -46.999906)
		(end 242.099846 -46.500034)
		(width 0.4572)
		(layer "F.Cu")
		(net "GND")
	)
	(segment
		(start 265.43127 -4.784598)
		(end 266.046966 -4.168902)
		(width 0.508)
		(layer "F.Cu")
		(net "GND")
	)
	(segment
		(start 239.708436 -7.6454)
		(end 240.164874 -7.188962)
		(width 0.508)
		(layer "F.Cu")
		(net "GND")
	)
	(segment
		(start 99.70008 -225.54438)
		(end 99.70008 -223.482408)
		(width 0.508)
		(layer "F.Cu")
		(net "GND")
	)
	(segment
		(start 228.6 -32.999934)
		(end 228.100128 -32.500062)
		(width 0.4572)
		(layer "F.Cu")
		(net "GND")
	)
	(segment
		(start 80.37068 -83.917028)
		(end 80.37068 -84.28482)
		(width 0.508)
		(layer "F.Cu")
		(net "GND")
	)
	(segment
		(start 249.599958 -55.999888)
		(end 250.09983 -56.49976)
		(width 0.4572)
		(layer "F.Cu")
		(net "GND")
	)
	(segment
		(start 32.232346 -146.7612)
		(end 32.6898 -146.7612)
		(width 0.381)
		(layer "F.Cu")
		(net "GND")
	)
	(segment
		(start 338.100162 -223.482154)
		(end 338.500212 -223.082104)
		(width 0.508)
		(layer "F.Cu")
		(net "GND")
	)
	(segment
		(start 238.59998 -63.999872)
		(end 238.100108 -64.499744)
		(width 0.4572)
		(layer "F.Cu")
		(net "GND")
	)
	(segment
		(start 20.56384 -151.24176)
		(end 20.3962 -151.4094)
		(width 0.3556)
		(layer "F.Cu")
		(net "GND")
	)
	(segment
		(start 46.186852 -32.057594)
		(end 46.186852 -31.193994)
		(width 0.508)
		(layer "F.Cu")
		(net "GND")
	)
	(segment
		(start 247.599962 -44.99991)
		(end 248.099834 -44.500038)
		(width 0.4572)
		(layer "F.Cu")
		(net "GND")
	)
	(segment
		(start 158.243778 -88.82634)
		(end 157.88894 -88.82634)
		(width 0.3048)
		(layer "F.Cu")
		(net "GND")
	)
	(segment
		(start 26.9113 -173.2026)
		(end 27.8892 -173.2026)
		(width 0.508)
		(layer "F.Cu")
		(net "GND")
	)
	(segment
		(start 21.5519 -149.9362)
		(end 21.3868 -149.9362)
		(width 0.508)
		(layer "F.Cu")
		(net "GND")
	)
	(segment
		(start 20.107656 -108.260134)
		(end 20.103338 -108.260134)
		(width 0.508)
		(layer "F.Cu")
		(net "GND")
	)
	(segment
		(start 49.149 -198.247)
		(end 48.26 -198.247)
		(width 0.508)
		(layer "F.Cu")
		(net "GND")
	)
	(segment
		(start 151.770588 -89.464388)
		(end 151.765 -89.4588)
		(width 0.508)
		(layer "F.Cu")
		(net "GND")
	)
	(segment
		(start 81.9658 -136.271)
		(end 81.4578 -135.763)
		(width 0.508)
		(layer "F.Cu")
		(net "GND")
	)
	(segment
		(start 71.749412 -196.934074)
		(end 71.749412 -196.133974)
		(width 0.508)
		(layer "F.Cu")
		(net "GND")
	)
	(segment
		(start 8.001 -55.9943)
		(end 8.001 -56.9976)
		(width 0.508)
		(layer "F.Cu")
		(net "GND")
	)
	(segment
		(start 68.21043 -125.92939)
		(end 67.746118 -125.92939)
		(width 0.4064)
		(layer "F.Cu")
		(net "GND")
	)
	(segment
		(start 13.569188 -89.702132)
		(end 14.200378 -89.070942)
		(width 0.508)
		(layer "F.Cu")
		(net "GND")
	)
	(segment
		(start 48.518572 -49.601628)
		(end 49.1236 -48.9966)
		(width 0.508)
		(layer "F.Cu")
		(net "GND")
	)
	(segment
		(start 153.283412 -94.279212)
		(end 153.289 -94.2848)
		(width 0.508)
		(layer "F.Cu")
		(net "GND")
	)
	(segment
		(start 245.599966 -57.999884)
		(end 246.099838 -58.499756)
		(width 0.4572)
		(layer "F.Cu")
		(net "GND")
	)
	(segment
		(start 249.599958 -48.999902)
		(end 250.09983 -49.499774)
		(width 0.4572)
		(layer "F.Cu")
		(net "GND")
	)
	(segment
		(start 135.579866 -85.592666)
		(end 136.428734 -85.592666)
		(width 0.508)
		(layer "F.Cu")
		(net "GND")
	)
	(segment
		(start 11.8745 -50.8254)
		(end 10.8712 -50.8254)
		(width 0.508)
		(layer "F.Cu")
		(net "GND")
	)
	(segment
		(start 227.10394 -12.5095)
		(end 226.53244 -13.081)
		(width 0.508)
		(layer "F.Cu")
		(net "GND")
	)
	(segment
		(start 269.300198 -225.54438)
		(end 269.300198 -223.482408)
		(width 0.508)
		(layer "F.Cu")
		(net "GND")
	)
	(segment
		(start 220.844872 -7.874762)
		(end 220.839538 -7.880096)
		(width 0.508)
		(layer "F.Cu")
		(net "GND")
	)
	(segment
		(start 249.599958 -50.999898)
		(end 250.09983 -51.49977)
		(width 0.4572)
		(layer "F.Cu")
		(net "GND")
	)
	(segment
		(start 251.599954 -55.999888)
		(end 252.099826 -56.49976)
		(width 0.4572)
		(layer "F.Cu")
		(net "GND")
	)
	(segment
		(start 319.659 -86.0425)
		(end 319.659 -85.217)
		(width 0.508)
		(layer "F.Cu")
		(net "GND")
	)
	(segment
		(start 217.8812 -3.504692)
		(end 217.996008 -3.6195)
		(width 0.508)
		(layer "F.Cu")
		(net "GND")
	)
	(segment
		(start 33.6296 -183.3372)
		(end 34.6456 -183.3372)
		(width 0.508)
		(layer "F.Cu")
		(net "GND")
	)
	(segment
		(start 60.0202 -57.8104)
		(end 60.0202 -57.72912)
		(width 0.508)
		(layer "F.Cu")
		(net "GND")
	)
	(segment
		(start 136.116314 -80.160114)
		(end 135.254746 -80.160114)
		(width 0.508)
		(layer "F.Cu")
		(net "GND")
	)
	(segment
		(start 199.300084 -223.482154)
		(end 199.700134 -223.082104)
		(width 0.508)
		(layer "F.Cu")
		(net "GND")
	)
	(segment
		(start 232.599992 -45.999908)
		(end 232.10012 -45.500036)
		(width 0.4572)
		(layer "F.Cu")
		(net "GND")
	)
	(segment
		(start 50.099976 -225.54438)
		(end 50.099976 -223.482154)
		(width 0.508)
		(layer "F.Cu")
		(net "GND")
	)
	(segment
		(start 193.6496 -32.5628)
		(end 193.9544 -32.8676)
		(width 0.508)
		(layer "F.Cu")
		(net "GND")
	)
	(segment
		(start 87.0966 -185.6486)
		(end 87.0966 -184.7088)
		(width 0.508)
		(layer "F.Cu")
		(net "GND")
	)
	(segment
		(start 224.600008 -44.99991)
		(end 225.100134 -45.500036)
		(width 0.4572)
		(layer "F.Cu")
		(net "GND")
	)
	(segment
		(start 203.9239 -26.1112)
		(end 203.073 -26.1112)
		(width 0.508)
		(layer "F.Cu")
		(net "GND")
	)
	(segment
		(start 39.705026 -129.685034)
		(end 40.104822 -130.08483)
		(width 0.3556)
		(layer "F.Cu")
		(net "GND")
	)
	(segment
		(start 329.565 -89.789)
		(end 329.565 -89.3572)
		(width 0.3048)
		(layer "F.Cu")
		(net "GND")
	)
	(segment
		(start 224.600008 -39.99992)
		(end 224.100136 -39.500048)
		(width 0.4572)
		(layer "F.Cu")
		(net "GND")
	)
	(segment
		(start 239.599978 -48.999902)
		(end 239.100106 -49.499774)
		(width 0.4572)
		(layer "F.Cu")
		(net "GND")
	)
	(segment
		(start 27.0256 -79.2988)
		(end 27.0129 -79.2988)
		(width 0.508)
		(layer "F.Cu")
		(net "GND")
	)
	(segment
		(start 286.100012 -225.54438)
		(end 286.100012 -223.482154)
		(width 0.508)
		(layer "F.Cu")
		(net "GND")
	)
	(segment
		(start 61.272674 -62.230254)
		(end 61.272674 -60.672726)
		(width 0.508)
		(layer "F.Cu")
		(net "GND")
	)
	(segment
		(start 257.599942 -31.999936)
		(end 258.099814 -31.500064)
		(width 0.4572)
		(layer "F.Cu")
		(net "GND")
	)
	(segment
		(start 232.599992 -52.999894)
		(end 232.10012 -53.499766)
		(width 0.4572)
		(layer "F.Cu")
		(net "GND")
	)
	(segment
		(start 211.224368 -7.4676)
		(end 211.224368 -8.740394)
		(width 0.2032)
		(layer "F.Cu")
		(net "GND")
	)
	(segment
		(start 131.949444 -199.647556)
		(end 132.715 -198.882)
		(width 0.3048)
		(layer "F.Cu")
		(net "GND")
	)
	(segment
		(start 36.105084 -129.284984)
		(end 36.90493 -130.08483)
		(width 0.3556)
		(layer "F.Cu")
		(net "GND")
	)
	(segment
		(start 240.599976 -53.999892)
		(end 241.099848 -54.499764)
		(width 0.4572)
		(layer "F.Cu")
		(net "GND")
	)
	(segment
		(start 18.8595 -128.651)
		(end 19.654774 -128.651)
		(width 0.508)
		(layer "F.Cu")
		(net "GND")
	)
	(segment
		(start 251.599954 -57.999884)
		(end 252.099826 -58.499756)
		(width 0.4572)
		(layer "F.Cu")
		(net "GND")
	)
	(segment
		(start 63.4238 -132.3975)
		(end 64.389 -132.3975)
		(width 0.508)
		(layer "F.Cu")
		(net "GND")
	)
	(segment
		(start 38.504876 -130.08483)
		(end 38.904926 -130.48488)
		(width 0.3556)
		(layer "F.Cu")
		(net "GND")
	)
	(segment
		(start 45.70476 -131.684776)
		(end 45.705014 -131.684776)
		(width 0.3556)
		(layer "F.Cu")
		(net "GND")
	)
	(segment
		(start 233.59999 -50.999898)
		(end 233.100118 -51.49977)
		(width 0.4572)
		(layer "F.Cu")
		(net "GND")
	)
	(segment
		(start 253.59995 -57.999884)
		(end 254.099822 -58.499756)
		(width 0.4572)
		(layer "F.Cu")
		(net "GND")
	)
	(segment
		(start 42.900092 -223.0628)
		(end 42.900092 -225.54438)
		(width 0.508)
		(layer "F.Cu")
		(net "GND")
	)
	(segment
		(start 16.0655 -50.8254)
		(end 16.0655 -52.0827)
		(width 0.508)
		(layer "F.Cu")
		(net "GND")
	)
	(segment
		(start 258.59994 -50.999898)
		(end 259.099812 -51.49977)
		(width 0.4572)
		(layer "F.Cu")
		(net "GND")
	)
	(segment
		(start 19.685 -147.8915)
		(end 19.6215 -147.828)
		(width 0.508)
		(layer "F.Cu")
		(net "GND")
	)
	(segment
		(start 115.809268 -29.020516)
		(end 114.9604 -29.020516)
		(width 0.508)
		(layer "F.Cu")
		(net "GND")
	)
	(segment
		(start 215.300052 -225.54438)
		(end 215.300052 -223.482154)
		(width 0.508)
		(layer "F.Cu")
		(net "GND")
	)
	(segment
		(start 239.599978 -30.999938)
		(end 239.100106 -30.500066)
		(width 0.4572)
		(layer "F.Cu")
		(net "GND")
	)
	(segment
		(start 345.09837 -69.97319)
		(end 345.100148 -69.97319)
		(width 0.508)
		(layer "F.Cu")
		(net "GND")
	)
	(segment
		(start 38.104572 -130.485134)
		(end 38.10508 -130.485134)
		(width 0.3556)
		(layer "F.Cu")
		(net "GND")
	)
	(segment
		(start 188.900054 -225.54438)
		(end 188.900054 -223.482154)
		(width 0.508)
		(layer "F.Cu")
		(net "GND")
	)
	(segment
		(start 226.600004 -50.999898)
		(end 226.100132 -51.49977)
		(width 0.4572)
		(layer "F.Cu")
		(net "GND")
	)
	(segment
		(start 25.0571 -50.6476)
		(end 25.0571 -50.080164)
		(width 0.508)
		(layer "F.Cu")
		(net "GND")
	)
	(segment
		(start 183.30926 -13.54836)
		(end 183.09336 -13.76426)
		(width 0.508)
		(layer "F.Cu")
		(net "GND")
	)
	(segment
		(start 123.6218 -93.4212)
		(end 123.6218 -92.4052)
		(width 0.508)
		(layer "F.Cu")
		(net "GND")
	)
	(segment
		(start 215.223598 -13.1064)
		(end 215.223598 -11.827002)
		(width 0.2032)
		(layer "F.Cu")
		(net "GND")
	)
	(segment
		(start 83.137756 -83.637628)
		(end 83.290664 -83.48472)
		(width 0.508)
		(layer "F.Cu")
		(net "GND")
	)
	(segment
		(start 331.700124 -223.482154)
		(end 332.100174 -223.082104)
		(width 0.508)
		(layer "F.Cu")
		(net "GND")
	)
	(segment
		(start 251.599954 -49.9999)
		(end 252.099826 -50.499772)
		(width 0.4572)
		(layer "F.Cu")
		(net "GND")
	)
	(segment
		(start 168.900094 -223.482154)
		(end 169.300144 -223.082104)
		(width 0.508)
		(layer "F.Cu")
		(net "GND")
	)
	(segment
		(start 251.599954 -40.999918)
		(end 252.099826 -40.500046)
		(width 0.4572)
		(layer "F.Cu")
		(net "GND")
	)
	(segment
		(start 68.49999 -225.54438)
		(end 68.49999 -223.482154)
		(width 0.508)
		(layer "F.Cu")
		(net "GND")
	)
	(segment
		(start 251.599954 -54.99989)
		(end 252.099826 -55.499762)
		(width 0.4572)
		(layer "F.Cu")
		(net "GND")
	)
	(segment
		(start 229.599998 -63.999872)
		(end 229.100126 -64.499744)
		(width 0.4572)
		(layer "F.Cu")
		(net "GND")
	)
	(segment
		(start 26.4287 -33.45434)
		(end 26.4287 -32.60852)
		(width 0.508)
		(layer "F.Cu")
		(net "GND")
	)
	(segment
		(start 273.30019 -225.54438)
		(end 273.30019 -223.482154)
		(width 0.508)
		(layer "F.Cu")
		(net "GND")
	)
	(segment
		(start 18.422366 -105.918)
		(end 18.423382 -105.916984)
		(width 0.508)
		(layer "F.Cu")
		(net "GND")
	)
	(segment
		(start 270.100044 -225.54438)
		(end 270.100044 -223.482154)
		(width 0.508)
		(layer "F.Cu")
		(net "GND")
	)
	(segment
		(start 238.59998 -38.999922)
		(end 238.100108 -38.50005)
		(width 0.4572)
		(layer "F.Cu")
		(net "GND")
	)
	(segment
		(start 248.59996 -63.999872)
		(end 249.099832 -64.499744)
		(width 0.4572)
		(layer "F.Cu")
		(net "GND")
	)
	(segment
		(start 218.5924 -12.319)
		(end 218.2368 -11.9634)
		(width 0.508)
		(layer "F.Cu")
		(net "GND")
	)
	(segment
		(start 252.068584 -11.444224)
		(end 252.433836 -11.809476)
		(width 0.508)
		(layer "F.Cu")
		(net "GND")
	)
	(segment
		(start 37.704776 -129.284984)
		(end 38.104826 -129.685034)
		(width 0.3556)
		(layer "F.Cu")
		(net "GND")
	)
	(segment
		(start 239.599978 -44.99991)
		(end 239.100106 -44.500038)
		(width 0.4572)
		(layer "F.Cu")
		(net "GND")
	)
	(segment
		(start 231.599994 -53.999892)
		(end 231.100122 -54.499764)
		(width 0.4572)
		(layer "F.Cu")
		(net "GND")
	)
	(segment
		(start 229.599998 -60.999878)
		(end 229.100126 -61.49975)
		(width 0.4572)
		(layer "F.Cu")
		(net "GND")
	)
	(segment
		(start 18.986246 -94.18574)
		(end 17.946116 -94.18574)
		(width 0.508)
		(layer "F.Cu")
		(net "GND")
	)
	(segment
		(start 64.068452 -146.72691)
		(end 64.068452 -145.856452)
		(width 0.508)
		(layer "F.Cu")
		(net "GND")
	)
	(segment
		(start 243.59997 -46.999906)
		(end 244.099842 -46.500034)
		(width 0.4572)
		(layer "F.Cu")
		(net "GND")
	)
	(segment
		(start 329.607672 -40.59809)
		(end 329.607672 -39.503096)
		(width 0.508)
		(layer "F.Cu")
		(net "GND")
	)
	(segment
		(start 133.288786 -81.480914)
		(end 132.691886 -80.884014)
		(width 0.508)
		(layer "F.Cu")
		(net "GND")
	)
	(segment
		(start 298.6278 -206.8068)
		(end 298.6278 -207.645)
		(width 0.508)
		(layer "F.Cu")
		(net "GND")
	)
	(segment
		(start 250.599956 -40.999918)
		(end 251.099828 -40.500046)
		(width 0.4572)
		(layer "F.Cu")
		(net "GND")
	)
	(segment
		(start 151.917654 -95.0976)
		(end 154.94 -95.0976)
		(width 0.3048)
		(layer "F.Cu")
		(net "GND")
	)
	(segment
		(start 69.30009 -223.482154)
		(end 69.70014 -223.082104)
		(width 0.508)
		(layer "F.Cu")
		(net "GND")
	)
	(segment
		(start 228.6 -62.999874)
		(end 228.100128 -63.499746)
		(width 0.4572)
		(layer "F.Cu")
		(net "GND")
	)
	(segment
		(start 26.37155 -174.7266)
		(end 27.3558 -174.7266)
		(width 0.508)
		(layer "F.Cu")
		(net "GND")
	)
	(segment
		(start 303.515522 -224.038922)
		(end 303.515522 -223.29775)
		(width 0.508)
		(layer "F.Cu")
		(net "GND")
	)
	(segment
		(start 148.682456 -59.174126)
		(end 147.365212 -59.174126)
		(width 0.508)
		(layer "F.Cu")
		(net "GND")
	)
	(segment
		(start 242.599972 -56.999886)
		(end 243.099844 -57.499758)
		(width 0.4572)
		(layer "F.Cu")
		(net "GND")
	)
	(segment
		(start 18.3642 -66.5353)
		(end 18.3642 -65.4177)
		(width 0.508)
		(layer "F.Cu")
		(net "GND")
	)
	(segment
		(start 165.6715 -86.3854)
		(end 165.672516 -86.384384)
		(width 0.508)
		(layer "F.Cu")
		(net "GND")
	)
	(segment
		(start 39.304722 -128.484884)
		(end 39.705026 -128.885188)
		(width 0.3556)
		(layer "F.Cu")
		(net "GND")
	)
	(segment
		(start 190.4365 -9.04875)
		(end 190.4365 -8.57504)
		(width 0.3556)
		(layer "F.Cu")
		(net "GND")
	)
	(segment
		(start 248.59996 -45.999908)
		(end 249.099832 -45.500036)
		(width 0.4572)
		(layer "F.Cu")
		(net "GND")
	)
	(segment
		(start 5.588 -43.4975)
		(end 5.588 -42.4688)
		(width 0.508)
		(layer "F.Cu")
		(net "GND")
	)
	(segment
		(start 251.599954 -50.999898)
		(end 252.099826 -51.49977)
		(width 0.4572)
		(layer "F.Cu")
		(net "GND")
	)
	(segment
		(start 25.009348 -106.552238)
		(end 24.395684 -107.165902)
		(width 0.508)
		(layer "F.Cu")
		(net "GND")
	)
	(segment
		(start 153.700226 -223.4819)
		(end 154.100022 -223.082104)
		(width 0.508)
		(layer "F.Cu")
		(net "GND")
	)
	(segment
		(start 244.599968 -31.999936)
		(end 245.09984 -31.500064)
		(width 0.4572)
		(layer "F.Cu")
		(net "GND")
	)
	(segment
		(start 243.59997 -44.99991)
		(end 244.099842 -44.500038)
		(width 0.4572)
		(layer "F.Cu")
		(net "GND")
	)
	(segment
		(start 54.1655 -121.412)
		(end 54.1655 -120.9675)
		(width 0.508)
		(layer "F.Cu")
		(net "GND")
	)
	(segment
		(start 13.7414 -107.20451)
		(end 14.33449 -107.20451)
		(width 0.3048)
		(layer "F.Cu")
		(net "GND")
	)
	(segment
		(start 175.300132 -223.482154)
		(end 175.700182 -223.082104)
		(width 0.508)
		(layer "F.Cu")
		(net "GND")
	)
	(segment
		(start 255.599946 -41.999916)
		(end 256.099818 -41.500044)
		(width 0.4572)
		(layer "F.Cu")
		(net "GND")
	)
	(segment
		(start 137.700004 -225.54438)
		(end 137.700004 -223.538796)
		(width 0.508)
		(layer "F.Cu")
		(net "GND")
	)
	(segment
		(start 50.165 -146.6342)
		(end 50.7365 -147.2057)
		(width 0.508)
		(layer "F.Cu")
		(net "GND")
	)
	(segment
		(start 38.568376 -151.579834)
		(end 38.968172 -151.180038)
		(width 0.3556)
		(layer "F.Cu")
		(net "GND")
	)
	(segment
		(start 73.0377 -118.11)
		(end 72.1868 -118.11)
		(width 0.508)
		(layer "F.Cu")
		(net "GND")
	)
	(segment
		(start 23.38324 -159.7025)
		(end 24.09444 -159.7025)
		(width 0.4064)
		(layer "F.Cu")
		(net "GND")
	)
	(segment
		(start 5.4356 -89.916)
		(end 5.4356 -86.614)
		(width 0.508)
		(layer "F.Cu")
		(net "GND")
	)
	(segment
		(start 10.748772 -67.3735)
		(end 11.256772 -67.8815)
		(width 0.508)
		(layer "F.Cu")
		(net "GND")
	)
	(segment
		(start 32.104838 -137.285222)
		(end 31.705042 -137.685018)
		(width 0.3556)
		(layer "F.Cu")
		(net "GND")
	)
	(segment
		(start 82.100166 -223.4819)
		(end 82.499962 -223.082104)
		(width 0.508)
		(layer "F.Cu")
		(net "GND")
	)
	(segment
		(start 195.300092 -225.54438)
		(end 195.300092 -223.482154)
		(width 0.508)
		(layer "F.Cu")
		(net "GND")
	)
	(segment
		(start 56.54548 -144.27708)
		(end 55.107078 -144.27708)
		(width 0.508)
		(layer "F.Cu")
		(net "GND")
	)
	(segment
		(start 37.704776 -131.684776)
		(end 38.504876 -132.484876)
		(width 0.3556)
		(layer "F.Cu")
		(net "GND")
	)
	(segment
		(start 20.447 -145.8595)
		(end 20.3581 -145.8595)
		(width 0.508)
		(layer "F.Cu")
		(net "GND")
	)
	(segment
		(start 227.600002 -57.999884)
		(end 227.10013 -58.499756)
		(width 0.4572)
		(layer "F.Cu")
		(net "GND")
	)
	(segment
		(start 52.1208 -48.966882)
		(end 52.073302 -48.919384)
		(width 0.508)
		(layer "F.Cu")
		(net "GND")
	)
	(segment
		(start 227.5459 -1.5875)
		(end 226.75723 -2.37617)
		(width 0.508)
		(layer "F.Cu")
		(net "GND")
	)
	(segment
		(start 62.0522 -59.3725)
		(end 62.865 -59.3725)
		(width 0.508)
		(layer "F.Cu")
		(net "GND")
	)
	(segment
		(start 39.367968 -157.179772)
		(end 39.367714 -157.179772)
		(width 0.3556)
		(layer "F.Cu")
		(net "GND")
	)
	(segment
		(start 235.599986 -44.99991)
		(end 235.100114 -44.500038)
		(width 0.4572)
		(layer "F.Cu")
		(net "GND")
	)
	(segment
		(start 229.599998 -53.999892)
		(end 229.100126 -54.499764)
		(width 0.4572)
		(layer "F.Cu")
		(net "GND")
	)
	(segment
		(start 59.871102 -16.151606)
		(end 57.942734 -16.151606)
		(width 0.508)
		(layer "F.Cu")
		(net "GND")
	)
	(segment
		(start 249.599958 -47.999904)
		(end 250.09983 -48.499776)
		(width 0.4572)
		(layer "F.Cu")
		(net "GND")
	)
	(segment
		(start 43.304714 -133.284976)
		(end 43.70451 -132.88518)
		(width 0.3556)
		(layer "F.Cu")
		(net "GND")
	)
	(segment
		(start 38.504876 -130.88493)
		(end 38.904926 -131.28498)
		(width 0.3556)
		(layer "F.Cu")
		(net "GND")
	)
	(segment
		(start 56.134 -134.4295)
		(end 57.15 -134.4295)
		(width 0.508)
		(layer "F.Cu")
		(net "GND")
	)
	(segment
		(start 4.572 -67.3354)
		(end 5.1562 -66.7512)
		(width 0.508)
		(layer "F.Cu")
		(net "GND")
	)
	(segment
		(start 248.59996 -43.999912)
		(end 249.099832 -43.50004)
		(width 0.4572)
		(layer "F.Cu")
		(net "GND")
	)
	(segment
		(start 203.073 -26.1112)
		(end 202.6412 -26.543)
		(width 0.508)
		(layer "F.Cu")
		(net "GND")
	)
	(segment
		(start 340.9442 -171.8945)
		(end 341.8459 -171.8945)
		(width 0.508)
		(layer "F.Cu")
		(net "GND")
	)
	(segment
		(start 237.599982 -44.99991)
		(end 237.10011 -44.500038)
		(width 0.4572)
		(layer "F.Cu")
		(net "GND")
	)
	(segment
		(start 258.59994 -59.99988)
		(end 259.099812 -60.499752)
		(width 0.4572)
		(layer "F.Cu")
		(net "GND")
	)
	(segment
		(start 231.599994 -49.9999)
		(end 231.100122 -50.499772)
		(width 0.4572)
		(layer "F.Cu")
		(net "GND")
	)
	(segment
		(start 223.60001 -32.999934)
		(end 223.100138 -32.500062)
		(width 0.4572)
		(layer "F.Cu")
		(net "GND")
	)
	(segment
		(start 325.300086 -225.54438)
		(end 325.300086 -223.482154)
		(width 0.508)
		(layer "F.Cu")
		(net "GND")
	)
	(segment
		(start 230.599996 -54.99989)
		(end 230.100124 -55.499762)
		(width 0.4572)
		(layer "F.Cu")
		(net "GND")
	)
	(segment
		(start 344.847164 -69.130164)
		(end 344.847164 -69.721984)
		(width 0.508)
		(layer "F.Cu")
		(net "GND")
	)
	(segment
		(start 27.5336 -98.6663)
		(end 27.5336 -97.845118)
		(width 0.508)
		(layer "F.Cu")
		(net "GND")
	)
	(segment
		(start 23.3172 -182.7911)
		(end 23.3172 -181.8894)
		(width 0.508)
		(layer "F.Cu")
		(net "GND")
	)
	(segment
		(start 240.599976 -38.999922)
		(end 241.099848 -38.50005)
		(width 0.4572)
		(layer "F.Cu")
		(net "GND")
	)
	(segment
		(start 242.951 -24.765)
		(end 242.951 -27.432)
		(width 0.508)
		(layer "F.Cu")
		(net "GND")
	)
	(segment
		(start 219.833698 -188.3283)
		(end 218.797124 -189.364874)
		(width 0.508)
		(layer "F.Cu")
		(net "GND")
	)
	(segment
		(start 225.600006 -59.99988)
		(end 225.100134 -60.499752)
		(width 0.4572)
		(layer "F.Cu")
		(net "GND")
	)
	(segment
		(start 204.900022 -225.54438)
		(end 204.900022 -223.482154)
		(width 0.508)
		(layer "F.Cu")
		(net "GND")
	)
	(segment
		(start 327.908412 -46.217332)
		(end 327.908412 -47.288958)
		(width 0.508)
		(layer "F.Cu")
		(net "GND")
	)
	(segment
		(start 154.813 -92.548202)
		(end 154.813 -91.622118)
		(width 0.508)
		(layer "F.Cu")
		(net "GND")
	)
	(segment
		(start 65.300098 -223.482408)
		(end 64.899794 -223.082104)
		(width 0.508)
		(layer "F.Cu")
		(net "GND")
	)
	(segment
		(start 32.96793 -150.779988)
		(end 32.96793 -149.979888)
		(width 0.3556)
		(layer "F.Cu")
		(net "GND")
	)
	(segment
		(start 222.600012 -32.999934)
		(end 222.10014 -32.500062)
		(width 0.4572)
		(layer "F.Cu")
		(net "GND")
	)
	(segment
		(start 18.82648 -65.30848)
		(end 19.34718 -65.82918)
		(width 0.508)
		(layer "F.Cu")
		(net "GND")
	)
	(segment
		(start 192.1002 -223.482408)
		(end 191.699896 -223.082104)
		(width 0.508)
		(layer "F.Cu")
		(net "GND")
	)
	(segment
		(start 45.9359 -73.525888)
		(end 45.9359 -72.5551)
		(width 0.508)
		(layer "F.Cu")
		(net "GND")
	)
	(segment
		(start 289.300158 -223.482154)
		(end 289.700208 -223.082104)
		(width 0.508)
		(layer "F.Cu")
		(net "GND")
	)
	(segment
		(start 60.028074 -57.818274)
		(end 60.0202 -57.8104)
		(width 0.508)
		(layer "F.Cu")
		(net "GND")
	)
	(segment
		(start 33.40862 -146.04238)
		(end 33.857946 -146.04238)
		(width 0.381)
		(layer "F.Cu")
		(net "GND")
	)
	(segment
		(start 217.327988 -2.5146)
		(end 217.8812 -3.067812)
		(width 0.508)
		(layer "F.Cu")
		(net "GND")
	)
	(segment
		(start 21.336 -145.8595)
		(end 22.1488 -145.8595)
		(width 0.508)
		(layer "F.Cu")
		(net "GND")
	)
	(segment
		(start 256.599944 -33.999932)
		(end 257.099816 -33.50006)
		(width 0.4572)
		(layer "F.Cu")
		(net "GND")
	)
	(segment
		(start 20.574 -147.8915)
		(end 19.685 -147.8915)
		(width 0.508)
		(layer "F.Cu")
		(net "GND")
	)
	(segment
		(start 56.15686 -150.96236)
		(end 54.989222 -150.96236)
		(width 0.3556)
		(layer "F.Cu")
		(net "GND")
	)
	(segment
		(start 243.59997 -62.999874)
		(end 244.099842 -63.499746)
		(width 0.4572)
		(layer "F.Cu")
		(net "GND")
	)
	(segment
		(start 189.700154 -225.54438)
		(end 189.700154 -223.482154)
		(width 0.508)
		(layer "F.Cu")
		(net "GND")
	)
	(segment
		(start 236.599984 -60.999878)
		(end 236.100112 -61.49975)
		(width 0.4572)
		(layer "F.Cu")
		(net "GND")
	)
	(segment
		(start 245.599966 -54.99989)
		(end 246.099838 -55.499762)
		(width 0.4572)
		(layer "F.Cu")
		(net "GND")
	)
	(segment
		(start 256.599944 -50.999898)
		(end 257.099816 -51.49977)
		(width 0.4572)
		(layer "F.Cu")
		(net "GND")
	)
	(segment
		(start 235.599986 -32.999934)
		(end 235.100114 -32.500062)
		(width 0.4572)
		(layer "F.Cu")
		(net "GND")
	)
	(segment
		(start 247.599962 -48.999902)
		(end 248.099834 -49.499774)
		(width 0.4572)
		(layer "F.Cu")
		(net "GND")
	)
	(segment
		(start 264.234676 -8.182864)
		(end 265.028172 -8.182864)
		(width 0.508)
		(layer "F.Cu")
		(net "GND")
	)
	(segment
		(start 17.7038 -176.5808)
		(end 17.7038 -175.3362)
		(width 0.508)
		(layer "F.Cu")
		(net "GND")
	)
	(segment
		(start 131.642358 -74.60996)
		(end 131.642358 -73.32472)
		(width 0.508)
		(layer "F.Cu")
		(net "GND")
	)
	(segment
		(start 256.599944 -62.999874)
		(end 257.099816 -63.499746)
		(width 0.4572)
		(layer "F.Cu")
		(net "GND")
	)
	(segment
		(start 67.746118 -125.92939)
		(end 67.314826 -126.360682)
		(width 0.4064)
		(layer "F.Cu")
		(net "GND")
	)
	(segment
		(start 255.599946 -63.999872)
		(end 256.099818 -64.499744)
		(width 0.4572)
		(layer "F.Cu")
		(net "GND")
	)
	(segment
		(start 36.105338 -132.484876)
		(end 36.10483 -132.484876)
		(width 0.3556)
		(layer "F.Cu")
		(net "GND")
	)
	(segment
		(start 240.599976 -41.999916)
		(end 241.099848 -41.500044)
		(width 0.4572)
		(layer "F.Cu")
		(net "GND")
	)
	(segment
		(start 321.691 -86.0425)
		(end 321.691 -85.217)
		(width 0.508)
		(layer "F.Cu")
		(net "GND")
	)
	(segment
		(start 40.62349 -85.264244)
		(end 39.596314 -86.29142)
		(width 0.508)
		(layer "F.Cu")
		(net "GND")
	)
	(segment
		(start 24.852122 -93.534484)
		(end 25.178512 -93.208094)
		(width 0.508)
		(layer "F.Cu")
		(net "GND")
	)
	(segment
		(start 63.4492 -89.90584)
		(end 63.4492 -90.71102)
		(width 0.4064)
		(layer "F.Cu")
		(net "GND")
	)
	(segment
		(start 234.599988 -34.99993)
		(end 234.100116 -34.500058)
		(width 0.4572)
		(layer "F.Cu")
		(net "GND")
	)
	(segment
		(start 249.599958 -52.999894)
		(end 250.09983 -53.499766)
		(width 0.4572)
		(layer "F.Cu")
		(net "GND")
	)
	(segment
		(start 38.504876 -128.484884)
		(end 38.504876 -128.485138)
		(width 0.3556)
		(layer "F.Cu")
		(net "GND")
	)
	(segment
		(start 225.600006 -45.999908)
		(end 225.100134 -45.500036)
		(width 0.4572)
		(layer "F.Cu")
		(net "GND")
	)
	(segment
		(start 218.6432 -2.8956)
		(end 218.6432 -3.060192)
		(width 0.508)
		(layer "F.Cu")
		(net "GND")
	)
	(segment
		(start 234.599988 -53.999892)
		(end 234.100116 -54.499764)
		(width 0.4572)
		(layer "F.Cu")
		(net "GND")
	)
	(segment
		(start 82.100166 -225.54438)
		(end 82.100166 -223.4819)
		(width 0.508)
		(layer "F.Cu")
		(net "GND")
	)
	(segment
		(start 272.50009 -223.482154)
		(end 272.10004 -223.082104)
		(width 0.508)
		(layer "F.Cu")
		(net "GND")
	)
	(segment
		(start 157.88894 -88.82634)
		(end 157.14472 -88.08212)
		(width 0.3048)
		(layer "F.Cu")
		(net "GND")
	)
	(segment
		(start 64.893698 -130.23088)
		(end 65.14211 -130.479292)
		(width 0.508)
		(layer "F.Cu")
		(net "GND")
	)
	(segment
		(start 233.59999 -54.99989)
		(end 233.100118 -55.499762)
		(width 0.4572)
		(layer "F.Cu")
		(net "GND")
	)
	(segment
		(start 227.600002 -37.999924)
		(end 227.10013 -37.500052)
		(width 0.4572)
		(layer "F.Cu")
		(net "GND")
	)
	(segment
		(start 20.103338 -108.260134)
		(end 19.602704 -107.7595)
		(width 0.508)
		(layer "F.Cu")
		(net "GND")
	)
	(segment
		(start 246.599964 -57.999884)
		(end 247.099836 -58.499756)
		(width 0.4572)
		(layer "F.Cu")
		(net "GND")
	)
	(segment
		(start 39.705026 -131.28498)
		(end 40.104822 -131.684776)
		(width 0.3556)
		(layer "F.Cu")
		(net "GND")
	)
	(segment
		(start 291.700204 -223.482408)
		(end 291.2999 -223.082104)
		(width 0.508)
		(layer "F.Cu")
		(net "GND")
	)
	(segment
		(start 79.007208 -56.312308)
		(end 78.0542 -56.312308)
		(width 0.508)
		(layer "F.Cu")
		(net "GND")
	)
	(segment
		(start 174.500032 -223.482154)
		(end 174.099982 -223.082104)
		(width 0.508)
		(layer "F.Cu")
		(net "GND")
	)
	(segment
		(start 231.599994 -64.99987)
		(end 231.100122 -65.499742)
		(width 0.4572)
		(layer "F.Cu")
		(net "GND")
	)
	(segment
		(start 36.967922 -157.179772)
		(end 36.568126 -156.779976)
		(width 0.3556)
		(layer "F.Cu")
		(net "GND")
	)
	(segment
		(start 230.505 -93.0148)
		(end 230.505 -93.472)
		(width 0.508)
		(layer "F.Cu")
		(net "GND")
	)
	(segment
		(start 9.779 -73.3806)
		(end 9.779 -74.7014)
		(width 0.508)
		(layer "F.Cu")
		(net "GND")
	)
	(segment
		(start 251.599954 -60.999878)
		(end 252.099826 -61.49975)
		(width 0.4572)
		(layer "F.Cu")
		(net "GND")
	)
	(segment
		(start 37.300154 -223.990154)
		(end 37.300154 -225.54438)
		(width 0.508)
		(layer "F.Cu")
		(net "GND")
	)
	(segment
		(start 238.59998 -60.999878)
		(end 238.100108 -61.49975)
		(width 0.4572)
		(layer "F.Cu")
		(net "GND")
	)
	(segment
		(start 203.9239 -27.0002)
		(end 203.0984 -27.0002)
		(width 0.508)
		(layer "F.Cu")
		(net "GND")
	)
	(segment
		(start 255.599946 -36.999926)
		(end 256.099818 -36.500054)
		(width 0.4572)
		(layer "F.Cu")
		(net "GND")
	)
	(segment
		(start 328.41692 -90.2462)
		(end 329.1078 -90.2462)
		(width 0.3048)
		(layer "F.Cu")
		(net "GND")
	)
	(segment
		(start 279.700228 -225.54438)
		(end 279.700228 -223.4819)
		(width 0.508)
		(layer "F.Cu")
		(net "GND")
	)
	(segment
		(start 140.10005 -223.482154)
		(end 139.7 -223.082104)
		(width 0.508)
		(layer "F.Cu")
		(net "GND")
	)
	(segment
		(start 223.60001 -50.999898)
		(end 223.100138 -51.49977)
		(width 0.4572)
		(layer "F.Cu")
		(net "GND")
	)
	(segment
		(start 83.745832 -74.938636)
		(end 83.745832 -74.230992)
		(width 0.508)
		(layer "F.Cu")
		(net "GND")
	)
	(segment
		(start 65.14211 -130.479292)
		(end 66.003678 -130.479292)
		(width 0.508)
		(layer "F.Cu")
		(net "GND")
	)
	(segment
		(start 73.914508 -124.4981)
		(end 73.914508 -126.289308)
		(width 0.381)
		(layer "F.Cu")
		(net "GND")
	)
	(segment
		(start 36.10483 -131.684776)
		(end 36.505134 -132.08508)
		(width 0.3556)
		(layer "F.Cu")
		(net "GND")
	)
	(segment
		(start 236.599984 -45.999908)
		(end 236.100112 -45.500036)
		(width 0.4572)
		(layer "F.Cu")
		(net "GND")
	)
	(segment
		(start 255.599946 -47.999904)
		(end 256.099818 -48.499776)
		(width 0.4572)
		(layer "F.Cu")
		(net "GND")
	)
	(segment
		(start 248.59996 -60.999878)
		(end 249.099832 -61.49975)
		(width 0.4572)
		(layer "F.Cu")
		(net "GND")
	)
	(segment
		(start 73.914508 -126.289308)
		(end 74.041 -126.4158)
		(width 0.381)
		(layer "F.Cu")
		(net "GND")
	)
	(segment
		(start 54.099968 -223.482154)
		(end 54.500018 -223.082104)
		(width 0.508)
		(layer "F.Cu")
		(net "GND")
	)
	(segment
		(start 39.304722 -130.88493)
		(end 39.704772 -131.28498)
		(width 0.3556)
		(layer "F.Cu")
		(net "GND")
	)
	(segment
		(start 54.864 -120.269)
		(end 55.470298 -120.269)
		(width 0.508)
		(layer "F.Cu")
		(net "GND")
	)
	(segment
		(start 199.300084 -225.54438)
		(end 199.300084 -223.482154)
		(width 0.508)
		(layer "F.Cu")
		(net "GND")
	)
	(segment
		(start 75.625452 -148.12391)
		(end 76.41209 -148.12391)
		(width 0.508)
		(layer "F.Cu")
		(net "GND")
	)
	(segment
		(start 194.0306 -31.8262)
		(end 193.6496 -32.2072)
		(width 0.508)
		(layer "F.Cu")
		(net "GND")
	)
	(segment
		(start 57.589166 -36.664646)
		(end 56.8325 -35.90798)
		(width 0.508)
		(layer "F.Cu")
		(net "GND")
	)
	(segment
		(start 100.50018 -223.4819)
		(end 100.899976 -223.082104)
		(width 0.508)
		(layer "F.Cu")
		(net "GND")
	)
	(segment
		(start 17.3355 -105.918)
		(end 18.422366 -105.918)
		(width 0.508)
		(layer "F.Cu")
		(net "GND")
	)
	(segment
		(start 160.10001 -225.54438)
		(end 160.10001 -223.482154)
		(width 0.508)
		(layer "F.Cu")
		(net "GND")
	)
	(segment
		(start 282.10002 -225.54438)
		(end 282.10002 -223.482154)
		(width 0.508)
		(layer "F.Cu")
		(net "GND")
	)
	(segment
		(start 71.7042 -126.8603)
		(end 72.460358 -126.8603)
		(width 0.4064)
		(layer "F.Cu")
		(net "GND")
	)
	(segment
		(start 133.034786 -84.401914)
		(end 132.641086 -84.795614)
		(width 0.508)
		(layer "F.Cu")
		(net "GND")
	)
	(segment
		(start 292.50005 -223.482154)
		(end 292.9001 -223.082104)
		(width 0.508)
		(layer "F.Cu")
		(net "GND")
	)
	(segment
		(start 25.7429 -49.4284)
		(end 26.4414 -49.4284)
		(width 0.508)
		(layer "F.Cu")
		(net "GND")
	)
	(segment
		(start 245.599966 -32.999934)
		(end 246.099838 -32.500062)
		(width 0.4572)
		(layer "F.Cu")
		(net "GND")
	)
	(segment
		(start 183.300116 -223.404684)
		(end 183.642 -223.0628)
		(width 0.508)
		(layer "F.Cu")
		(net "GND")
	)
	(segment
		(start 267.8811 -10.305034)
		(end 267.8811 -11.2776)
		(width 0.508)
		(layer "F.Cu")
		(net "GND")
	)
	(segment
		(start 18.06067 -142.24)
		(end 18.034 -142.21333)
		(width 0.508)
		(layer "F.Cu")
		(net "GND")
	)
	(segment
		(start 11.256772 -67.8815)
		(end 11.256772 -67.8942)
		(width 0.508)
		(layer "F.Cu")
		(net "GND")
	)
	(segment
		(start 124.848112 -40.672512)
		(end 125.5522 -41.3766)
		(width 0.508)
		(layer "F.Cu")
		(net "GND")
	)
	(segment
		(start 186.279028 1.152144)
		(end 186.279028 0.982726)
		(width 0.508)
		(layer "F.Cu")
		(net "GND")
	)
	(segment
		(start 238.59998 -56.999886)
		(end 238.100108 -57.499758)
		(width 0.4572)
		(layer "F.Cu")
		(net "GND")
	)
	(segment
		(start 36.745418 -86.673182)
		(end 36.745418 -85.63356)
		(width 0.508)
		(layer "F.Cu")
		(net "GND")
	)
	(segment
		(start 27.0129 -79.2988)
		(end 26.5176 -78.8035)
		(width 0.508)
		(layer "F.Cu")
		(net "GND")
	)
	(segment
		(start 211.429854 -11.833098)
		(end 211.624418 -12.027662)
		(width 0.2032)
		(layer "F.Cu")
		(net "GND")
	)
	(segment
		(start 70.1802 -165.5318)
		(end 71.3994 -165.5318)
		(width 0.508)
		(layer "F.Cu")
		(net "GND")
	)
	(segment
		(start 243.59997 -40.999918)
		(end 244.099842 -40.500046)
		(width 0.4572)
		(layer "F.Cu")
		(net "GND")
	)
	(segment
		(start 334.10017 -225.54438)
		(end 334.10017 -223.482408)
		(width 0.508)
		(layer "F.Cu")
		(net "GND")
	)
	(segment
		(start 154.7114 -87.4268)
		(end 155.194 -87.9094)
		(width 0.508)
		(layer "F.Cu")
		(net "GND")
	)
	(segment
		(start 37.374322 -151.176736)
		(end 36.971224 -151.579834)
		(width 0.3556)
		(layer "F.Cu")
		(net "GND")
	)
	(segment
		(start 166.625524 -52.055268)
		(end 166.625524 -54.100476)
		(width 0.508)
		(layer "F.Cu")
		(net "GND")
	)
	(segment
		(start 170.181524 -53.251608)
		(end 170.465496 -53.53558)
		(width 0.508)
		(layer "F.Cu")
		(net "GND")
	)
	(segment
		(start 321.300094 -225.54438)
		(end 321.300094 -223.482154)
		(width 0.508)
		(layer "F.Cu")
		(net "GND")
	)
	(segment
		(start 246.599964 -51.999896)
		(end 247.099836 -52.499768)
		(width 0.4572)
		(layer "F.Cu")
		(net "GND")
	)
	(segment
		(start 150.50008 -223.482154)
		(end 150.90013 -223.082104)
		(width 0.508)
		(layer "F.Cu")
		(net "GND")
	)
	(segment
		(start 230.599996 -53.999892)
		(end 230.100124 -54.499764)
		(width 0.4572)
		(layer "F.Cu")
		(net "GND")
	)
	(segment
		(start 12.322048 -88.261952)
		(end 12.322048 -90.547952)
		(width 0.508)
		(layer "F.Cu")
		(net "GND")
	)
	(segment
		(start 63.530226 -147.670774)
		(end 63.119 -148.082)
		(width 0.508)
		(layer "F.Cu")
		(net "GND")
	)
	(segment
		(start 157.2768 -93.726)
		(end 157.8102 -93.1926)
		(width 0.3048)
		(layer "F.Cu")
		(net "GND")
	)
	(segment
		(start 57.792874 -18.691606)
		(end 57.539382 -18.438114)
		(width 0.508)
		(layer "F.Cu")
		(net "GND")
	)
	(segment
		(start 66.100198 -225.54438)
		(end 66.100198 -223.4819)
		(width 0.508)
		(layer "F.Cu")
		(net "GND")
	)
	(segment
		(start 266.900152 -223.482154)
		(end 267.300202 -223.082104)
		(width 0.508)
		(layer "F.Cu")
		(net "GND")
	)
	(segment
		(start 235.599986 -55.999888)
		(end 235.100114 -56.49976)
		(width 0.4572)
		(layer "F.Cu")
		(net "GND")
	)
	(segment
		(start 68.326 -126.04496)
		(end 68.21043 -125.92939)
		(width 0.4064)
		(layer "F.Cu")
		(net "GND")
	)
	(segment
		(start 288.500058 -225.54438)
		(end 288.500058 -223.482154)
		(width 0.508)
		(layer "F.Cu")
		(net "GND")
	)
	(segment
		(start 276.500082 -225.54438)
		(end 276.500082 -223.482154)
		(width 0.508)
		(layer "F.Cu")
		(net "GND")
	)
	(segment
		(start 224.4344 -188.4172)
		(end 224.8916 -188.8744)
		(width 0.508)
		(layer "F.Cu")
		(net "GND")
	)
	(segment
		(start 8.001 -93.1926)
		(end 6.223 -93.1926)
		(width 0.508)
		(layer "F.Cu")
		(net "GND")
	)
	(segment
		(start 237.599982 -52.999894)
		(end 237.10011 -53.499766)
		(width 0.4572)
		(layer "F.Cu")
		(net "GND")
	)
	(segment
		(start 245.599966 -42.999914)
		(end 246.099838 -42.500042)
		(width 0.4572)
		(layer "F.Cu")
		(net "GND")
	)
	(segment
		(start 54.5211 -131.8006)
		(end 54.590188 -131.8006)
		(width 0.508)
		(layer "F.Cu")
		(net "GND")
	)
	(segment
		(start 225.600006 -49.9999)
		(end 225.100134 -50.499772)
		(width 0.4572)
		(layer "F.Cu")
		(net "GND")
	)
	(segment
		(start 71.515478 -223.29775)
		(end 71.299832 -223.082104)
		(width 0.508)
		(layer "F.Cu")
		(net "GND")
	)
	(segment
		(start 40.500046 -223.082104)
		(end 40.500046 -225.54438)
		(width 0.508)
		(layer "F.Cu")
		(net "GND")
	)
	(segment
		(start 254.599948 -62.999874)
		(end 255.09982 -63.499746)
		(width 0.4572)
		(layer "F.Cu")
		(net "GND")
	)
	(segment
		(start 47.700184 -225.54438)
		(end 47.700184 -223.645984)
		(width 0.508)
		(layer "F.Cu")
		(net "GND")
	)
	(segment
		(start 251.599954 -31.999936)
		(end 252.099826 -31.500064)
		(width 0.4572)
		(layer "F.Cu")
		(net "GND")
	)
	(segment
		(start 40.967914 -157.179772)
		(end 41.362122 -156.785564)
		(width 0.3556)
		(layer "F.Cu")
		(net "GND")
	)
	(segment
		(start 36.505134 -132.08508)
		(end 36.505134 -132.084572)
		(width 0.3556)
		(layer "F.Cu")
		(net "GND")
	)
	(segment
		(start 60.028074 -58.50382)
		(end 60.028074 -57.818274)
		(width 0.508)
		(layer "F.Cu")
		(net "GND")
	)
	(segment
		(start 46.50486 -131.684776)
		(end 46.50486 -131.684522)
		(width 0.3556)
		(layer "F.Cu")
		(net "GND")
	)
	(segment
		(start 149.1234 -59.6392)
		(end 148.682456 -59.198256)
		(width 0.508)
		(layer "F.Cu")
		(net "GND")
	)
	(segment
		(start 117.954806 -81.66354)
		(end 117.192806 -80.90154)
		(width 0.508)
		(layer "F.Cu")
		(net "GND")
	)
	(segment
		(start 18.6182 -109.347)
		(end 19.618452 -109.347)
		(width 0.508)
		(layer "F.Cu")
		(net "GND")
	)
	(segment
		(start 255.599946 -40.999918)
		(end 256.099818 -40.500046)
		(width 0.4572)
		(layer "F.Cu")
		(net "GND")
	)
	(segment
		(start 124.944124 -195.998592)
		(end 124.944124 -195.206874)
		(width 0.508)
		(layer "F.Cu")
		(net "GND")
	)
	(segment
		(start 225.600006 -54.99989)
		(end 225.100134 -55.499762)
		(width 0.4572)
		(layer "F.Cu")
		(net "GND")
	)
	(segment
		(start 248.59996 -56.999886)
		(end 249.099832 -57.499758)
		(width 0.4572)
		(layer "F.Cu")
		(net "GND")
	)
	(segment
		(start 249.599958 -65.999868)
		(end 250.09983 -66.49974)
		(width 0.4572)
		(layer "F.Cu")
		(net "GND")
	)
	(segment
		(start 247.599962 -42.999914)
		(end 248.099834 -42.500042)
		(width 0.4572)
		(layer "F.Cu")
		(net "GND")
	)
	(segment
		(start 39.367714 -157.179772)
		(end 38.967918 -156.779976)
		(width 0.3556)
		(layer "F.Cu")
		(net "GND")
	)
	(segment
		(start 250.599956 -30.999938)
		(end 251.099828 -30.500066)
		(width 0.4572)
		(layer "F.Cu")
		(net "GND")
	)
	(segment
		(start 30.968188 -156.779976)
		(end 31.367984 -157.179772)
		(width 0.3556)
		(layer "F.Cu")
		(net "GND")
	)
	(segment
		(start 250.599956 -62.999874)
		(end 251.099828 -63.499746)
		(width 0.4572)
		(layer "F.Cu")
		(net "GND")
	)
	(segment
		(start 38.504876 -130.08483)
		(end 38.50513 -130.08483)
		(width 0.3556)
		(layer "F.Cu")
		(net "GND")
	)
	(segment
		(start 36.105084 -130.88493)
		(end 36.90493 -131.684776)
		(width 0.3556)
		(layer "F.Cu")
		(net "GND")
	)
	(segment
		(start 76.581 -123.7107)
		(end 76.581 -124.206)
		(width 0.508)
		(layer "F.Cu")
		(net "GND")
	)
	(segment
		(start 53.2511 -196.55536)
		(end 54.65064 -196.55536)
		(width 0.381)
		(layer "F.Cu")
		(net "GND")
	)
	(segment
		(start 230.599996 -45.999908)
		(end 230.100124 -45.500036)
		(width 0.4572)
		(layer "F.Cu")
		(net "GND")
	)
	(segment
		(start 38.967918 -155.98013)
		(end 38.568122 -156.379926)
		(width 0.3556)
		(layer "F.Cu")
		(net "GND")
	)
	(segment
		(start 39.304722 -129.284984)
		(end 39.704772 -129.685034)
		(width 0.3556)
		(layer "F.Cu")
		(net "GND")
	)
	(segment
		(start 10.8966 -72.263)
		(end 9.779 -73.3806)
		(width 0.508)
		(layer "F.Cu")
		(net "GND")
	)
	(segment
		(start 237.599982 -32.999934)
		(end 237.10011 -32.500062)
		(width 0.4572)
		(layer "F.Cu")
		(net "GND")
	)
	(segment
		(start 232.599992 -48.999902)
		(end 232.10012 -49.499774)
		(width 0.4572)
		(layer "F.Cu")
		(net "GND")
	)
	(segment
		(start 62.900052 -225.54438)
		(end 62.900052 -223.4819)
		(width 0.508)
		(layer "F.Cu")
		(net "GND")
	)
	(segment
		(start 223.60001 -59.99988)
		(end 223.100138 -60.499752)
		(width 0.4572)
		(layer "F.Cu")
		(net "GND")
	)
	(segment
		(start 237.599982 -59.99988)
		(end 237.10011 -60.499752)
		(width 0.4572)
		(layer "F.Cu")
		(net "GND")
	)
	(segment
		(start 226.53244 -13.081)
		(end 226.3521 -13.081)
		(width 0.508)
		(layer "F.Cu")
		(net "GND")
	)
	(segment
		(start 322.100194 -223.482154)
		(end 322.500244 -223.082104)
		(width 0.508)
		(layer "F.Cu")
		(net "GND")
	)
	(segment
		(start 250.27001 -3.59664)
		(end 250.27001 -3.66395)
		(width 0.508)
		(layer "F.Cu")
		(net "GND")
	)
	(segment
		(start 73.7108 -179.4002)
		(end 72.8726 -179.4002)
		(width 0.508)
		(layer "F.Cu")
		(net "GND")
	)
	(segment
		(start 235.599986 -50.999898)
		(end 235.100114 -51.49977)
		(width 0.4572)
		(layer "F.Cu")
		(net "GND")
	)
	(segment
		(start 231.599994 -60.999878)
		(end 231.100122 -61.49975)
		(width 0.4572)
		(layer "F.Cu")
		(net "GND")
	)
	(segment
		(start 227.600002 -55.999888)
		(end 227.10013 -56.49976)
		(width 0.4572)
		(layer "F.Cu")
		(net "GND")
	)
	(segment
		(start 309.300118 -225.54438)
		(end 309.300118 -223.031304)
		(width 0.508)
		(layer "F.Cu")
		(net "GND")
	)
	(segment
		(start 275.700236 -225.54438)
		(end 275.700236 -223.482408)
		(width 0.508)
		(layer "F.Cu")
		(net "GND")
	)
	(segment
		(start 183.300116 -225.54438)
		(end 183.300116 -223.404684)
		(width 0.508)
		(layer "F.Cu")
		(net "GND")
	)
	(segment
		(start 116.865146 -53.591206)
		(end 116.456206 -53.591206)
		(width 0.508)
		(layer "F.Cu")
		(net "GND")
	)
	(segment
		(start 36.90493 -122.0851)
		(end 37.30498 -122.48515)
		(width 0.3556)
		(layer "F.Cu")
		(net "GND")
	)
	(segment
		(start 232.599992 -60.999878)
		(end 232.10012 -61.49975)
		(width 0.4572)
		(layer "F.Cu")
		(net "GND")
	)
	(segment
		(start 222.600012 -62.999874)
		(end 222.10014 -63.499746)
		(width 0.4572)
		(layer "F.Cu")
		(net "GND")
	)
	(segment
		(start 38.50513 -130.08483)
		(end 38.904926 -129.685034)
		(width 0.3556)
		(layer "F.Cu")
		(net "GND")
	)
	(segment
		(start 225.600006 -58.999882)
		(end 225.100134 -59.499754)
		(width 0.4572)
		(layer "F.Cu")
		(net "GND")
	)
	(segment
		(start 229.6922 -92.202)
		(end 230.505 -93.0148)
		(width 0.508)
		(layer "F.Cu")
		(net "GND")
	)
	(segment
		(start 28.524454 -162.162744)
		(end 28.524454 -162.734244)
		(width 0.508)
		(layer "F.Cu")
		(net "GND")
	)
	(segment
		(start 242.599972 -58.999882)
		(end 243.099844 -59.499754)
		(width 0.4572)
		(layer "F.Cu")
		(net "GND")
	)
	(segment
		(start 232.599992 -50.999898)
		(end 232.10012 -51.49977)
		(width 0.4572)
		(layer "F.Cu")
		(net "GND")
	)
	(segment
		(start 38.1 -162.687)
		(end 38.117526 -162.687)
		(width 0.508)
		(layer "F.Cu")
		(net "GND")
	)
	(segment
		(start 224.600008 -41.999916)
		(end 224.100136 -41.500044)
		(width 0.4572)
		(layer "F.Cu")
		(net "GND")
	)
	(segment
		(start 13.8938 -176.32045)
		(end 13.0683 -176.32045)
		(width 0.508)
		(layer "F.Cu")
		(net "GND")
	)
	(segment
		(start 244.599968 -60.999878)
		(end 245.09984 -61.49975)
		(width 0.4572)
		(layer "F.Cu")
		(net "GND")
	)
	(segment
		(start 237.599982 -42.999914)
		(end 237.10011 -42.500042)
		(width 0.4572)
		(layer "F.Cu")
		(net "GND")
	)
	(segment
		(start 25.970992 -103.790496)
		(end 25.629616 -104.131872)
		(width 0.4064)
		(layer "F.Cu")
		(net "GND")
	)
	(segment
		(start 234.599988 -60.999878)
		(end 234.100116 -61.49975)
		(width 0.4572)
		(layer "F.Cu")
		(net "GND")
	)
	(segment
		(start 229.599998 -55.999888)
		(end 229.100126 -56.49976)
		(width 0.4572)
		(layer "F.Cu")
		(net "GND")
	)
	(segment
		(start 17.1704 -52.0192)
		(end 17.1704 -53.213)
		(width 0.508)
		(layer "F.Cu")
		(net "GND")
	)
	(segment
		(start 334.10017 -223.482408)
		(end 333.699866 -223.082104)
		(width 0.508)
		(layer "F.Cu")
		(net "GND")
	)
	(segment
		(start 156.77007 -88.856058)
		(end 156.67101 -88.856058)
		(width 0.3048)
		(layer "F.Cu")
		(net "GND")
	)
	(segment
		(start 291.24275 -58.1025)
		(end 292.1635 -58.1025)
		(width 0.508)
		(layer "F.Cu")
		(net "GND")
	)
	(segment
		(start 37.30498 -132.08508)
		(end 37.704776 -132.484876)
		(width 0.3556)
		(layer "F.Cu")
		(net "GND")
	)
	(segment
		(start 139.8905 -35.2552)
		(end 139.8905 -34.949638)
		(width 0.508)
		(layer "F.Cu")
		(net "GND")
	)
	(segment
		(start 19.4183 -176.5681)
		(end 19.4183 -177.5841)
		(width 0.508)
		(layer "F.Cu")
		(net "GND")
	)
	(segment
		(start 240.599976 -45.999908)
		(end 241.099848 -45.500036)
		(width 0.4572)
		(layer "F.Cu")
		(net "GND")
	)
	(segment
		(start 228.43236 -80.90154)
		(end 228.43236 -82.00136)
		(width 0.3048)
		(layer "F.Cu")
		(net "GND")
	)
	(segment
		(start 45.705014 -131.684776)
		(end 46.50486 -130.88493)
		(width 0.3556)
		(layer "F.Cu")
		(net "GND")
	)
	(segment
		(start 10.541 -67.3735)
		(end 10.748772 -67.3735)
		(width 0.508)
		(layer "F.Cu")
		(net "GND")
	)
	(segment
		(start 81.300066 -223.482408)
		(end 80.899762 -223.082104)
		(width 0.508)
		(layer "F.Cu")
		(net "GND")
	)
	(segment
		(start 25.970992 -103.007668)
		(end 25.970992 -103.790496)
		(width 0.4064)
		(layer "F.Cu")
		(net "GND")
	)
	(segment
		(start 224.600008 -57.999884)
		(end 224.100136 -58.499756)
		(width 0.4572)
		(layer "F.Cu")
		(net "GND")
	)
	(segment
		(start 46.186852 -31.193994)
		(end 46.161452 -31.168594)
		(width 0.508)
		(layer "F.Cu")
		(net "GND")
	)
	(segment
		(start 72.771 -196.1515)
		(end 71.766938 -196.1515)
		(width 0.508)
		(layer "F.Cu")
		(net "GND")
	)
	(segment
		(start 301.300134 -223.482154)
		(end 301.700184 -223.082104)
		(width 0.508)
		(layer "F.Cu")
		(net "GND")
	)
	(segment
		(start 137.034778 -84.019898)
		(end 137.034778 -81.844642)
		(width 0.508)
		(layer "F.Cu")
		(net "GND")
	)
	(segment
		(start 224.600008 -35.999928)
		(end 224.100136 -35.500056)
		(width 0.4572)
		(layer "F.Cu")
		(net "GND")
	)
	(segment
		(start 144.100042 -223.482154)
		(end 144.500092 -223.082104)
		(width 0.508)
		(layer "F.Cu")
		(net "GND")
	)
	(segment
		(start 68.326 -126.6952)
		(end 67.649344 -126.6952)
		(width 0.4064)
		(layer "F.Cu")
		(net "GND")
	)
	(segment
		(start 223.60001 -41.999916)
		(end 223.100138 -41.500044)
		(width 0.4572)
		(layer "F.Cu")
		(net "GND")
	)
	(segment
		(start 285.496 -57.15)
		(end 286.131 -56.515)
		(width 0.508)
		(layer "F.Cu")
		(net "GND")
	)
	(segment
		(start 232.599992 -56.999886)
		(end 232.10012 -57.499758)
		(width 0.4572)
		(layer "F.Cu")
		(net "GND")
	)
	(segment
		(start 135.769604 -61.905134)
		(end 135.758174 -61.893704)
		(width 0.508)
		(layer "F.Cu")
		(net "GND")
	)
	(segment
		(start 233.59999 -42.999914)
		(end 233.100118 -42.500042)
		(width 0.4572)
		(layer "F.Cu")
		(net "GND")
	)
	(segment
		(start 222.0722 -3.98145)
		(end 221.8055 -3.71475)
		(width 0.508)
		(layer "F.Cu")
		(net "GND")
	)
	(segment
		(start 256.599944 -53.999892)
		(end 257.099816 -54.499764)
		(width 0.4572)
		(layer "F.Cu")
		(net "GND")
	)
	(segment
		(start 192.3923 -27.7622)
		(end 191.7954 -27.7622)
		(width 0.508)
		(layer "F.Cu")
		(net "GND")
	)
	(segment
		(start 36.905184 -131.684776)
		(end 37.30498 -131.28498)
		(width 0.3556)
		(layer "F.Cu")
		(net "GND")
	)
	(segment
		(start 256.599944 -41.999916)
		(end 257.099816 -41.500044)
		(width 0.4572)
		(layer "F.Cu")
		(net "GND")
	)
	(segment
		(start 251.599954 -44.99991)
		(end 252.099826 -44.500038)
		(width 0.4572)
		(layer "F.Cu")
		(net "GND")
	)
	(segment
		(start 135.361934 -74.820018)
		(end 135.361934 -75.802744)
		(width 0.508)
		(layer "F.Cu")
		(net "GND")
	)
	(segment
		(start 12.3063 -81.1784)
		(end 12.3063 -81.972912)
		(width 0.508)
		(layer "F.Cu")
		(net "GND")
	)
	(segment
		(start 244.599968 -58.999882)
		(end 245.09984 -59.499754)
		(width 0.4572)
		(layer "F.Cu")
		(net "GND")
	)
	(segment
		(start 322.100194 -225.54438)
		(end 322.100194 -223.482154)
		(width 0.508)
		(layer "F.Cu")
		(net "GND")
	)
	(segment
		(start 19.602704 -107.7595)
		(end 18.415 -107.7595)
		(width 0.508)
		(layer "F.Cu")
		(net "GND")
	)
	(segment
		(start 151.765 -89.4588)
		(end 151.765 -89.4207)
		(width 0.508)
		(layer "F.Cu")
		(net "GND")
	)
	(segment
		(start 229.599998 -57.999884)
		(end 229.100126 -58.499756)
		(width 0.4572)
		(layer "F.Cu")
		(net "GND")
	)
	(segment
		(start 39.304722 -131.684776)
		(end 40.104822 -132.484876)
		(width 0.3556)
		(layer "F.Cu")
		(net "GND")
	)
	(segment
		(start 24.852122 -94.286578)
		(end 24.852122 -93.534484)
		(width 0.508)
		(layer "F.Cu")
		(net "GND")
	)
	(segment
		(start 221.361 -7.874)
		(end 221.360238 -7.874762)
		(width 0.508)
		(layer "F.Cu")
		(net "GND")
	)
	(segment
		(start 140.10005 -225.54438)
		(end 140.10005 -223.482154)
		(width 0.508)
		(layer "F.Cu")
		(net "GND")
	)
	(segment
		(start 248.59996 -47.999904)
		(end 249.099832 -48.499776)
		(width 0.4572)
		(layer "F.Cu")
		(net "GND")
	)
	(segment
		(start 241.599974 -40.999918)
		(end 242.099846 -40.500046)
		(width 0.4572)
		(layer "F.Cu")
		(net "GND")
	)
	(segment
		(start 76.581 -124.206)
		(end 77.089 -124.714)
		(width 0.508)
		(layer "F.Cu")
		(net "GND")
	)
	(segment
		(start 54.099968 -225.54438)
		(end 54.099968 -223.482154)
		(width 0.508)
		(layer "F.Cu")
		(net "GND")
	)
	(segment
		(start 36.90493 -128.485138)
		(end 37.704776 -129.284984)
		(width 0.3556)
		(layer "F.Cu")
		(net "GND")
	)
	(segment
		(start 245.599966 -52.999894)
		(end 246.099838 -53.499766)
		(width 0.4572)
		(layer "F.Cu")
		(net "GND")
	)
	(segment
		(start 232.599992 -41.999916)
		(end 232.10012 -41.500044)
		(width 0.4572)
		(layer "F.Cu")
		(net "GND")
	)
	(segment
		(start 129.669286 -86.116414)
		(end 128.983486 -85.430614)
		(width 0.508)
		(layer "F.Cu")
		(net "GND")
	)
	(segment
		(start 229.5525 -89.916)
		(end 230.886 -89.916)
		(width 0.508)
		(layer "F.Cu")
		(net "GND")
	)
	(segment
		(start 250.599956 -50.999898)
		(end 251.099828 -51.49977)
		(width 0.4572)
		(layer "F.Cu")
		(net "GND")
	)
	(segment
		(start 53.34 -192.913)
		(end 53.34 -191.897)
		(width 0.508)
		(layer "F.Cu")
		(net "GND")
	)
	(segment
		(start 32.104838 -137.284968)
		(end 32.105092 -137.284968)
		(width 0.3556)
		(layer "F.Cu")
		(net "GND")
	)
	(segment
		(start 335.8896 -170.0657)
		(end 336.8675 -170.0657)
		(width 0.508)
		(layer "F.Cu")
		(net "GND")
	)
	(segment
		(start 159.385 -94.996)
		(end 159.131 -94.742)
		(width 0.508)
		(layer "F.Cu")
		(net "GND")
	)
	(segment
		(start 71.515478 -224.118678)
		(end 71.515478 -223.29775)
		(width 0.508)
		(layer "F.Cu")
		(net "GND")
	)
	(segment
		(start 266.900152 -225.54438)
		(end 266.900152 -223.482154)
		(width 0.508)
		(layer "F.Cu")
		(net "GND")
	)
	(segment
		(start 276.500082 -223.482154)
		(end 276.900132 -223.082104)
		(width 0.508)
		(layer "F.Cu")
		(net "GND")
	)
	(segment
		(start 236.599984 -47.999904)
		(end 236.100112 -48.499776)
		(width 0.4572)
		(layer "F.Cu")
		(net "GND")
	)
	(segment
		(start 243.59997 -37.999924)
		(end 244.099842 -37.500052)
		(width 0.4572)
		(layer "F.Cu")
		(net "GND")
	)
	(segment
		(start 152.1714 -88.5698)
		(end 152.14981 -88.54821)
		(width 0.3048)
		(layer "F.Cu")
		(net "GND")
	)
	(segment
		(start 246.599964 -37.999924)
		(end 247.099836 -37.500052)
		(width 0.4572)
		(layer "F.Cu")
		(net "GND")
	)
	(segment
		(start 241.599974 -62.999874)
		(end 242.099846 -63.499746)
		(width 0.4572)
		(layer "F.Cu")
		(net "GND")
	)
	(segment
		(start 87.700104 -223.482408)
		(end 87.2998 -223.082104)
		(width 0.508)
		(layer "F.Cu")
		(net "GND")
	)
	(segment
		(start 67.8942 -75.3745)
		(end 67.8942 -76.3524)
		(width 0.508)
		(layer "F.Cu")
		(net "GND")
	)
	(segment
		(start 224.600008 -32.999934)
		(end 224.100136 -32.500062)
		(width 0.4572)
		(layer "F.Cu")
		(net "GND")
	)
	(segment
		(start 78.744064 -185.335926)
		(end 78.744064 -185.367422)
		(width 0.3048)
		(layer "F.Cu")
		(net "GND")
	)
	(segment
		(start 50.038 -148.1455)
		(end 49.657 -148.1455)
		(width 0.508)
		(layer "F.Cu")
		(net "GND")
	)
	(segment
		(start 134.5438 -210.7438)
		(end 134.5438 -211.1756)
		(width 0.508)
		(layer "F.Cu")
		(net "GND")
	)
	(segment
		(start 240.599976 -49.9999)
		(end 241.099848 -50.499772)
		(width 0.4572)
		(layer "F.Cu")
		(net "GND")
	)
	(segment
		(start 251.599954 -48.999902)
		(end 252.099826 -49.499774)
		(width 0.4572)
		(layer "F.Cu")
		(net "GND")
	)
	(segment
		(start 35.571938 -96.5327)
		(end 35.571938 -97.801938)
		(width 0.3048)
		(layer "F.Cu")
		(net "GND")
	)
	(segment
		(start 36.967922 -150.779988)
		(end 36.977574 -150.779988)
		(width 0.3048)
		(layer "F.Cu")
		(net "GND")
	)
	(segment
		(start 249.599958 -63.999872)
		(end 250.09983 -64.499744)
		(width 0.4572)
		(layer "F.Cu")
		(net "GND")
	)
	(segment
		(start 128.404112 -41.750488)
		(end 128.2954 -41.8592)
		(width 0.508)
		(layer "F.Cu")
		(net "GND")
	)
	(segment
		(start 227.600002 -39.99992)
		(end 227.10013 -39.500048)
		(width 0.4572)
		(layer "F.Cu")
		(net "GND")
	)
	(segment
		(start 55.6387 -130.4925)
		(end 55.3212 -130.175)
		(width 0.508)
		(layer "F.Cu")
		(net "GND")
	)
	(segment
		(start 245.599966 -48.999902)
		(end 246.099838 -49.499774)
		(width 0.4572)
		(layer "F.Cu")
		(net "GND")
	)
	(segment
		(start 146.500088 -223.482154)
		(end 146.100038 -223.082104)
		(width 0.508)
		(layer "F.Cu")
		(net "GND")
	)
	(segment
		(start 239.599978 -59.99988)
		(end 239.100106 -60.499752)
		(width 0.4572)
		(layer "F.Cu")
		(net "GND")
	)
	(segment
		(start 285.300166 -223.482408)
		(end 284.899862 -223.082104)
		(width 0.508)
		(layer "F.Cu")
		(net "GND")
	)
	(segment
		(start 11.395964 -97.613978)
		(end 11.395964 -96.173036)
		(width 0.508)
		(layer "F.Cu")
		(net "GND")
	)
	(segment
		(start 250.599956 -47.999904)
		(end 251.099828 -48.499776)
		(width 0.4572)
		(layer "F.Cu")
		(net "GND")
	)
	(segment
		(start 291.700204 -225.54438)
		(end 291.700204 -223.482408)
		(width 0.508)
		(layer "F.Cu")
		(net "GND")
	)
	(segment
		(start 227.127308 -194.131692)
		(end 227.400612 -193.858388)
		(width 0.3048)
		(layer "F.Cu")
		(net "GND")
	)
	(segment
		(start 229.599998 -51.999896)
		(end 229.100126 -52.499768)
		(width 0.4572)
		(layer "F.Cu")
		(net "GND")
	)
	(segment
		(start 34.06648 -67.13982)
		(end 34.06648 -67.97802)
		(width 0.508)
		(layer "F.Cu")
		(net "GND")
	)
	(segment
		(start 243.59997 -54.99989)
		(end 244.099842 -55.499762)
		(width 0.4572)
		(layer "F.Cu")
		(net "GND")
	)
	(segment
		(start 224.600008 -50.999898)
		(end 224.100136 -51.49977)
		(width 0.4572)
		(layer "F.Cu")
		(net "GND")
	)
	(segment
		(start 36.449 -223.901)
		(end 36.500054 -223.952054)
		(width 0.508)
		(layer "F.Cu")
		(net "GND")
	)
	(segment
		(start 38.504876 -130.08483)
		(end 38.10508 -130.484626)
		(width 0.3556)
		(layer "F.Cu")
		(net "GND")
	)
	(segment
		(start 173.737524 -53.230272)
		(end 174.01921 -53.511958)
		(width 0.508)
		(layer "F.Cu")
		(net "GND")
	)
	(segment
		(start 103.700072 -223.482154)
		(end 104.100122 -223.082104)
		(width 0.508)
		(layer "F.Cu")
		(net "GND")
	)
	(segment
		(start 34.29 -224.028)
		(end 34.100008 -224.217992)
		(width 0.508)
		(layer "F.Cu")
		(net "GND")
	)
	(segment
		(start 32.6898 -192.1002)
		(end 33.5788 -192.1002)
		(width 0.508)
		(layer "F.Cu")
		(net "GND")
	)
	(segment
		(start 136.428734 -85.592666)
		(end 137.034778 -84.986622)
		(width 0.508)
		(layer "F.Cu")
		(net "GND")
	)
	(segment
		(start 106.899964 -225.54438)
		(end 106.899964 -223.482154)
		(width 0.508)
		(layer "F.Cu")
		(net "GND")
	)
	(segment
		(start 38.10508 -131.28498)
		(end 38.504876 -131.684776)
		(width 0.3556)
		(layer "F.Cu")
		(net "GND")
	)
	(segment
		(start 255.599946 -49.9999)
		(end 256.099818 -50.499772)
		(width 0.4572)
		(layer "F.Cu")
		(net "GND")
	)
	(segment
		(start 204.900022 -223.482154)
		(end 204.499972 -223.082104)
		(width 0.508)
		(layer "F.Cu")
		(net "GND")
	)
	(segment
		(start 197.240652 -28.33116)
		(end 197.240652 -27.219148)
		(width 0.3556)
		(layer "F.Cu")
		(net "GND")
	)
	(segment
		(start 146.5072 -95.25)
		(end 146.5072 -93.7768)
		(width 0.508)
		(layer "F.Cu")
		(net "GND")
	)
	(segment
		(start 158.243778 -92.32646)
		(end 158.243778 -92.759022)
		(width 0.3048)
		(layer "F.Cu")
		(net "GND")
	)
	(segment
		(start 130.532886 -86.116414)
		(end 129.669286 -86.116414)
		(width 0.508)
		(layer "F.Cu")
		(net "GND")
	)
	(segment
		(start 32.6898 -193.3702)
		(end 33.5788 -193.3702)
		(width 0.508)
		(layer "F.Cu")
		(net "GND")
	)
	(segment
		(start 237.599982 -55.999888)
		(end 237.10011 -56.49976)
		(width 0.4572)
		(layer "F.Cu")
		(net "GND")
	)
	(segment
		(start 242.599972 -49.9999)
		(end 243.099844 -50.499772)
		(width 0.4572)
		(layer "F.Cu")
		(net "GND")
	)
	(segment
		(start 50.900076 -225.54438)
		(end 50.900076 -223.482154)
		(width 0.508)
		(layer "F.Cu")
		(net "GND")
	)
	(segment
		(start 255.599946 -52.999894)
		(end 256.099818 -53.499766)
		(width 0.4572)
		(layer "F.Cu")
		(net "GND")
	)
	(segment
		(start 285.300166 -225.54438)
		(end 285.300166 -223.482408)
		(width 0.508)
		(layer "F.Cu")
		(net "GND")
	)
	(segment
		(start 125.5522 -41.3766)
		(end 125.6792 -41.3766)
		(width 0.508)
		(layer "F.Cu")
		(net "GND")
	)
	(segment
		(start 224.600008 -62.999874)
		(end 224.100136 -63.499746)
		(width 0.4572)
		(layer "F.Cu")
		(net "GND")
	)
	(segment
		(start 48.518572 -61.303916)
		(end 48.518572 -62.606428)
		(width 0.508)
		(layer "F.Cu")
		(net "GND")
	)
	(segment
		(start 244.599968 -63.999872)
		(end 245.09984 -64.499744)
		(width 0.4572)
		(layer "F.Cu")
		(net "GND")
	)
	(segment
		(start 9.271 -75.2094)
		(end 7.1628 -75.2094)
		(width 0.508)
		(layer "F.Cu")
		(net "GND")
	)
	(segment
		(start 232.599992 -55.999888)
		(end 232.10012 -56.49976)
		(width 0.4572)
		(layer "F.Cu")
		(net "GND")
	)
	(segment
		(start 35.367976 -151.579834)
		(end 34.96818 -151.180038)
		(width 0.3556)
		(layer "F.Cu")
		(net "GND")
	)
	(segment
		(start 7.1628 -75.2094)
		(end 5.08 -75.2094)
		(width 0.508)
		(layer "F.Cu")
		(net "GND")
	)
	(segment
		(start 242.599972 -43.999912)
		(end 243.099844 -43.50004)
		(width 0.4572)
		(layer "F.Cu")
		(net "GND")
	)
	(segment
		(start 229.599998 -32.999934)
		(end 229.100126 -32.500062)
		(width 0.4572)
		(layer "F.Cu")
		(net "GND")
	)
	(segment
		(start 47.244 -194.1195)
		(end 47.244 -193.294)
		(width 0.508)
		(layer "F.Cu")
		(net "GND")
	)
	(segment
		(start 59.871102 -21.231606)
		(end 57.909206 -21.231606)
		(width 0.508)
		(layer "F.Cu")
		(net "GND")
	)
	(segment
		(start 50.7365 -147.2057)
		(end 50.7365 -147.447)
		(width 0.508)
		(layer "F.Cu")
		(net "GND")
	)
	(segment
		(start 272.32356 -4.177538)
		(end 272.311622 -4.1656)
		(width 0.508)
		(layer "F.Cu")
		(net "GND")
	)
	(segment
		(start 160.528 -81.4959)
		(end 161.3789 -81.4959)
		(width 0.508)
		(layer "F.Cu")
		(net "GND")
	)
	(segment
		(start 236.599984 -63.999872)
		(end 236.100112 -64.499744)
		(width 0.4572)
		(layer "F.Cu")
		(net "GND")
	)
	(segment
		(start 172.10024 -223.4819)
		(end 172.500036 -223.082104)
		(width 0.508)
		(layer "F.Cu")
		(net "GND")
	)
	(segment
		(start 97.300034 -225.54438)
		(end 97.300034 -223.482154)
		(width 0.508)
		(layer "F.Cu")
		(net "GND")
	)
	(segment
		(start 248.59996 -41.999916)
		(end 249.099832 -41.500044)
		(width 0.4572)
		(layer "F.Cu")
		(net "GND")
	)
	(segment
		(start 36.10483 -128.484884)
		(end 36.90493 -129.284984)
		(width 0.3556)
		(layer "F.Cu")
		(net "GND")
	)
	(segment
		(start 241.599974 -29.99994)
		(end 242.099846 -29.500068)
		(width 0.4572)
		(layer "F.Cu")
		(net "GND")
	)
	(segment
		(start 231.599994 -47.999904)
		(end 231.100122 -48.499776)
		(width 0.4572)
		(layer "F.Cu")
		(net "GND")
	)
	(segment
		(start 222.600012 -63.999872)
		(end 222.10014 -64.499744)
		(width 0.4572)
		(layer "F.Cu")
		(net "GND")
	)
	(segment
		(start 257.599942 -32.999934)
		(end 258.099814 -32.500062)
		(width 0.4572)
		(layer "F.Cu")
		(net "GND")
	)
	(segment
		(start 272.83156 -3.57378)
		(end 272.32356 -4.08178)
		(width 0.508)
		(layer "F.Cu")
		(net "GND")
	)
	(segment
		(start 255.599946 -60.999878)
		(end 256.099818 -61.49975)
		(width 0.4572)
		(layer "F.Cu")
		(net "GND")
	)
	(segment
		(start 230.599996 -56.999886)
		(end 230.100124 -57.499758)
		(width 0.4572)
		(layer "F.Cu")
		(net "GND")
	)
	(segment
		(start 238.59998 -41.999916)
		(end 238.100108 -41.500044)
		(width 0.4572)
		(layer "F.Cu")
		(net "GND")
	)
	(segment
		(start 220.307408 -188.3283)
		(end 219.833698 -188.3283)
		(width 0.508)
		(layer "F.Cu")
		(net "GND")
	)
	(segment
		(start 49.657 -152.8445)
		(end 49.9364 -152.8445)
		(width 0.508)
		(layer "F.Cu")
		(net "GND")
	)
	(segment
		(start 236.599984 -31.999936)
		(end 236.100112 -31.500064)
		(width 0.4572)
		(layer "F.Cu")
		(net "GND")
	)
	(segment
		(start 119.4308 -16.6243)
		(end 119.4308 -15.8242)
		(width 0.508)
		(layer "F.Cu")
		(net "GND")
	)
	(segment
		(start 103.700072 -225.54438)
		(end 103.700072 -223.482154)
		(width 0.508)
		(layer "F.Cu")
		(net "GND")
	)
	(segment
		(start 49.1236 -48.9966)
		(end 49.788572 -49.661572)
		(width 0.508)
		(layer "F.Cu")
		(net "GND")
	)
	(segment
		(start 43.70451 -132.08508)
		(end 43.304714 -132.484876)
		(width 0.3556)
		(layer "F.Cu")
		(net "GND")
	)
	(segment
		(start 246.599964 -60.999878)
		(end 247.099836 -61.49975)
		(width 0.4572)
		(layer "F.Cu")
		(net "GND")
	)
	(segment
		(start 106.100118 -225.54438)
		(end 106.100118 -223.482408)
		(width 0.508)
		(layer "F.Cu")
		(net "GND")
	)
	(segment
		(start 5.8674 -55.9943)
		(end 5.8674 -57.023)
		(width 0.508)
		(layer "F.Cu")
		(net "GND")
	)
	(segment
		(start 60.8584 -37.1221)
		(end 60.8584 -36.2966)
		(width 0.508)
		(layer "F.Cu")
		(net "GND")
	)
	(segment
		(start 226.7966 -13.972032)
		(end 227.35032 -13.418312)
		(width 0.508)
		(layer "F.Cu")
		(net "GND")
	)
	(segment
		(start 76.3524 -197.0278)
		(end 75.7936 -197.0278)
		(width 0.508)
		(layer "F.Cu")
		(net "GND")
	)
	(segment
		(start 55.6387 -131.6355)
		(end 55.245 -132.0292)
		(width 0.508)
		(layer "F.Cu")
		(net "GND")
	)
	(segment
		(start 231.599994 -55.999888)
		(end 231.100122 -56.49976)
		(width 0.4572)
		(layer "F.Cu")
		(net "GND")
	)
	(segment
		(start 156.718 -96.3549)
		(end 156.718 -97.155)
		(width 0.508)
		(layer "F.Cu")
		(net "GND")
	)
	(segment
		(start 238.59998 -58.999882)
		(end 238.100108 -59.499754)
		(width 0.4572)
		(layer "F.Cu")
		(net "GND")
	)
	(segment
		(start 37.704776 -130.88493)
		(end 37.30498 -131.284726)
		(width 0.3556)
		(layer "F.Cu")
		(net "GND")
	)
	(segment
		(start 30.6578 -53.721)
		(end 29.464 -53.721)
		(width 0.508)
		(layer "F.Cu")
		(net "GND")
	)
	(segment
		(start 230.599996 -57.999884)
		(end 230.100124 -58.499756)
		(width 0.4572)
		(layer "F.Cu")
		(net "GND")
	)
	(segment
		(start 187.071 -6.1595)
		(end 186.737244 -5.825744)
		(width 0.508)
		(layer "F.Cu")
		(net "GND")
	)
	(segment
		(start 38.1508 -186.0931)
		(end 38.1508 -185.2676)
		(width 0.508)
		(layer "F.Cu")
		(net "GND")
	)
	(segment
		(start 35.988498 -102.74681)
		(end 36.222432 -102.512876)
		(width 0.508)
		(layer "F.Cu")
		(net "GND")
	)
	(segment
		(start 39.30523 -129.284984)
		(end 39.304722 -129.284984)
		(width 0.3556)
		(layer "F.Cu")
		(net "GND")
	)
	(segment
		(start 253.59995 -39.99992)
		(end 254.099822 -39.500048)
		(width 0.4572)
		(layer "F.Cu")
		(net "GND")
	)
	(segment
		(start 20.574 -101.369114)
		(end 21.405596 -101.369114)
		(width 0.508)
		(layer "F.Cu")
		(net "GND")
	)
	(segment
		(start 78.570074 -185.335926)
		(end 78.744064 -185.335926)
		(width 0.3048)
		(layer "F.Cu")
		(net "GND")
	)
	(segment
		(start 270.100044 -223.482154)
		(end 270.500094 -223.082104)
		(width 0.508)
		(layer "F.Cu")
		(net "GND")
	)
	(segment
		(start 240.599976 -65.999868)
		(end 241.099848 -66.49974)
		(width 0.4572)
		(layer "F.Cu")
		(net "GND")
	)
	(segment
		(start 162.500056 -223.656144)
		(end 163.1188 -223.0374)
		(width 0.508)
		(layer "F.Cu")
		(net "GND")
	)
	(segment
		(start 324.50024 -223.482408)
		(end 324.099936 -223.082104)
		(width 0.508)
		(layer "F.Cu")
		(net "GND")
	)
	(segment
		(start 29.337 -116.2685)
		(end 29.337 -115.4938)
		(width 0.508)
		(layer "F.Cu")
		(net "GND")
	)
	(segment
		(start 62.920118 -160.841182)
		(end 62.3062 -161.4551)
		(width 0.508)
		(layer "F.Cu")
		(net "GND")
	)
	(segment
		(start 331.700124 -225.54438)
		(end 331.700124 -223.482154)
		(width 0.508)
		(layer "F.Cu")
		(net "GND")
	)
	(segment
		(start 165.700202 -225.54438)
		(end 165.700202 -223.478598)
		(width 0.508)
		(layer "F.Cu")
		(net "GND")
	)
	(segment
		(start 236.599984 -54.99989)
		(end 236.100112 -55.499762)
		(width 0.4572)
		(layer "F.Cu")
		(net "GND")
	)
	(segment
		(start 239.599978 -50.999898)
		(end 239.100106 -51.49977)
		(width 0.4572)
		(layer "F.Cu")
		(net "GND")
	)
	(segment
		(start 231.599994 -46.999906)
		(end 231.100122 -46.500034)
		(width 0.4572)
		(layer "F.Cu")
		(net "GND")
	)
	(segment
		(start 133.453886 -84.401914)
		(end 133.034786 -84.401914)
		(width 0.508)
		(layer "F.Cu")
		(net "GND")
	)
	(segment
		(start 336.8294 -187.3631)
		(end 336.8294 -187.995306)
		(width 0.508)
		(layer "F.Cu")
		(net "GND")
	)
	(segment
		(start 17.1704 -84.6582)
		(end 16.8656 -84.963)
		(width 0.381)
		(layer "F.Cu")
		(net "GND")
	)
	(segment
		(start 137.0203 -81.0641)
		(end 136.116314 -80.160114)
		(width 0.508)
		(layer "F.Cu")
		(net "GND")
	)
	(segment
		(start 53.34 -184.15)
		(end 54.229 -184.15)
		(width 0.508)
		(layer "F.Cu")
		(net "GND")
	)
	(segment
		(start 242.824 -24.638)
		(end 242.951 -24.765)
		(width 0.508)
		(layer "F.Cu")
		(net "GND")
	)
	(segment
		(start 256.599944 -59.99988)
		(end 257.099816 -60.499752)
		(width 0.4572)
		(layer "F.Cu")
		(net "GND")
	)
	(segment
		(start 235.599986 -42.999914)
		(end 235.100114 -42.500042)
		(width 0.4572)
		(layer "F.Cu")
		(net "GND")
	)
	(segment
		(start 36.322 -200.0885)
		(end 36.322 -199.263)
		(width 0.508)
		(layer "F.Cu")
		(net "GND")
	)
	(segment
		(start 228.43236 -82.00136)
		(end 228.981 -82.55)
		(width 0.3048)
		(layer "F.Cu")
		(net "GND")
	)
	(segment
		(start 249.599958 -51.999896)
		(end 250.09983 -52.499768)
		(width 0.4572)
		(layer "F.Cu")
		(net "GND")
	)
	(segment
		(start 48.518572 -62.606428)
		(end 48.514 -62.611)
		(width 0.508)
		(layer "F.Cu")
		(net "GND")
	)
	(segment
		(start 231.599994 -43.999912)
		(end 231.100122 -43.50004)
		(width 0.4572)
		(layer "F.Cu")
		(net "GND")
	)
	(segment
		(start 230.599996 -47.999904)
		(end 230.100124 -48.499776)
		(width 0.4572)
		(layer "F.Cu")
		(net "GND")
	)
	(segment
		(start 227.600002 -48.999902)
		(end 227.10013 -49.499774)
		(width 0.4572)
		(layer "F.Cu")
		(net "GND")
	)
	(segment
		(start 241.599974 -30.999938)
		(end 242.099846 -30.500066)
		(width 0.4572)
		(layer "F.Cu")
		(net "GND")
	)
	(segment
		(start 250.599956 -49.9999)
		(end 251.099828 -50.499772)
		(width 0.4572)
		(layer "F.Cu")
		(net "GND")
	)
	(segment
		(start 71.700136 -224.303336)
		(end 71.515478 -224.118678)
		(width 0.508)
		(layer "F.Cu")
		(net "GND")
	)
	(segment
		(start 39.116 -204.216)
		(end 38.227 -204.216)
		(width 0.508)
		(layer "F.Cu")
		(net "GND")
	)
	(segment
		(start 174.500032 -225.54438)
		(end 174.500032 -223.482154)
		(width 0.508)
		(layer "F.Cu")
		(net "GND")
	)
	(via
		(at 318.516 -100.838)
		(size 0.508)
		(drill 0.254)
		(layers "F.Cu" "B.Cu")
		(net "GND")
	)
	(via
		(at 41.36771 -153.57983)
		(size 0.4572)
		(drill 0.2032)
		(layers "F.Cu" "B.Cu")
		(net "GND")
	)
	(via
		(at 218.10853 -193.0146)
		(size 0.508)
		(drill 0.254)
		(layers "F.Cu" "B.Cu")
		(net "GND")
	)
	(via
		(at 334.148684 -180.213)
		(size 0.508)
		(drill 0.254)
		(layers "F.Cu" "B.Cu")
		(net "GND")
	)
	(via
		(at 38.862 -57.15)
		(size 0.508)
		(drill 0.254)
		(layers "F.Cu" "B.Cu")
		(net "GND")
	)
	(via
		(at 218.797124 -189.364874)
		(size 0.508)
		(drill 0.254)
		(layers "F.Cu" "B.Cu")
		(net "GND")
	)
	(via
		(at 230.100124 -40.500046)
		(size 0.4572)
		(drill 0.2032)
		(layers "F.Cu" "B.Cu")
		(net "GND")
	)
	(via
		(at 183.2356 -59.3852)
		(size 0.7112)
		(drill 0.4064)
		(layers "F.Cu" "B.Cu")
		(net "GND")
	)
	(via
		(at 7.956296 -104.3432)
		(size 0.508)
		(drill 0.254)
		(layers "F.Cu" "B.Cu")
		(net "GND")
	)
	(via
		(at 19.802856 -72.56018)
		(size 0.508)
		(drill 0.254)
		(layers "F.Cu" "B.Cu")
		(net "GND")
	)
	(via
		(at 157.14472 -88.08212)
		(size 0.508)
		(drill 0.254)
		(layers "F.Cu" "B.Cu")
		(net "GND")
	)
	(via
		(at 242.099846 -31.500064)
		(size 0.4572)
		(drill 0.2032)
		(layers "F.Cu" "B.Cu")
		(net "GND")
	)
	(via
		(at 134.097014 -219.62872)
		(size 0.508)
		(drill 0.254)
		(layers "F.Cu" "B.Cu")
		(net "GND")
	)
	(via
		(at 259.099812 -65.499742)
		(size 0.4572)
		(drill 0.2032)
		(layers "F.Cu" "B.Cu")
		(net "GND")
	)
	(via
		(at 309.5244 -14.224)
		(size 0.508)
		(drill 0.254)
		(layers "F.Cu" "B.Cu")
		(net "GND")
	)
	(via
		(at 67.5259 -154.0256)
		(size 0.508)
		(drill 0.254)
		(layers "F.Cu" "B.Cu")
		(net "GND")
	)
	(via
		(at 137.5918 -23.4442)
		(size 0.508)
		(drill 0.254)
		(layers "F.Cu" "B.Cu")
		(net "GND")
	)
	(via
		(at 229.100126 -51.49977)
		(size 0.4572)
		(drill 0.2032)
		(layers "F.Cu" "B.Cu")
		(net "GND")
	)
	(via
		(at 229.100126 -56.49976)
		(size 0.4572)
		(drill 0.2032)
		(layers "F.Cu" "B.Cu")
		(net "GND")
	)
	(via
		(at 223.2152 -12.5984)
		(size 0.508)
		(drill 0.254)
		(layers "F.Cu" "B.Cu")
		(net "GND")
	)
	(via
		(at 329.52944 -35.603688)
		(size 0.508)
		(drill 0.254)
		(layers "F.Cu" "B.Cu")
		(net "GND")
	)
	(via
		(at 33.5788 -193.3702)
		(size 0.508)
		(drill 0.254)
		(layers "F.Cu" "B.Cu")
		(net "GND")
	)
	(via
		(at 229.100126 -40.500046)
		(size 0.4572)
		(drill 0.2032)
		(layers "F.Cu" "B.Cu")
		(net "GND")
	)
	(via
		(at 8.001 -56.9976)
		(size 0.508)
		(drill 0.254)
		(layers "F.Cu" "B.Cu")
		(net "GND")
	)
	(via
		(at 5.588 -42.4688)
		(size 0.508)
		(drill 0.254)
		(layers "F.Cu" "B.Cu")
		(net "GND")
	)
	(via
		(at 228.100128 -32.500062)
		(size 0.4572)
		(drill 0.2032)
		(layers "F.Cu" "B.Cu")
		(net "GND")
	)
	(via
		(at 231.100122 -58.499756)
		(size 0.4572)
		(drill 0.2032)
		(layers "F.Cu" "B.Cu")
		(net "GND")
	)
	(via
		(at 65.58915 -49.266602)
		(size 0.7112)
		(drill 0.4064)
		(layers "F.Cu" "B.Cu")
		(net "GND")
	)
	(via
		(at 49.904396 -211.373212)
		(size 0.508)
		(drill 0.254)
		(layers "F.Cu" "B.Cu")
		(net "GND")
	)
	(via
		(at 146.5072 -23.2664)
		(size 0.508)
		(drill 0.254)
		(layers "F.Cu" "B.Cu")
		(net "GND")
	)
	(via
		(at 227.10013 -61.49975)
		(size 0.4572)
		(drill 0.2032)
		(layers "F.Cu" "B.Cu")
		(net "GND")
	)
	(via
		(at 230.5685 -13.1445)
		(size 0.508)
		(drill 0.254)
		(layers "F.Cu" "B.Cu")
		(net "GND")
	)
	(via
		(at 303.070768 -36.31438)
		(size 0.508)
		(drill 0.254)
		(layers "F.Cu" "B.Cu")
		(net "GND")
	)
	(via
		(at 258.099814 -31.500064)
		(size 0.4572)
		(drill 0.2032)
		(layers "F.Cu" "B.Cu")
		(net "GND")
	)
	(via
		(at 182.0926 -59.3852)
		(size 0.7112)
		(drill 0.4064)
		(layers "F.Cu" "B.Cu")
		(net "GND")
	)
	(via
		(at 26.289 -115.4938)
		(size 0.508)
		(drill 0.254)
		(layers "F.Cu" "B.Cu")
		(net "GND")
	)
	(via
		(at 234.100116 -34.500058)
		(size 0.4572)
		(drill 0.2032)
		(layers "F.Cu" "B.Cu")
		(net "GND")
	)
	(via
		(at 36.322 -98.552)
		(size 0.508)
		(drill 0.254)
		(layers "F.Cu" "B.Cu")
		(net "GND")
	)
	(via
		(at 238.100108 -57.499758)
		(size 0.4572)
		(drill 0.2032)
		(layers "F.Cu" "B.Cu")
		(net "GND")
	)
	(via
		(at 354.203 -208.185004)
		(size 0.508)
		(drill 0.254)
		(layers "F.Cu" "B.Cu")
		(net "GND")
	)
	(via
		(at 338.328 -66.421)
		(size 0.508)
		(drill 0.254)
		(layers "F.Cu" "B.Cu")
		(net "GND")
	)
	(via
		(at 248.099834 -56.49976)
		(size 0.4572)
		(drill 0.2032)
		(layers "F.Cu" "B.Cu")
		(net "GND")
	)
	(via
		(at 12.70508 -212.102954)
		(size 0.508)
		(drill 0.254)
		(layers "F.Cu" "B.Cu")
		(net "GND")
	)
	(via
		(at 354.203 -152.305004)
		(size 0.508)
		(drill 0.254)
		(layers "F.Cu" "B.Cu")
		(net "GND")
	)
	(via
		(at 252.099826 -64.499744)
		(size 0.4572)
		(drill 0.2032)
		(layers "F.Cu" "B.Cu")
		(net "GND")
	)
	(via
		(at 276.85238 -210.152996)
		(size 0.508)
		(drill 0.254)
		(layers "F.Cu" "B.Cu")
		(net "GND")
	)
	(via
		(at 294.499792 -223.082104)
		(size 0.508)
		(drill 0.254)
		(layers "F.Cu" "B.Cu")
		(net "GND")
	)
	(via
		(at 311.531 -51.181)
		(size 0.7112)
		(drill 0.4064)
		(layers "F.Cu" "B.Cu")
		(net "GND")
	)
	(via
		(at 251.099828 -63.499746)
		(size 0.4572)
		(drill 0.2032)
		(layers "F.Cu" "B.Cu")
		(net "GND")
	)
	(via
		(at 266.192 -207.01)
		(size 0.7112)
		(drill 0.3556)
		(layers "F.Cu" "B.Cu")
		(net "GND")
	)
	(via
		(at 286.452564 -210.152996)
		(size 0.508)
		(drill 0.254)
		(layers "F.Cu" "B.Cu")
		(net "GND")
	)
	(via
		(at 264.6426 -167.1574)
		(size 0.508)
		(drill 0.254)
		(layers "F.Cu" "B.Cu")
		(net "GND")
	)
	(via
		(at 222.10014 -62.499748)
		(size 0.4572)
		(drill 0.2032)
		(layers "F.Cu" "B.Cu")
		(net "GND")
	)
	(via
		(at 267.25245 -210.152996)
		(size 0.508)
		(drill 0.254)
		(layers "F.Cu" "B.Cu")
		(net "GND")
	)
	(via
		(at 251.099828 -57.499758)
		(size 0.4572)
		(drill 0.2032)
		(layers "F.Cu" "B.Cu")
		(net "GND")
	)
	(via
		(at 248.099834 -55.499762)
		(size 0.4572)
		(drill 0.2032)
		(layers "F.Cu" "B.Cu")
		(net "GND")
	)
	(via
		(at 168.375838 -88.105742)
		(size 0.508)
		(drill 0.254)
		(layers "F.Cu" "B.Cu")
		(net "GND")
	)
	(via
		(at 256.099818 -57.499758)
		(size 0.4572)
		(drill 0.2032)
		(layers "F.Cu" "B.Cu")
		(net "GND")
	)
	(via
		(at 65.36436 -86.01456)
		(size 0.508)
		(drill 0.254)
		(layers "F.Cu" "B.Cu")
		(net "GND")
	)
	(via
		(at 227.10013 -35.500056)
		(size 0.4572)
		(drill 0.2032)
		(layers "F.Cu" "B.Cu")
		(net "GND")
	)
	(via
		(at 274.574 -170.18)
		(size 0.508)
		(drill 0.254)
		(layers "F.Cu" "B.Cu")
		(net "GND")
	)
	(via
		(at 336.900012 -223.082104)
		(size 0.508)
		(drill 0.254)
		(layers "F.Cu" "B.Cu")
		(net "GND")
	)
	(via
		(at 211.429854 -11.803888)
		(size 0.508)
		(drill 0.254)
		(layers "F.Cu" "B.Cu")
		(net "GND")
	)
	(via
		(at 239.100106 -29.500068)
		(size 0.4572)
		(drill 0.2032)
		(layers "F.Cu" "B.Cu")
		(net "GND")
	)
	(via
		(at 22.987 -149.098)
		(size 0.508)
		(drill 0.254)
		(layers "F.Cu" "B.Cu")
		(net "GND")
	)
	(via
		(at 163.6014 -124.1298)
		(size 0.508)
		(drill 0.254)
		(layers "F.Cu" "B.Cu")
		(net "GND")
	)
	(via
		(at 59.3471 -210.152996)
		(size 0.508)
		(drill 0.254)
		(layers "F.Cu" "B.Cu")
		(net "GND")
	)
	(via
		(at 243.2812 -144.8562)
		(size 0.508)
		(drill 0.254)
		(layers "F.Cu" "B.Cu")
		(net "GND")
	)
	(via
		(at 101.9048 -38.1508)
		(size 0.508)
		(drill 0.254)
		(layers "F.Cu" "B.Cu")
		(net "GND")
	)
	(via
		(at 230.505 -82.55)
		(size 0.508)
		(drill 0.254)
		(layers "F.Cu" "B.Cu")
		(net "GND")
	)
	(via
		(at 130.524504 -35.804856)
		(size 0.508)
		(drill 0.254)
		(layers "F.Cu" "B.Cu")
		(net "GND")
	)
	(via
		(at 243.099844 -61.49975)
		(size 0.4572)
		(drill 0.2032)
		(layers "F.Cu" "B.Cu")
		(net "GND")
	)
	(via
		(at 168.298622 -56.813958)
		(size 0.7112)
		(drill 0.4064)
		(layers "F.Cu" "B.Cu")
		(net "GND")
	)
	(via
		(at 185.299858 -223.082104)
		(size 0.508)
		(drill 0.254)
		(layers "F.Cu" "B.Cu")
		(net "GND")
	)
	(via
		(at 236.100112 -59.499754)
		(size 0.4572)
		(drill 0.2032)
		(layers "F.Cu" "B.Cu")
		(net "GND")
	)
	(via
		(at 322.453 -40.894)
		(size 0.7112)
		(drill 0.3556)
		(layers "F.Cu" "B.Cu")
		(net "GND")
	)
	(via
		(at 19.6596 -141.986)
		(size 0.508)
		(drill 0.254)
		(layers "F.Cu" "B.Cu")
		(net "GND")
	)
	(via
		(at 224.100136 -32.500062)
		(size 0.4572)
		(drill 0.2032)
		(layers "F.Cu" "B.Cu")
		(net "GND")
	)
	(via
		(at 53.347112 -13.36167)
		(size 0.508)
		(drill 0.254)
		(layers "F.Cu" "B.Cu")
		(net "GND")
	)
	(via
		(at 165.989 -208.0514)
		(size 0.508)
		(drill 0.254)
		(layers "F.Cu" "B.Cu")
		(net "GND")
	)
	(via
		(at 309.300118 -223.031304)
		(size 0.508)
		(drill 0.254)
		(layers "F.Cu" "B.Cu")
		(net "GND")
	)
	(via
		(at 159.865822 -35.674554)
		(size 0.508)
		(drill 0.254)
		(layers "F.Cu" "B.Cu")
		(net "GND")
	)
	(via
		(at 146.3802 -26.2382)
		(size 0.508)
		(drill 0.254)
		(layers "F.Cu" "B.Cu")
		(net "GND")
	)
	(via
		(at 175.705262 -60.421012)
		(size 0.7112)
		(drill 0.4064)
		(layers "F.Cu" "B.Cu")
		(net "GND")
	)
	(via
		(at 229.100126 -50.499772)
		(size 0.4572)
		(drill 0.2032)
		(layers "F.Cu" "B.Cu")
		(net "GND")
	)
	(via
		(at 100.3554 -114.0714)
		(size 0.508)
		(drill 0.254)
		(layers "F.Cu" "B.Cu")
		(net "GND")
	)
	(via
		(at 249.099832 -31.500064)
		(size 0.4572)
		(drill 0.2032)
		(layers "F.Cu" "B.Cu")
		(net "GND")
	)
	(via
		(at 26.3398 -51.0032)
		(size 0.508)
		(drill 0.254)
		(layers "F.Cu" "B.Cu")
		(net "GND")
	)
	(via
		(at 83.525868 -76.210668)
		(size 0.508)
		(drill 0.254)
		(layers "F.Cu" "B.Cu")
		(net "GND")
	)
	(via
		(at 168.43756 -89.911428)
		(size 0.508)
		(drill 0.254)
		(layers "F.Cu" "B.Cu")
		(net "GND")
	)
	(via
		(at 149.733 -91.694)
		(size 0.508)
		(drill 0.254)
		(layers "F.Cu" "B.Cu")
		(net "GND")
	)
	(via
		(at 154.321002 -70.131432)
		(size 0.7112)
		(drill 0.4064)
		(layers "F.Cu" "B.Cu")
		(net "GND")
	)
	(via
		(at 224.100136 -63.499746)
		(size 0.4572)
		(drill 0.2032)
		(layers "F.Cu" "B.Cu")
		(net "GND")
	)
	(via
		(at 224.100136 -60.499752)
		(size 0.4572)
		(drill 0.2032)
		(layers "F.Cu" "B.Cu")
		(net "GND")
	)
	(via
		(at 289.8648 -22.0472)
		(size 0.508)
		(drill 0.254)
		(layers "F.Cu" "B.Cu")
		(net "GND")
	)
	(via
		(at 231.648 -11.43)
		(size 0.508)
		(drill 0.254)
		(layers "F.Cu" "B.Cu")
		(net "GND")
	)
	(via
		(at 322.452492 -210.152996)
		(size 0.508)
		(drill 0.254)
		(layers "F.Cu" "B.Cu")
		(net "GND")
	)
	(via
		(at 82.814414 -83.637628)
		(size 0.508)
		(drill 0.254)
		(layers "F.Cu" "B.Cu")
		(net "GND")
	)
	(via
		(at 257.099816 -54.499764)
		(size 0.4572)
		(drill 0.2032)
		(layers "F.Cu" "B.Cu")
		(net "GND")
	)
	(via
		(at 241.099848 -57.499758)
		(size 0.4572)
		(drill 0.2032)
		(layers "F.Cu" "B.Cu")
		(net "GND")
	)
	(via
		(at 54.934612 -144.104614)
		(size 0.508)
		(drill 0.254)
		(layers "F.Cu" "B.Cu")
		(net "GND")
	)
	(via
		(at 35.179 -222.3008)
		(size 0.508)
		(drill 0.254)
		(layers "F.Cu" "B.Cu")
		(net "GND")
	)
	(via
		(at 31.126938 -141.7574)
		(size 0.4572)
		(drill 0.2032)
		(layers "F.Cu" "B.Cu")
		(net "GND")
	)
	(via
		(at 251.099828 -40.500046)
		(size 0.4572)
		(drill 0.2032)
		(layers "F.Cu" "B.Cu")
		(net "GND")
	)
	(via
		(at 193.300096 -223.082104)
		(size 0.508)
		(drill 0.254)
		(layers "F.Cu" "B.Cu")
		(net "GND")
	)
	(via
		(at 229.100126 -43.50004)
		(size 0.4572)
		(drill 0.2032)
		(layers "F.Cu" "B.Cu")
		(net "GND")
	)
	(via
		(at 236.100112 -57.499758)
		(size 0.4572)
		(drill 0.2032)
		(layers "F.Cu" "B.Cu")
		(net "GND")
	)
	(via
		(at 186.0042 -73.914)
		(size 0.7112)
		(drill 0.4064)
		(layers "F.Cu" "B.Cu")
		(net "GND")
	)
	(via
		(at 142.346172 -72.084946)
		(size 0.7112)
		(drill 0.4064)
		(layers "F.Cu" "B.Cu")
		(net "GND")
	)
	(via
		(at 46.44644 -188.52896)
		(size 0.508)
		(drill 0.254)
		(layers "F.Cu" "B.Cu")
		(net "GND")
	)
	(via
		(at 187.2742 -73.914)
		(size 0.7112)
		(drill 0.4064)
		(layers "F.Cu" "B.Cu")
		(net "GND")
	)
	(via
		(at 230.100124 -52.499768)
		(size 0.4572)
		(drill 0.2032)
		(layers "F.Cu" "B.Cu")
		(net "GND")
	)
	(via
		(at 143.526002 -65.178432)
		(size 0.7112)
		(drill 0.4064)
		(layers "F.Cu" "B.Cu")
		(net "GND")
	)
	(via
		(at 283.700982 -21.651722)
		(size 0.508)
		(drill 0.254)
		(layers "F.Cu" "B.Cu")
		(net "GND")
	)
	(via
		(at 354.203 -55.785004)
		(size 0.508)
		(drill 0.254)
		(layers "F.Cu" "B.Cu")
		(net "GND")
	)
	(via
		(at 170.465496 -53.53558)
		(size 0.508)
		(drill 0.254)
		(layers "F.Cu" "B.Cu")
		(net "GND")
	)
	(via
		(at 323.3928 -26.2128)
		(size 0.508)
		(drill 0.254)
		(layers "F.Cu" "B.Cu")
		(net "GND")
	)
	(via
		(at 27.8892 -173.2026)
		(size 0.508)
		(drill 0.254)
		(layers "F.Cu" "B.Cu")
		(net "GND")
	)
	(via
		(at 36.195 -219.075)
		(size 0.508)
		(drill 0.254)
		(layers "F.Cu" "B.Cu")
		(net "GND")
	)
	(via
		(at 232.10012 -43.50004)
		(size 0.4572)
		(drill 0.2032)
		(layers "F.Cu" "B.Cu")
		(net "GND")
	)
	(via
		(at 230.100124 -57.499758)
		(size 0.4572)
		(drill 0.2032)
		(layers "F.Cu" "B.Cu")
		(net "GND")
	)
	(via
		(at 57.023 -43.307)
		(size 0.7112)
		(drill 0.4064)
		(layers "F.Cu" "B.Cu")
		(net "GND")
	)
	(via
		(at 167.5638 -21.9456)
		(size 0.508)
		(drill 0.254)
		(layers "F.Cu" "B.Cu")
		(net "GND")
	)
	(via
		(at 294.547036 -210.152996)
		(size 0.508)
		(drill 0.254)
		(layers "F.Cu" "B.Cu")
		(net "GND")
	)
	(via
		(at 302.8442 -11.7094)
		(size 0.508)
		(drill 0.254)
		(layers "F.Cu" "B.Cu")
		(net "GND")
	)
	(via
		(at 149.347174 -210.152996)
		(size 0.508)
		(drill 0.254)
		(layers "F.Cu" "B.Cu")
		(net "GND")
	)
	(via
		(at 33.2486 -180.5432)
		(size 0.508)
		(drill 0.254)
		(layers "F.Cu" "B.Cu")
		(net "GND")
	)
	(via
		(at 211.224368 -8.740394)
		(size 0.508)
		(drill 0.254)
		(layers "F.Cu" "B.Cu")
		(net "GND")
	)
	(via
		(at 290.449 -23.6982)
		(size 0.508)
		(drill 0.254)
		(layers "F.Cu" "B.Cu")
		(net "GND")
	)
	(via
		(at 1.397 -152.291034)
		(size 0.508)
		(drill 0.254)
		(layers "F.Cu" "B.Cu")
		(net "GND")
	)
	(via
		(at 65.913 -38.608)
		(size 0.508)
		(drill 0.254)
		(layers "F.Cu" "B.Cu")
		(net "GND")
	)
	(via
		(at 336.971894 -188.1378)
		(size 0.508)
		(drill 0.254)
		(layers "F.Cu" "B.Cu")
		(net "GND")
	)
	(via
		(at 202.196954 -44.487338)
		(size 0.508)
		(drill 0.254)
		(layers "F.Cu" "B.Cu")
		(net "GND")
	)
	(via
		(at 162.854386 -35.0012)
		(size 0.508)
		(drill 0.254)
		(layers "F.Cu" "B.Cu")
		(net "GND")
	)
	(via
		(at 250.09983 -59.499754)
		(size 0.4572)
		(drill 0.2032)
		(layers "F.Cu" "B.Cu")
		(net "GND")
	)
	(via
		(at 30.569154 -160.909)
		(size 0.508)
		(drill 0.254)
		(layers "F.Cu" "B.Cu")
		(net "GND")
	)
	(via
		(at 137.0203 -81.830164)
		(size 0.508)
		(drill 0.254)
		(layers "F.Cu" "B.Cu")
		(net "GND")
	)
	(via
		(at 323.469 -113.919)
		(size 0.7112)
		(drill 0.3556)
		(layers "F.Cu" "B.Cu")
		(net "GND")
	)
	(via
		(at 297.942 -71.12)
		(size 0.7112)
		(drill 0.4064)
		(layers "F.Cu" "B.Cu")
		(net "GND")
	)
	(via
		(at 55.245 -134.4295)
		(size 0.508)
		(drill 0.254)
		(layers "F.Cu" "B.Cu")
		(net "GND")
	)
	(via
		(at 186.772804 -26.07564)
		(size 0.508)
		(drill 0.254)
		(layers "F.Cu" "B.Cu")
		(net "GND")
	)
	(via
		(at 225.100134 -45.500036)
		(size 0.4572)
		(drill 0.2032)
		(layers "F.Cu" "B.Cu")
		(net "GND")
	)
	(via
		(at 1.397 -30.371034)
		(size 0.508)
		(drill 0.254)
		(layers "F.Cu" "B.Cu")
		(net "GND")
	)
	(via
		(at 251.099828 -49.499774)
		(size 0.4572)
		(drill 0.2032)
		(layers "F.Cu" "B.Cu")
		(net "GND")
	)
	(via
		(at 238.100108 -38.50005)
		(size 0.4572)
		(drill 0.2032)
		(layers "F.Cu" "B.Cu")
		(net "GND")
	)
	(via
		(at 243.099844 -43.50004)
		(size 0.4572)
		(drill 0.2032)
		(layers "F.Cu" "B.Cu")
		(net "GND")
	)
	(via
		(at 231.100122 -43.50004)
		(size 0.4572)
		(drill 0.2032)
		(layers "F.Cu" "B.Cu")
		(net "GND")
	)
	(via
		(at 320.5226 -18.043906)
		(size 0.508)
		(drill 0.254)
		(layers "F.Cu" "B.Cu")
		(net "GND")
	)
	(via
		(at 149.352 -18.3388)
		(size 0.508)
		(drill 0.254)
		(layers "F.Cu" "B.Cu")
		(net "GND")
	)
	(via
		(at 241.099848 -64.499744)
		(size 0.4572)
		(drill 0.2032)
		(layers "F.Cu" "B.Cu")
		(net "GND")
	)
	(via
		(at 147.1168 -35.6616)
		(size 0.508)
		(drill 0.254)
		(layers "F.Cu" "B.Cu")
		(net "GND")
	)
	(via
		(at 145.0086 -14.2748)
		(size 0.508)
		(drill 0.254)
		(layers "F.Cu" "B.Cu")
		(net "GND")
	)
	(via
		(at 92.100146 -223.082104)
		(size 0.508)
		(drill 0.254)
		(layers "F.Cu" "B.Cu")
		(net "GND")
	)
	(via
		(at 151.95296 -35.0012)
		(size 0.508)
		(drill 0.254)
		(layers "F.Cu" "B.Cu")
		(net "GND")
	)
	(via
		(at 348.488 -61.087)
		(size 0.7112)
		(drill 0.4064)
		(layers "F.Cu" "B.Cu")
		(net "GND")
	)
	(via
		(at 155.337002 -72.290432)
		(size 0.7112)
		(drill 0.4064)
		(layers "F.Cu" "B.Cu")
		(net "GND")
	)
	(via
		(at 323.469 -100.838)
		(size 0.508)
		(drill 0.254)
		(layers "F.Cu" "B.Cu")
		(net "GND")
	)
	(via
		(at 276.672294 3.60299)
		(size 0.508)
		(drill 0.254)
		(layers "F.Cu" "B.Cu")
		(net "GND")
	)
	(via
		(at 22.7076 -119.4816)
		(size 0.508)
		(drill 0.254)
		(layers "F.Cu" "B.Cu")
		(net "GND")
	)
	(via
		(at 231.100122 -44.500038)
		(size 0.4572)
		(drill 0.2032)
		(layers "F.Cu" "B.Cu")
		(net "GND")
	)
	(via
		(at 248.9454 -3.683)
		(size 0.508)
		(drill 0.254)
		(layers "F.Cu" "B.Cu")
		(net "GND")
	)
	(via
		(at 216.281 -179.197)
		(size 0.508)
		(drill 0.254)
		(layers "F.Cu" "B.Cu")
		(net "GND")
	)
	(via
		(at 139.7 -223.082104)
		(size 0.508)
		(drill 0.254)
		(layers "F.Cu" "B.Cu")
		(net "GND")
	)
	(via
		(at 224.100136 -41.500044)
		(size 0.4572)
		(drill 0.2032)
		(layers "F.Cu" "B.Cu")
		(net "GND")
	)
	(via
		(at 7.366 -156.464)
		(size 0.7112)
		(drill 0.3556)
		(layers "F.Cu" "B.Cu")
		(net "GND")
	)
	(via
		(at 28.2956 -182.4482)
		(size 0.508)
		(drill 0.254)
		(layers "F.Cu" "B.Cu")
		(net "GND")
	)
	(via
		(at 319.024 -26.2382)
		(size 0.508)
		(drill 0.254)
		(layers "F.Cu" "B.Cu")
		(net "GND")
	)
	(via
		(at 248.099834 -63.499746)
		(size 0.4572)
		(drill 0.2032)
		(layers "F.Cu" "B.Cu")
		(net "GND")
	)
	(via
		(at 214.099902 -223.082104)
		(size 0.508)
		(drill 0.254)
		(layers "F.Cu" "B.Cu")
		(net "GND")
	)
	(via
		(at 259.7404 -137.6934)
		(size 0.508)
		(drill 0.254)
		(layers "F.Cu" "B.Cu")
		(net "GND")
	)
	(via
		(at 161.671 -90.551)
		(size 0.508)
		(drill 0.254)
		(layers "F.Cu" "B.Cu")
		(net "GND")
	)
	(via
		(at 229.682548 -3.783076)
		(size 0.508)
		(drill 0.254)
		(layers "F.Cu" "B.Cu")
		(net "GND")
	)
	(via
		(at 235.100114 -55.499762)
		(size 0.4572)
		(drill 0.2032)
		(layers "F.Cu" "B.Cu")
		(net "GND")
	)
	(via
		(at 322.9102 -19.5834)
		(size 0.508)
		(drill 0.254)
		(layers "F.Cu" "B.Cu")
		(net "GND")
	)
	(via
		(at 152.499822 -223.082104)
		(size 0.508)
		(drill 0.254)
		(layers "F.Cu" "B.Cu")
		(net "GND")
	)
	(via
		(at 229.235 -93.98)
		(size 0.508)
		(drill 0.254)
		(layers "F.Cu" "B.Cu")
		(net "GND")
	)
	(via
		(at 6.3627 -182.0926)
		(size 0.508)
		(drill 0.254)
		(layers "F.Cu" "B.Cu")
		(net "GND")
	)
	(via
		(at 148.4884 -19.8628)
		(size 0.508)
		(drill 0.254)
		(layers "F.Cu" "B.Cu")
		(net "GND")
	)
	(via
		(at 324.14718 -210.152996)
		(size 0.508)
		(drill 0.254)
		(layers "F.Cu" "B.Cu")
		(net "GND")
	)
	(via
		(at 291.8714 -11.7602)
		(size 0.508)
		(drill 0.254)
		(layers "F.Cu" "B.Cu")
		(net "GND")
	)
	(via
		(at 27.89174 -78.830932)
		(size 0.508)
		(drill 0.254)
		(layers "F.Cu" "B.Cu")
		(net "GND")
	)
	(via
		(at 194.947286 -210.152996)
		(size 0.508)
		(drill 0.254)
		(layers "F.Cu" "B.Cu")
		(net "GND")
	)
	(via
		(at 303.23663 -35.01517)
		(size 0.508)
		(drill 0.254)
		(layers "F.Cu" "B.Cu")
		(net "GND")
	)
	(via
		(at 135.361934 -75.802744)
		(size 0.508)
		(drill 0.254)
		(layers "F.Cu" "B.Cu")
		(net "GND")
	)
	(via
		(at 65.913 -40.8305)
		(size 0.508)
		(drill 0.254)
		(layers "F.Cu" "B.Cu")
		(net "GND")
	)
	(via
		(at 242.099846 -29.500068)
		(size 0.4572)
		(drill 0.2032)
		(layers "F.Cu" "B.Cu")
		(net "GND")
	)
	(via
		(at 169.799 -177.8)
		(size 0.508)
		(drill 0.254)
		(layers "F.Cu" "B.Cu")
		(net "GND")
	)
	(via
		(at 69.652388 -210.152996)
		(size 0.508)
		(drill 0.254)
		(layers "F.Cu" "B.Cu")
		(net "GND")
	)
	(via
		(at 347.479112 -44.63923)
		(size 0.508)
		(drill 0.254)
		(layers "F.Cu" "B.Cu")
		(net "GND")
	)
	(via
		(at 25.634696 -104.131872)
		(size 0.508)
		(drill 0.254)
		(layers "F.Cu" "B.Cu")
		(net "GND")
	)
	(via
		(at 241.099848 -41.500044)
		(size 0.4572)
		(drill 0.2032)
		(layers "F.Cu" "B.Cu")
		(net "GND")
	)
	(via
		(at 148.6154 -26.2382)
		(size 0.508)
		(drill 0.254)
		(layers "F.Cu" "B.Cu")
		(net "GND")
	)
	(via
		(at 53.34 -191.897)
		(size 0.508)
		(drill 0.254)
		(layers "F.Cu" "B.Cu")
		(net "GND")
	)
	(via
		(at 303.8348 -71.12)
		(size 0.7112)
		(drill 0.4064)
		(layers "F.Cu" "B.Cu")
		(net "GND")
	)
	(via
		(at 29.464 -49.911)
		(size 0.508)
		(drill 0.254)
		(layers "F.Cu" "B.Cu")
		(net "GND")
	)
	(via
		(at 249.099832 -45.500036)
		(size 0.4572)
		(drill 0.2032)
		(layers "F.Cu" "B.Cu")
		(net "GND")
	)
	(via
		(at 223.100138 -31.500064)
		(size 0.4572)
		(drill 0.2032)
		(layers "F.Cu" "B.Cu")
		(net "GND")
	)
	(via
		(at 159.5882 -26.2382)
		(size 0.508)
		(drill 0.254)
		(layers "F.Cu" "B.Cu")
		(net "GND")
	)
	(via
		(at 300.895766 -34.98596)
		(size 0.508)
		(drill 0.254)
		(layers "F.Cu" "B.Cu")
		(net "GND")
	)
	(via
		(at 298.100242 -223.0628)
		(size 0.508)
		(drill 0.254)
		(layers "F.Cu" "B.Cu")
		(net "GND")
	)
	(via
		(at 354.203 -106.585004)
		(size 0.508)
		(drill 0.254)
		(layers "F.Cu" "B.Cu")
		(net "GND")
	)
	(via
		(at 37.12591 -112.998504)
		(size 0.508)
		(drill 0.254)
		(layers "F.Cu" "B.Cu")
		(net "GND")
	)
	(via
		(at 79.097124 -136.129776)
		(size 0.508)
		(drill 0.254)
		(layers "F.Cu" "B.Cu")
		(net "GND")
	)
	(via
		(at 265.700002 -223.082104)
		(size 0.508)
		(drill 0.254)
		(layers "F.Cu" "B.Cu")
		(net "GND")
	)
	(via
		(at 38.17112 -161.70148)
		(size 0.508)
		(drill 0.254)
		(layers "F.Cu" "B.Cu")
		(net "GND")
	)
	(via
		(at 257.099816 -37.500052)
		(size 0.4572)
		(drill 0.2032)
		(layers "F.Cu" "B.Cu")
		(net "GND")
	)
	(via
		(at 303.403 -54.7878)
		(size 0.7112)
		(drill 0.4064)
		(layers "F.Cu" "B.Cu")
		(net "GND")
	)
	(via
		(at 90.54719 -210.152996)
		(size 0.508)
		(drill 0.254)
		(layers "F.Cu" "B.Cu")
		(net "GND")
	)
	(via
		(at 320.5226 -21.844)
		(size 0.508)
		(drill 0.254)
		(layers "F.Cu" "B.Cu")
		(net "GND")
	)
	(via
		(at 298.958 -26.1112)
		(size 0.508)
		(drill 0.254)
		(layers "F.Cu" "B.Cu")
		(net "GND")
	)
	(via
		(at 27.4193 -174.6631)
		(size 0.508)
		(drill 0.254)
		(layers "F.Cu" "B.Cu")
		(net "GND")
	)
	(via
		(at 19.115024 -94.056962)
		(size 0.508)
		(drill 0.254)
		(layers "F.Cu" "B.Cu")
		(net "GND")
	)
	(via
		(at 248.92 -71.4502)
		(size 0.7112)
		(drill 0.3556)
		(layers "F.Cu" "B.Cu")
		(net "GND")
	)
	(via
		(at 60.900056 -223.082104)
		(size 0.508)
		(drill 0.254)
		(layers "F.Cu" "B.Cu")
		(net "GND")
	)
	(via
		(at 155.699968 -223.082104)
		(size 0.508)
		(drill 0.254)
		(layers "F.Cu" "B.Cu")
		(net "GND")
	)
	(via
		(at 33.782 -115.4938)
		(size 0.508)
		(drill 0.254)
		(layers "F.Cu" "B.Cu")
		(net "GND")
	)
	(via
		(at 231.100122 -65.499742)
		(size 0.4572)
		(drill 0.2032)
		(layers "F.Cu" "B.Cu")
		(net "GND")
	)
	(via
		(at 39.66718 -80.848708)
		(size 0.7112)
		(drill 0.4064)
		(layers "F.Cu" "B.Cu")
		(net "GND")
	)
	(via
		(at 63.4238 -133.537198)
		(size 0.508)
		(drill 0.254)
		(layers "F.Cu" "B.Cu")
		(net "GND")
	)
	(via
		(at 34.937954 -159.981646)
		(size 0.508)
		(drill 0.254)
		(layers "F.Cu" "B.Cu")
		(net "GND")
	)
	(via
		(at 190.941198 -49.286668)
		(size 0.508)
		(drill 0.254)
		(layers "F.Cu" "B.Cu")
		(net "GND")
	)
	(via
		(at 254.099822 -32.500062)
		(size 0.4572)
		(drill 0.2032)
		(layers "F.Cu" "B.Cu")
		(net "GND")
	)
	(via
		(at 49.149 -191.897)
		(size 0.508)
		(drill 0.254)
		(layers "F.Cu" "B.Cu")
		(net "GND")
	)
	(via
		(at 291.347144 -210.152996)
		(size 0.508)
		(drill 0.254)
		(layers "F.Cu" "B.Cu")
		(net "GND")
	)
	(via
		(at 186.729878 -24.63927)
		(size 0.508)
		(drill 0.254)
		(layers "F.Cu" "B.Cu")
		(net "GND")
	)
	(via
		(at 7.2136 -66.7512)
		(size 0.508)
		(drill 0.254)
		(layers "F.Cu" "B.Cu")
		(net "GND")
	)
	(via
		(at 254.099822 -61.49975)
		(size 0.4572)
		(drill 0.2032)
		(layers "F.Cu" "B.Cu")
		(net "GND")
	)
	(via
		(at 31.126938 -140.143992)
		(size 0.4572)
		(drill 0.2032)
		(layers "F.Cu" "B.Cu")
		(net "GND")
	)
	(via
		(at 198.147178 -210.152996)
		(size 0.508)
		(drill 0.254)
		(layers "F.Cu" "B.Cu")
		(net "GND")
	)
	(via
		(at 134.1374 -194.8942)
		(size 0.5588)
		(drill 0.3048)
		(layers "F.Cu" "B.Cu")
		(net "GND")
	)
	(via
		(at 229.100126 -61.49975)
		(size 0.4572)
		(drill 0.2032)
		(layers "F.Cu" "B.Cu")
		(net "GND")
	)
	(via
		(at 215.876124 -204.350874)
		(size 0.508)
		(drill 0.254)
		(layers "F.Cu" "B.Cu")
		(net "GND")
	)
	(via
		(at 17.9832 -142.21333)
		(size 0.508)
		(drill 0.254)
		(layers "F.Cu" "B.Cu")
		(net "GND")
	)
	(via
		(at 225.100134 -55.499762)
		(size 0.4572)
		(drill 0.2032)
		(layers "F.Cu" "B.Cu")
		(net "GND")
	)
	(via
		(at 256.099818 -32.500062)
		(size 0.4572)
		(drill 0.2032)
		(layers "F.Cu" "B.Cu")
		(net "GND")
	)
	(via
		(at 30.099 -46.99)
		(size 0.508)
		(drill 0.254)
		(layers "F.Cu" "B.Cu")
		(net "GND")
	)
	(via
		(at 6.731 -50.673)
		(size 0.508)
		(drill 0.254)
		(layers "F.Cu" "B.Cu")
		(net "GND")
	)
	(via
		(at 92.052394 -210.152996)
		(size 0.508)
		(drill 0.254)
		(layers "F.Cu" "B.Cu")
		(net "GND")
	)
	(via
		(at 354.203 -71.025004)
		(size 0.508)
		(drill 0.254)
		(layers "F.Cu" "B.Cu")
		(net "GND")
	)
	(via
		(at 74.676 -181.864)
		(size 0.5588)
		(drill 0.3048)
		(layers "F.Cu" "B.Cu")
		(net "GND")
	)
	(via
		(at 47.117 -223.0628)
		(size 0.508)
		(drill 0.254)
		(layers "F.Cu" "B.Cu")
		(net "GND")
	)
	(via
		(at 41.31818 -79.832708)
		(size 0.7112)
		(drill 0.4064)
		(layers "F.Cu" "B.Cu")
		(net "GND")
	)
	(via
		(at 235.5215 -7.9883)
		(size 0.508)
		(drill 0.254)
		(layers "F.Cu" "B.Cu")
		(net "GND")
	)
	(via
		(at 154.321002 -67.464432)
		(size 0.7112)
		(drill 0.4064)
		(layers "F.Cu" "B.Cu")
		(net "GND")
	)
	(via
		(at 278.499824 -223.082104)
		(size 0.508)
		(drill 0.254)
		(layers "F.Cu" "B.Cu")
		(net "GND")
	)
	(via
		(at 221.2086 -206.274416)
		(size 0.508)
		(drill 0.254)
		(layers "F.Cu" "B.Cu")
		(net "GND")
	)
	(via
		(at 51.181 -220.6498)
		(size 0.508)
		(drill 0.254)
		(layers "F.Cu" "B.Cu")
		(net "GND")
	)
	(via
		(at 337.392518 -62.557914)
		(size 0.7112)
		(drill 0.4064)
		(layers "F.Cu" "B.Cu")
		(net "GND")
	)
	(via
		(at 183.734202 -75.160632)
		(size 0.7112)
		(drill 0.4064)
		(layers "F.Cu" "B.Cu")
		(net "GND")
	)
	(via
		(at 231.100122 -37.500052)
		(size 0.4572)
		(drill 0.2032)
		(layers "F.Cu" "B.Cu")
		(net "GND")
	)
	(via
		(at 20.999704 -53.03139)
		(size 0.508)
		(drill 0.254)
		(layers "F.Cu" "B.Cu")
		(net "GND")
	)
	(via
		(at 231.100122 -63.499746)
		(size 0.4572)
		(drill 0.2032)
		(layers "F.Cu" "B.Cu")
		(net "GND")
	)
	(via
		(at 25.178512 -93.208094)
		(size 0.508)
		(drill 0.254)
		(layers "F.Cu" "B.Cu")
		(net "GND")
	)
	(via
		(at 139.0396 -34.58718)
		(size 0.508)
		(drill 0.254)
		(layers "F.Cu" "B.Cu")
		(net "GND")
	)
	(via
		(at 153.101802 -62.257432)
		(size 0.508)
		(drill 0.254)
		(layers "F.Cu" "B.Cu")
		(net "GND")
	)
	(via
		(at 230.100124 -45.500036)
		(size 0.4572)
		(drill 0.2032)
		(layers "F.Cu" "B.Cu")
		(net "GND")
	)
	(via
		(at 245.09984 -54.499764)
		(size 0.4572)
		(drill 0.2032)
		(layers "F.Cu" "B.Cu")
		(net "GND")
	)
	(via
		(at 251.099828 -32.500062)
		(size 0.4572)
		(drill 0.2032)
		(layers "F.Cu" "B.Cu")
		(net "GND")
	)
	(via
		(at 312.166 -53.467)
		(size 0.7112)
		(drill 0.4064)
		(layers "F.Cu" "B.Cu")
		(net "GND")
	)
	(via
		(at 287.4772 -21.7424)
		(size 0.508)
		(drill 0.254)
		(layers "F.Cu" "B.Cu")
		(net "GND")
	)
	(via
		(at 57.023 -42.2402)
		(size 0.7112)
		(drill 0.4064)
		(layers "F.Cu" "B.Cu")
		(net "GND")
	)
	(via
		(at 229.100126 -48.499776)
		(size 0.4572)
		(drill 0.2032)
		(layers "F.Cu" "B.Cu")
		(net "GND")
	)
	(via
		(at 276.900132 -223.082104)
		(size 0.508)
		(drill 0.254)
		(layers "F.Cu" "B.Cu")
		(net "GND")
	)
	(via
		(at 147.5232 -19.304)
		(size 0.508)
		(drill 0.254)
		(layers "F.Cu" "B.Cu")
		(net "GND")
	)
	(via
		(at 80.947006 -210.152996)
		(size 0.508)
		(drill 0.254)
		(layers "F.Cu" "B.Cu")
		(net "GND")
	)
	(via
		(at 248.099834 -57.499758)
		(size 0.4572)
		(drill 0.2032)
		(layers "F.Cu" "B.Cu")
		(net "GND")
	)
	(via
		(at 247.099836 -61.49975)
		(size 0.4572)
		(drill 0.2032)
		(layers "F.Cu" "B.Cu")
		(net "GND")
	)
	(via
		(at 121.8438 -22.8854)
		(size 0.508)
		(drill 0.254)
		(layers "F.Cu" "B.Cu")
		(net "GND")
	)
	(via
		(at 135.579866 -85.592666)
		(size 0.508)
		(drill 0.254)
		(layers "F.Cu" "B.Cu")
		(net "GND")
	)
	(via
		(at 354.203 -126.905004)
		(size 0.508)
		(drill 0.254)
		(layers "F.Cu" "B.Cu")
		(net "GND")
	)
	(via
		(at 160.2994 -18.3642)
		(size 0.508)
		(drill 0.254)
		(layers "F.Cu" "B.Cu")
		(net "GND")
	)
	(via
		(at 155.337002 -70.639432)
		(size 0.7112)
		(drill 0.4064)
		(layers "F.Cu" "B.Cu")
		(net "GND")
	)
	(via
		(at 227.10013 -58.499756)
		(size 0.4572)
		(drill 0.2032)
		(layers "F.Cu" "B.Cu")
		(net "GND")
	)
	(via
		(at 37.211 -199.263)
		(size 0.508)
		(drill 0.254)
		(layers "F.Cu" "B.Cu")
		(net "GND")
	)
	(via
		(at 227.10013 -64.499744)
		(size 0.4572)
		(drill 0.2032)
		(layers "F.Cu" "B.Cu")
		(net "GND")
	)
	(via
		(at 181.9402 -58.0898)
		(size 0.7112)
		(drill 0.4064)
		(layers "F.Cu" "B.Cu")
		(net "GND")
	)
	(via
		(at 23.792688 -68.618862)
		(size 0.508)
		(drill 0.254)
		(layers "F.Cu" "B.Cu")
		(net "GND")
	)
	(via
		(at 231.100122 -54.499764)
		(size 0.4572)
		(drill 0.2032)
		(layers "F.Cu" "B.Cu")
		(net "GND")
	)
	(via
		(at 190.052452 -210.152996)
		(size 0.508)
		(drill 0.254)
		(layers "F.Cu" "B.Cu")
		(net "GND")
	)
	(via
		(at 138.8872 -11.7602)
		(size 0.508)
		(drill 0.254)
		(layers "F.Cu" "B.Cu")
		(net "GND")
	)
	(via
		(at 53.0098 -210.312)
		(size 0.508)
		(drill 0.254)
		(layers "F.Cu" "B.Cu")
		(net "GND")
	)
	(via
		(at 136.1694 -14.4018)
		(size 0.508)
		(drill 0.254)
		(layers "F.Cu" "B.Cu")
		(net "GND")
	)
	(via
		(at 146.177 -19.939)
		(size 0.508)
		(drill 0.254)
		(layers "F.Cu" "B.Cu")
		(net "GND")
	)
	(via
		(at 81.833212 -185.211212)
		(size 0.508)
		(drill 0.254)
		(layers "F.Cu" "B.Cu")
		(net "GND")
	)
	(via
		(at 229.100126 -55.499762)
		(size 0.4572)
		(drill 0.2032)
		(layers "F.Cu" "B.Cu")
		(net "GND")
	)
	(via
		(at 32.2072 -92.075)
		(size 0.508)
		(drill 0.254)
		(layers "F.Cu" "B.Cu")
		(net "GND")
	)
	(via
		(at 280.226262 -19.53514)
		(size 0.508)
		(drill 0.254)
		(layers "F.Cu" "B.Cu")
		(net "GND")
	)
	(via
		(at 231.100122 -50.499772)
		(size 0.4572)
		(drill 0.2032)
		(layers "F.Cu" "B.Cu")
		(net "GND")
	)
	(via
		(at 67.691 -48.387)
		(size 0.7112)
		(drill 0.4064)
		(layers "F.Cu" "B.Cu")
		(net "GND")
	)
	(via
		(at 161.0614 -11.8872)
		(size 0.508)
		(drill 0.254)
		(layers "F.Cu" "B.Cu")
		(net "GND")
	)
	(via
		(at 153.686002 -65.432432)
		(size 0.7112)
		(drill 0.4064)
		(layers "F.Cu" "B.Cu")
		(net "GND")
	)
	(via
		(at 211.893658 -2.286)
		(size 0.508)
		(drill 0.254)
		(layers "F.Cu" "B.Cu")
		(net "GND")
	)
	(via
		(at 77.879448 -116.884958)
		(size 0.508)
		(drill 0.254)
		(layers "F.Cu" "B.Cu")
		(net "GND")
	)
	(via
		(at 197.240652 -27.219148)
		(size 0.508)
		(drill 0.254)
		(layers "F.Cu" "B.Cu")
		(net "GND")
	)
	(via
		(at 228.219 -126.746)
		(size 0.7112)
		(drill 0.3556)
		(layers "F.Cu" "B.Cu")
		(net "GND")
	)
	(via
		(at 135.2296 -19.8628)
		(size 0.508)
		(drill 0.254)
		(layers "F.Cu" "B.Cu")
		(net "GND")
	)
	(via
		(at 166.497 -54.229)
		(size 0.508)
		(drill 0.254)
		(layers "F.Cu" "B.Cu")
		(net "GND")
	)
	(via
		(at 214.249 -2.3241)
		(size 0.508)
		(drill 0.254)
		(layers "F.Cu" "B.Cu")
		(net "GND")
	)
	(via
		(at 250.09983 -54.499764)
		(size 0.4572)
		(drill 0.2032)
		(layers "F.Cu" "B.Cu")
		(net "GND")
	)
	(via
		(at 29.5402 -55.3974)
		(size 0.7112)
		(drill 0.3556)
		(layers "F.Cu" "B.Cu")
		(net "GND")
	)
	(via
		(at 230.100124 -31.500064)
		(size 0.4572)
		(drill 0.2032)
		(layers "F.Cu" "B.Cu")
		(net "GND")
	)
	(via
		(at 308.9402 -18.5166)
		(size 0.508)
		(drill 0.254)
		(layers "F.Cu" "B.Cu")
		(net "GND")
	)
	(via
		(at 72.1868 -118.11)
		(size 0.508)
		(drill 0.254)
		(layers "F.Cu" "B.Cu")
		(net "GND")
	)
	(via
		(at 273.70024 -223.082104)
		(size 0.508)
		(drill 0.254)
		(layers "F.Cu" "B.Cu")
		(net "GND")
	)
	(via
		(at 27.554936 -88.487758)
		(size 0.508)
		(drill 0.254)
		(layers "F.Cu" "B.Cu")
		(net "GND")
	)
	(via
		(at 292.9001 -223.082104)
		(size 0.508)
		(drill 0.254)
		(layers "F.Cu" "B.Cu")
		(net "GND")
	)
	(via
		(at 283.30017 -223.082104)
		(size 0.508)
		(drill 0.254)
		(layers "F.Cu" "B.Cu")
		(net "GND")
	)
	(via
		(at 339.598 -67.945)
		(size 0.508)
		(drill 0.254)
		(layers "F.Cu" "B.Cu")
		(net "GND")
	)
	(via
		(at 43.561 -52.705)
		(size 0.508)
		(drill 0.254)
		(layers "F.Cu" "B.Cu")
		(net "GND")
	)
	(via
		(at 252.099826 -32.500062)
		(size 0.4572)
		(drill 0.2032)
		(layers "F.Cu" "B.Cu")
		(net "GND")
	)
	(via
		(at 227.838 -24.5618)
		(size 0.508)
		(drill 0.254)
		(layers "F.Cu" "B.Cu")
		(net "GND")
	)
	(via
		(at 151.831802 -63.527432)
		(size 0.508)
		(drill 0.254)
		(layers "F.Cu" "B.Cu")
		(net "GND")
	)
	(via
		(at 247.099836 -59.499754)
		(size 0.4572)
		(drill 0.2032)
		(layers "F.Cu" "B.Cu")
		(net "GND")
	)
	(via
		(at 37.30498 -129.685034)
		(size 0.4572)
		(drill 0.2032)
		(layers "F.Cu" "B.Cu")
		(net "GND")
	)
	(via
		(at 85.700108 -223.082104)
		(size 0.508)
		(drill 0.254)
		(layers "F.Cu" "B.Cu")
		(net "GND")
	)
	(via
		(at 179.670202 -75.719432)
		(size 0.7112)
		(drill 0.4064)
		(layers "F.Cu" "B.Cu")
		(net "GND")
	)
	(via
		(at 196.5706 -35.1282)
		(size 0.508)
		(drill 0.254)
		(layers "F.Cu" "B.Cu")
		(net "GND")
	)
	(via
		(at 67.8942 -76.3524)
		(size 0.508)
		(drill 0.254)
		(layers "F.Cu" "B.Cu")
		(net "GND")
	)
	(via
		(at 245.09984 -50.499772)
		(size 0.4572)
		(drill 0.2032)
		(layers "F.Cu" "B.Cu")
		(net "GND")
	)
	(via
		(at 303.276 -23.6728)
		(size 0.508)
		(drill 0.254)
		(layers "F.Cu" "B.Cu")
		(net "GND")
	)
	(via
		(at 241.099848 -63.499746)
		(size 0.4572)
		(drill 0.2032)
		(layers "F.Cu" "B.Cu")
		(net "GND")
	)
	(via
		(at 18.1356 -146.8882)
		(size 0.508)
		(drill 0.254)
		(layers "F.Cu" "B.Cu")
		(net "GND")
	)
	(via
		(at 255.09982 -60.499752)
		(size 0.4572)
		(drill 0.2032)
		(layers "F.Cu" "B.Cu")
		(net "GND")
	)
	(via
		(at 102.5906 -80.134968)
		(size 0.508)
		(drill 0.254)
		(layers "F.Cu" "B.Cu")
		(net "GND")
	)
	(via
		(at 246.099838 -40.500046)
		(size 0.4572)
		(drill 0.2032)
		(layers "F.Cu" "B.Cu")
		(net "GND")
	)
	(via
		(at 67.183 -39.9415)
		(size 0.508)
		(drill 0.254)
		(layers "F.Cu" "B.Cu")
		(net "GND")
	)
	(via
		(at 46.161452 -31.168594)
		(size 0.508)
		(drill 0.254)
		(layers "F.Cu" "B.Cu")
		(net "GND")
	)
	(via
		(at 256.099818 -51.49977)
		(size 0.4572)
		(drill 0.2032)
		(layers "F.Cu" "B.Cu")
		(net "GND")
	)
	(via
		(at 17.78508 -212.102954)
		(size 0.508)
		(drill 0.254)
		(layers "F.Cu" "B.Cu")
		(net "GND")
	)
	(via
		(at 69.699124 -182.015892)
		(size 0.508)
		(drill 0.254)
		(layers "F.Cu" "B.Cu")
		(net "GND")
	)
	(via
		(at 116.1796 -35.2806)
		(size 0.508)
		(drill 0.254)
		(layers "F.Cu" "B.Cu")
		(net "GND")
	)
	(via
		(at 259.099812 -61.49975)
		(size 0.4572)
		(drill 0.2032)
		(layers "F.Cu" "B.Cu")
		(net "GND")
	)
	(via
		(at 174.099982 -223.082104)
		(size 0.508)
		(drill 0.254)
		(layers "F.Cu" "B.Cu")
		(net "GND")
	)
	(via
		(at 258.099814 -32.500062)
		(size 0.4572)
		(drill 0.2032)
		(layers "F.Cu" "B.Cu")
		(net "GND")
	)
	(via
		(at 87.0966 -184.7088)
		(size 0.508)
		(drill 0.254)
		(layers "F.Cu" "B.Cu")
		(net "GND")
	)
	(via
		(at 68.58 -186.0931)
		(size 0.508)
		(drill 0.254)
		(layers "F.Cu" "B.Cu")
		(net "GND")
	)
	(via
		(at 237.10011 -58.499756)
		(size 0.4572)
		(drill 0.2032)
		(layers "F.Cu" "B.Cu")
		(net "GND")
	)
	(via
		(at 320.900044 -223.082104)
		(size 0.508)
		(drill 0.254)
		(layers "F.Cu" "B.Cu")
		(net "GND")
	)
	(via
		(at 245.09984 -43.50004)
		(size 0.4572)
		(drill 0.2032)
		(layers "F.Cu" "B.Cu")
		(net "GND")
	)
	(via
		(at 138.052556 -210.152996)
		(size 0.508)
		(drill 0.254)
		(layers "F.Cu" "B.Cu")
		(net "GND")
	)
	(via
		(at 346.4306 -136.5504)
		(size 0.508)
		(drill 0.254)
		(layers "F.Cu" "B.Cu")
		(net "GND")
	)
	(via
		(at 244.099842 -46.500034)
		(size 0.4572)
		(drill 0.2032)
		(layers "F.Cu" "B.Cu")
		(net "GND")
	)
	(via
		(at 184.568084 -10.833354)
		(size 0.508)
		(drill 0.254)
		(layers "F.Cu" "B.Cu")
		(net "GND")
	)
	(via
		(at 307.467 -71.12)
		(size 0.7112)
		(drill 0.4064)
		(layers "F.Cu" "B.Cu")
		(net "GND")
	)
	(via
		(at 303.299876 -223.082104)
		(size 0.508)
		(drill 0.254)
		(layers "F.Cu" "B.Cu")
		(net "GND")
	)
	(via
		(at 118.2624 -108.712)
		(size 0.7112)
		(drill 0.3556)
		(layers "F.Cu" "B.Cu")
		(net "GND")
	)
	(via
		(at 247.099836 -58.499756)
		(size 0.4572)
		(drill 0.2032)
		(layers "F.Cu" "B.Cu")
		(net "GND")
	)
	(via
		(at 258.099814 -64.499744)
		(size 0.4572)
		(drill 0.2032)
		(layers "F.Cu" "B.Cu")
		(net "GND")
	)
	(via
		(at 195.9356 -47.223426)
		(size 0.508)
		(drill 0.254)
		(layers "F.Cu" "B.Cu")
		(net "GND")
	)
	(via
		(at 6.6802 -80.6704)
		(size 0.508)
		(drill 0.254)
		(layers "F.Cu" "B.Cu")
		(net "GND")
	)
	(via
		(at 328.744072 -221.530926)
		(size 0.508)
		(drill 0.254)
		(layers "F.Cu" "B.Cu")
		(net "GND")
	)
	(via
		(at 252.099826 -56.49976)
		(size 0.4572)
		(drill 0.2032)
		(layers "F.Cu" "B.Cu")
		(net "GND")
	)
	(via
		(at 243.099844 -57.499758)
		(size 0.4572)
		(drill 0.2032)
		(layers "F.Cu" "B.Cu")
		(net "GND")
	)
	(via
		(at 229.100126 -52.499768)
		(size 0.4572)
		(drill 0.2032)
		(layers "F.Cu" "B.Cu")
		(net "GND")
	)
	(via
		(at 30.167834 -151.179784)
		(size 0.4572)
		(drill 0.2032)
		(layers "F.Cu" "B.Cu")
		(net "GND")
	)
	(via
		(at 244.099842 -63.499746)
		(size 0.4572)
		(drill 0.2032)
		(layers "F.Cu" "B.Cu")
		(net "GND")
	)
	(via
		(at 354.203 -172.625004)
		(size 0.508)
		(drill 0.254)
		(layers "F.Cu" "B.Cu")
		(net "GND")
	)
	(via
		(at 234.100116 -57.499758)
		(size 0.4572)
		(drill 0.2032)
		(layers "F.Cu" "B.Cu")
		(net "GND")
	)
	(via
		(at 12.192 -109.093)
		(size 0.508)
		(drill 0.254)
		(layers "F.Cu" "B.Cu")
		(net "GND")
	)
	(via
		(at 32.505142 -137.685018)
		(size 0.4572)
		(drill 0.2032)
		(layers "F.Cu" "B.Cu")
		(net "GND")
	)
	(via
		(at 67.794124 -196.984874)
		(size 0.508)
		(drill 0.254)
		(layers "F.Cu" "B.Cu")
		(net "GND")
	)
	(via
		(at 38.227 -204.216)
		(size 0.508)
		(drill 0.254)
		(layers "F.Cu" "B.Cu")
		(net "GND")
	)
	(via
		(at 174.147226 -210.152996)
		(size 0.508)
		(drill 0.254)
		(layers "F.Cu" "B.Cu")
		(net "GND")
	)
	(via
		(at 216.789 -65.278)
		(size 0.7112)
		(drill 0.3556)
		(layers "F.Cu" "B.Cu")
		(net "GND")
	)
	(via
		(at 129.9972 -195.1482)
		(size 0.508)
		(drill 0.254)
		(layers "F.Cu" "B.Cu")
		(net "GND")
	)
	(via
		(at 255.09982 -63.499746)
		(size 0.4572)
		(drill 0.2032)
		(layers "F.Cu" "B.Cu")
		(net "GND")
	)
	(via
		(at 64.068452 -145.856452)
		(size 0.508)
		(drill 0.254)
		(layers "F.Cu" "B.Cu")
		(net "GND")
	)
	(via
		(at 217.781124 -189.381892)
		(size 0.508)
		(drill 0.254)
		(layers "F.Cu" "B.Cu")
		(net "GND")
	)
	(via
		(at 259.099812 -60.499752)
		(size 0.4572)
		(drill 0.2032)
		(layers "F.Cu" "B.Cu")
		(net "GND")
	)
	(via
		(at 67.314826 -126.360682)
		(size 0.508)
		(drill 0.254)
		(layers "F.Cu" "B.Cu")
		(net "GND")
	)
	(via
		(at 117.3226 -15.8242)
		(size 0.508)
		(drill 0.254)
		(layers "F.Cu" "B.Cu")
		(net "GND")
	)
	(via
		(at 309.753 -23.6982)
		(size 0.508)
		(drill 0.254)
		(layers "F.Cu" "B.Cu")
		(net "GND")
	)
	(via
		(at 320.675 -49.403)
		(size 0.7112)
		(drill 0.4064)
		(layers "F.Cu" "B.Cu")
		(net "GND")
	)
	(via
		(at 83.312 -50.1396)
		(size 0.7112)
		(drill 0.4064)
		(layers "F.Cu" "B.Cu")
		(net "GND")
	)
	(via
		(at 46.904656 -131.284726)
		(size 0.4572)
		(drill 0.2032)
		(layers "F.Cu" "B.Cu")
		(net "GND")
	)
	(via
		(at 16.637 -74.1426)
		(size 0.508)
		(drill 0.254)
		(layers "F.Cu" "B.Cu")
		(net "GND")
	)
	(via
		(at 252.099826 -51.49977)
		(size 0.4572)
		(drill 0.2032)
		(layers "F.Cu" "B.Cu")
		(net "GND")
	)
	(via
		(at 249.809 -72.009)
		(size 0.508)
		(drill 0.254)
		(layers "F.Cu" "B.Cu")
		(net "GND")
	)
	(via
		(at 62.865 -59.3725)
		(size 0.508)
		(drill 0.254)
		(layers "F.Cu" "B.Cu")
		(net "GND")
	)
	(via
		(at 22.346412 -57.555384)
		(size 0.508)
		(drill 0.254)
		(layers "F.Cu" "B.Cu")
		(net "GND")
	)
	(via
		(at 247.099836 -37.500052)
		(size 0.4572)
		(drill 0.2032)
		(layers "F.Cu" "B.Cu")
		(net "GND")
	)
	(via
		(at 147.700238 -223.082104)
		(size 0.508)
		(drill 0.254)
		(layers "F.Cu" "B.Cu")
		(net "GND")
	)
	(via
		(at 243.099844 -59.499754)
		(size 0.4572)
		(drill 0.2032)
		(layers "F.Cu" "B.Cu")
		(net "GND")
	)
	(via
		(at 236.347 -14.605)
		(size 0.7112)
		(drill 0.4064)
		(layers "F.Cu" "B.Cu")
		(net "GND")
	)
	(via
		(at 57.942734 -16.151606)
		(size 0.508)
		(drill 0.254)
		(layers "F.Cu" "B.Cu")
		(net "GND")
	)
	(via
		(at 311.911746 -36.18611)
		(size 0.508)
		(drill 0.254)
		(layers "F.Cu" "B.Cu")
		(net "GND")
	)
	(via
		(at 256.099818 -60.499752)
		(size 0.4572)
		(drill 0.2032)
		(layers "F.Cu" "B.Cu")
		(net "GND")
	)
	(via
		(at 75.819 -191.008)
		(size 0.508)
		(drill 0.254)
		(layers "F.Cu" "B.Cu")
		(net "GND")
	)
	(via
		(at 17.380966 -73.205848)
		(size 0.508)
		(drill 0.254)
		(layers "F.Cu" "B.Cu")
		(net "GND")
	)
	(via
		(at 191.201802 -9.814052)
		(size 0.508)
		(drill 0.254)
		(layers "F.Cu" "B.Cu")
		(net "GND")
	)
	(via
		(at 260.097016 -217.396822)
		(size 0.508)
		(drill 0.254)
		(layers "F.Cu" "B.Cu")
		(net "GND")
	)
	(via
		(at 242.099846 -51.49977)
		(size 0.4572)
		(drill 0.2032)
		(layers "F.Cu" "B.Cu")
		(net "GND")
	)
	(via
		(at 59.182 -197.079362)
		(size 0.508)
		(drill 0.254)
		(layers "F.Cu" "B.Cu")
		(net "GND")
	)
	(via
		(at 230.100124 -53.499766)
		(size 0.4572)
		(drill 0.2032)
		(layers "F.Cu" "B.Cu")
		(net "GND")
	)
	(via
		(at 134.0358 -149.225)
		(size 0.508)
		(drill 0.254)
		(layers "F.Cu" "B.Cu")
		(net "GND")
	)
	(via
		(at 251.099828 -29.500068)
		(size 0.4572)
		(drill 0.2032)
		(layers "F.Cu" "B.Cu")
		(net "GND")
	)
	(via
		(at 340.868 -65.405)
		(size 0.508)
		(drill 0.254)
		(layers "F.Cu" "B.Cu")
		(net "GND")
	)
	(via
		(at 1.397 -157.371034)
		(size 0.508)
		(drill 0.254)
		(layers "F.Cu" "B.Cu")
		(net "GND")
	)
	(via
		(at 233.100118 -49.499774)
		(size 0.4572)
		(drill 0.2032)
		(layers "F.Cu" "B.Cu")
		(net "GND")
	)
	(via
		(at 57.700164 -223.082104)
		(size 0.508)
		(drill 0.254)
		(layers "F.Cu" "B.Cu")
		(net "GND")
	)
	(via
		(at 304.6222 -54.7878)
		(size 0.7112)
		(drill 0.4064)
		(layers "F.Cu" "B.Cu")
		(net "GND")
	)
	(via
		(at 100.852478 -210.152996)
		(size 0.508)
		(drill 0.254)
		(layers "F.Cu" "B.Cu")
		(net "GND")
	)
	(via
		(at 239.395 -7.6454)
		(size 0.508)
		(drill 0.254)
		(layers "F.Cu" "B.Cu")
		(net "GND")
	)
	(via
		(at 68.09994 -223.082104)
		(size 0.508)
		(drill 0.254)
		(layers "F.Cu" "B.Cu")
		(net "GND")
	)
	(via
		(at 194.625976 -47.217838)
		(size 0.508)
		(drill 0.254)
		(layers "F.Cu" "B.Cu")
		(net "GND")
	)
	(via
		(at 1.397 -142.131034)
		(size 0.508)
		(drill 0.254)
		(layers "F.Cu" "B.Cu")
		(net "GND")
	)
	(via
		(at 224.100136 -58.499756)
		(size 0.4572)
		(drill 0.2032)
		(layers "F.Cu" "B.Cu")
		(net "GND")
	)
	(via
		(at 153.101802 -60.098432)
		(size 0.508)
		(drill 0.254)
		(layers "F.Cu" "B.Cu")
		(net "GND")
	)
	(via
		(at 243.099844 -55.499762)
		(size 0.4572)
		(drill 0.2032)
		(layers "F.Cu" "B.Cu")
		(net "GND")
	)
	(via
		(at 125.6792 -41.3766)
		(size 0.508)
		(drill 0.254)
		(layers "F.Cu" "B.Cu")
		(net "GND")
	)
	(via
		(at 311.912 -14.478)
		(size 0.508)
		(drill 0.254)
		(layers "F.Cu" "B.Cu")
		(net "GND")
	)
	(via
		(at 19.1516 -78.6638)
		(size 0.508)
		(drill 0.254)
		(layers "F.Cu" "B.Cu")
		(net "GND")
	)
	(via
		(at 312.7756 -14.8082)
		(size 0.508)
		(drill 0.254)
		(layers "F.Cu" "B.Cu")
		(net "GND")
	)
	(via
		(at 224.832418 -207.414622)
		(size 0.508)
		(drill 0.254)
		(layers "F.Cu" "B.Cu")
		(net "GND")
	)
	(via
		(at 65.913 -39.6875)
		(size 0.508)
		(drill 0.254)
		(layers "F.Cu" "B.Cu")
		(net "GND")
	)
	(via
		(at 191.8208 -56.8452)
		(size 0.7112)
		(drill 0.3556)
		(layers "F.Cu" "B.Cu")
		(net "GND")
	)
	(via
		(at 40.0177 -101.3714)
		(size 0.508)
		(drill 0.254)
		(layers "F.Cu" "B.Cu")
		(net "GND")
	)
	(via
		(at 69.117464 -191.920368)
		(size 0.508)
		(drill 0.254)
		(layers "F.Cu" "B.Cu")
		(net "GND")
	)
	(via
		(at 225.100134 -53.499766)
		(size 0.4572)
		(drill 0.2032)
		(layers "F.Cu" "B.Cu")
		(net "GND")
	)
	(via
		(at 32.220154 -160.896046)
		(size 0.508)
		(drill 0.254)
		(layers "F.Cu" "B.Cu")
		(net "GND")
	)
	(via
		(at 301.0662 -54.7878)
		(size 0.7112)
		(drill 0.4064)
		(layers "F.Cu" "B.Cu")
		(net "GND")
	)
	(via
		(at 37.30498 -131.28498)
		(size 0.4572)
		(drill 0.2032)
		(layers "F.Cu" "B.Cu")
		(net "GND")
	)
	(via
		(at 86.233 -50.165)
		(size 0.7112)
		(drill 0.4064)
		(layers "F.Cu" "B.Cu")
		(net "GND")
	)
	(via
		(at 141.3002 -223.082104)
		(size 0.508)
		(drill 0.254)
		(layers "F.Cu" "B.Cu")
		(net "GND")
	)
	(via
		(at 30.099 -43.942)
		(size 0.508)
		(drill 0.254)
		(layers "F.Cu" "B.Cu")
		(net "GND")
	)
	(via
		(at 232.745026 -192.681352)
		(size 0.508)
		(drill 0.254)
		(layers "F.Cu" "B.Cu")
		(net "GND")
	)
	(via
		(at 354.203 -60.865004)
		(size 0.508)
		(drill 0.254)
		(layers "F.Cu" "B.Cu")
		(net "GND")
	)
	(via
		(at 193.6496 -32.4104)
		(size 0.508)
		(drill 0.254)
		(layers "F.Cu" "B.Cu")
		(net "GND")
	)
	(via
		(at 7.1628 -75.2094)
		(size 0.508)
		(drill 0.254)
		(layers "F.Cu" "B.Cu")
		(net "GND")
	)
	(via
		(at 331.4192 -206.2226)
		(size 0.508)
		(drill 0.254)
		(layers "F.Cu" "B.Cu")
		(net "GND")
	)
	(via
		(at 337.256628 -48.915066)
		(size 0.7112)
		(drill 0.4064)
		(layers "F.Cu" "B.Cu")
		(net "GND")
	)
	(via
		(at 338.501482 -63.197486)
		(size 0.7112)
		(drill 0.4064)
		(layers "F.Cu" "B.Cu")
		(net "GND")
	)
	(via
		(at 38.904926 -131.28498)
		(size 0.4572)
		(drill 0.2032)
		(layers "F.Cu" "B.Cu")
		(net "GND")
	)
	(via
		(at 19.8247 -49.8602)
		(size 0.508)
		(drill 0.254)
		(layers "F.Cu" "B.Cu")
		(net "GND")
	)
	(via
		(at 65.494154 -16.151606)
		(size 0.508)
		(drill 0.254)
		(layers "F.Cu" "B.Cu")
		(net "GND")
	)
	(via
		(at 104.2162 -161.925)
		(size 0.508)
		(drill 0.254)
		(layers "F.Cu" "B.Cu")
		(net "GND")
	)
	(via
		(at 254.099822 -52.499768)
		(size 0.4572)
		(drill 0.2032)
		(layers "F.Cu" "B.Cu")
		(net "GND")
	)
	(via
		(at 94.107 -223.0628)
		(size 0.508)
		(drill 0.254)
		(layers "F.Cu" "B.Cu")
		(net "GND")
	)
	(via
		(at 32.505142 -135.284972)
		(size 0.4572)
		(drill 0.2032)
		(layers "F.Cu" "B.Cu")
		(net "GND")
	)
	(via
		(at 287.5026 -17.9578)
		(size 0.508)
		(drill 0.254)
		(layers "F.Cu" "B.Cu")
		(net "GND")
	)
	(via
		(at 87.2998 -223.082104)
		(size 0.508)
		(drill 0.254)
		(layers "F.Cu" "B.Cu")
		(net "GND")
	)
	(via
		(at 235.100114 -46.500034)
		(size 0.4572)
		(drill 0.2032)
		(layers "F.Cu" "B.Cu")
		(net "GND")
	)
	(via
		(at 26.533094 -145.21561)
		(size 0.508)
		(drill 0.254)
		(layers "F.Cu" "B.Cu")
		(net "GND")
	)
	(via
		(at 78.0542 -56.312308)
		(size 0.508)
		(drill 0.254)
		(layers "F.Cu" "B.Cu")
		(net "GND")
	)
	(via
		(at 232.10012 -49.499774)
		(size 0.4572)
		(drill 0.2032)
		(layers "F.Cu" "B.Cu")
		(net "GND")
	)
	(via
		(at 348.488 -63.373)
		(size 0.7112)
		(drill 0.4064)
		(layers "F.Cu" "B.Cu")
		(net "GND")
	)
	(via
		(at 301.498 -71.12)
		(size 0.7112)
		(drill 0.4064)
		(layers "F.Cu" "B.Cu")
		(net "GND")
	)
	(via
		(at 269.875 -187.452)
		(size 0.508)
		(drill 0.254)
		(layers "F.Cu" "B.Cu")
		(net "GND")
	)
	(via
		(at 250.09983 -50.499772)
		(size 0.4572)
		(drill 0.2032)
		(layers "F.Cu" "B.Cu")
		(net "GND")
	)
	(via
		(at 231.100122 -66.49974)
		(size 0.4572)
		(drill 0.2032)
		(layers "F.Cu" "B.Cu")
		(net "GND")
	)
	(via
		(at 227.35032 -13.418312)
		(size 0.508)
		(drill 0.254)
		(layers "F.Cu" "B.Cu")
		(net "GND")
	)
	(via
		(at 302.768 -71.12)
		(size 0.7112)
		(drill 0.4064)
		(layers "F.Cu" "B.Cu")
		(net "GND")
	)
	(via
		(at 139.7 -96.774)
		(size 0.508)
		(drill 0.254)
		(layers "F.Cu" "B.Cu")
		(net "GND")
	)
	(via
		(at 354.203 -121.825004)
		(size 0.508)
		(drill 0.254)
		(layers "F.Cu" "B.Cu")
		(net "GND")
	)
	(via
		(at 147.2946 -14.1732)
		(size 0.508)
		(drill 0.254)
		(layers "F.Cu" "B.Cu")
		(net "GND")
	)
	(via
		(at 222.221298 -192.850262)
		(size 0.508)
		(drill 0.254)
		(layers "F.Cu" "B.Cu")
		(net "GND")
	)
	(via
		(at 347.9038 -107.8484)
		(size 0.508)
		(drill 0.254)
		(layers "F.Cu" "B.Cu")
		(net "GND")
	)
	(via
		(at 51.216814 -210.298538)
		(size 0.508)
		(drill 0.254)
		(layers "F.Cu" "B.Cu")
		(net "GND")
	)
	(via
		(at 137.795 -204.724)
		(size 0.508)
		(drill 0.254)
		(layers "F.Cu" "B.Cu")
		(net "GND")
	)
	(via
		(at 143.9418 -12.3698)
		(size 0.508)
		(drill 0.254)
		(layers "F.Cu" "B.Cu")
		(net "GND")
	)
	(via
		(at 216.2302 -11.619992)
		(size 0.508)
		(drill 0.254)
		(layers "F.Cu" "B.Cu")
		(net "GND")
	)
	(via
		(at 137.922 -19.3802)
		(size 0.508)
		(drill 0.254)
		(layers "F.Cu" "B.Cu")
		(net "GND")
	)
	(via
		(at 77.07376 -120.74144)
		(size 0.508)
		(drill 0.254)
		(layers "F.Cu" "B.Cu")
		(net "GND")
	)
	(via
		(at 118.5418 -98.7552)
		(size 0.508)
		(drill 0.254)
		(layers "F.Cu" "B.Cu")
		(net "GND")
	)
	(via
		(at 332.7654 -186.1566)
		(size 0.508)
		(drill 0.254)
		(layers "F.Cu" "B.Cu")
		(net "GND")
	)
	(via
		(at 135.758174 -61.893704)
		(size 0.508)
		(drill 0.254)
		(layers "F.Cu" "B.Cu")
		(net "GND")
	)
	(via
		(at 292.852348 -210.152996)
		(size 0.508)
		(drill 0.254)
		(layers "F.Cu" "B.Cu")
		(net "GND")
	)
	(via
		(at 23.192994 -115.978686)
		(size 0.508)
		(drill 0.254)
		(layers "F.Cu" "B.Cu")
		(net "GND")
	)
	(via
		(at 256.099818 -59.499754)
		(size 0.4572)
		(drill 0.2032)
		(layers "F.Cu" "B.Cu")
		(net "GND")
	)
	(via
		(at 320.802 -51.308)
		(size 0.7112)
		(drill 0.4064)
		(layers "F.Cu" "B.Cu")
		(net "GND")
	)
	(via
		(at 319.405 -100.838)
		(size 0.508)
		(drill 0.254)
		(layers "F.Cu" "B.Cu")
		(net "GND")
	)
	(via
		(at 15.39494 -96.94291)
		(size 0.508)
		(drill 0.254)
		(layers "F.Cu" "B.Cu")
		(net "GND")
	)
	(via
		(at 88.1634 -153.7462)
		(size 0.508)
		(drill 0.254)
		(layers "F.Cu" "B.Cu")
		(net "GND")
	)
	(via
		(at 251.099828 -45.500036)
		(size 0.4572)
		(drill 0.2032)
		(layers "F.Cu" "B.Cu")
		(net "GND")
	)
	(via
		(at 186.85256 -210.152996)
		(size 0.508)
		(drill 0.254)
		(layers "F.Cu" "B.Cu")
		(net "GND")
	)
	(via
		(at 11.395964 -96.173036)
		(size 0.508)
		(drill 0.254)
		(layers "F.Cu" "B.Cu")
		(net "GND")
	)
	(via
		(at 290.9443 -35.014154)
		(size 0.508)
		(drill 0.254)
		(layers "F.Cu" "B.Cu")
		(net "GND")
	)
	(via
		(at 163.558728 -80.798416)
		(size 0.508)
		(drill 0.254)
		(layers "F.Cu" "B.Cu")
		(net "GND")
	)
	(via
		(at 10.988548 -90.693748)
		(size 0.508)
		(drill 0.254)
		(layers "F.Cu" "B.Cu")
		(net "GND")
	)
	(via
		(at 354.203 -157.385004)
		(size 0.508)
		(drill 0.254)
		(layers "F.Cu" "B.Cu")
		(net "GND")
	)
	(via
		(at 127.474218 -75.05446)
		(size 0.508)
		(drill 0.254)
		(layers "F.Cu" "B.Cu")
		(net "GND")
	)
	(via
		(at 87.61857 -77.684122)
		(size 0.508)
		(drill 0.254)
		(layers "F.Cu" "B.Cu")
		(net "GND")
	)
	(via
		(at 41.36771 -151.179784)
		(size 0.4572)
		(drill 0.2032)
		(layers "F.Cu" "B.Cu")
		(net "GND")
	)
	(via
		(at 196.500242 -223.082104)
		(size 0.508)
		(drill 0.254)
		(layers "F.Cu" "B.Cu")
		(net "GND")
	)
	(via
		(at 136.652 -223.0628)
		(size 0.508)
		(drill 0.254)
		(layers "F.Cu" "B.Cu")
		(net "GND")
	)
	(via
		(at 125.623828 -203.327)
		(size 0.508)
		(drill 0.254)
		(layers "F.Cu" "B.Cu")
		(net "GND")
	)
	(via
		(at 180.9496 -59.3852)
		(size 0.7112)
		(drill 0.4064)
		(layers "F.Cu" "B.Cu")
		(net "GND")
	)
	(via
		(at 315.468 -70.866)
		(size 0.7112)
		(drill 0.4064)
		(layers "F.Cu" "B.Cu")
		(net "GND")
	)
	(via
		(at 157.3276 -19.685)
		(size 0.508)
		(drill 0.254)
		(layers "F.Cu" "B.Cu")
		(net "GND")
	)
	(via
		(at 248.099834 -32.500062)
		(size 0.4572)
		(drill 0.2032)
		(layers "F.Cu" "B.Cu")
		(net "GND")
	)
	(via
		(at 230.100124 -50.499772)
		(size 0.4572)
		(drill 0.2032)
		(layers "F.Cu" "B.Cu")
		(net "GND")
	)
	(via
		(at 119.4308 -92.4052)
		(size 0.508)
		(drill 0.254)
		(layers "F.Cu" "B.Cu")
		(net "GND")
	)
	(via
		(at 313.7916 -92.5576)
		(size 0.508)
		(drill 0.254)
		(layers "F.Cu" "B.Cu")
		(net "GND")
	)
	(via
		(at 230.100124 -30.500066)
		(size 0.4572)
		(drill 0.2032)
		(layers "F.Cu" "B.Cu")
		(net "GND")
	)
	(via
		(at 71.299832 -223.082104)
		(size 0.508)
		(drill 0.254)
		(layers "F.Cu" "B.Cu")
		(net "GND")
	)
	(via
		(at 160.3248 -22.1488)
		(size 0.508)
		(drill 0.254)
		(layers "F.Cu" "B.Cu")
		(net "GND")
	)
	(via
		(at 239.100106 -58.499756)
		(size 0.4572)
		(drill 0.2032)
		(layers "F.Cu" "B.Cu")
		(net "GND")
	)
	(via
		(at 18.423382 -105.916984)
		(size 0.508)
		(drill 0.254)
		(layers "F.Cu" "B.Cu")
		(net "GND")
	)
	(via
		(at 152.5016 -136.652)
		(size 0.508)
		(drill 0.254)
		(layers "F.Cu" "B.Cu")
		(net "GND")
	)
	(via
		(at 39.596314 -86.29142)
		(size 0.508)
		(drill 0.254)
		(layers "F.Cu" "B.Cu")
		(net "GND")
	)
	(via
		(at 64.643 -37.1475)
		(size 0.508)
		(drill 0.254)
		(layers "F.Cu" "B.Cu")
		(net "GND")
	)
	(via
		(at 101.854 -146.177)
		(size 0.508)
		(drill 0.254)
		(layers "F.Cu" "B.Cu")
		(net "GND")
	)
	(via
		(at 318.135 -49.403)
		(size 0.7112)
		(drill 0.4064)
		(layers "F.Cu" "B.Cu")
		(net "GND")
	)
	(via
		(at 173.752002 -73.763632)
		(size 0.7112)
		(drill 0.4064)
		(layers "F.Cu" "B.Cu")
		(net "GND")
	)
	(via
		(at 175.700182 -223.082104)
		(size 0.508)
		(drill 0.254)
		(layers "F.Cu" "B.Cu")
		(net "GND")
	)
	(via
		(at 250.09983 -32.500062)
		(size 0.4572)
		(drill 0.2032)
		(layers "F.Cu" "B.Cu")
		(net "GND")
	)
	(via
		(at 1.397 -192.931034)
		(size 0.508)
		(drill 0.254)
		(layers "F.Cu" "B.Cu")
		(net "GND")
	)
	(via
		(at 338.501482 -62.130686)
		(size 0.7112)
		(drill 0.4064)
		(layers "F.Cu" "B.Cu")
		(net "GND")
	)
	(via
		(at 30.238954 -166.092124)
		(size 0.508)
		(drill 0.254)
		(layers "F.Cu" "B.Cu")
		(net "GND")
	)
	(via
		(at 290.174172 -19.974052)
		(size 0.508)
		(drill 0.254)
		(layers "F.Cu" "B.Cu")
		(net "GND")
	)
	(via
		(at 29.337 -115.4938)
		(size 0.508)
		(drill 0.254)
		(layers "F.Cu" "B.Cu")
		(net "GND")
	)
	(via
		(at 224.100136 -42.500042)
		(size 0.4572)
		(drill 0.2032)
		(layers "F.Cu" "B.Cu")
		(net "GND")
	)
	(via
		(at 31.126938 -143.370808)
		(size 0.4572)
		(drill 0.2032)
		(layers "F.Cu" "B.Cu")
		(net "GND")
	)
	(via
		(at 80.34401 -93.951806)
		(size 0.508)
		(drill 0.254)
		(layers "F.Cu" "B.Cu")
		(net "GND")
	)
	(via
		(at 271.37106 -15.649194)
		(size 0.508)
		(drill 0.254)
		(layers "F.Cu" "B.Cu")
		(net "GND")
	)
	(via
		(at 18.161 -75.6666)
		(size 0.508)
		(drill 0.254)
		(layers "F.Cu" "B.Cu")
		(net "GND")
	)
	(via
		(at 67.691 -46.863)
		(size 0.7112)
		(drill 0.4064)
		(layers "F.Cu" "B.Cu")
		(net "GND")
	)
	(via
		(at 257.099816 -51.49977)
		(size 0.4572)
		(drill 0.2032)
		(layers "F.Cu" "B.Cu")
		(net "GND")
	)
	(via
		(at 57.761886 -197.079362)
		(size 0.508)
		(drill 0.254)
		(layers "F.Cu" "B.Cu")
		(net "GND")
	)
	(via
		(at 39.9796 -64.516)
		(size 0.508)
		(drill 0.254)
		(layers "F.Cu" "B.Cu")
		(net "GND")
	)
	(via
		(at 258.099814 -51.49977)
		(size 0.4572)
		(drill 0.2032)
		(layers "F.Cu" "B.Cu")
		(net "GND")
	)
	(via
		(at 134.7216 -18.3896)
		(size 0.508)
		(drill 0.254)
		(layers "F.Cu" "B.Cu")
		(net "GND")
	)
	(via
		(at 238.100108 -41.500044)
		(size 0.4572)
		(drill 0.2032)
		(layers "F.Cu" "B.Cu")
		(net "GND")
	)
	(via
		(at 46.0248 -190.2206)
		(size 0.508)
		(drill 0.254)
		(layers "F.Cu" "B.Cu")
		(net "GND")
	)
	(via
		(at 254.099822 -46.500034)
		(size 0.4572)
		(drill 0.2032)
		(layers "F.Cu" "B.Cu")
		(net "GND")
	)
	(via
		(at 33.2486 -181.4322)
		(size 0.508)
		(drill 0.254)
		(layers "F.Cu" "B.Cu")
		(net "GND")
	)
	(via
		(at 84.963 -48.895)
		(size 0.7112)
		(drill 0.4064)
		(layers "F.Cu" "B.Cu")
		(net "GND")
	)
	(via
		(at 29.603954 -163.813744)
		(size 0.508)
		(drill 0.254)
		(layers "F.Cu" "B.Cu")
		(net "GND")
	)
	(via
		(at 275.347176 -210.152996)
		(size 0.508)
		(drill 0.254)
		(layers "F.Cu" "B.Cu")
		(net "GND")
	)
	(via
		(at 289.652456 -210.152996)
		(size 0.508)
		(drill 0.254)
		(layers "F.Cu" "B.Cu")
		(net "GND")
	)
	(via
		(at 77.851 -220.6498)
		(size 0.508)
		(drill 0.254)
		(layers "F.Cu" "B.Cu")
		(net "GND")
	)
	(via
		(at 247.099836 -56.49976)
		(size 0.4572)
		(drill 0.2032)
		(layers "F.Cu" "B.Cu")
		(net "GND")
	)
	(via
		(at 41.371774 -156.785564)
		(size 0.4572)
		(drill 0.2032)
		(layers "F.Cu" "B.Cu")
		(net "GND")
	)
	(via
		(at 80.31607 -95.505524)
		(size 0.508)
		(drill 0.254)
		(layers "F.Cu" "B.Cu")
		(net "GND")
	)
	(via
		(at 164.308536 -90.326464)
		(size 0.508)
		(drill 0.254)
		(layers "F.Cu" "B.Cu")
		(net "GND")
	)
	(via
		(at 115.90909 -212.102954)
		(size 0.508)
		(drill 0.254)
		(layers "F.Cu" "B.Cu")
		(net "GND")
	)
	(via
		(at 54.9402 -139.827)
		(size 0.508)
		(drill 0.254)
		(layers "F.Cu" "B.Cu")
		(net "GND")
	)
	(via
		(at 113.707926 -1.397)
		(size 0.508)
		(drill 0.254)
		(layers "F.Cu" "B.Cu")
		(net "GND")
	)
	(via
		(at 237.10011 -55.499762)
		(size 0.4572)
		(drill 0.2032)
		(layers "F.Cu" "B.Cu")
		(net "GND")
	)
	(via
		(at 176.9872 -60.4266)
		(size 0.7112)
		(drill 0.4064)
		(layers "F.Cu" "B.Cu")
		(net "GND")
	)
	(via
		(at 256.099818 -40.500046)
		(size 0.4572)
		(drill 0.2032)
		(layers "F.Cu" "B.Cu")
		(net "GND")
	)
	(via
		(at 66.421 -46.863)
		(size 0.7112)
		(drill 0.4064)
		(layers "F.Cu" "B.Cu")
		(net "GND")
	)
	(via
		(at 24.186642 -97.968816)
		(size 0.508)
		(drill 0.254)
		(layers "F.Cu" "B.Cu")
		(net "GND")
	)
	(via
		(at 220.839538 -7.880096)
		(size 0.508)
		(drill 0.254)
		(layers "F.Cu" "B.Cu")
		(net "GND")
	)
	(via
		(at 82.452464 -210.152996)
		(size 0.508)
		(drill 0.254)
		(layers "F.Cu" "B.Cu")
		(net "GND")
	)
	(via
		(at 79.616808 -191.479424)
		(size 0.508)
		(drill 0.254)
		(layers "F.Cu" "B.Cu")
		(net "GND")
	)
	(via
		(at 337.271614 -58.074306)
		(size 0.7112)
		(drill 0.4064)
		(layers "F.Cu" "B.Cu")
		(net "GND")
	)
	(via
		(at 271.35201 -14.25448)
		(size 0.508)
		(drill 0.254)
		(layers "F.Cu" "B.Cu")
		(net "GND")
	)
	(via
		(at 323.2658 -22.352)
		(size 0.508)
		(drill 0.254)
		(layers "F.Cu" "B.Cu")
		(net "GND")
	)
	(via
		(at 254.099822 -31.500064)
		(size 0.4572)
		(drill 0.2032)
		(layers "F.Cu" "B.Cu")
		(net "GND")
	)
	(via
		(at 326.136 -153.416)
		(size 0.7112)
		(drill 0.3556)
		(layers "F.Cu" "B.Cu")
		(net "GND")
	)
	(via
		(at 39.9542 -66.0146)
		(size 0.508)
		(drill 0.254)
		(layers "F.Cu" "B.Cu")
		(net "GND")
	)
	(via
		(at 33.367726 -155.18003)
		(size 0.4572)
		(drill 0.2032)
		(layers "F.Cu" "B.Cu")
		(net "GND")
	)
	(via
		(at 172.452538 -210.152996)
		(size 0.508)
		(drill 0.254)
		(layers "F.Cu" "B.Cu")
		(net "GND")
	)
	(via
		(at 346.964 -120.1166)
		(size 0.508)
		(drill 0.254)
		(layers "F.Cu" "B.Cu")
		(net "GND")
	)
	(via
		(at 8.001 -113.538)
		(size 0.508)
		(drill 0.254)
		(layers "F.Cu" "B.Cu")
		(net "GND")
	)
	(via
		(at 230.8098 -88.2142)
		(size 0.508)
		(drill 0.254)
		(layers "F.Cu" "B.Cu")
		(net "GND")
	)
	(via
		(at 252.538992 -199.597772)
		(size 0.508)
		(drill 0.254)
		(layers "F.Cu" "B.Cu")
		(net "GND")
	)
	(via
		(at 63.4238 -132.3975)
		(size 0.508)
		(drill 0.254)
		(layers "F.Cu" "B.Cu")
		(net "GND")
	)
	(via
		(at 155.2194 -26.2382)
		(size 0.508)
		(drill 0.254)
		(layers "F.Cu" "B.Cu")
		(net "GND")
	)
	(via
		(at 95.06585 -183.621426)
		(size 0.508)
		(drill 0.254)
		(layers "F.Cu" "B.Cu")
		(net "GND")
	)
	(via
		(at 46.068234 -152.815544)
		(size 0.508)
		(drill 0.254)
		(layers "F.Cu" "B.Cu")
		(net "GND")
	)
	(via
		(at 165.862 -96.647)
		(size 0.508)
		(drill 0.254)
		(layers "F.Cu" "B.Cu")
		(net "GND")
	)
	(via
		(at 60.0202 -57.72912)
		(size 0.508)
		(drill 0.254)
		(layers "F.Cu" "B.Cu")
		(net "GND")
	)
	(via
		(at 183.9976 -159.131)
		(size 0.508)
		(drill 0.254)
		(layers "F.Cu" "B.Cu")
		(net "GND")
	)
	(via
		(at 314.198 -74.168)
		(size 0.7112)
		(drill 0.4064)
		(layers "F.Cu" "B.Cu")
		(net "GND")
	)
	(via
		(at 72.689974 -126.630684)
		(size 0.508)
		(drill 0.254)
		(layers "F.Cu" "B.Cu")
		(net "GND")
	)
	(via
		(at 230.100124 -29.500068)
		(size 0.4572)
		(drill 0.2032)
		(layers "F.Cu" "B.Cu")
		(net "GND")
	)
	(via
		(at 233.100118 -55.499762)
		(size 0.4572)
		(drill 0.2032)
		(layers "F.Cu" "B.Cu")
		(net "GND")
	)
	(via
		(at 252.099826 -31.500064)
		(size 0.4572)
		(drill 0.2032)
		(layers "F.Cu" "B.Cu")
		(net "GND")
	)
	(via
		(at 36.957 -97.917)
		(size 0.508)
		(drill 0.254)
		(layers "F.Cu" "B.Cu")
		(net "GND")
	)
	(via
		(at 57.023 -44.3738)
		(size 0.7112)
		(drill 0.4064)
		(layers "F.Cu" "B.Cu")
		(net "GND")
	)
	(via
		(at 172.339 -173.736)
		(size 0.508)
		(drill 0.254)
		(layers "F.Cu" "B.Cu")
		(net "GND")
	)
	(via
		(at 234.100116 -45.500036)
		(size 0.4572)
		(drill 0.2032)
		(layers "F.Cu" "B.Cu")
		(net "GND")
	)
	(via
		(at 300.9392 -22.1488)
		(size 0.508)
		(drill 0.254)
		(layers "F.Cu" "B.Cu")
		(net "GND")
	)
	(via
		(at 354.203 -76.105004)
		(size 0.508)
		(drill 0.254)
		(layers "F.Cu" "B.Cu")
		(net "GND")
	)
	(via
		(at 49.699926 -223.082104)
		(size 0.508)
		(drill 0.254)
		(layers "F.Cu" "B.Cu")
		(net "GND")
	)
	(via
		(at 345.100148 -69.97319)
		(size 0.508)
		(drill 0.254)
		(layers "F.Cu" "B.Cu")
		(net "GND")
	)
	(via
		(at 314.500006 -223.082104)
		(size 0.508)
		(drill 0.254)
		(layers "F.Cu" "B.Cu")
		(net "GND")
	)
	(via
		(at 1.397 -96.411034)
		(size 0.508)
		(drill 0.254)
		(layers "F.Cu" "B.Cu")
		(net "GND")
	)
	(via
		(at 257.099816 -63.499746)
		(size 0.4572)
		(drill 0.2032)
		(layers "F.Cu" "B.Cu")
		(net "GND")
	)
	(via
		(at 250.09983 -64.499744)
		(size 0.4572)
		(drill 0.2032)
		(layers "F.Cu" "B.Cu")
		(net "GND")
	)
	(via
		(at 8.8392 -81.5848)
		(size 0.508)
		(drill 0.254)
		(layers "F.Cu" "B.Cu")
		(net "GND")
	)
	(via
		(at 242.099846 -49.499774)
		(size 0.4572)
		(drill 0.2032)
		(layers "F.Cu" "B.Cu")
		(net "GND")
	)
	(via
		(at 7.9756 -53.13426)
		(size 0.508)
		(drill 0.254)
		(layers "F.Cu" "B.Cu")
		(net "GND")
	)
	(via
		(at 267.76934 -13.55598)
		(size 0.508)
		(drill 0.254)
		(layers "F.Cu" "B.Cu")
		(net "GND")
	)
	(via
		(at 168.2496 -19.8374)
		(size 0.508)
		(drill 0.254)
		(layers "F.Cu" "B.Cu")
		(net "GND")
	)
	(via
		(at 137.4648 -18.6436)
		(size 0.508)
		(drill 0.254)
		(layers "F.Cu" "B.Cu")
		(net "GND")
	)
	(via
		(at 22.422104 -59.1058)
		(size 0.508)
		(drill 0.254)
		(layers "F.Cu" "B.Cu")
		(net "GND")
	)
	(via
		(at 251.099828 -56.49976)
		(size 0.4572)
		(drill 0.2032)
		(layers "F.Cu" "B.Cu")
		(net "GND")
	)
	(via
		(at 37.592 -211.709)
		(size 0.7112)
		(drill 0.3556)
		(layers "F.Cu" "B.Cu")
		(net "GND")
	)
	(via
		(at 255.09982 -41.500044)
		(size 0.4572)
		(drill 0.2032)
		(layers "F.Cu" "B.Cu")
		(net "GND")
	)
	(via
		(at 259.099812 -51.49977)
		(size 0.4572)
		(drill 0.2032)
		(layers "F.Cu" "B.Cu")
		(net "GND")
	)
	(via
		(at 229.100126 -32.500062)
		(size 0.4572)
		(drill 0.2032)
		(layers "F.Cu" "B.Cu")
		(net "GND")
	)
	(via
		(at 343.4588 -223.1136)
		(size 0.508)
		(drill 0.254)
		(layers "F.Cu" "B.Cu")
		(net "GND")
	)
	(via
		(at 34.9504 -213.233)
		(size 0.508)
		(drill 0.254)
		(layers "F.Cu" "B.Cu")
		(net "GND")
	)
	(via
		(at 319.8368 -119.8372)
		(size 0.508)
		(drill 0.254)
		(layers "F.Cu" "B.Cu")
		(net "GND")
	)
	(via
		(at 28.503118 -75.29449)
		(size 0.508)
		(drill 0.254)
		(layers "F.Cu" "B.Cu")
		(net "GND")
	)
	(via
		(at 252.099826 -50.499772)
		(size 0.4572)
		(drill 0.2032)
		(layers "F.Cu" "B.Cu")
		(net "GND")
	)
	(via
		(at 198.099934 -223.082104)
		(size 0.508)
		(drill 0.254)
		(layers "F.Cu" "B.Cu")
		(net "GND")
	)
	(via
		(at 249.099832 -48.499776)
		(size 0.4572)
		(drill 0.2032)
		(layers "F.Cu" "B.Cu")
		(net "GND")
	)
	(via
		(at 136.8552 -19.5326)
		(size 0.508)
		(drill 0.254)
		(layers "F.Cu" "B.Cu")
		(net "GND")
	)
	(via
		(at 324.65264 -35.698938)
		(size 0.508)
		(drill 0.254)
		(layers "F.Cu" "B.Cu")
		(net "GND")
	)
	(via
		(at 160.782 -89.662)
		(size 0.508)
		(drill 0.254)
		(layers "F.Cu" "B.Cu")
		(net "GND")
	)
	(via
		(at 301.0408 -18.4404)
		(size 0.508)
		(drill 0.254)
		(layers "F.Cu" "B.Cu")
		(net "GND")
	)
	(via
		(at 314.198 -49.403)
		(size 0.7112)
		(drill 0.4064)
		(layers "F.Cu" "B.Cu")
		(net "GND")
	)
	(via
		(at 284.988254 -32.149796)
		(size 0.508)
		(drill 0.254)
		(layers "F.Cu" "B.Cu")
		(net "GND")
	)
	(via
		(at 135.9916 -22.1996)
		(size 0.508)
		(drill 0.254)
		(layers "F.Cu" "B.Cu")
		(net "GND")
	)
	(via
		(at 64.643 -40.9575)
		(size 0.508)
		(drill 0.254)
		(layers "F.Cu" "B.Cu")
		(net "GND")
	)
	(via
		(at 148.24456 -35.721544)
		(size 0.508)
		(drill 0.254)
		(layers "F.Cu" "B.Cu")
		(net "GND")
	)
	(via
		(at 252.538992 -189.437772)
		(size 0.508)
		(drill 0.254)
		(layers "F.Cu" "B.Cu")
		(net "GND")
	)
	(via
		(at 183.809386 -24.712168)
		(size 0.508)
		(drill 0.254)
		(layers "F.Cu" "B.Cu")
		(net "GND")
	)
	(via
		(at 167.699944 -223.082104)
		(size 0.508)
		(drill 0.254)
		(layers "F.Cu" "B.Cu")
		(net "GND")
	)
	(via
		(at 248.099834 -49.499774)
		(size 0.4572)
		(drill 0.2032)
		(layers "F.Cu" "B.Cu")
		(net "GND")
	)
	(via
		(at 131.5974 -115.1128)
		(size 0.508)
		(drill 0.254)
		(layers "F.Cu" "B.Cu")
		(net "GND")
	)
	(via
		(at 231.100122 -49.499774)
		(size 0.4572)
		(drill 0.2032)
		(layers "F.Cu" "B.Cu")
		(net "GND")
	)
	(via
		(at 337.256628 -54.757066)
		(size 0.7112)
		(drill 0.4064)
		(layers "F.Cu" "B.Cu")
		(net "GND")
	)
	(via
		(at 10.8712 -50.8254)
		(size 0.508)
		(drill 0.254)
		(layers "F.Cu" "B.Cu")
		(net "GND")
	)
	(via
		(at 133.673596 -204.724)
		(size 0.508)
		(drill 0.254)
		(layers "F.Cu" "B.Cu")
		(net "GND")
	)
	(via
		(at 269.86738 -8.083042)
		(size 0.508)
		(drill 0.254)
		(layers "F.Cu" "B.Cu")
		(net "GND")
	)
	(via
		(at 324.612 -175.006)
		(size 0.508)
		(drill 0.254)
		(layers "F.Cu" "B.Cu")
		(net "GND")
	)
	(via
		(at 354.203 -147.225004)
		(size 0.508)
		(drill 0.254)
		(layers "F.Cu" "B.Cu")
		(net "GND")
	)
	(via
		(at 233.100118 -56.49976)
		(size 0.4572)
		(drill 0.2032)
		(layers "F.Cu" "B.Cu")
		(net "GND")
	)
	(via
		(at 158.496 -19.304)
		(size 0.508)
		(drill 0.254)
		(layers "F.Cu" "B.Cu")
		(net "GND")
	)
	(via
		(at 99.299776 -223.082104)
		(size 0.508)
		(drill 0.254)
		(layers "F.Cu" "B.Cu")
		(net "GND")
	)
	(via
		(at 139.7762 -39.3192)
		(size 0.508)
		(drill 0.254)
		(layers "F.Cu" "B.Cu")
		(net "GND")
	)
	(via
		(at 303.292002 -219.525342)
		(size 0.508)
		(drill 0.254)
		(layers "F.Cu" "B.Cu")
		(net "GND")
	)
	(via
		(at 336.8675 -170.0657)
		(size 0.7112)
		(drill 0.4064)
		(layers "F.Cu" "B.Cu")
		(net "GND")
	)
	(via
		(at 237.10011 -32.500062)
		(size 0.4572)
		(drill 0.2032)
		(layers "F.Cu" "B.Cu")
		(net "GND")
	)
	(via
		(at 190.100204 -223.082104)
		(size 0.508)
		(drill 0.254)
		(layers "F.Cu" "B.Cu")
		(net "GND")
	)
	(via
		(at 315.468 -87.122)
		(size 0.508)
		(drill 0.254)
		(layers "F.Cu" "B.Cu")
		(net "GND")
	)
	(via
		(at 234.100116 -48.499776)
		(size 0.4572)
		(drill 0.2032)
		(layers "F.Cu" "B.Cu")
		(net "GND")
	)
	(via
		(at 173.244002 -75.973432)
		(size 0.7112)
		(drill 0.4064)
		(layers "F.Cu" "B.Cu")
		(net "GND")
	)
	(via
		(at 313.944 -206.756)
		(size 0.7112)
		(drill 0.3556)
		(layers "F.Cu" "B.Cu")
		(net "GND")
	)
	(via
		(at 250.09983 -61.49975)
		(size 0.4572)
		(drill 0.2032)
		(layers "F.Cu" "B.Cu")
		(net "GND")
	)
	(via
		(at 162.068002 -73.814432)
		(size 0.7112)
		(drill 0.3556)
		(layers "F.Cu" "B.Cu")
		(net "GND")
	)
	(via
		(at 232.10012 -42.500042)
		(size 0.4572)
		(drill 0.2032)
		(layers "F.Cu" "B.Cu")
		(net "GND")
	)
	(via
		(at 250.09983 -51.49977)
		(size 0.4572)
		(drill 0.2032)
		(layers "F.Cu" "B.Cu")
		(net "GND")
	)
	(via
		(at 39.767764 -155.18003)
		(size 0.4572)
		(drill 0.2032)
		(layers "F.Cu" "B.Cu")
		(net "GND")
	)
	(via
		(at 259.524754 -29.837126)
		(size 0.4572)
		(drill 0.2032)
		(layers "F.Cu" "B.Cu")
		(net "GND")
	)
	(via
		(at 69.70014 -223.082104)
		(size 0.508)
		(drill 0.254)
		(layers "F.Cu" "B.Cu")
		(net "GND")
	)
	(via
		(at 135.758174 -72.866504)
		(size 0.508)
		(drill 0.254)
		(layers "F.Cu" "B.Cu")
		(net "GND")
	)
	(via
		(at 243.099844 -50.499772)
		(size 0.4572)
		(drill 0.2032)
		(layers "F.Cu" "B.Cu")
		(net "GND")
	)
	(via
		(at 183.769254 -21.00072)
		(size 0.508)
		(drill 0.254)
		(layers "F.Cu" "B.Cu")
		(net "GND")
	)
	(via
		(at 154.321002 -71.655432)
		(size 0.7112)
		(drill 0.4064)
		(layers "F.Cu" "B.Cu")
		(net "GND")
	)
	(via
		(at 230.505 -93.472)
		(size 0.508)
		(drill 0.254)
		(layers "F.Cu" "B.Cu")
		(net "GND")
	)
	(via
		(at 66.275966 -87.775034)
		(size 0.508)
		(drill 0.254)
		(layers "F.Cu" "B.Cu")
		(net "GND")
	)
	(via
		(at 140.4112 -35.7632)
		(size 0.508)
		(drill 0.254)
		(layers "F.Cu" "B.Cu")
		(net "GND")
	)
	(via
		(at 250.09983 -55.499762)
		(size 0.4572)
		(drill 0.2032)
		(layers "F.Cu" "B.Cu")
		(net "GND")
	)
	(via
		(at 329.607672 -39.503096)
		(size 0.508)
		(drill 0.254)
		(layers "F.Cu" "B.Cu")
		(net "GND")
	)
	(via
		(at 287.5534 -14.3002)
		(size 0.508)
		(drill 0.254)
		(layers "F.Cu" "B.Cu")
		(net "GND")
	)
	(via
		(at 222.10014 -65.499742)
		(size 0.4572)
		(drill 0.2032)
		(layers "F.Cu" "B.Cu")
		(net "GND")
	)
	(via
		(at 297.6118 -11.6586)
		(size 0.508)
		(drill 0.254)
		(layers "F.Cu" "B.Cu")
		(net "GND")
	)
	(via
		(at 154.702002 -64.924432)
		(size 0.7112)
		(drill 0.4064)
		(layers "F.Cu" "B.Cu")
		(net "GND")
	)
	(via
		(at 25.908 -152.146)
		(size 0.508)
		(drill 0.254)
		(layers "F.Cu" "B.Cu")
		(net "GND")
	)
	(via
		(at 231.100122 -61.49975)
		(size 0.4572)
		(drill 0.2032)
		(layers "F.Cu" "B.Cu")
		(net "GND")
	)
	(via
		(at 19.1643 -176.3141)
		(size 0.508)
		(drill 0.254)
		(layers "F.Cu" "B.Cu")
		(net "GND")
	)
	(via
		(at 167.7924 -23.6982)
		(size 0.508)
		(drill 0.254)
		(layers "F.Cu" "B.Cu")
		(net "GND")
	)
	(via
		(at 66.421 -45.466)
		(size 0.7112)
		(drill 0.4064)
		(layers "F.Cu" "B.Cu")
		(net "GND")
	)
	(via
		(at 19.730974 -126.754382)
		(size 0.508)
		(drill 0.254)
		(layers "F.Cu" "B.Cu")
		(net "GND")
	)
	(via
		(at 160.51276 -35.0012)
		(size 0.508)
		(drill 0.254)
		(layers "F.Cu" "B.Cu")
		(net "GND")
	)
	(via
		(at 30.099 -47.879)
		(size 0.508)
		(drill 0.254)
		(layers "F.Cu" "B.Cu")
		(net "GND")
	)
	(via
		(at 114.9604 -29.020516)
		(size 0.508)
		(drill 0.254)
		(layers "F.Cu" "B.Cu")
		(net "GND")
	)
	(via
		(at 15.029942 -73.199244)
		(size 0.508)
		(drill 0.254)
		(layers "F.Cu" "B.Cu")
		(net "GND")
	)
	(via
		(at 143.526002 -64.035432)
		(size 0.7112)
		(drill 0.4064)
		(layers "F.Cu" "B.Cu")
		(net "GND")
	)
	(via
		(at 164.8206 -198.755)
		(size 0.508)
		(drill 0.254)
		(layers "F.Cu" "B.Cu")
		(net "GND")
	)
	(via
		(at 32.224726 -146.75358)
		(size 0.4572)
		(drill 0.2032)
		(layers "F.Cu" "B.Cu")
		(net "GND")
	)
	(via
		(at 217.106246 -175.805592)
		(size 0.7112)
		(drill 0.3556)
		(layers "F.Cu" "B.Cu")
		(net "GND")
	)
	(via
		(at 22.86508 -212.102954)
		(size 0.508)
		(drill 0.254)
		(layers "F.Cu" "B.Cu")
		(net "GND")
	)
	(via
		(at 210.90001 -223.082104)
		(size 0.508)
		(drill 0.254)
		(layers "F.Cu" "B.Cu")
		(net "GND")
	)
	(via
		(at 201.299826 -223.082104)
		(size 0.508)
		(drill 0.254)
		(layers "F.Cu" "B.Cu")
		(net "GND")
	)
	(via
		(at 171.3484 -18.3388)
		(size 0.508)
		(drill 0.254)
		(layers "F.Cu" "B.Cu")
		(net "GND")
	)
	(via
		(at 292.2778 -16.0782)
		(size 0.508)
		(drill 0.254)
		(layers "F.Cu" "B.Cu")
		(net "GND")
	)
	(via
		(at 14.200378 -89.070942)
		(size 0.508)
		(drill 0.254)
		(layers "F.Cu" "B.Cu")
		(net "GND")
	)
	(via
		(at 282.108656 -19.934682)
		(size 0.508)
		(drill 0.254)
		(layers "F.Cu" "B.Cu")
		(net "GND")
	)
	(via
		(at 354.203 -35.465004)
		(size 0.508)
		(drill 0.254)
		(layers "F.Cu" "B.Cu")
		(net "GND")
	)
	(via
		(at 250.09983 -49.499774)
		(size 0.4572)
		(drill 0.2032)
		(layers "F.Cu" "B.Cu")
		(net "GND")
	)
	(via
		(at 229.100126 -54.499764)
		(size 0.4572)
		(drill 0.2032)
		(layers "F.Cu" "B.Cu")
		(net "GND")
	)
	(via
		(at 151.9682 -38.8239)
		(size 0.508)
		(drill 0.254)
		(layers "F.Cu" "B.Cu")
		(net "GND")
	)
	(via
		(at 308.7116 -14.6304)
		(size 0.508)
		(drill 0.254)
		(layers "F.Cu" "B.Cu")
		(net "GND")
	)
	(via
		(at 161.0106 -37.9984)
		(size 0.508)
		(drill 0.254)
		(layers "F.Cu" "B.Cu")
		(net "GND")
	)
	(via
		(at 313.8932 -11.7856)
		(size 0.508)
		(drill 0.254)
		(layers "F.Cu" "B.Cu")
		(net "GND")
	)
	(via
		(at 233.100118 -59.499754)
		(size 0.4572)
		(drill 0.2032)
		(layers "F.Cu" "B.Cu")
		(net "GND")
	)
	(via
		(at 193.6115 -11.3411)
		(size 0.508)
		(drill 0.254)
		(layers "F.Cu" "B.Cu")
		(net "GND")
	)
	(via
		(at 251.099828 -51.49977)
		(size 0.4572)
		(drill 0.2032)
		(layers "F.Cu" "B.Cu")
		(net "GND")
	)
	(via
		(at 319.300098 -223.082104)
		(size 0.508)
		(drill 0.254)
		(layers "F.Cu" "B.Cu")
		(net "GND")
	)
	(via
		(at 37.30498 -122.48515)
		(size 0.4572)
		(drill 0.2032)
		(layers "F.Cu" "B.Cu")
		(net "GND")
	)
	(via
		(at 231.100122 -51.49977)
		(size 0.4572)
		(drill 0.2032)
		(layers "F.Cu" "B.Cu")
		(net "GND")
	)
	(via
		(at 28.7782 -70.2564)
		(size 0.5588)
		(drill 0.3048)
		(layers "F.Cu" "B.Cu")
		(net "GND")
	)
	(via
		(at 252.099826 -57.499758)
		(size 0.4572)
		(drill 0.2032)
		(layers "F.Cu" "B.Cu")
		(net "GND")
	)
	(via
		(at 233.100118 -57.499758)
		(size 0.4572)
		(drill 0.2032)
		(layers "F.Cu" "B.Cu")
		(net "GND")
	)
	(via
		(at 204.547216 -210.152996)
		(size 0.508)
		(drill 0.254)
		(layers "F.Cu" "B.Cu")
		(net "GND")
	)
	(via
		(at 112.903 -219.5703)
		(size 0.508)
		(drill 0.254)
		(layers "F.Cu" "B.Cu")
		(net "GND")
	)
	(via
		(at 151.831802 -61.622432)
		(size 0.508)
		(drill 0.254)
		(layers "F.Cu" "B.Cu")
		(net "GND")
	)
	(via
		(at 264.9982 -160.3502)
		(size 0.508)
		(drill 0.254)
		(layers "F.Cu" "B.Cu")
		(net "GND")
	)
	(via
		(at 223.744282 -7.768082)
		(size 0.508)
		(drill 0.254)
		(layers "F.Cu" "B.Cu")
		(net "GND")
	)
	(via
		(at 221.234 -197.231)
		(size 0.508)
		(drill 0.254)
		(layers "F.Cu" "B.Cu")
		(net "GND")
	)
	(via
		(at 71.310246 -130.236976)
		(size 0.508)
		(drill 0.254)
		(layers "F.Cu" "B.Cu")
		(net "GND")
	)
	(via
		(at 178.7144 -59.3598)
		(size 0.7112)
		(drill 0.4064)
		(layers "F.Cu" "B.Cu")
		(net "GND")
	)
	(via
		(at 232.3338 -71.3994)
		(size 0.7112)
		(drill 0.3556)
		(layers "F.Cu" "B.Cu")
		(net "GND")
	)
	(via
		(at 224.100136 -39.500048)
		(size 0.4572)
		(drill 0.2032)
		(layers "F.Cu" "B.Cu")
		(net "GND")
	)
	(via
		(at 134.9248 -22.3266)
		(size 0.508)
		(drill 0.254)
		(layers "F.Cu" "B.Cu")
		(net "GND")
	)
	(via
		(at 174.260002 -58.447432)
		(size 0.7112)
		(drill 0.4064)
		(layers "F.Cu" "B.Cu")
		(net "GND")
	)
	(via
		(at 298.5008 -21.8186)
		(size 0.508)
		(drill 0.254)
		(layers "F.Cu" "B.Cu")
		(net "GND")
	)
	(via
		(at 237.10011 -51.49977)
		(size 0.4572)
		(drill 0.2032)
		(layers "F.Cu" "B.Cu")
		(net "GND")
	)
	(via
		(at 188.500004 -223.082104)
		(size 0.508)
		(drill 0.254)
		(layers "F.Cu" "B.Cu")
		(net "GND")
	)
	(via
		(at 182.591202 -75.160632)
		(size 0.7112)
		(drill 0.4064)
		(layers "F.Cu" "B.Cu")
		(net "GND")
	)
	(via
		(at 150.209758 -31.952438)
		(size 0.508)
		(drill 0.254)
		(layers "F.Cu" "B.Cu")
		(net "GND")
	)
	(via
		(at 312.90006 -223.082104)
		(size 0.508)
		(drill 0.254)
		(layers "F.Cu" "B.Cu")
		(net "GND")
	)
	(via
		(at 237.10011 -49.499774)
		(size 0.4572)
		(drill 0.2032)
		(layers "F.Cu" "B.Cu")
		(net "GND")
	)
	(via
		(at 323.359272 -35.690556)
		(size 0.508)
		(drill 0.254)
		(layers "F.Cu" "B.Cu")
		(net "GND")
	)
	(via
		(at 54.45252 -210.152996)
		(size 0.508)
		(drill 0.254)
		(layers "F.Cu" "B.Cu")
		(net "GND")
	)
	(via
		(at 151.831802 -62.511432)
		(size 0.508)
		(drill 0.254)
		(layers "F.Cu" "B.Cu")
		(net "GND")
	)
	(via
		(at 292.1635 -58.1025)
		(size 0.508)
		(drill 0.254)
		(layers "F.Cu" "B.Cu")
		(net "GND")
	)
	(via
		(at 255.09982 -32.500062)
		(size 0.4572)
		(drill 0.2032)
		(layers "F.Cu" "B.Cu")
		(net "GND")
	)
	(via
		(at 22.23897 -142.51559)
		(size 0.508)
		(drill 0.254)
		(layers "F.Cu" "B.Cu")
		(net "GND")
	)
	(via
		(at 252.099826 -59.499754)
		(size 0.4572)
		(drill 0.2032)
		(layers "F.Cu" "B.Cu")
		(net "GND")
	)
	(via
		(at 249.809 -70.993)
		(size 0.508)
		(drill 0.254)
		(layers "F.Cu" "B.Cu")
		(net "GND")
	)
	(via
		(at 250.09983 -66.49974)
		(size 0.4572)
		(drill 0.2032)
		(layers "F.Cu" "B.Cu")
		(net "GND")
	)
	(via
		(at 288.100008 -223.082104)
		(size 0.508)
		(drill 0.254)
		(layers "F.Cu" "B.Cu")
		(net "GND")
	)
	(via
		(at 53.347112 -18.44167)
		(size 0.508)
		(drill 0.254)
		(layers "F.Cu" "B.Cu")
		(net "GND")
	)
	(via
		(at 188.849 -91.948)
		(size 0.508)
		(drill 0.254)
		(layers "F.Cu" "B.Cu")
		(net "GND")
	)
	(via
		(at 250.09983 -52.499768)
		(size 0.4572)
		(drill 0.2032)
		(layers "F.Cu" "B.Cu")
		(net "GND")
	)
	(via
		(at 298.4754 -14.1478)
		(size 0.508)
		(drill 0.254)
		(layers "F.Cu" "B.Cu")
		(net "GND")
	)
	(via
		(at 183.804052 -30.061662)
		(size 0.508)
		(drill 0.254)
		(layers "F.Cu" "B.Cu")
		(net "GND")
	)
	(via
		(at 149.29993 -223.082104)
		(size 0.508)
		(drill 0.254)
		(layers "F.Cu" "B.Cu")
		(net "GND")
	)
	(via
		(at 27.4828 -96.178624)
		(size 0.508)
		(drill 0.254)
		(layers "F.Cu" "B.Cu")
		(net "GND")
	)
	(via
		(at 244.099842 -49.499774)
		(size 0.4572)
		(drill 0.2032)
		(layers "F.Cu" "B.Cu")
		(net "GND")
	)
	(via
		(at 12.5222 -88.0618)
		(size 0.508)
		(drill 0.254)
		(layers "F.Cu" "B.Cu")
		(net "GND")
	)
	(via
		(at 162.14725 -210.152996)
		(size 0.508)
		(drill 0.254)
		(layers "F.Cu" "B.Cu")
		(net "GND")
	)
	(via
		(at 104.052624 -210.152996)
		(size 0.508)
		(drill 0.254)
		(layers "F.Cu" "B.Cu")
		(net "GND")
	)
	(via
		(at 304.899314 -39.821866)
		(size 0.508)
		(drill 0.254)
		(layers "F.Cu" "B.Cu")
		(net "GND")
	)
	(via
		(at 236.100112 -43.50004)
		(size 0.4572)
		(drill 0.2032)
		(layers "F.Cu" "B.Cu")
		(net "GND")
	)
	(via
		(at 238.100108 -59.499754)
		(size 0.4572)
		(drill 0.2032)
		(layers "F.Cu" "B.Cu")
		(net "GND")
	)
	(via
		(at 14.98346 -87.0458)
		(size 0.508)
		(drill 0.254)
		(layers "F.Cu" "B.Cu")
		(net "GND")
	)
	(via
		(at 154.371802 -62.511432)
		(size 0.508)
		(drill 0.254)
		(layers "F.Cu" "B.Cu")
		(net "GND")
	)
	(via
		(at 57.652412 -210.152996)
		(size 0.508)
		(drill 0.254)
		(layers "F.Cu" "B.Cu")
		(net "GND")
	)
	(via
		(at 30.118558 -27.407108)
		(size 0.508)
		(drill 0.254)
		(layers "F.Cu" "B.Cu")
		(net "GND")
	)
	(via
		(at 316.46114 -35.00374)
		(size 0.508)
		(drill 0.254)
		(layers "F.Cu" "B.Cu")
		(net "GND")
	)
	(via
		(at 245.09984 -31.500064)
		(size 0.4572)
		(drill 0.2032)
		(layers "F.Cu" "B.Cu")
		(net "GND")
	)
	(via
		(at 222.10014 -51.49977)
		(size 0.4572)
		(drill 0.2032)
		(layers "F.Cu" "B.Cu")
		(net "GND")
	)
	(via
		(at 124.944124 -195.206874)
		(size 0.508)
		(drill 0.254)
		(layers "F.Cu" "B.Cu")
		(net "GND")
	)
	(via
		(at 56.147208 -210.152996)
		(size 0.508)
		(drill 0.254)
		(layers "F.Cu" "B.Cu")
		(net "GND")
	)
	(via
		(at 167.9194 -18.542)
		(size 0.508)
		(drill 0.254)
		(layers "F.Cu" "B.Cu")
		(net "GND")
	)
	(via
		(at 174.562262 -60.421012)
		(size 0.7112)
		(drill 0.4064)
		(layers "F.Cu" "B.Cu")
		(net "GND")
	)
	(via
		(at 63.627 -163.195)
		(size 0.508)
		(drill 0.254)
		(layers "F.Cu" "B.Cu")
		(net "GND")
	)
	(via
		(at 335.300066 -223.082104)
		(size 0.508)
		(drill 0.254)
		(layers "F.Cu" "B.Cu")
		(net "GND")
	)
	(via
		(at 112.522 -151.511)
		(size 0.508)
		(drill 0.254)
		(layers "F.Cu" "B.Cu")
		(net "GND")
	)
	(via
		(at 354.203 -137.065004)
		(size 0.508)
		(drill 0.254)
		(layers "F.Cu" "B.Cu")
		(net "GND")
	)
	(via
		(at 250.09983 -53.499766)
		(size 0.4572)
		(drill 0.2032)
		(layers "F.Cu" "B.Cu")
		(net "GND")
	)
	(via
		(at 35.814 -222.9358)
		(size 0.508)
		(drill 0.254)
		(layers "F.Cu" "B.Cu")
		(net "GND")
	)
	(via
		(at 14.8336 -69.0372)
		(size 0.508)
		(drill 0.254)
		(layers "F.Cu" "B.Cu")
		(net "GND")
	)
	(via
		(at 156.6672 -18.3388)
		(size 0.508)
		(drill 0.254)
		(layers "F.Cu" "B.Cu")
		(net "GND")
	)
	(via
		(at 244.099842 -58.499756)
		(size 0.4572)
		(drill 0.2032)
		(layers "F.Cu" "B.Cu")
		(net "GND")
	)
	(via
		(at 158.368492 -35.730434)
		(size 0.508)
		(drill 0.254)
		(layers "F.Cu" "B.Cu")
		(net "GND")
	)
	(via
		(at 17.9578 -112.583976)
		(size 0.508)
		(drill 0.254)
		(layers "F.Cu" "B.Cu")
		(net "GND")
	)
	(via
		(at 312.3946 -26.1874)
		(size 0.508)
		(drill 0.254)
		(layers "F.Cu" "B.Cu")
		(net "GND")
	)
	(via
		(at 338.501482 -61.063886)
		(size 0.7112)
		(drill 0.4064)
		(layers "F.Cu" "B.Cu")
		(net "GND")
	)
	(via
		(at 71.724012 -196.959474)
		(size 0.508)
		(drill 0.254)
		(layers "F.Cu" "B.Cu")
		(net "GND")
	)
	(via
		(at 230.759 -68.707)
		(size 0.508)
		(drill 0.254)
		(layers "F.Cu" "B.Cu")
		(net "GND")
	)
	(via
		(at 53.347112 -23.52167)
		(size 0.508)
		(drill 0.254)
		(layers "F.Cu" "B.Cu")
		(net "GND")
	)
	(via
		(at 39.0398 -185.2676)
		(size 0.508)
		(drill 0.254)
		(layers "F.Cu" "B.Cu")
		(net "GND")
	)
	(via
		(at 20.4724 -55.0418)
		(size 0.508)
		(drill 0.254)
		(layers "F.Cu" "B.Cu")
		(net "GND")
	)
	(via
		(at 16.3068 -135.763)
		(size 0.508)
		(drill 0.254)
		(layers "F.Cu" "B.Cu")
		(net "GND")
	)
	(via
		(at 43.70451 -132.88518)
		(size 0.4572)
		(drill 0.2032)
		(layers "F.Cu" "B.Cu")
		(net "GND")
	)
	(via
		(at 40.3352 -103.18877)
		(size 0.508)
		(drill 0.254)
		(layers "F.Cu" "B.Cu")
		(net "GND")
	)
	(via
		(at 124.272294 3.60299)
		(size 0.508)
		(drill 0.254)
		(layers "F.Cu" "B.Cu")
		(net "GND")
	)
	(via
		(at 75.7936 -197.0278)
		(size 0.508)
		(drill 0.254)
		(layers "F.Cu" "B.Cu")
		(net "GND")
	)
	(via
		(at 230.886 -89.8144)
		(size 0.508)
		(drill 0.254)
		(layers "F.Cu" "B.Cu")
		(net "GND")
	)
	(via
		(at 211.10575 -17.21485)
		(size 0.508)
		(drill 0.254)
		(layers "F.Cu" "B.Cu")
		(net "GND")
	)
	(via
		(at 125.269244 -69.193156)
		(size 0.508)
		(drill 0.254)
		(layers "F.Cu" "B.Cu")
		(net "GND")
	)
	(via
		(at 253.099824 -52.499768)
		(size 0.4572)
		(drill 0.2032)
		(layers "F.Cu" "B.Cu")
		(net "GND")
	)
	(via
		(at 319.2526 -210.152996)
		(size 0.508)
		(drill 0.254)
		(layers "F.Cu" "B.Cu")
		(net "GND")
	)
	(via
		(at 195.4276 -28.4226)
		(size 0.508)
		(drill 0.254)
		(layers "F.Cu" "B.Cu")
		(net "GND")
	)
	(via
		(at 150.90013 -223.082104)
		(size 0.508)
		(drill 0.254)
		(layers "F.Cu" "B.Cu")
		(net "GND")
	)
	(via
		(at 56.134 -137.4902)
		(size 0.508)
		(drill 0.254)
		(layers "F.Cu" "B.Cu")
		(net "GND")
	)
	(via
		(at 271.592294 3.60299)
		(size 0.508)
		(drill 0.254)
		(layers "F.Cu" "B.Cu")
		(net "GND")
	)
	(via
		(at 122.023124 -210.192874)
		(size 0.508)
		(drill 0.254)
		(layers "F.Cu" "B.Cu")
		(net "GND")
	)
	(via
		(at 105.6894 -119.5832)
		(size 0.508)
		(drill 0.254)
		(layers "F.Cu" "B.Cu")
		(net "GND")
	)
	(via
		(at 258.5212 -145.4658)
		(size 0.508)
		(drill 0.254)
		(layers "F.Cu" "B.Cu")
		(net "GND")
	)
	(via
		(at 252.068584 -11.448542)
		(size 0.508)
		(drill 0.254)
		(layers "F.Cu" "B.Cu")
		(net "GND")
	)
	(via
		(at 354.203 -30.385004)
		(size 0.508)
		(drill 0.254)
		(layers "F.Cu" "B.Cu")
		(net "GND")
	)
	(via
		(at 290.0426 -16.0782)
		(size 0.508)
		(drill 0.254)
		(layers "F.Cu" "B.Cu")
		(net "GND")
	)
	(via
		(at 184.8612 -73.914)
		(size 0.7112)
		(drill 0.4064)
		(layers "F.Cu" "B.Cu")
		(net "GND")
	)
	(via
		(at 238.100108 -43.50004)
		(size 0.4572)
		(drill 0.2032)
		(layers "F.Cu" "B.Cu")
		(net "GND")
	)
	(via
		(at 223.100138 -51.49977)
		(size 0.4572)
		(drill 0.2032)
		(layers "F.Cu" "B.Cu")
		(net "GND")
	)
	(via
		(at 175.133 -87.376)
		(size 0.508)
		(drill 0.254)
		(layers "F.Cu" "B.Cu")
		(net "GND")
	)
	(via
		(at 280.052526 -210.152996)
		(size 0.508)
		(drill 0.254)
		(layers "F.Cu" "B.Cu")
		(net "GND")
	)
	(via
		(at 231.100122 -53.499766)
		(size 0.4572)
		(drill 0.2032)
		(layers "F.Cu" "B.Cu")
		(net "GND")
	)
	(via
		(at 28.7274 -72.1614)
		(size 0.5588)
		(drill 0.3048)
		(layers "F.Cu" "B.Cu")
		(net "GND")
	)
	(via
		(at 170.958002 -60.479432)
		(size 0.7112)
		(drill 0.4064)
		(layers "F.Cu" "B.Cu")
		(net "GND")
	)
	(via
		(at 301.00778 -36.165536)
		(size 0.508)
		(drill 0.254)
		(layers "F.Cu" "B.Cu")
		(net "GND")
	)
	(via
		(at 298.666154 -36.17214)
		(size 0.508)
		(drill 0.254)
		(layers "F.Cu" "B.Cu")
		(net "GND")
	)
	(via
		(at 34.967926 -153.57983)
		(size 0.4572)
		(drill 0.2032)
		(layers "F.Cu" "B.Cu")
		(net "GND")
	)
	(via
		(at 1.397 -208.171034)
		(size 0.508)
		(drill 0.254)
		(layers "F.Cu" "B.Cu")
		(net "GND")
	)
	(via
		(at 26.416 -32.59582)
		(size 0.508)
		(drill 0.254)
		(layers "F.Cu" "B.Cu")
		(net "GND")
	)
	(via
		(at 140.8176 -85.3186)
		(size 0.508)
		(drill 0.254)
		(layers "F.Cu" "B.Cu")
		(net "GND")
	)
	(via
		(at 296.2402 -54.7878)
		(size 0.7112)
		(drill 0.4064)
		(layers "F.Cu" "B.Cu")
		(net "GND")
	)
	(via
		(at 238.100108 -31.500064)
		(size 0.4572)
		(drill 0.2032)
		(layers "F.Cu" "B.Cu")
		(net "GND")
	)
	(via
		(at 44.61764 -202.52436)
		(size 0.508)
		(drill 0.254)
		(layers "F.Cu" "B.Cu")
		(net "GND")
	)
	(via
		(at 19.6596 -146.558)
		(size 0.508)
		(drill 0.254)
		(layers "F.Cu" "B.Cu")
		(net "GND")
	)
	(via
		(at 54.65064 -182.45836)
		(size 0.508)
		(drill 0.254)
		(layers "F.Cu" "B.Cu")
		(net "GND")
	)
	(via
		(at 246.099838 -32.500062)
		(size 0.4572)
		(drill 0.2032)
		(layers "F.Cu" "B.Cu")
		(net "GND")
	)
	(via
		(at 79.252318 -210.152996)
		(size 0.508)
		(drill 0.254)
		(layers "F.Cu" "B.Cu")
		(net "GND")
	)
	(via
		(at 63.25235 -210.152996)
		(size 0.508)
		(drill 0.254)
		(layers "F.Cu" "B.Cu")
		(net "GND")
	)
	(via
		(at 265.43 -156.845)
		(size 0.508)
		(drill 0.254)
		(layers "F.Cu" "B.Cu")
		(net "GND")
	)
	(via
		(at 244.099842 -32.500062)
		(size 0.4572)
		(drill 0.2032)
		(layers "F.Cu" "B.Cu")
		(net "GND")
	)
	(via
		(at 214.147146 -210.152996)
		(size 0.508)
		(drill 0.254)
		(layers "F.Cu" "B.Cu")
		(net "GND")
	)
	(via
		(at 237.10011 -35.500056)
		(size 0.4572)
		(drill 0.2032)
		(layers "F.Cu" "B.Cu")
		(net "GND")
	)
	(via
		(at 336.061304 -174.497746)
		(size 0.508)
		(drill 0.254)
		(layers "F.Cu" "B.Cu")
		(net "GND")
	)
	(via
		(at 135.3566 -23.4696)
		(size 0.508)
		(drill 0.254)
		(layers "F.Cu" "B.Cu")
		(net "GND")
	)
	(via
		(at 195.9864 -6.1468)
		(size 0.508)
		(drill 0.254)
		(layers "F.Cu" "B.Cu")
		(net "GND")
	)
	(via
		(at 338.328 -65.405)
		(size 0.508)
		(drill 0.254)
		(layers "F.Cu" "B.Cu")
		(net "GND")
	)
	(via
		(at 54.88686 -150.859998)
		(size 0.508)
		(drill 0.254)
		(layers "F.Cu" "B.Cu")
		(net "GND")
	)
	(via
		(at 159.5374 -19.7358)
		(size 0.508)
		(drill 0.254)
		(layers "F.Cu" "B.Cu")
		(net "GND")
	)
	(via
		(at 354.203 -142.145004)
		(size 0.508)
		(drill 0.254)
		(layers "F.Cu" "B.Cu")
		(net "GND")
	)
	(via
		(at 160.3502 -14.5034)
		(size 0.508)
		(drill 0.254)
		(layers "F.Cu" "B.Cu")
		(net "GND")
	)
	(via
		(at 71.501 -190.119)
		(size 0.508)
		(drill 0.254)
		(layers "F.Cu" "B.Cu")
		(net "GND")
	)
	(via
		(at 10.0584 -80.6704)
		(size 0.508)
		(drill 0.254)
		(layers "F.Cu" "B.Cu")
		(net "GND")
	)
	(via
		(at 236.100112 -61.49975)
		(size 0.4572)
		(drill 0.2032)
		(layers "F.Cu" "B.Cu")
		(net "GND")
	)
	(via
		(at 354.203 -177.705004)
		(size 0.508)
		(drill 0.254)
		(layers "F.Cu" "B.Cu")
		(net "GND")
	)
	(via
		(at 248.099834 -51.49977)
		(size 0.4572)
		(drill 0.2032)
		(layers "F.Cu" "B.Cu")
		(net "GND")
	)
	(via
		(at 232.745026 -182.521352)
		(size 0.508)
		(drill 0.254)
		(layers "F.Cu" "B.Cu")
		(net "GND")
	)
	(via
		(at 268.236446 -4.672584)
		(size 0.508)
		(drill 0.254)
		(layers "F.Cu" "B.Cu")
		(net "GND")
	)
	(via
		(at 325.652384 -210.152996)
		(size 0.508)
		(drill 0.254)
		(layers "F.Cu" "B.Cu")
		(net "GND")
	)
	(via
		(at 252.099826 -61.49975)
		(size 0.4572)
		(drill 0.2032)
		(layers "F.Cu" "B.Cu")
		(net "GND")
	)
	(via
		(at 133.438138 -85.592666)
		(size 0.508)
		(drill 0.254)
		(layers "F.Cu" "B.Cu")
		(net "GND")
	)
	(via
		(at 303.2506 -19.812)
		(size 0.508)
		(drill 0.254)
		(layers "F.Cu" "B.Cu")
		(net "GND")
	)
	(via
		(at 323.9008 -15.5448)
		(size 0.508)
		(drill 0.254)
		(layers "F.Cu" "B.Cu")
		(net "GND")
	)
	(via
		(at 31.76778 -156.779976)
		(size 0.4572)
		(drill 0.2032)
		(layers "F.Cu" "B.Cu")
		(net "GND")
	)
	(via
		(at 186.7916 -59.3852)
		(size 0.7112)
		(drill 0.4064)
		(layers "F.Cu" "B.Cu")
		(net "GND")
	)
	(via
		(at 241.099848 -61.49975)
		(size 0.4572)
		(drill 0.2032)
		(layers "F.Cu" "B.Cu")
		(net "GND")
	)
	(via
		(at 154.309826 -76.072238)
		(size 0.7112)
		(drill 0.4064)
		(layers "F.Cu" "B.Cu")
		(net "GND")
	)
	(via
		(at 162.433 -94.234)
		(size 0.508)
		(drill 0.254)
		(layers "F.Cu" "B.Cu")
		(net "GND")
	)
	(via
		(at 157.2768 -15.9512)
		(size 0.508)
		(drill 0.254)
		(layers "F.Cu" "B.Cu")
		(net "GND")
	)
	(via
		(at 172.2882 -23.6474)
		(size 0.508)
		(drill 0.254)
		(layers "F.Cu" "B.Cu")
		(net "GND")
	)
	(via
		(at 246.1514 -3.7084)
		(size 0.508)
		(drill 0.254)
		(layers "F.Cu" "B.Cu")
		(net "GND")
	)
	(via
		(at 286.3342 -11.7602)
		(size 0.508)
		(drill 0.254)
		(layers "F.Cu" "B.Cu")
		(net "GND")
	)
	(via
		(at 1.397 -203.091034)
		(size 0.508)
		(drill 0.254)
		(layers "F.Cu" "B.Cu")
		(net "GND")
	)
	(via
		(at 307.721 -26.1366)
		(size 0.508)
		(drill 0.254)
		(layers "F.Cu" "B.Cu")
		(net "GND")
	)
	(via
		(at 232.10012 -51.49977)
		(size 0.4572)
		(drill 0.2032)
		(layers "F.Cu" "B.Cu")
		(net "GND")
	)
	(via
		(at 256.099818 -50.499772)
		(size 0.4572)
		(drill 0.2032)
		(layers "F.Cu" "B.Cu")
		(net "GND")
	)
	(via
		(at 141.252702 -210.152996)
		(size 0.508)
		(drill 0.254)
		(layers "F.Cu" "B.Cu")
		(net "GND")
	)
	(via
		(at 306.197 -71.12)
		(size 0.7112)
		(drill 0.4064)
		(layers "F.Cu" "B.Cu")
		(net "GND")
	)
	(via
		(at 158.242 -97.155)
		(size 0.508)
		(drill 0.254)
		(layers "F.Cu" "B.Cu")
		(net "GND")
	)
	(via
		(at 251.099828 -44.500038)
		(size 0.4572)
		(drill 0.2032)
		(layers "F.Cu" "B.Cu")
		(net "GND")
	)
	(via
		(at 47.244 -179.197)
		(size 0.508)
		(drill 0.254)
		(layers "F.Cu" "B.Cu")
		(net "GND")
	)
	(via
		(at 153.101802 -63.400432)
		(size 0.508)
		(drill 0.254)
		(layers "F.Cu" "B.Cu")
		(net "GND")
	)
	(via
		(at 246.099838 -60.499752)
		(size 0.4572)
		(drill 0.2032)
		(layers "F.Cu" "B.Cu")
		(net "GND")
	)
	(via
		(at 339.598 -64.643)
		(size 0.508)
		(drill 0.254)
		(layers "F.Cu" "B.Cu")
		(net "GND")
	)
	(via
		(at 348.488 -62.3062)
		(size 0.7112)
		(drill 0.4064)
		(layers "F.Cu" "B.Cu")
		(net "GND")
	)
	(via
		(at 231.100122 -45.500036)
		(size 0.4572)
		(drill 0.2032)
		(layers "F.Cu" "B.Cu")
		(net "GND")
	)
	(via
		(at 264.100056 -223.082104)
		(size 0.508)
		(drill 0.254)
		(layers "F.Cu" "B.Cu")
		(net "GND")
	)
	(via
		(at 232.745026 -177.441352)
		(size 0.508)
		(drill 0.254)
		(layers "F.Cu" "B.Cu")
		(net "GND")
	)
	(via
		(at 336.51063 -33.153858)
		(size 0.508)
		(drill 0.254)
		(layers "F.Cu" "B.Cu")
		(net "GND")
	)
	(via
		(at 123.6218 -92.4052)
		(size 0.508)
		(drill 0.254)
		(layers "F.Cu" "B.Cu")
		(net "GND")
	)
	(via
		(at 170.923458 -55.797958)
		(size 0.7112)
		(drill 0.4064)
		(layers "F.Cu" "B.Cu")
		(net "GND")
	)
	(via
		(at 25.43556 -142.05204)
		(size 0.508)
		(drill 0.254)
		(layers "F.Cu" "B.Cu")
		(net "GND")
	)
	(via
		(at 173.752002 -72.620632)
		(size 0.7112)
		(drill 0.4064)
		(layers "F.Cu" "B.Cu")
		(net "GND")
	)
	(via
		(at 46.355 -179.197)
		(size 0.508)
		(drill 0.254)
		(layers "F.Cu" "B.Cu")
		(net "GND")
	)
	(via
		(at 354.203 -111.665004)
		(size 0.508)
		(drill 0.254)
		(layers "F.Cu" "B.Cu")
		(net "GND")
	)
	(via
		(at 225.100134 -38.50005)
		(size 0.4572)
		(drill 0.2032)
		(layers "F.Cu" "B.Cu")
		(net "GND")
	)
	(via
		(at 299.2374 -19.812)
		(size 0.508)
		(drill 0.254)
		(layers "F.Cu" "B.Cu")
		(net "GND")
	)
	(via
		(at 233.100118 -58.499756)
		(size 0.4572)
		(drill 0.2032)
		(layers "F.Cu" "B.Cu")
		(net "GND")
	)
	(via
		(at 252.099826 -58.499756)
		(size 0.4572)
		(drill 0.2032)
		(layers "F.Cu" "B.Cu")
		(net "GND")
	)
	(via
		(at 149.59457 -35.7124)
		(size 0.508)
		(drill 0.254)
		(layers "F.Cu" "B.Cu")
		(net "GND")
	)
	(via
		(at 168.656 -23.1394)
		(size 0.508)
		(drill 0.254)
		(layers "F.Cu" "B.Cu")
		(net "GND")
	)
	(via
		(at 320.77152 -36.298886)
		(size 0.508)
		(drill 0.254)
		(layers "F.Cu" "B.Cu")
		(net "GND")
	)
	(via
		(at 67.183 -39.0525)
		(size 0.508)
		(drill 0.254)
		(layers "F.Cu" "B.Cu")
		(net "GND")
	)
	(via
		(at 91.313 -113.9952)
		(size 0.508)
		(drill 0.254)
		(layers "F.Cu" "B.Cu")
		(net "GND")
	)
	(via
		(at 234.100116 -54.499764)
		(size 0.4572)
		(drill 0.2032)
		(layers "F.Cu" "B.Cu")
		(net "GND")
	)
	(via
		(at 254.25019 -7.443978)
		(size 0.508)
		(drill 0.254)
		(layers "F.Cu" "B.Cu")
		(net "GND")
	)
	(via
		(at 335.252568 -210.152996)
		(size 0.508)
		(drill 0.254)
		(layers "F.Cu" "B.Cu")
		(net "GND")
	)
	(via
		(at 242.099846 -40.500046)
		(size 0.4572)
		(drill 0.2032)
		(layers "F.Cu" "B.Cu")
		(net "GND")
	)
	(via
		(at 183.30926 -13.54836)
		(size 0.508)
		(drill 0.254)
		(layers "F.Cu" "B.Cu")
		(net "GND")
	)
	(via
		(at 78.86065 -92.505022)
		(size 0.508)
		(drill 0.254)
		(layers "F.Cu" "B.Cu")
		(net "GND")
	)
	(via
		(at 90.499946 -223.082104)
		(size 0.508)
		(drill 0.254)
		(layers "F.Cu" "B.Cu")
		(net "GND")
	)
	(via
		(at 76.41209 -146.85391)
		(size 0.508)
		(drill 0.254)
		(layers "F.Cu" "B.Cu")
		(net "GND")
	)
	(via
		(at 1.397 -137.051034)
		(size 0.508)
		(drill 0.254)
		(layers "F.Cu" "B.Cu")
		(net "GND")
	)
	(via
		(at 87.376 -48.895)
		(size 0.7112)
		(drill 0.4064)
		(layers "F.Cu" "B.Cu")
		(net "GND")
	)
	(via
		(at 231.100122 -62.499748)
		(size 0.4572)
		(drill 0.2032)
		(layers "F.Cu" "B.Cu")
		(net "GND")
	)
	(via
		(at 182.5752 -73.914)
		(size 0.7112)
		(drill 0.4064)
		(layers "F.Cu" "B.Cu")
		(net "GND")
	)
	(via
		(at 257.099816 -42.500042)
		(size 0.4572)
		(drill 0.2032)
		(layers "F.Cu" "B.Cu")
		(net "GND")
	)
	(via
		(at 206.05242 -210.152996)
		(size 0.508)
		(drill 0.254)
		(layers "F.Cu" "B.Cu")
		(net "GND")
	)
	(via
		(at 323.1388 -18.5166)
		(size 0.508)
		(drill 0.254)
		(layers "F.Cu" "B.Cu")
		(net "GND")
	)
	(via
		(at 241.099848 -62.499748)
		(size 0.4572)
		(drill 0.2032)
		(layers "F.Cu" "B.Cu")
		(net "GND")
	)
	(via
		(at 241.099848 -55.499762)
		(size 0.4572)
		(drill 0.2032)
		(layers "F.Cu" "B.Cu")
		(net "GND")
	)
	(via
		(at 17.83334 -87.0458)
		(size 0.508)
		(drill 0.254)
		(layers "F.Cu" "B.Cu")
		(net "GND")
	)
	(via
		(at 28.2956 -188.4172)
		(size 0.508)
		(drill 0.254)
		(layers "F.Cu" "B.Cu")
		(net "GND")
	)
	(via
		(at 1.397 -86.251034)
		(size 0.508)
		(drill 0.254)
		(layers "F.Cu" "B.Cu")
		(net "GND")
	)
	(via
		(at 32.34182 -62.999366)
		(size 0.508)
		(drill 0.254)
		(layers "F.Cu" "B.Cu")
		(net "GND")
	)
	(via
		(at 153.101802 -61.177932)
		(size 0.508)
		(drill 0.254)
		(layers "F.Cu" "B.Cu")
		(net "GND")
	)
	(via
		(at 250.09983 -42.500042)
		(size 0.4572)
		(drill 0.2032)
		(layers "F.Cu" "B.Cu")
		(net "GND")
	)
	(via
		(at 184.72531 -13.357352)
		(size 0.508)
		(drill 0.254)
		(layers "F.Cu" "B.Cu")
		(net "GND")
	)
	(via
		(at 301.652432 -210.152996)
		(size 0.508)
		(drill 0.254)
		(layers "F.Cu" "B.Cu")
		(net "GND")
	)
	(via
		(at 31.705042 -137.685018)
		(size 0.4572)
		(drill 0.2032)
		(layers "F.Cu" "B.Cu")
		(net "GND")
	)
	(via
		(at 232.10012 -31.500064)
		(size 0.4572)
		(drill 0.2032)
		(layers "F.Cu" "B.Cu")
		(net "GND")
	)
	(via
		(at 312.1406 -18.5166)
		(size 0.508)
		(drill 0.254)
		(layers "F.Cu" "B.Cu")
		(net "GND")
	)
	(via
		(at 116.6368 -93.8022)
		(size 0.508)
		(drill 0.254)
		(layers "F.Cu" "B.Cu")
		(net "GND")
	)
	(via
		(at 157.8102 -93.1926)
		(size 0.508)
		(drill 0.254)
		(layers "F.Cu" "B.Cu")
		(net "GND")
	)
	(via
		(at 173.6852 -74.93)
		(size 0.7112)
		(drill 0.4064)
		(layers "F.Cu" "B.Cu")
		(net "GND")
	)
	(via
		(at 298.703746 -54.7878)
		(size 0.7112)
		(drill 0.4064)
		(layers "F.Cu" "B.Cu")
		(net "GND")
	)
	(via
		(at 163.1188 -222.9866)
		(size 0.508)
		(drill 0.254)
		(layers "F.Cu" "B.Cu")
		(net "GND")
	)
	(via
		(at 231.100122 -57.499758)
		(size 0.4572)
		(drill 0.2032)
		(layers "F.Cu" "B.Cu")
		(net "GND")
	)
	(via
		(at 226.100132 -63.499746)
		(size 0.4572)
		(drill 0.2032)
		(layers "F.Cu" "B.Cu")
		(net "GND")
	)
	(via
		(at 305.7652 -54.7878)
		(size 0.7112)
		(drill 0.4064)
		(layers "F.Cu" "B.Cu")
		(net "GND")
	)
	(via
		(at 184.2262 -58.0898)
		(size 0.7112)
		(drill 0.4064)
		(layers "F.Cu" "B.Cu")
		(net "GND")
	)
	(via
		(at 146.2532 -16.0274)
		(size 0.508)
		(drill 0.254)
		(layers "F.Cu" "B.Cu")
		(net "GND")
	)
	(via
		(at 151.852884 -31.908242)
		(size 0.508)
		(drill 0.254)
		(layers "F.Cu" "B.Cu")
		(net "GND")
	)
	(via
		(at 230.886 -70.866)
		(size 0.508)
		(drill 0.254)
		(layers "F.Cu" "B.Cu")
		(net "GND")
	)
	(via
		(at 154.371802 -59.717432)
		(size 0.508)
		(drill 0.254)
		(layers "F.Cu" "B.Cu")
		(net "GND")
	)
	(via
		(at 39.03218 -79.832708)
		(size 0.7112)
		(drill 0.4064)
		(layers "F.Cu" "B.Cu")
		(net "GND")
	)
	(via
		(at 16.9418 -181.229)
		(size 0.508)
		(drill 0.254)
		(layers "F.Cu" "B.Cu")
		(net "GND")
	)
	(via
		(at 217.424 -223.0628)
		(size 0.508)
		(drill 0.254)
		(layers "F.Cu" "B.Cu")
		(net "GND")
	)
	(via
		(at 322.58 -123.825)
		(size 0.7112)
		(drill 0.3556)
		(layers "F.Cu" "B.Cu")
		(net "GND")
	)
	(via
		(at 76.41209 -148.12391)
		(size 0.508)
		(drill 0.254)
		(layers "F.Cu" "B.Cu")
		(net "GND")
	)
	(via
		(at 135.254746 -80.160114)
		(size 0.508)
		(drill 0.254)
		(layers "F.Cu" "B.Cu")
		(net "GND")
	)
	(via
		(at 16.0655 -52.0827)
		(size 0.508)
		(drill 0.254)
		(layers "F.Cu" "B.Cu")
		(net "GND")
	)
	(via
		(at 231.100122 -59.499754)
		(size 0.4572)
		(drill 0.2032)
		(layers "F.Cu" "B.Cu")
		(net "GND")
	)
	(via
		(at 183.79694 -27.03322)
		(size 0.508)
		(drill 0.254)
		(layers "F.Cu" "B.Cu")
		(net "GND")
	)
	(via
		(at 292.478968 -19.981672)
		(size 0.508)
		(drill 0.254)
		(layers "F.Cu" "B.Cu")
		(net "GND")
	)
	(via
		(at 232.10012 -64.499744)
		(size 0.4572)
		(drill 0.2032)
		(layers "F.Cu" "B.Cu")
		(net "GND")
	)
	(via
		(at 338.709 -180.213)
		(size 0.508)
		(drill 0.254)
		(layers "F.Cu" "B.Cu")
		(net "GND")
	)
	(via
		(at 160.782 -90.5764)
		(size 0.508)
		(drill 0.254)
		(layers "F.Cu" "B.Cu")
		(net "GND")
	)
	(via
		(at 152.54732 -210.152996)
		(size 0.508)
		(drill 0.254)
		(layers "F.Cu" "B.Cu")
		(net "GND")
	)
	(via
		(at 224.100136 -51.49977)
		(size 0.4572)
		(drill 0.2032)
		(layers "F.Cu" "B.Cu")
		(net "GND")
	)
	(via
		(at 327.299828 -223.082104)
		(size 0.508)
		(drill 0.254)
		(layers "F.Cu" "B.Cu")
		(net "GND")
	)
	(via
		(at 222.10014 -32.500062)
		(size 0.4572)
		(drill 0.2032)
		(layers "F.Cu" "B.Cu")
		(net "GND")
	)
	(via
		(at 165.9382 -12.3444)
		(size 0.508)
		(drill 0.254)
		(layers "F.Cu" "B.Cu")
		(net "GND")
	)
	(via
		(at 51.534568 -47.864014)
		(size 0.508)
		(drill 0.254)
		(layers "F.Cu" "B.Cu")
		(net "GND")
	)
	(via
		(at 129.921 -203.962)
		(size 0.508)
		(drill 0.254)
		(layers "F.Cu" "B.Cu")
		(net "GND")
	)
	(via
		(at 250.09983 -45.500036)
		(size 0.4572)
		(drill 0.2032)
		(layers "F.Cu" "B.Cu")
		(net "GND")
	)
	(via
		(at 46.355 -193.294)
		(size 0.508)
		(drill 0.254)
		(layers "F.Cu" "B.Cu")
		(net "GND")
	)
	(via
		(at 57.539382 -18.438114)
		(size 0.508)
		(drill 0.254)
		(layers "F.Cu" "B.Cu")
		(net "GND")
	)
	(via
		(at 224.640648 -212.102954)
		(size 0.508)
		(drill 0.254)
		(layers "F.Cu" "B.Cu")
		(net "GND")
	)
	(via
		(at 229.100126 -31.500064)
		(size 0.4572)
		(drill 0.2032)
		(layers "F.Cu" "B.Cu")
		(net "GND")
	)
	(via
		(at 235.100114 -53.499766)
		(size 0.4572)
		(drill 0.2032)
		(layers "F.Cu" "B.Cu")
		(net "GND")
	)
	(via
		(at 108.947204 -210.152996)
		(size 0.508)
		(drill 0.254)
		(layers "F.Cu" "B.Cu")
		(net "GND")
	)
	(via
		(at 12.192 -107.315)
		(size 0.508)
		(drill 0.254)
		(layers "F.Cu" "B.Cu")
		(net "GND")
	)
	(via
		(at 145.7706 -91.5924)
		(size 0.508)
		(drill 0.254)
		(layers "F.Cu" "B.Cu")
		(net "GND")
	)
	(via
		(at 327.059798 -36.674044)
		(size 0.508)
		(drill 0.254)
		(layers "F.Cu" "B.Cu")
		(net "GND")
	)
	(via
		(at 55.819802 -119.935498)
		(size 0.508)
		(drill 0.254)
		(layers "F.Cu" "B.Cu")
		(net "GND")
	)
	(via
		(at 229.100126 -53.499766)
		(size 0.4572)
		(drill 0.2032)
		(layers "F.Cu" "B.Cu")
		(net "GND")
	)
	(via
		(at 144.452594 -210.152996)
		(size 0.508)
		(drill 0.254)
		(layers "F.Cu" "B.Cu")
		(net "GND")
	)
	(via
		(at 70.715124 -181.998874)
		(size 0.508)
		(drill 0.254)
		(layers "F.Cu" "B.Cu")
		(net "GND")
	)
	(via
		(at 64.893698 -130.163316)
		(size 0.508)
		(drill 0.254)
		(layers "F.Cu" "B.Cu")
		(net "GND")
	)
	(via
		(at 18.525236 -59.09945)
		(size 0.508)
		(drill 0.254)
		(layers "F.Cu" "B.Cu")
		(net "GND")
	)
	(via
		(at 92.52585 -183.650382)
		(size 0.508)
		(drill 0.254)
		(layers "F.Cu" "B.Cu")
		(net "GND")
	)
	(via
		(at 340.868 -68.199)
		(size 0.508)
		(drill 0.254)
		(layers "F.Cu" "B.Cu")
		(net "GND")
	)
	(via
		(at 178.900074 -223.082104)
		(size 0.508)
		(drill 0.254)
		(layers "F.Cu" "B.Cu")
		(net "GND")
	)
	(via
		(at 354.203 -192.945004)
		(size 0.508)
		(drill 0.254)
		(layers "F.Cu" "B.Cu")
		(net "GND")
	)
	(via
		(at 27.0256 -79.2988)
		(size 0.508)
		(drill 0.254)
		(layers "F.Cu" "B.Cu")
		(net "GND")
	)
	(via
		(at 235.100114 -32.500062)
		(size 0.4572)
		(drill 0.2032)
		(layers "F.Cu" "B.Cu")
		(net "GND")
	)
	(via
		(at 5.4356 -83.2866)
		(size 0.508)
		(drill 0.254)
		(layers "F.Cu" "B.Cu")
		(net "GND")
	)
	(via
		(at 249.428 -67.945)
		(size 0.508)
		(drill 0.254)
		(layers "F.Cu" "B.Cu")
		(net "GND")
	)
	(via
		(at 235.4834 -24.6126)
		(size 0.508)
		(drill 0.254)
		(layers "F.Cu" "B.Cu")
		(net "GND")
	)
	(via
		(at 236.100112 -64.499744)
		(size 0.4572)
		(drill 0.2032)
		(layers "F.Cu" "B.Cu")
		(net "GND")
	)
	(via
		(at 241.099848 -43.50004)
		(size 0.4572)
		(drill 0.2032)
		(layers "F.Cu" "B.Cu")
		(net "GND")
	)
	(via
		(at 59.299856 -223.082104)
		(size 0.508)
		(drill 0.254)
		(layers "F.Cu" "B.Cu")
		(net "GND")
	)
	(via
		(at 222.10014 -64.499744)
		(size 0.4572)
		(drill 0.2032)
		(layers "F.Cu" "B.Cu")
		(net "GND")
	)
	(via
		(at 18.725134 -82.77098)
		(size 0.508)
		(drill 0.254)
		(layers "F.Cu" "B.Cu")
		(net "GND")
	)
	(via
		(at 35.179 -212.09)
		(size 0.508)
		(drill 0.254)
		(layers "F.Cu" "B.Cu")
		(net "GND")
	)
	(via
		(at 254.099822 -37.500052)
		(size 0.4572)
		(drill 0.2032)
		(layers "F.Cu" "B.Cu")
		(net "GND")
	)
	(via
		(at 225.100134 -59.499754)
		(size 0.4572)
		(drill 0.2032)
		(layers "F.Cu" "B.Cu")
		(net "GND")
	)
	(via
		(at 354.203 -86.265004)
		(size 0.508)
		(drill 0.254)
		(layers "F.Cu" "B.Cu")
		(net "GND")
	)
	(via
		(at 243.099844 -48.499776)
		(size 0.4572)
		(drill 0.2032)
		(layers "F.Cu" "B.Cu")
		(net "GND")
	)
	(via
		(at 252.099826 -54.499764)
		(size 0.4572)
		(drill 0.2032)
		(layers "F.Cu" "B.Cu")
		(net "GND")
	)
	(via
		(at 76.454 -149.52091)
		(size 0.508)
		(drill 0.254)
		(layers "F.Cu" "B.Cu")
		(net "GND")
	)
	(via
		(at 330.740512 -171.213018)
		(size 0.508)
		(drill 0.254)
		(layers "F.Cu" "B.Cu")
		(net "GND")
	)
	(via
		(at 307.469794 -13.2842)
		(size 0.508)
		(drill 0.254)
		(layers "F.Cu" "B.Cu")
		(net "GND")
	)
	(via
		(at 257.099816 -33.50006)
		(size 0.4572)
		(drill 0.2032)
		(layers "F.Cu" "B.Cu")
		(net "GND")
	)
	(via
		(at 196.45249 -210.152996)
		(size 0.508)
		(drill 0.254)
		(layers "F.Cu" "B.Cu")
		(net "GND")
	)
	(via
		(at 136.4996 -23.114)
		(size 0.508)
		(drill 0.254)
		(layers "F.Cu" "B.Cu")
		(net "GND")
	)
	(via
		(at 247.099836 -57.499758)
		(size 0.4572)
		(drill 0.2032)
		(layers "F.Cu" "B.Cu")
		(net "GND")
	)
	(via
		(at 296.7736 -26.162)
		(size 0.508)
		(drill 0.254)
		(layers "F.Cu" "B.Cu")
		(net "GND")
	)
	(via
		(at 320.802 -53.417978)
		(size 0.7112)
		(drill 0.4064)
		(layers "F.Cu" "B.Cu")
		(net "GND")
	)
	(via
		(at 127.2032 -144.0688)
		(size 0.508)
		(drill 0.254)
		(layers "F.Cu" "B.Cu")
		(net "GND")
	)
	(via
		(at 267.73886 -14.85138)
		(size 0.508)
		(drill 0.254)
		(layers "F.Cu" "B.Cu")
		(net "GND")
	)
	(via
		(at 291.2999 -223.082104)
		(size 0.508)
		(drill 0.254)
		(layers "F.Cu" "B.Cu")
		(net "GND")
	)
	(via
		(at 101.9302 -40.5892)
		(size 0.508)
		(drill 0.254)
		(layers "F.Cu" "B.Cu")
		(net "GND")
	)
	(via
		(at 20.2184 -101.3968)
		(size 0.508)
		(drill 0.254)
		(layers "F.Cu" "B.Cu")
		(net "GND")
	)
	(via
		(at 232.10012 -52.499768)
		(size 0.4572)
		(drill 0.2032)
		(layers "F.Cu" "B.Cu")
		(net "GND")
	)
	(via
		(at 234.100116 -43.50004)
		(size 0.4572)
		(drill 0.2032)
		(layers "F.Cu" "B.Cu")
		(net "GND")
	)
	(via
		(at 254.099822 -39.500048)
		(size 0.4572)
		(drill 0.2032)
		(layers "F.Cu" "B.Cu")
		(net "GND")
	)
	(via
		(at 264.052558 -210.152996)
		(size 0.508)
		(drill 0.254)
		(layers "F.Cu" "B.Cu")
		(net "GND")
	)
	(via
		(at 137.1854 -26.1366)
		(size 0.508)
		(drill 0.254)
		(layers "F.Cu" "B.Cu")
		(net "GND")
	)
	(via
		(at 336.658966 -37.66058)
		(size 0.508)
		(drill 0.254)
		(layers "F.Cu" "B.Cu")
		(net "GND")
	)
	(via
		(at 166.0525 -210.152996)
		(size 0.508)
		(drill 0.254)
		(layers "F.Cu" "B.Cu")
		(net "GND")
	)
	(via
		(at 259.099812 -62.499748)
		(size 0.4572)
		(drill 0.2032)
		(layers "F.Cu" "B.Cu")
		(net "GND")
	)
	(via
		(at 299.872654 -54.7878)
		(size 0.7112)
		(drill 0.4064)
		(layers "F.Cu" "B.Cu")
		(net "GND")
	)
	(via
		(at 232.10012 -61.49975)
		(size 0.4572)
		(drill 0.2032)
		(layers "F.Cu" "B.Cu")
		(net "GND")
	)
	(via
		(at 39.9542 -62.611)
		(size 0.508)
		(drill 0.254)
		(layers "F.Cu" "B.Cu")
		(net "GND")
	)
	(via
		(at 108.627926 -1.397)
		(size 0.508)
		(drill 0.254)
		(layers "F.Cu" "B.Cu")
		(net "GND")
	)
	(via
		(at 233.100118 -46.500034)
		(size 0.4572)
		(drill 0.2032)
		(layers "F.Cu" "B.Cu")
		(net "GND")
	)
	(via
		(at 136.913874 -34.5948)
		(size 0.508)
		(drill 0.254)
		(layers "F.Cu" "B.Cu")
		(net "GND")
	)
	(via
		(at 319.506346 -36.291774)
		(size 0.508)
		(drill 0.254)
		(layers "F.Cu" "B.Cu")
		(net "GND")
	)
	(via
		(at 236.100112 -50.499772)
		(size 0.4572)
		(drill 0.2032)
		(layers "F.Cu" "B.Cu")
		(net "GND")
	)
	(via
		(at 256.099818 -45.500036)
		(size 0.4572)
		(drill 0.2032)
		(layers "F.Cu" "B.Cu")
		(net "GND")
	)
	(via
		(at 115.537234 -31.061914)
		(size 0.508)
		(drill 0.254)
		(layers "F.Cu" "B.Cu")
		(net "GND")
	)
	(via
		(at 236.100112 -31.500064)
		(size 0.4572)
		(drill 0.2032)
		(layers "F.Cu" "B.Cu")
		(net "GND")
	)
	(via
		(at 232.10012 -56.49976)
		(size 0.4572)
		(drill 0.2032)
		(layers "F.Cu" "B.Cu")
		(net "GND")
	)
	(via
		(at 17.1704 -53.213)
		(size 0.508)
		(drill 0.254)
		(layers "F.Cu" "B.Cu")
		(net "GND")
	)
	(via
		(at 318.008 -74.168)
		(size 0.7112)
		(drill 0.4064)
		(layers "F.Cu" "B.Cu")
		(net "GND")
	)
	(via
		(at 316.738 -70.866)
		(size 0.7112)
		(drill 0.4064)
		(layers "F.Cu" "B.Cu")
		(net "GND")
	)
	(via
		(at 323.977 -23.114)
		(size 0.508)
		(drill 0.254)
		(layers "F.Cu" "B.Cu")
		(net "GND")
	)
	(via
		(at 47.244 -193.294)
		(size 0.508)
		(drill 0.254)
		(layers "F.Cu" "B.Cu")
		(net "GND")
	)
	(via
		(at 343.34704 -210.152996)
		(size 0.508)
		(drill 0.254)
		(layers "F.Cu" "B.Cu")
		(net "GND")
	)
	(via
		(at 230.100124 -48.499776)
		(size 0.4572)
		(drill 0.2032)
		(layers "F.Cu" "B.Cu")
		(net "GND")
	)
	(via
		(at 202.852528 -210.152996)
		(size 0.508)
		(drill 0.254)
		(layers "F.Cu" "B.Cu")
		(net "GND")
	)
	(via
		(at 157.4038 -23.3934)
		(size 0.508)
		(drill 0.254)
		(layers "F.Cu" "B.Cu")
		(net "GND")
	)
	(via
		(at 233.100118 -51.49977)
		(size 0.4572)
		(drill 0.2032)
		(layers "F.Cu" "B.Cu")
		(net "GND")
	)
	(via
		(at 155.747212 -210.152996)
		(size 0.508)
		(drill 0.254)
		(layers "F.Cu" "B.Cu")
		(net "GND")
	)
	(via
		(at 54.500018 -223.082104)
		(size 0.508)
		(drill 0.254)
		(layers "F.Cu" "B.Cu")
		(net "GND")
	)
	(via
		(at 222.10014 -63.499746)
		(size 0.4572)
		(drill 0.2032)
		(layers "F.Cu" "B.Cu")
		(net "GND")
	)
	(via
		(at 218.059 -8.128)
		(size 0.508)
		(drill 0.254)
		(layers "F.Cu" "B.Cu")
		(net "GND")
	)
	(via
		(at 318.389 -170.688)
		(size 0.508)
		(drill 0.254)
		(layers "F.Cu" "B.Cu")
		(net "GND")
	)
	(via
		(at 252.538992 -174.197772)
		(size 0.508)
		(drill 0.254)
		(layers "F.Cu" "B.Cu")
		(net "GND")
	)
	(via
		(at 176.403 -92.964)
		(size 0.7112)
		(drill 0.3556)
		(layers "F.Cu" "B.Cu")
		(net "GND")
	)
	(via
		(at 354.203 -116.745004)
		(size 0.508)
		(drill 0.254)
		(layers "F.Cu" "B.Cu")
		(net "GND")
	)
	(via
		(at 156.4132 -23.1648)
		(size 0.508)
		(drill 0.254)
		(layers "F.Cu" "B.Cu")
		(net "GND")
	)
	(via
		(at 28.702 -71.247)
		(size 0.5588)
		(drill 0.3048)
		(layers "F.Cu" "B.Cu")
		(net "GND")
	)
	(via
		(at 338.500212 -223.082104)
		(size 0.508)
		(drill 0.254)
		(layers "F.Cu" "B.Cu")
		(net "GND")
	)
	(via
		(at 207.747108 -210.152996)
		(size 0.508)
		(drill 0.254)
		(layers "F.Cu" "B.Cu")
		(net "GND")
	)
	(via
		(at 250.09983 -62.499748)
		(size 0.4572)
		(drill 0.2032)
		(layers "F.Cu" "B.Cu")
		(net "GND")
	)
	(via
		(at 215.265 -182.245)
		(size 0.508)
		(drill 0.254)
		(layers "F.Cu" "B.Cu")
		(net "GND")
	)
	(via
		(at 336.947256 -210.152996)
		(size 0.508)
		(drill 0.254)
		(layers "F.Cu" "B.Cu")
		(net "GND")
	)
	(via
		(at 298.7548 -23.5966)
		(size 0.508)
		(drill 0.254)
		(layers "F.Cu" "B.Cu")
		(net "GND")
	)
	(via
		(at 250.09983 -65.499742)
		(size 0.4572)
		(drill 0.2032)
		(layers "F.Cu" "B.Cu")
		(net "GND")
	)
	(via
		(at 26.746962 -106.552238)
		(size 0.508)
		(drill 0.254)
		(layers "F.Cu" "B.Cu")
		(net "GND")
	)
	(via
		(at 258.537202 -11.444224)
		(size 0.508)
		(drill 0.254)
		(layers "F.Cu" "B.Cu")
		(net "GND")
	)
	(via
		(at 125.999494 -198.546212)
		(size 0.508)
		(drill 0.254)
		(layers "F.Cu" "B.Cu")
		(net "GND")
	)
	(via
		(at 149.1234 -59.6392)
		(size 0.508)
		(drill 0.254)
		(layers "F.Cu" "B.Cu")
		(net "GND")
	)
	(via
		(at 237.10011 -60.499752)
		(size 0.4572)
		(drill 0.2032)
		(layers "F.Cu" "B.Cu")
		(net "GND")
	)
	(via
		(at 103.547926 -1.397)
		(size 0.508)
		(drill 0.254)
		(layers "F.Cu" "B.Cu")
		(net "GND")
	)
	(via
		(at 247.099836 -31.500064)
		(size 0.4572)
		(drill 0.2032)
		(layers "F.Cu" "B.Cu")
		(net "GND")
	)
	(via
		(at 71.347076 -210.152996)
		(size 0.508)
		(drill 0.254)
		(layers "F.Cu" "B.Cu")
		(net "GND")
	)
	(via
		(at 321.3608 -19.6596)
		(size 0.508)
		(drill 0.254)
		(layers "F.Cu" "B.Cu")
		(net "GND")
	)
	(via
		(at 18.057876 -72.639174)
		(size 0.508)
		(drill 0.254)
		(layers "F.Cu" "B.Cu")
		(net "GND")
	)
	(via
		(at 320.675 -72.644)
		(size 0.7112)
		(drill 0.4064)
		(layers "F.Cu" "B.Cu")
		(net "GND")
	)
	(via
		(at 159.5628 -15.9004)
		(size 0.508)
		(drill 0.254)
		(layers "F.Cu" "B.Cu")
		(net "GND")
	)
	(via
		(at 98.467926 -1.397)
		(size 0.508)
		(drill 0.254)
		(layers "F.Cu" "B.Cu")
		(net "GND")
	)
	(via
		(at 30.105096 -124.884688)
		(size 0.4572)
		(drill 0.2032)
		(layers "F.Cu" "B.Cu")
		(net "GND")
	)
	(via
		(at 55.0164 -126.1237)
		(size 0.508)
		(drill 0.254)
		(layers "F.Cu" "B.Cu")
		(net "GND")
	)
	(via
		(at 132.641086 -84.795614)
		(size 0.508)
		(drill 0.254)
		(layers "F.Cu" "B.Cu")
		(net "GND")
	)
	(via
		(at 75.623166 -92.093034)
		(size 0.508)
		(drill 0.254)
		(layers "F.Cu" "B.Cu")
		(net "GND")
	)
	(via
		(at 23.20798 -113.130076)
		(size 0.508)
		(drill 0.254)
		(layers "F.Cu" "B.Cu")
		(net "GND")
	)
	(via
		(at 241.099848 -38.50005)
		(size 0.4572)
		(drill 0.2032)
		(layers "F.Cu" "B.Cu")
		(net "GND")
	)
	(via
		(at 43.307 -197.866)
		(size 0.508)
		(drill 0.254)
		(layers "F.Cu" "B.Cu")
		(net "GND")
	)
	(via
		(at 255.09982 -51.49977)
		(size 0.4572)
		(drill 0.2032)
		(layers "F.Cu" "B.Cu")
		(net "GND")
	)
	(via
		(at 132.45211 -35.804856)
		(size 0.508)
		(drill 0.254)
		(layers "F.Cu" "B.Cu")
		(net "GND")
	)
	(via
		(at 227.10013 -32.500062)
		(size 0.4572)
		(drill 0.2032)
		(layers "F.Cu" "B.Cu")
		(net "GND")
	)
	(via
		(at 183.764174 -19.50212)
		(size 0.508)
		(drill 0.254)
		(layers "F.Cu" "B.Cu")
		(net "GND")
	)
	(via
		(at 156.0322 -14.1732)
		(size 0.508)
		(drill 0.254)
		(layers "F.Cu" "B.Cu")
		(net "GND")
	)
	(via
		(at 57.023 -45.4406)
		(size 0.7112)
		(drill 0.4064)
		(layers "F.Cu" "B.Cu")
		(net "GND")
	)
	(via
		(at 67.183 -38.1635)
		(size 0.508)
		(drill 0.254)
		(layers "F.Cu" "B.Cu")
		(net "GND")
	)
	(via
		(at 156.718 -97.155)
		(size 0.508)
		(drill 0.254)
		(layers "F.Cu" "B.Cu")
		(net "GND")
	)
	(via
		(at 339.598 -69.088)
		(size 0.508)
		(drill 0.254)
		(layers "F.Cu" "B.Cu")
		(net "GND")
	)
	(via
		(at 148.4884 -16.0528)
		(size 0.508)
		(drill 0.254)
		(layers "F.Cu" "B.Cu")
		(net "GND")
	)
	(via
		(at 36.567618 -155.18003)
		(size 0.4572)
		(drill 0.2032)
		(layers "F.Cu" "B.Cu")
		(net "GND")
	)
	(via
		(at 16.1798 -65.3542)
		(size 0.508)
		(drill 0.254)
		(layers "F.Cu" "B.Cu")
		(net "GND")
	)
	(via
		(at 257.099816 -41.500044)
		(size 0.4572)
		(drill 0.2032)
		(layers "F.Cu" "B.Cu")
		(net "GND")
	)
	(via
		(at 305.054 -71.12)
		(size 0.7112)
		(drill 0.4064)
		(layers "F.Cu" "B.Cu")
		(net "GND")
	)
	(via
		(at 160.452562 -210.152996)
		(size 0.508)
		(drill 0.254)
		(layers "F.Cu" "B.Cu")
		(net "GND")
	)
	(via
		(at 229.100126 -42.500042)
		(size 0.4572)
		(drill 0.2032)
		(layers "F.Cu" "B.Cu")
		(net "GND")
	)
	(via
		(at 241.099848 -52.499768)
		(size 0.4572)
		(drill 0.2032)
		(layers "F.Cu" "B.Cu")
		(net "GND")
	)
	(via
		(at 14.91742 -76.075032)
		(size 0.508)
		(drill 0.254)
		(layers "F.Cu" "B.Cu")
		(net "GND")
	)
	(via
		(at 330.644246 -31.871666)
		(size 0.508)
		(drill 0.254)
		(layers "F.Cu" "B.Cu")
		(net "GND")
	)
	(via
		(at 87.619332 -76.38796)
		(size 0.508)
		(drill 0.254)
		(layers "F.Cu" "B.Cu")
		(net "GND")
	)
	(via
		(at 324.099936 -223.082104)
		(size 0.508)
		(drill 0.254)
		(layers "F.Cu" "B.Cu")
		(net "GND")
	)
	(via
		(at 345.1098 -166.5478)
		(size 0.508)
		(drill 0.254)
		(layers "F.Cu" "B.Cu")
		(net "GND")
	)
	(via
		(at 160.50006 -223.082104)
		(size 0.508)
		(drill 0.254)
		(layers "F.Cu" "B.Cu")
		(net "GND")
	)
	(via
		(at 252.538992 -179.277772)
		(size 0.508)
		(drill 0.254)
		(layers "F.Cu" "B.Cu")
		(net "GND")
	)
	(via
		(at 25.26284 -143.8148)
		(size 0.508)
		(drill 0.254)
		(layers "F.Cu" "B.Cu")
		(net "GND")
	)
	(via
		(at 138.8872 -19.3548)
		(size 0.508)
		(drill 0.254)
		(layers "F.Cu" "B.Cu")
		(net "GND")
	)
	(via
		(at 188.722 -151.892)
		(size 0.508)
		(drill 0.254)
		(layers "F.Cu" "B.Cu")
		(net "GND")
	)
	(via
		(at 90.805 -142.621)
		(size 0.7112)
		(drill 0.3556)
		(layers "F.Cu" "B.Cu")
		(net "GND")
	)
	(via
		(at 286.1056 -23.4188)
		(size 0.508)
		(drill 0.254)
		(layers "F.Cu" "B.Cu")
		(net "GND")
	)
	(via
		(at 29.048456 -31.001716)
		(size 0.508)
		(drill 0.254)
		(layers "F.Cu" "B.Cu")
		(net "GND")
	)
	(via
		(at 249.099832 -50.499772)
		(size 0.4572)
		(drill 0.2032)
		(layers "F.Cu" "B.Cu")
		(net "GND")
	)
	(via
		(at 128.525524 -32.050482)
		(size 0.508)
		(drill 0.254)
		(layers "F.Cu" "B.Cu")
		(net "GND")
	)
	(via
		(at 265.938 -163.576)
		(size 0.508)
		(drill 0.254)
		(layers "F.Cu" "B.Cu")
		(net "GND")
	)
	(via
		(at 349.341186 -58.44794)
		(size 0.7112)
		(drill 0.4064)
		(layers "F.Cu" "B.Cu")
		(net "GND")
	)
	(via
		(at 24.194008 -145.196052)
		(size 0.508)
		(drill 0.254)
		(layers "F.Cu" "B.Cu")
		(net "GND")
	)
	(via
		(at 27.392376 -105.35539)
		(size 0.508)
		(drill 0.254)
		(layers "F.Cu" "B.Cu")
		(net "GND")
	)
	(via
		(at 40.9448 -183.8706)
		(size 0.508)
		(drill 0.254)
		(layers "F.Cu" "B.Cu")
		(net "GND")
	)
	(via
		(at 246.099838 -46.500034)
		(size 0.4572)
		(drill 0.2032)
		(layers "F.Cu" "B.Cu")
		(net "GND")
	)
	(via
		(at 232.10012 -57.499758)
		(size 0.4572)
		(drill 0.2032)
		(layers "F.Cu" "B.Cu")
		(net "GND")
	)
	(via
		(at 123.928124 -195.223892)
		(size 0.508)
		(drill 0.254)
		(layers "F.Cu" "B.Cu")
		(net "GND")
	)
	(via
		(at 230.100124 -54.499764)
		(size 0.4572)
		(drill 0.2032)
		(layers "F.Cu" "B.Cu")
		(net "GND")
	)
	(via
		(at 260.17982 -8.732266)
		(size 0.508)
		(drill 0.254)
		(layers "F.Cu" "B.Cu")
		(net "GND")
	)
	(via
		(at 230.100124 -51.49977)
		(size 0.4572)
		(drill 0.2032)
		(layers "F.Cu" "B.Cu")
		(net "GND")
	)
	(via
		(at 281.747214 -210.152996)
		(size 0.508)
		(drill 0.254)
		(layers "F.Cu" "B.Cu")
		(net "GND")
	)
	(via
		(at 40.567864 -151.97963)
		(size 0.4572)
		(drill 0.2032)
		(layers "F.Cu" "B.Cu")
		(net "GND")
	)
	(via
		(at 301.700184 -223.082104)
		(size 0.508)
		(drill 0.254)
		(layers "F.Cu" "B.Cu")
		(net "GND")
	)
	(via
		(at 30.968188 -150.380192)
		(size 0.4572)
		(drill 0.2032)
		(layers "F.Cu" "B.Cu")
		(net "GND")
	)
	(via
		(at 179.5272 -73.8378)
		(size 0.7112)
		(drill 0.4064)
		(layers "F.Cu" "B.Cu")
		(net "GND")
	)
	(via
		(at 232.745026 -202.841352)
		(size 0.508)
		(drill 0.254)
		(layers "F.Cu" "B.Cu")
		(net "GND")
	)
	(via
		(at 227.10013 -44.500038)
		(size 0.4572)
		(drill 0.2032)
		(layers "F.Cu" "B.Cu")
		(net "GND")
	)
	(via
		(at 82.499962 -223.082104)
		(size 0.508)
		(drill 0.254)
		(layers "F.Cu" "B.Cu")
		(net "GND")
	)
	(via
		(at 311.29986 -223.082104)
		(size 0.508)
		(drill 0.254)
		(layers "F.Cu" "B.Cu")
		(net "GND")
	)
	(via
		(at 275.299932 -223.082104)
		(size 0.508)
		(drill 0.254)
		(layers "F.Cu" "B.Cu")
		(net "GND")
	)
	(via
		(at 251.099828 -53.499766)
		(size 0.4572)
		(drill 0.2032)
		(layers "F.Cu" "B.Cu")
		(net "GND")
	)
	(via
		(at 13.8684 -83.4644)
		(size 0.508)
		(drill 0.254)
		(layers "F.Cu" "B.Cu")
		(net "GND")
	)
	(via
		(at 157.3784 -26.2382)
		(size 0.508)
		(drill 0.254)
		(layers "F.Cu" "B.Cu")
		(net "GND")
	)
	(via
		(at 226.100132 -32.500062)
		(size 0.4572)
		(drill 0.2032)
		(layers "F.Cu" "B.Cu")
		(net "GND")
	)
	(via
		(at 230.100124 -44.500038)
		(size 0.4572)
		(drill 0.2032)
		(layers "F.Cu" "B.Cu")
		(net "GND")
	)
	(via
		(at 259.099812 -41.500044)
		(size 0.4572)
		(drill 0.2032)
		(layers "F.Cu" "B.Cu")
		(net "GND")
	)
	(via
		(at 151.831802 -58.828432)
		(size 0.508)
		(drill 0.254)
		(layers "F.Cu" "B.Cu")
		(net "GND")
	)
	(via
		(at 330.6572 -223.0374)
		(size 0.508)
		(drill 0.254)
		(layers "F.Cu" "B.Cu")
		(net "GND")
	)
	(via
		(at 229.100126 -44.500038)
		(size 0.4572)
		(drill 0.2032)
		(layers "F.Cu" "B.Cu")
		(net "GND")
	)
	(via
		(at 229.100126 -57.499758)
		(size 0.4572)
		(drill 0.2032)
		(layers "F.Cu" "B.Cu")
		(net "GND")
	)
	(via
		(at 1.397 -116.731034)
		(size 0.508)
		(drill 0.254)
		(layers "F.Cu" "B.Cu")
		(net "GND")
	)
	(via
		(at 55.38978 -86.421976)
		(size 0.508)
		(drill 0.254)
		(layers "F.Cu" "B.Cu")
		(net "GND")
	)
	(via
		(at 196.950838 -46.79061)
		(size 0.508)
		(drill 0.254)
		(layers "F.Cu" "B.Cu")
		(net "GND")
	)
	(via
		(at 242.099846 -46.500034)
		(size 0.4572)
		(drill 0.2032)
		(layers "F.Cu" "B.Cu")
		(net "GND")
	)
	(via
		(at 33.286954 -166.734744)
		(size 0.508)
		(drill 0.254)
		(layers "F.Cu" "B.Cu")
		(net "GND")
	)
	(via
		(at 234.100116 -55.499762)
		(size 0.4572)
		(drill 0.2032)
		(layers "F.Cu" "B.Cu")
		(net "GND")
	)
	(via
		(at 245.09984 -48.499776)
		(size 0.4572)
		(drill 0.2032)
		(layers "F.Cu" "B.Cu")
		(net "GND")
	)
	(via
		(at 18.235676 -95.920306)
		(size 0.508)
		(drill 0.254)
		(layers "F.Cu" "B.Cu")
		(net "GND")
	)
	(via
		(at 296.545 -74.803)
		(size 0.7112)
		(drill 0.3556)
		(layers "F.Cu" "B.Cu")
		(net "GND")
	)
	(via
		(at 35.8394 -209.423)
		(size 0.508)
		(drill 0.254)
		(layers "F.Cu" "B.Cu")
		(net "GND")
	)
	(via
		(at 289.700208 -223.082104)
		(size 0.508)
		(drill 0.254)
		(layers "F.Cu" "B.Cu")
		(net "GND")
	)
	(via
		(at 132.691886 -80.884014)
		(size 0.508)
		(drill 0.254)
		(layers "F.Cu" "B.Cu")
		(net "GND")
	)
	(via
		(at 251.099828 -52.499768)
		(size 0.4572)
		(drill 0.2032)
		(layers "F.Cu" "B.Cu")
		(net "GND")
	)
	(via
		(at 124.5108 -98.7552)
		(size 0.508)
		(drill 0.254)
		(layers "F.Cu" "B.Cu")
		(net "GND")
	)
	(via
		(at 231.100122 -48.499776)
		(size 0.4572)
		(drill 0.2032)
		(layers "F.Cu" "B.Cu")
		(net "GND")
	)
	(via
		(at 319.405 -49.403)
		(size 0.7112)
		(drill 0.4064)
		(layers "F.Cu" "B.Cu")
		(net "GND")
	)
	(via
		(at 239.100106 -35.500056)
		(size 0.4572)
		(drill 0.2032)
		(layers "F.Cu" "B.Cu")
		(net "GND")
	)
	(via
		(at 252.538992 -169.117772)
		(size 0.508)
		(drill 0.254)
		(layers "F.Cu" "B.Cu")
		(net "GND")
	)
	(via
		(at 143.7894 -26.1874)
		(size 0.508)
		(drill 0.254)
		(layers "F.Cu" "B.Cu")
		(net "GND")
	)
	(via
		(at 259.6642 -3.5306)
		(size 0.508)
		(drill 0.254)
		(layers "F.Cu" "B.Cu")
		(net "GND")
	)
	(via
		(at 65.8622 -162.3822)
		(size 0.508)
		(drill 0.254)
		(layers "F.Cu" "B.Cu")
		(net "GND")
	)
	(via
		(at 149.0726 -181.1528)
		(size 0.508)
		(drill 0.254)
		(layers "F.Cu" "B.Cu")
		(net "GND")
	)
	(via
		(at 1.397 -101.491034)
		(size 0.508)
		(drill 0.254)
		(layers "F.Cu" "B.Cu")
		(net "GND")
	)
	(via
		(at 212.452458 -210.152996)
		(size 0.508)
		(drill 0.254)
		(layers "F.Cu" "B.Cu")
		(net "GND")
	)
	(via
		(at 238.100108 -52.499768)
		(size 0.4572)
		(drill 0.2032)
		(layers "F.Cu" "B.Cu")
		(net "GND")
	)
	(via
		(at 50.4444 -152.3365)
		(size 0.508)
		(drill 0.254)
		(layers "F.Cu" "B.Cu")
		(net "GND")
	)
	(via
		(at 154.432 -178.0032)
		(size 0.508)
		(drill 0.254)
		(layers "F.Cu" "B.Cu")
		(net "GND")
	)
	(via
		(at 19.662902 -128.642872)
		(size 0.508)
		(drill 0.254)
		(layers "F.Cu" "B.Cu")
		(net "GND")
	)
	(via
		(at 1.397 -182.771034)
		(size 0.508)
		(drill 0.254)
		(layers "F.Cu" "B.Cu")
		(net "GND")
	)
	(via
		(at 216.38006 -200.47458)
		(size 0.508)
		(drill 0.254)
		(layers "F.Cu" "B.Cu")
		(net "GND")
	)
	(via
		(at 11.2776 -55.0164)
		(size 0.508)
		(drill 0.254)
		(layers "F.Cu" "B.Cu")
		(net "GND")
	)
	(via
		(at 202.206606 -46.020228)
		(size 0.508)
		(drill 0.254)
		(layers "F.Cu" "B.Cu")
		(net "GND")
	)
	(via
		(at 291.8206 -19.2786)
		(size 0.508)
		(drill 0.254)
		(layers "F.Cu" "B.Cu")
		(net "GND")
	)
	(via
		(at 135.5852 -212.217)
		(size 0.508)
		(drill 0.254)
		(layers "F.Cu" "B.Cu")
		(net "GND")
	)
	(via
		(at 234.100116 -31.500064)
		(size 0.4572)
		(drill 0.2032)
		(layers "F.Cu" "B.Cu")
		(net "GND")
	)
	(via
		(at 215.223598 -11.827002)
		(size 0.508)
		(drill 0.254)
		(layers "F.Cu" "B.Cu")
		(net "GND")
	)
	(via
		(at 241.099848 -50.499772)
		(size 0.4572)
		(drill 0.2032)
		(layers "F.Cu" "B.Cu")
		(net "GND")
	)
	(via
		(at 219.806012 -204.325474)
		(size 0.508)
		(drill 0.254)
		(layers "F.Cu" "B.Cu")
		(net "GND")
	)
	(via
		(at 171.3992 -22.0472)
		(size 0.508)
		(drill 0.254)
		(layers "F.Cu" "B.Cu")
		(net "GND")
	)
	(via
		(at 30.607 -177.165)
		(size 0.7112)
		(drill 0.3556)
		(layers "F.Cu" "B.Cu")
		(net "GND")
	)
	(via
		(at 145.415 -23.1648)
		(size 0.508)
		(drill 0.254)
		(layers "F.Cu" "B.Cu")
		(net "GND")
	)
	(via
		(at 226.100132 -60.499752)
		(size 0.4572)
		(drill 0.2032)
		(layers "F.Cu" "B.Cu")
		(net "GND")
	)
	(via
		(at 235.100114 -40.500046)
		(size 0.4572)
		(drill 0.2032)
		(layers "F.Cu" "B.Cu")
		(net "GND")
	)
	(via
		(at 318.5668 -24.4602)
		(size 0.508)
		(drill 0.254)
		(layers "F.Cu" "B.Cu")
		(net "GND")
	)
	(via
		(at 1.397 -65.931034)
		(size 0.508)
		(drill 0.254)
		(layers "F.Cu" "B.Cu")
		(net "GND")
	)
	(via
		(at 67.5386 -158.0896)
		(size 0.508)
		(drill 0.254)
		(layers "F.Cu" "B.Cu")
		(net "GND")
	)
	(via
		(at 177.3174 -208.6864)
		(size 0.508)
		(drill 0.254)
		(layers "F.Cu" "B.Cu")
		(net "GND")
	)
	(via
		(at 263.088882 -13.074142)
		(size 0.508)
		(drill 0.254)
		(layers "F.Cu" "B.Cu")
		(net "GND")
	)
	(via
		(at 252.099826 -48.499776)
		(size 0.4572)
		(drill 0.2032)
		(layers "F.Cu" "B.Cu")
		(net "GND")
	)
	(via
		(at 86.9442 -129.9464)
		(size 0.508)
		(drill 0.254)
		(layers "F.Cu" "B.Cu")
		(net "GND")
	)
	(via
		(at 268.947138 -210.152996)
		(size 0.508)
		(drill 0.254)
		(layers "F.Cu" "B.Cu")
		(net "GND")
	)
	(via
		(at 256.598166 -4.831588)
		(size 0.508)
		(drill 0.254)
		(layers "F.Cu" "B.Cu")
		(net "GND")
	)
	(via
		(at 231.100122 -56.49976)
		(size 0.4572)
		(drill 0.2032)
		(layers "F.Cu" "B.Cu")
		(net "GND")
	)
	(via
		(at 65.7098 -42.291)
		(size 0.7112)
		(drill 0.4064)
		(layers "F.Cu" "B.Cu")
		(net "GND")
	)
	(via
		(at 132.7658 -26.1366)
		(size 0.508)
		(drill 0.254)
		(layers "F.Cu" "B.Cu")
		(net "GND")
	)
	(via
		(at 72.8472 -219.2782)
		(size 0.508)
		(drill 0.254)
		(layers "F.Cu" "B.Cu")
		(net "GND")
	)
	(via
		(at 333.039974 -47.383192)
		(size 0.508)
		(drill 0.254)
		(layers "F.Cu" "B.Cu")
		(net "GND")
	)
	(via
		(at 115.8494 -184.658)
		(size 0.7112)
		(drill 0.3556)
		(layers "F.Cu" "B.Cu")
		(net "GND")
	)
	(via
		(at 257.099816 -32.500062)
		(size 0.4572)
		(drill 0.2032)
		(layers "F.Cu" "B.Cu")
		(net "GND")
	)
	(via
		(at 253.099824 -32.500062)
		(size 0.4572)
		(drill 0.2032)
		(layers "F.Cu" "B.Cu")
		(net "GND")
	)
	(via
		(at 19.685 -74.1426)
		(size 0.508)
		(drill 0.254)
		(layers "F.Cu" "B.Cu")
		(net "GND")
	)
	(via
		(at 145.8214 -22.3012)
		(size 0.508)
		(drill 0.254)
		(layers "F.Cu" "B.Cu")
		(net "GND")
	)
	(via
		(at 272.147284 -210.152996)
		(size 0.508)
		(drill 0.254)
		(layers "F.Cu" "B.Cu")
		(net "GND")
	)
	(via
		(at 322.5546 -15.5194)
		(size 0.508)
		(drill 0.254)
		(layers "F.Cu" "B.Cu")
		(net "GND")
	)
	(via
		(at 21.973794 -87.4268)
		(size 0.508)
		(drill 0.254)
		(layers "F.Cu" "B.Cu")
		(net "GND")
	)
	(via
		(at 258.099814 -41.500044)
		(size 0.4572)
		(drill 0.2032)
		(layers "F.Cu" "B.Cu")
		(net "GND")
	)
	(via
		(at 80.37068 -84.28482)
		(size 0.508)
		(drill 0.254)
		(layers "F.Cu" "B.Cu")
		(net "GND")
	)
	(via
		(at 246.752364 -6.776974)
		(size 0.7112)
		(drill 0.4064)
		(layers "F.Cu" "B.Cu")
		(net "GND")
	)
	(via
		(at 245.09984 -57.499758)
		(size 0.4572)
		(drill 0.2032)
		(layers "F.Cu" "B.Cu")
		(net "GND")
	)
	(via
		(at 251.099828 -50.499772)
		(size 0.4572)
		(drill 0.2032)
		(layers "F.Cu" "B.Cu")
		(net "GND")
	)
	(via
		(at 49.53 -209.31886)
		(size 0.508)
		(drill 0.254)
		(layers "F.Cu" "B.Cu")
		(net "GND")
	)
	(via
		(at 58.039 -35.0774)
		(size 0.508)
		(drill 0.254)
		(layers "F.Cu" "B.Cu")
		(net "GND")
	)
	(via
		(at 179.8066 -59.3852)
		(size 0.7112)
		(drill 0.4064)
		(layers "F.Cu" "B.Cu")
		(net "GND")
	)
	(via
		(at 232.10012 -55.499762)
		(size 0.4572)
		(drill 0.2032)
		(layers "F.Cu" "B.Cu")
		(net "GND")
	)
	(via
		(at 257.099816 -46.500034)
		(size 0.4572)
		(drill 0.2032)
		(layers "F.Cu" "B.Cu")
		(net "GND")
	)
	(via
		(at 309.921656 -51.824382)
		(size 0.7112)
		(drill 0.3556)
		(layers "F.Cu" "B.Cu")
		(net "GND")
	)
	(via
		(at 264.215372 -8.16356)
		(size 0.508)
		(drill 0.254)
		(layers "F.Cu" "B.Cu")
		(net "GND")
	)
	(via
		(at 270.500094 -223.082104)
		(size 0.508)
		(drill 0.254)
		(layers "F.Cu" "B.Cu")
		(net "GND")
	)
	(via
		(at 242.951 -27.432)
		(size 0.508)
		(drill 0.254)
		(layers "F.Cu" "B.Cu")
		(net "GND")
	)
	(via
		(at 204.004926 -50.5079)
		(size 0.508)
		(drill 0.254)
		(layers "F.Cu" "B.Cu")
		(net "GND")
	)
	(via
		(at 266.046966 -3.868166)
		(size 0.508)
		(drill 0.254)
		(layers "F.Cu" "B.Cu")
		(net "GND")
	)
	(via
		(at 63.299848 -223.082104)
		(size 0.508)
		(drill 0.254)
		(layers "F.Cu" "B.Cu")
		(net "GND")
	)
	(via
		(at 340.868 -67.31)
		(size 0.508)
		(drill 0.254)
		(layers "F.Cu" "B.Cu")
		(net "GND")
	)
	(via
		(at 284.947106 -210.152996)
		(size 0.508)
		(drill 0.254)
		(layers "F.Cu" "B.Cu")
		(net "GND")
	)
	(via
		(at 238.100108 -61.49975)
		(size 0.4572)
		(drill 0.2032)
		(layers "F.Cu" "B.Cu")
		(net "GND")
	)
	(via
		(at 65.24117 -126.785116)
		(size 0.508)
		(drill 0.254)
		(layers "F.Cu" "B.Cu")
		(net "GND")
	)
	(via
		(at 186.737244 -5.261356)
		(size 0.508)
		(drill 0.254)
		(layers "F.Cu" "B.Cu")
		(net "GND")
	)
	(via
		(at 34.6456 -183.3372)
		(size 0.508)
		(drill 0.254)
		(layers "F.Cu" "B.Cu")
		(net "GND")
	)
	(via
		(at 256.099818 -41.500044)
		(size 0.4572)
		(drill 0.2032)
		(layers "F.Cu" "B.Cu")
		(net "GND")
	)
	(via
		(at 16.2052 -67.8434)
		(size 0.508)
		(drill 0.254)
		(layers "F.Cu" "B.Cu")
		(net "GND")
	)
	(via
		(at 36.322 -87.0966)
		(size 0.508)
		(drill 0.254)
		(layers "F.Cu" "B.Cu")
		(net "GND")
	)
	(via
		(at 98.171 -154.4066)
		(size 0.508)
		(drill 0.254)
		(layers "F.Cu" "B.Cu")
		(net "GND")
	)
	(via
		(at 311.347358 -210.152996)
		(size 0.508)
		(drill 0.254)
		(layers "F.Cu" "B.Cu")
		(net "GND")
	)
	(via
		(at 35.814 -210.9978)
		(size 0.508)
		(drill 0.254)
		(layers "F.Cu" "B.Cu")
		(net "GND")
	)
	(via
		(at 230.100124 -63.499746)
		(size 0.4572)
		(drill 0.2032)
		(layers "F.Cu" "B.Cu")
		(net "GND")
	)
	(via
		(at 239.100106 -55.499762)
		(size 0.4572)
		(drill 0.2032)
		(layers "F.Cu" "B.Cu")
		(net "GND")
	)
	(via
		(at 53.347112 -3.20167)
		(size 0.508)
		(drill 0.254)
		(layers "F.Cu" "B.Cu")
		(net "GND")
	)
	(via
		(at 119.4308 -15.8242)
		(size 0.508)
		(drill 0.254)
		(layers "F.Cu" "B.Cu")
		(net "GND")
	)
	(via
		(at 249.099832 -49.499774)
		(size 0.4572)
		(drill 0.2032)
		(layers "F.Cu" "B.Cu")
		(net "GND")
	)
	(via
		(at 310.1848 -16.1036)
		(size 0.508)
		(drill 0.254)
		(layers "F.Cu" "B.Cu")
		(net "GND")
	)
	(via
		(at 246.099838 -56.49976)
		(size 0.4572)
		(drill 0.2032)
		(layers "F.Cu" "B.Cu")
		(net "GND")
	)
	(via
		(at 178.943 -87.122)
		(size 0.508)
		(drill 0.254)
		(layers "F.Cu" "B.Cu")
		(net "GND")
	)
	(via
		(at 354.203 -167.545004)
		(size 0.508)
		(drill 0.254)
		(layers "F.Cu" "B.Cu")
		(net "GND")
	)
	(via
		(at 125.953012 -210.167474)
		(size 0.508)
		(drill 0.254)
		(layers "F.Cu" "B.Cu")
		(net "GND")
	)
	(via
		(at 224.100136 -49.499774)
		(size 0.4572)
		(drill 0.2032)
		(layers "F.Cu" "B.Cu")
		(net "GND")
	)
	(via
		(at 244.099842 -40.500046)
		(size 0.4572)
		(drill 0.2032)
		(layers "F.Cu" "B.Cu")
		(net "GND")
	)
	(via
		(at 238.100108 -64.499744)
		(size 0.4572)
		(drill 0.2032)
		(layers "F.Cu" "B.Cu")
		(net "GND")
	)
	(via
		(at 138.176 -223.0628)
		(size 0.508)
		(drill 0.254)
		(layers "F.Cu" "B.Cu")
		(net "GND")
	)
	(via
		(at 71.3994 -165.5318)
		(size 0.508)
		(drill 0.254)
		(layers "F.Cu" "B.Cu")
		(net "GND")
	)
	(via
		(at 289.7886 -18.0594)
		(size 0.508)
		(drill 0.254)
		(layers "F.Cu" "B.Cu")
		(net "GND")
	)
	(via
		(at 238.480092 -162.602926)
		(size 0.508)
		(drill 0.254)
		(layers "F.Cu" "B.Cu")
		(net "GND")
	)
	(via
		(at 256.099818 -64.499744)
		(size 0.4572)
		(drill 0.2032)
		(layers "F.Cu" "B.Cu")
		(net "GND")
	)
	(via
		(at 244.099842 -56.49976)
		(size 0.4572)
		(drill 0.2032)
		(layers "F.Cu" "B.Cu")
		(net "GND")
	)
	(via
		(at 247.671844 -15.7226)
		(size 0.7112)
		(drill 0.4064)
		(layers "F.Cu" "B.Cu")
		(net "GND")
	)
	(via
		(at 66.204084 -126.791974)
		(size 0.508)
		(drill 0.254)
		(layers "F.Cu" "B.Cu")
		(net "GND")
	)
	(via
		(at 142.320772 -75.107546)
		(size 0.7112)
		(drill 0.4064)
		(layers "F.Cu" "B.Cu")
		(net "GND")
	)
	(via
		(at 24.1808 -53.5432)
		(size 0.508)
		(drill 0.254)
		(layers "F.Cu" "B.Cu")
		(net "GND")
	)
	(via
		(at 244.099842 -51.49977)
		(size 0.4572)
		(drill 0.2032)
		(layers "F.Cu" "B.Cu")
		(net "GND")
	)
	(via
		(at 107.300014 -223.082104)
		(size 0.508)
		(drill 0.254)
		(layers "F.Cu" "B.Cu")
		(net "GND")
	)
	(via
		(at 320.7512 -23.6474)
		(size 0.508)
		(drill 0.254)
		(layers "F.Cu" "B.Cu")
		(net "GND")
	)
	(via
		(at 257.099816 -52.499768)
		(size 0.4572)
		(drill 0.2032)
		(layers "F.Cu" "B.Cu")
		(net "GND")
	)
	(via
		(at 201.26706 -50.588164)
		(size 0.508)
		(drill 0.254)
		(layers "F.Cu" "B.Cu")
		(net "GND")
	)
	(via
		(at 66.421 -44.069)
		(size 0.7112)
		(drill 0.4064)
		(layers "F.Cu" "B.Cu")
		(net "GND")
	)
	(via
		(at 4.572 -73.5076)
		(size 0.508)
		(drill 0.254)
		(layers "F.Cu" "B.Cu")
		(net "GND")
	)
	(via
		(at 39.9288 -61.3156)
		(size 0.508)
		(drill 0.254)
		(layers "F.Cu" "B.Cu")
		(net "GND")
	)
	(via
		(at 327.88098 -47.31639)
		(size 0.508)
		(drill 0.254)
		(layers "F.Cu" "B.Cu")
		(net "GND")
	)
	(via
		(at 145.7452 -18.3896)
		(size 0.508)
		(drill 0.254)
		(layers "F.Cu" "B.Cu")
		(net "GND")
	)
	(via
		(at 65.473326 -21.231606)
		(size 0.508)
		(drill 0.254)
		(layers "F.Cu" "B.Cu")
		(net "GND")
	)
	(via
		(at 228.809296 -198.508874)
		(size 0.508)
		(drill 0.254)
		(layers "F.Cu" "B.Cu")
		(net "GND")
	)
	(via
		(at 340.099904 -223.082104)
		(size 0.508)
		(drill 0.254)
		(layers "F.Cu" "B.Cu")
		(net "GND")
	)
	(via
		(at 247.099836 -64.499744)
		(size 0.4572)
		(drill 0.2032)
		(layers "F.Cu" "B.Cu")
		(net "GND")
	)
	(via
		(at 55.397908 -85.05952)
		(size 0.508)
		(drill 0.254)
		(layers "F.Cu" "B.Cu")
		(net "GND")
	)
	(via
		(at 35.179 -220.853)
		(size 0.508)
		(drill 0.254)
		(layers "F.Cu" "B.Cu")
		(net "GND")
	)
	(via
		(at 284.988254 -34.765996)
		(size 0.508)
		(drill 0.254)
		(layers "F.Cu" "B.Cu")
		(net "GND")
	)
	(via
		(at 30.968188 -156.779976)
		(size 0.4572)
		(drill 0.2032)
		(layers "F.Cu" "B.Cu")
		(net "GND")
	)
	(via
		(at 80.899762 -223.082104)
		(size 0.508)
		(drill 0.254)
		(layers "F.Cu" "B.Cu")
		(net "GND")
	)
	(via
		(at 338.328 -67.31)
		(size 0.508)
		(drill 0.254)
		(layers "F.Cu" "B.Cu")
		(net "GND")
	)
	(via
		(at 16.8656 -84.963)
		(size 0.508)
		(drill 0.254)
		(layers "F.Cu" "B.Cu")
		(net "GND")
	)
	(via
		(at 123.7996 -124.9934)
		(size 0.508)
		(drill 0.254)
		(layers "F.Cu" "B.Cu")
		(net "GND")
	)
	(via
		(at 159.120332 -94.620334)
		(size 0.508)
		(drill 0.254)
		(layers "F.Cu" "B.Cu")
		(net "GND")
	)
	(via
		(at 40.52316 -113.205768)
		(size 0.508)
		(drill 0.254)
		(layers "F.Cu" "B.Cu")
		(net "GND")
	)
	(via
		(at 245.09984 -61.49975)
		(size 0.4572)
		(drill 0.2032)
		(layers "F.Cu" "B.Cu")
		(net "GND")
	)
	(via
		(at 174.260002 -57.050432)
		(size 0.7112)
		(drill 0.4064)
		(layers "F.Cu" "B.Cu")
		(net "GND")
	)
	(via
		(at 252.099826 -52.499768)
		(size 0.4572)
		(drill 0.2032)
		(layers "F.Cu" "B.Cu")
		(net "GND")
	)
	(via
		(at 300.355 -71.12)
		(size 0.7112)
		(drill 0.4064)
		(layers "F.Cu" "B.Cu")
		(net "GND")
	)
	(via
		(at 198.3232 -138.6586)
		(size 0.508)
		(drill 0.254)
		(layers "F.Cu" "B.Cu")
		(net "GND")
	)
	(via
		(at 130.2004 -47.371)
		(size 0.508)
		(drill 0.254)
		(layers "F.Cu" "B.Cu")
		(net "GND")
	)
	(via
		(at 354.203 -198.025004)
		(size 0.508)
		(drill 0.254)
		(layers "F.Cu" "B.Cu")
		(net "GND")
	)
	(via
		(at 14.605 -66.8782)
		(size 0.508)
		(drill 0.254)
		(layers "F.Cu" "B.Cu")
		(net "GND")
	)
	(via
		(at 34.96818 -151.180038)
		(size 0.4572)
		(drill 0.2032)
		(layers "F.Cu" "B.Cu")
		(net "GND")
	)
	(via
		(at 196.950838 -45.50791)
		(size 0.508)
		(drill 0.254)
		(layers "F.Cu" "B.Cu")
		(net "GND")
	)
	(via
		(at 223.100138 -60.499752)
		(size 0.4572)
		(drill 0.2032)
		(layers "F.Cu" "B.Cu")
		(net "GND")
	)
	(via
		(at 320.675 -70.993)
		(size 0.7112)
		(drill 0.4064)
		(layers "F.Cu" "B.Cu")
		(net "GND")
	)
	(via
		(at 287.49752 -25.495758)
		(size 0.508)
		(drill 0.254)
		(layers "F.Cu" "B.Cu")
		(net "GND")
	)
	(via
		(at 237.49 -24.7396)
		(size 0.508)
		(drill 0.254)
		(layers "F.Cu" "B.Cu")
		(net "GND")
	)
	(via
		(at 232.10012 -41.500044)
		(size 0.4572)
		(drill 0.2032)
		(layers "F.Cu" "B.Cu")
		(net "GND")
	)
	(via
		(at 234.100116 -41.500044)
		(size 0.4572)
		(drill 0.2032)
		(layers "F.Cu" "B.Cu")
		(net "GND")
	)
	(via
		(at 52.899818 -223.082104)
		(size 0.508)
		(drill 0.254)
		(layers "F.Cu" "B.Cu")
		(net "GND")
	)
	(via
		(at 157.692852 -14.891512)
		(size 0.508)
		(drill 0.254)
		(layers "F.Cu" "B.Cu")
		(net "GND")
	)
	(via
		(at 137.5664 -15.9004)
		(size 0.508)
		(drill 0.254)
		(layers "F.Cu" "B.Cu")
		(net "GND")
	)
	(via
		(at 8.9281 -69.4055)
		(size 0.508)
		(drill 0.254)
		(layers "F.Cu" "B.Cu")
		(net "GND")
	)
	(via
		(at 288.3281 -35.014154)
		(size 0.508)
		(drill 0.254)
		(layers "F.Cu" "B.Cu")
		(net "GND")
	)
	(via
		(at 102.499922 -223.082104)
		(size 0.508)
		(drill 0.254)
		(layers "F.Cu" "B.Cu")
		(net "GND")
	)
	(via
		(at 330.638912 -180.6448)
		(size 0.508)
		(drill 0.254)
		(layers "F.Cu" "B.Cu")
		(net "GND")
	)
	(via
		(at 258.099814 -61.49975)
		(size 0.4572)
		(drill 0.2032)
		(layers "F.Cu" "B.Cu")
		(net "GND")
	)
	(via
		(at 249.099832 -51.49977)
		(size 0.4572)
		(drill 0.2032)
		(layers "F.Cu" "B.Cu")
		(net "GND")
	)
	(via
		(at 347.98 -54.991)
		(size 0.7112)
		(drill 0.3556)
		(layers "F.Cu" "B.Cu")
		(net "GND")
	)
	(via
		(at 17.930114 -91.264486)
		(size 0.508)
		(drill 0.254)
		(layers "F.Cu" "B.Cu")
		(net "GND")
	)
	(via
		(at 30.965394 -155.975304)
		(size 0.4572)
		(drill 0.2032)
		(layers "F.Cu" "B.Cu")
		(net "GND")
	)
	(via
		(at 191.389 -24.5364)
		(size 0.508)
		(drill 0.254)
		(layers "F.Cu" "B.Cu")
		(net "GND")
	)
	(via
		(at 249.555 -68.961)
		(size 0.508)
		(drill 0.254)
		(layers "F.Cu" "B.Cu")
		(net "GND")
	)
	(via
		(at 161.3789 -81.4959)
		(size 0.508)
		(drill 0.254)
		(layers "F.Cu" "B.Cu")
		(net "GND")
	)
	(via
		(at 247.099836 -50.499772)
		(size 0.4572)
		(drill 0.2032)
		(layers "F.Cu" "B.Cu")
		(net "GND")
	)
	(via
		(at 222.10014 -60.499752)
		(size 0.4572)
		(drill 0.2032)
		(layers "F.Cu" "B.Cu")
		(net "GND")
	)
	(via
		(at 235.100114 -44.500038)
		(size 0.4572)
		(drill 0.2032)
		(layers "F.Cu" "B.Cu")
		(net "GND")
	)
	(via
		(at 154.100022 -223.082104)
		(size 0.508)
		(drill 0.254)
		(layers "F.Cu" "B.Cu")
		(net "GND")
	)
	(via
		(at 303.16297 -15.71625)
		(size 0.508)
		(drill 0.254)
		(layers "F.Cu" "B.Cu")
		(net "GND")
	)
	(via
		(at 304.98669 -219.525342)
		(size 0.508)
		(drill 0.254)
		(layers "F.Cu" "B.Cu")
		(net "GND")
	)
	(via
		(at 246.099838 -51.49977)
		(size 0.4572)
		(drill 0.2032)
		(layers "F.Cu" "B.Cu")
		(net "GND")
	)
	(via
		(at 96.099884 -223.082104)
		(size 0.508)
		(drill 0.254)
		(layers "F.Cu" "B.Cu")
		(net "GND")
	)
	(via
		(at 11.87704 -53.125878)
		(size 0.508)
		(drill 0.254)
		(layers "F.Cu" "B.Cu")
		(net "GND")
	)
	(via
		(at 215.65235 -210.152996)
		(size 0.508)
		(drill 0.254)
		(layers "F.Cu" "B.Cu")
		(net "GND")
	)
	(via
		(at 256.099818 -34.500058)
		(size 0.4572)
		(drill 0.2032)
		(layers "F.Cu" "B.Cu")
		(net "GND")
	)
	(via
		(at 333.699866 -223.082104)
		(size 0.508)
		(drill 0.254)
		(layers "F.Cu" "B.Cu")
		(net "GND")
	)
	(via
		(at 106.4006 -134.4422)
		(size 0.508)
		(drill 0.254)
		(layers "F.Cu" "B.Cu")
		(net "GND")
	)
	(via
		(at 36.957 -222.9358)
		(size 0.508)
		(drill 0.254)
		(layers "F.Cu" "B.Cu")
		(net "GND")
	)
	(via
		(at 301.0154 -23.622)
		(size 0.508)
		(drill 0.254)
		(layers "F.Cu" "B.Cu")
		(net "GND")
	)
	(via
		(at 1.397 -126.891034)
		(size 0.508)
		(drill 0.254)
		(layers "F.Cu" "B.Cu")
		(net "GND")
	)
	(via
		(at 180.11648 -9.13892)
		(size 0.508)
		(drill 0.254)
		(layers "F.Cu" "B.Cu")
		(net "GND")
	)
	(via
		(at 109.699806 -223.082104)
		(size 0.508)
		(drill 0.254)
		(layers "F.Cu" "B.Cu")
		(net "GND")
	)
	(via
		(at 191.389 -28.1686)
		(size 0.508)
		(drill 0.254)
		(layers "F.Cu" "B.Cu")
		(net "GND")
	)
	(via
		(at 153.289 -94.2848)
		(size 0.508)
		(drill 0.254)
		(layers "F.Cu" "B.Cu")
		(net "GND")
	)
	(via
		(at 93.747082 -210.152996)
		(size 0.508)
		(drill 0.254)
		(layers "F.Cu" "B.Cu")
		(net "GND")
	)
	(via
		(at 338.45246 -210.152996)
		(size 0.508)
		(drill 0.254)
		(layers "F.Cu" "B.Cu")
		(net "GND")
	)
	(via
		(at 257.099816 -39.500048)
		(size 0.4572)
		(drill 0.2032)
		(layers "F.Cu" "B.Cu")
		(net "GND")
	)
	(via
		(at 211.8106 -118.618)
		(size 0.508)
		(drill 0.254)
		(layers "F.Cu" "B.Cu")
		(net "GND")
	)
	(via
		(at 23.559008 -110.285022)
		(size 0.508)
		(drill 0.254)
		(layers "F.Cu" "B.Cu")
		(net "GND")
	)
	(via
		(at 242.099846 -56.49976)
		(size 0.4572)
		(drill 0.2032)
		(layers "F.Cu" "B.Cu")
		(net "GND")
	)
	(via
		(at 76.898246 -84.493354)
		(size 0.508)
		(drill 0.254)
		(layers "F.Cu" "B.Cu")
		(net "GND")
	)
	(via
		(at 232.10012 -45.500036)
		(size 0.4572)
		(drill 0.2032)
		(layers "F.Cu" "B.Cu")
		(net "GND")
	)
	(via
		(at 1.397 -147.211034)
		(size 0.508)
		(drill 0.254)
		(layers "F.Cu" "B.Cu")
		(net "GND")
	)
	(via
		(at 1.397 -76.091034)
		(size 0.508)
		(drill 0.254)
		(layers "F.Cu" "B.Cu")
		(net "GND")
	)
	(via
		(at 177.3682 -57.531)
		(size 0.7112)
		(drill 0.4064)
		(layers "F.Cu" "B.Cu")
		(net "GND")
	)
	(via
		(at 224.79 -75.438)
		(size 0.7112)
		(drill 0.3556)
		(layers "F.Cu" "B.Cu")
		(net "GND")
	)
	(via
		(at 214.4141 -193.5861)
		(size 0.508)
		(drill 0.254)
		(layers "F.Cu" "B.Cu")
		(net "GND")
	)
	(via
		(at 171.8818 -96.2152)
		(size 0.508)
		(drill 0.254)
		(layers "F.Cu" "B.Cu")
		(net "GND")
	)
	(via
		(at 48.26 -198.247)
		(size 0.508)
		(drill 0.254)
		(layers "F.Cu" "B.Cu")
		(net "GND")
	)
	(via
		(at 274.32 -165.227)
		(size 0.508)
		(drill 0.254)
		(layers "F.Cu" "B.Cu")
		(net "GND")
	)
	(via
		(at 26.5176 -149.9362)
		(size 0.508)
		(drill 0.254)
		(layers "F.Cu" "B.Cu")
		(net "GND")
	)
	(via
		(at 316.865 -53.086)
		(size 0.7112)
		(drill 0.4064)
		(layers "F.Cu" "B.Cu")
		(net "GND")
	)
	(via
		(at 44.728892 -112.86617)
		(size 0.508)
		(drill 0.254)
		(layers "F.Cu" "B.Cu")
		(net "GND")
	)
	(via
		(at 130.898392 -41.427654)
		(size 0.508)
		(drill 0.254)
		(layers "F.Cu" "B.Cu")
		(net "GND")
	)
	(via
		(at 250.09983 -56.49976)
		(size 0.4572)
		(drill 0.2032)
		(layers "F.Cu" "B.Cu")
		(net "GND")
	)
	(via
		(at 143.526002 -62.892432)
		(size 0.7112)
		(drill 0.4064)
		(layers "F.Cu" "B.Cu")
		(net "GND")
	)
	(via
		(at 224.100136 -33.50006)
		(size 0.4572)
		(drill 0.2032)
		(layers "F.Cu" "B.Cu")
		(net "GND")
	)
	(via
		(at 133.096 -11.049)
		(size 0.508)
		(drill 0.254)
		(layers "F.Cu" "B.Cu")
		(net "GND")
	)
	(via
		(at 11.183366 -69.233288)
		(size 0.508)
		(drill 0.254)
		(layers "F.Cu" "B.Cu")
		(net "GND")
	)
	(via
		(at 242.099846 -63.499746)
		(size 0.4572)
		(drill 0.2032)
		(layers "F.Cu" "B.Cu")
		(net "GND")
	)
	(via
		(at 30.099 -45.974)
		(size 0.508)
		(drill 0.254)
		(layers "F.Cu" "B.Cu")
		(net "GND")
	)
	(via
		(at 96.5962 -129.2098)
		(size 0.508)
		(drill 0.254)
		(layers "F.Cu" "B.Cu")
		(net "GND")
	)
	(via
		(at 222.2627 -14.2875)
		(size 0.508)
		(drill 0.254)
		(layers "F.Cu" "B.Cu")
		(net "GND")
	)
	(via
		(at 254.099822 -54.499764)
		(size 0.4572)
		(drill 0.2032)
		(layers "F.Cu" "B.Cu")
		(net "GND")
	)
	(via
		(at 64.643 -38.1635)
		(size 0.508)
		(drill 0.254)
		(layers "F.Cu" "B.Cu")
		(net "GND")
	)
	(via
		(at 164.550852 -221.488)
		(size 0.508)
		(drill 0.254)
		(layers "F.Cu" "B.Cu")
		(net "GND")
	)
	(via
		(at 248.640092 -162.602926)
		(size 0.508)
		(drill 0.254)
		(layers "F.Cu" "B.Cu")
		(net "GND")
	)
	(via
		(at 39.586154 -160.286954)
		(size 0.508)
		(drill 0.254)
		(layers "F.Cu" "B.Cu")
		(net "GND")
	)
	(via
		(at 217.297 -196.977)
		(size 0.508)
		(drill 0.254)
		(layers "F.Cu" "B.Cu")
		(net "GND")
	)
	(via
		(at 354.203 -91.345004)
		(size 0.508)
		(drill 0.254)
		(layers "F.Cu" "B.Cu")
		(net "GND")
	)
	(via
		(at 153.904696 -32.105092)
		(size 0.508)
		(drill 0.254)
		(layers "F.Cu" "B.Cu")
		(net "GND")
	)
	(via
		(at 249.099832 -59.499754)
		(size 0.4572)
		(drill 0.2032)
		(layers "F.Cu" "B.Cu")
		(net "GND")
	)
	(via
		(at 65.8622 -160.6296)
		(size 0.508)
		(drill 0.254)
		(layers "F.Cu" "B.Cu")
		(net "GND")
	)
	(via
		(at 38.904926 -129.685034)
		(size 0.4572)
		(drill 0.2032)
		(layers "F.Cu" "B.Cu")
		(net "GND")
	)
	(via
		(at 152.1714 -88.5698)
		(size 0.508)
		(drill 0.254)
		(layers "F.Cu" "B.Cu")
		(net "GND")
	)
	(via
		(at 44.061634 -115.4938)
		(size 0.508)
		(drill 0.254)
		(layers "F.Cu" "B.Cu")
		(net "GND")
	)
	(via
		(at 234.100116 -50.499772)
		(size 0.4572)
		(drill 0.2032)
		(layers "F.Cu" "B.Cu")
		(net "GND")
	)
	(via
		(at 71.5518 -161.2646)
		(size 0.508)
		(drill 0.254)
		(layers "F.Cu" "B.Cu")
		(net "GND")
	)
	(via
		(at 317.699898 -223.082104)
		(size 0.508)
		(drill 0.254)
		(layers "F.Cu" "B.Cu")
		(net "GND")
	)
	(via
		(at 230.100124 -42.500042)
		(size 0.4572)
		(drill 0.2032)
		(layers "F.Cu" "B.Cu")
		(net "GND")
	)
	(via
		(at 232.745026 -207.921352)
		(size 0.508)
		(drill 0.254)
		(layers "F.Cu" "B.Cu")
		(net "GND")
	)
	(via
		(at 158.89986 -223.082104)
		(size 0.508)
		(drill 0.254)
		(layers "F.Cu" "B.Cu")
		(net "GND")
	)
	(via
		(at 256.099818 -61.49975)
		(size 0.4572)
		(drill 0.2032)
		(layers "F.Cu" "B.Cu")
		(net "GND")
	)
	(via
		(at 5.8166 -92.7862)
		(size 0.508)
		(drill 0.254)
		(layers "F.Cu" "B.Cu")
		(net "GND")
	)
	(via
		(at 30.886654 -145.970244)
		(size 0.4572)
		(drill 0.2032)
		(layers "F.Cu" "B.Cu")
		(net "GND")
	)
	(via
		(at 317.747396 -210.152996)
		(size 0.508)
		(drill 0.254)
		(layers "F.Cu" "B.Cu")
		(net "GND")
	)
	(via
		(at 253.33579 -7.443978)
		(size 0.508)
		(drill 0.254)
		(layers "F.Cu" "B.Cu")
		(net "GND")
	)
	(via
		(at 338.328 -64.516)
		(size 0.508)
		(drill 0.254)
		(layers "F.Cu" "B.Cu")
		(net "GND")
	)
	(via
		(at 329.2856 -137.7696)
		(size 0.508)
		(drill 0.254)
		(layers "F.Cu" "B.Cu")
		(net "GND")
	)
	(via
		(at 254.099822 -56.49976)
		(size 0.4572)
		(drill 0.2032)
		(layers "F.Cu" "B.Cu")
		(net "GND")
	)
	(via
		(at 39.116 -197.866)
		(size 0.508)
		(drill 0.254)
		(layers "F.Cu" "B.Cu")
		(net "GND")
	)
	(via
		(at 184.877202 -75.160632)
		(size 0.7112)
		(drill 0.4064)
		(layers "F.Cu" "B.Cu")
		(net "GND")
	)
	(via
		(at 73.152 -49.022)
		(size 0.7112)
		(drill 0.3556)
		(layers "F.Cu" "B.Cu")
		(net "GND")
	)
	(via
		(at 81.8134 -162.179)
		(size 0.508)
		(drill 0.254)
		(layers "F.Cu" "B.Cu")
		(net "GND")
	)
	(via
		(at 242.099846 -34.500058)
		(size 0.4572)
		(drill 0.2032)
		(layers "F.Cu" "B.Cu")
		(net "GND")
	)
	(via
		(at 97.700084 -223.082104)
		(size 0.508)
		(drill 0.254)
		(layers "F.Cu" "B.Cu")
		(net "GND")
	)
	(via
		(at 230.100124 -49.499774)
		(size 0.4572)
		(drill 0.2032)
		(layers "F.Cu" "B.Cu")
		(net "GND")
	)
	(via
		(at 236.100112 -54.499764)
		(size 0.4572)
		(drill 0.2032)
		(layers "F.Cu" "B.Cu")
		(net "GND")
	)
	(via
		(at 68.834 -46.863)
		(size 0.7112)
		(drill 0.4064)
		(layers "F.Cu" "B.Cu")
		(net "GND")
	)
	(via
		(at 268.859 -192.532)
		(size 0.508)
		(drill 0.254)
		(layers "F.Cu" "B.Cu")
		(net "GND")
	)
	(via
		(at 325.676006 -36.667694)
		(size 0.508)
		(drill 0.254)
		(layers "F.Cu" "B.Cu")
		(net "GND")
	)
	(via
		(at 93.165168 -186.479434)
		(size 0.508)
		(drill 0.254)
		(layers "F.Cu" "B.Cu")
		(net "GND")
	)
	(via
		(at 118.787926 -1.397)
		(size 0.508)
		(drill 0.254)
		(layers "F.Cu" "B.Cu")
		(net "GND")
	)
	(via
		(at 231.100122 -34.500058)
		(size 0.4572)
		(drill 0.2032)
		(layers "F.Cu" "B.Cu")
		(net "GND")
	)
	(via
		(at 66.0654 -164.4396)
		(size 0.508)
		(drill 0.254)
		(layers "F.Cu" "B.Cu")
		(net "GND")
	)
	(via
		(at 36.222432 -102.512876)
		(size 0.508)
		(drill 0.254)
		(layers "F.Cu" "B.Cu")
		(net "GND")
	)
	(via
		(at 228.853746 -190.1317)
		(size 0.508)
		(drill 0.254)
		(layers "F.Cu" "B.Cu")
		(net "GND")
	)
	(via
		(at 94.488 -147.1422)
		(size 0.508)
		(drill 0.254)
		(layers "F.Cu" "B.Cu")
		(net "GND")
	)
	(via
		(at 237.10011 -56.49976)
		(size 0.4572)
		(drill 0.2032)
		(layers "F.Cu" "B.Cu")
		(net "GND")
	)
	(via
		(at 272.32356 -4.177538)
		(size 0.508)
		(drill 0.254)
		(layers "F.Cu" "B.Cu")
		(net "GND")
	)
	(via
		(at 217.294206 -2.491994)
		(size 0.508)
		(drill 0.254)
		(layers "F.Cu" "B.Cu")
		(net "GND")
	)
	(via
		(at 68.39458 -80.202786)
		(size 0.508)
		(drill 0.254)
		(layers "F.Cu" "B.Cu")
		(net "GND")
	)
	(via
		(at 62.920118 -160.841182)
		(size 0.508)
		(drill 0.254)
		(layers "F.Cu" "B.Cu")
		(net "GND")
	)
	(via
		(at 65.8622 -161.5186)
		(size 0.508)
		(drill 0.254)
		(layers "F.Cu" "B.Cu")
		(net "GND")
	)
	(via
		(at 29.464 -48.768)
		(size 0.508)
		(drill 0.254)
		(layers "F.Cu" "B.Cu")
		(net "GND")
	)
	(via
		(at 244.099842 -44.500038)
		(size 0.4572)
		(drill 0.2032)
		(layers "F.Cu" "B.Cu")
		(net "GND")
	)
	(via
		(at 38.0238 -222.9358)
		(size 0.508)
		(drill 0.254)
		(layers "F.Cu" "B.Cu")
		(net "GND")
	)
	(via
		(at 243.099844 -52.499768)
		(size 0.4572)
		(drill 0.2032)
		(layers "F.Cu" "B.Cu")
		(net "GND")
	)
	(via
		(at 162.433 -172.339)
		(size 0.508)
		(drill 0.254)
		(layers "F.Cu" "B.Cu")
		(net "GND")
	)
	(via
		(at 233.100118 -42.500042)
		(size 0.4572)
		(drill 0.2032)
		(layers "F.Cu" "B.Cu")
		(net "GND")
	)
	(via
		(at 227.10394 -12.5095)
		(size 0.508)
		(drill 0.254)
		(layers "F.Cu" "B.Cu")
		(net "GND")
	)
	(via
		(at 100.899976 -223.082104)
		(size 0.508)
		(drill 0.254)
		(layers "F.Cu" "B.Cu")
		(net "GND")
	)
	(via
		(at 256.011934 -10.05459)
		(size 0.508)
		(drill 0.254)
		(layers "F.Cu" "B.Cu")
		(net "GND")
	)
	(via
		(at 293.257478 -35.18027)
		(size 0.508)
		(drill 0.254)
		(layers "F.Cu" "B.Cu")
		(net "GND")
	)
	(via
		(at 228.100128 -63.499746)
		(size 0.4572)
		(drill 0.2032)
		(layers "F.Cu" "B.Cu")
		(net "GND")
	)
	(via
		(at 162.695128 -80.797146)
		(size 0.508)
		(drill 0.254)
		(layers "F.Cu" "B.Cu")
		(net "GND")
	)
	(via
		(at 1.397 -198.011034)
		(size 0.508)
		(drill 0.254)
		(layers "F.Cu" "B.Cu")
		(net "GND")
	)
	(via
		(at 326.39 -176.276)
		(size 0.508)
		(drill 0.254)
		(layers "F.Cu" "B.Cu")
		(net "GND")
	)
	(via
		(at 223.100138 -32.500062)
		(size 0.4572)
		(drill 0.2032)
		(layers "F.Cu" "B.Cu")
		(net "GND")
	)
	(via
		(at 141.351 -90.932)
		(size 0.508)
		(drill 0.254)
		(layers "F.Cu" "B.Cu")
		(net "GND")
	)
	(via
		(at 1.397 -177.691034)
		(size 0.508)
		(drill 0.254)
		(layers "F.Cu" "B.Cu")
		(net "GND")
	)
	(via
		(at 135.935212 -198.374)
		(size 0.508)
		(drill 0.254)
		(layers "F.Cu" "B.Cu")
		(net "GND")
	)
	(via
		(at 312.1914 -22.3266)
		(size 0.508)
		(drill 0.254)
		(layers "F.Cu" "B.Cu")
		(net "GND")
	)
	(via
		(at 225.100134 -36.500054)
		(size 0.4572)
		(drill 0.2032)
		(layers "F.Cu" "B.Cu")
		(net "GND")
	)
	(via
		(at 301.8028 -15.6464)
		(size 0.508)
		(drill 0.254)
		(layers "F.Cu" "B.Cu")
		(net "GND")
	)
	(via
		(at 114.173 -21.59)
		(size 0.7112)
		(drill 0.3556)
		(layers "F.Cu" "B.Cu")
		(net "GND")
	)
	(via
		(at 12.7508 -53.848)
		(size 0.508)
		(drill 0.254)
		(layers "F.Cu" "B.Cu")
		(net "GND")
	)
	(via
		(at 154.321002 -74.576432)
		(size 0.7112)
		(drill 0.4064)
		(layers "F.Cu" "B.Cu")
		(net "GND")
	)
	(via
		(at 53.34 -177.8)
		(size 0.508)
		(drill 0.254)
		(layers "F.Cu" "B.Cu")
		(net "GND")
	)
	(via
		(at 225.100134 -60.499752)
		(size 0.4572)
		(drill 0.2032)
		(layers "F.Cu" "B.Cu")
		(net "GND")
	)
	(via
		(at 319.786 -172.72)
		(size 0.508)
		(drill 0.254)
		(layers "F.Cu" "B.Cu")
		(net "GND")
	)
	(via
		(at 354.203 -96.425004)
		(size 0.508)
		(drill 0.254)
		(layers "F.Cu" "B.Cu")
		(net "GND")
	)
	(via
		(at 158.5976 -23.1394)
		(size 0.508)
		(drill 0.254)
		(layers "F.Cu" "B.Cu")
		(net "GND")
	)
	(via
		(at 354.203 -40.545004)
		(size 0.508)
		(drill 0.254)
		(layers "F.Cu" "B.Cu")
		(net "GND")
	)
	(via
		(at 339.598 -66.8655)
		(size 0.508)
		(drill 0.254)
		(layers "F.Cu" "B.Cu")
		(net "GND")
	)
	(via
		(at 1.397 -50.691034)
		(size 0.508)
		(drill 0.254)
		(layers "F.Cu" "B.Cu")
		(net "GND")
	)
	(via
		(at 183.642 -223.0628)
		(size 0.508)
		(drill 0.254)
		(layers "F.Cu" "B.Cu")
		(net "GND")
	)
	(via
		(at 243.099844 -41.500044)
		(size 0.4572)
		(drill 0.2032)
		(layers "F.Cu" "B.Cu")
		(net "GND")
	)
	(via
		(at 192.0748 -76.1492)
		(size 0.7112)
		(drill 0.3556)
		(layers "F.Cu" "B.Cu")
		(net "GND")
	)
	(via
		(at 238.100108 -50.499772)
		(size 0.4572)
		(drill 0.2032)
		(layers "F.Cu" "B.Cu")
		(net "GND")
	)
	(via
		(at 256.099818 -36.500054)
		(size 0.4572)
		(drill 0.2032)
		(layers "F.Cu" "B.Cu")
		(net "GND")
	)
	(via
		(at 5.5626 -50.7238)
		(size 0.508)
		(drill 0.254)
		(layers "F.Cu" "B.Cu")
		(net "GND")
	)
	(via
		(at 244.099842 -53.499766)
		(size 0.4572)
		(drill 0.2032)
		(layers "F.Cu" "B.Cu")
		(net "GND")
	)
	(via
		(at 252.538992 -184.357772)
		(size 0.508)
		(drill 0.254)
		(layers "F.Cu" "B.Cu")
		(net "GND")
	)
	(via
		(at 227.10013 -52.499768)
		(size 0.4572)
		(drill 0.2032)
		(layers "F.Cu" "B.Cu")
		(net "GND")
	)
	(via
		(at 185.30697 -8.4074)
		(size 0.508)
		(drill 0.254)
		(layers "F.Cu" "B.Cu")
		(net "GND")
	)
	(via
		(at 132.715 -198.635874)
		(size 0.508)
		(drill 0.254)
		(layers "F.Cu" "B.Cu")
		(net "GND")
	)
	(via
		(at 143.2814 -90.9574)
		(size 0.508)
		(drill 0.254)
		(layers "F.Cu" "B.Cu")
		(net "GND")
	)
	(via
		(at 1.397 -131.971034)
		(size 0.508)
		(drill 0.254)
		(layers "F.Cu" "B.Cu")
		(net "GND")
	)
	(via
		(at 181.448202 -75.160632)
		(size 0.7112)
		(drill 0.4064)
		(layers "F.Cu" "B.Cu")
		(net "GND")
	)
	(via
		(at 12.4714 -83.3882)
		(size 0.508)
		(drill 0.254)
		(layers "F.Cu" "B.Cu")
		(net "GND")
	)
	(via
		(at 340.147148 -210.152996)
		(size 0.508)
		(drill 0.254)
		(layers "F.Cu" "B.Cu")
		(net "GND")
	)
	(via
		(at 49.1236 -48.9966)
		(size 0.508)
		(drill 0.254)
		(layers "F.Cu" "B.Cu")
		(net "GND")
	)
	(via
		(at 217.347038 -210.152996)
		(size 0.508)
		(drill 0.254)
		(layers "F.Cu" "B.Cu")
		(net "GND")
	)
	(via
		(at 65.572386 -18.691606)
		(size 0.508)
		(drill 0.254)
		(layers "F.Cu" "B.Cu")
		(net "GND")
	)
	(via
		(at 117.192806 -80.90154)
		(size 0.508)
		(drill 0.254)
		(layers "F.Cu" "B.Cu")
		(net "GND")
	)
	(via
		(at 45.358558 -27.407108)
		(size 0.508)
		(drill 0.254)
		(layers "F.Cu" "B.Cu")
		(net "GND")
	)
	(via
		(at 248.099834 -53.499766)
		(size 0.4572)
		(drill 0.2032)
		(layers "F.Cu" "B.Cu")
		(net "GND")
	)
	(via
		(at 24.0284 -70.3834)
		(size 0.508)
		(drill 0.254)
		(layers "F.Cu" "B.Cu")
		(net "GND")
	)
	(via
		(at 62.907926 -1.397)
		(size 0.508)
		(drill 0.254)
		(layers "F.Cu" "B.Cu")
		(net "GND")
	)
	(via
		(at 66.452496 -210.152996)
		(size 0.508)
		(drill 0.254)
		(layers "F.Cu" "B.Cu")
		(net "GND")
	)
	(via
		(at 225.100134 -57.499758)
		(size 0.4572)
		(drill 0.2032)
		(layers "F.Cu" "B.Cu")
		(net "GND")
	)
	(via
		(at 60.8584 -36.2966)
		(size 0.508)
		(drill 0.254)
		(layers "F.Cu" "B.Cu")
		(net "GND")
	)
	(via
		(at 189.738 -11.2522)
		(size 0.508)
		(drill 0.254)
		(layers "F.Cu" "B.Cu")
		(net "GND")
	)
	(via
		(at 252.538992 -204.677772)
		(size 0.508)
		(drill 0.254)
		(layers "F.Cu" "B.Cu")
		(net "GND")
	)
	(via
		(at 29.367988 -153.580084)
		(size 0.4572)
		(drill 0.2032)
		(layers "F.Cu" "B.Cu")
		(net "GND")
	)
	(via
		(at 176.2252 -57.531)
		(size 0.7112)
		(drill 0.4064)
		(layers "F.Cu" "B.Cu")
		(net "GND")
	)
	(via
		(at 40.17518 -79.832708)
		(size 0.7112)
		(drill 0.4064)
		(layers "F.Cu" "B.Cu")
		(net "GND")
	)
	(via
		(at 107.252516 -210.152996)
		(size 0.508)
		(drill 0.254)
		(layers "F.Cu" "B.Cu")
		(net "GND")
	)
	(via
		(at 200.2917 -7.4549)
		(size 0.508)
		(drill 0.254)
		(layers "F.Cu" "B.Cu")
		(net "GND")
	)
	(via
		(at 250.09983 -41.500044)
		(size 0.4572)
		(drill 0.2032)
		(layers "F.Cu" "B.Cu")
		(net "GND")
	)
	(via
		(at 257.099816 -56.49976)
		(size 0.4572)
		(drill 0.2032)
		(layers "F.Cu" "B.Cu")
		(net "GND")
	)
	(via
		(at 320.8528 -26.0858)
		(size 0.508)
		(drill 0.254)
		(layers "F.Cu" "B.Cu")
		(net "GND")
	)
	(via
		(at 12.192 -108.204)
		(size 0.508)
		(drill 0.254)
		(layers "F.Cu" "B.Cu")
		(net "GND")
	)
	(via
		(at 347.228668 -56.86933)
		(size 0.7112)
		(drill 0.4064)
		(layers "F.Cu" "B.Cu")
		(net "GND")
	)
	(via
		(at 298.5262 -18.0594)
		(size 0.508)
		(drill 0.254)
		(layers "F.Cu" "B.Cu")
		(net "GND")
	)
	(via
		(at 231.648 -10.414)
		(size 0.508)
		(drill 0.254)
		(layers "F.Cu" "B.Cu")
		(net "GND")
	)
	(via
		(at 183.753252 -28.6258)
		(size 0.508)
		(drill 0.254)
		(layers "F.Cu" "B.Cu")
		(net "GND")
	)
	(via
		(at 349.299784 -55.169562)
		(size 0.7112)
		(drill 0.4064)
		(layers "F.Cu" "B.Cu")
		(net "GND")
	)
	(via
		(at 124.832364 -32.177482)
		(size 0.508)
		(drill 0.254)
		(layers "F.Cu" "B.Cu")
		(net "GND")
	)
	(via
		(at 250.27001 -3.66395)
		(size 0.508)
		(drill 0.254)
		(layers "F.Cu" "B.Cu")
		(net "GND")
	)
	(via
		(at 72.517 -179.0446)
		(size 0.508)
		(drill 0.254)
		(layers "F.Cu" "B.Cu")
		(net "GND")
	)
	(via
		(at 104.100122 -223.082104)
		(size 0.508)
		(drill 0.254)
		(layers "F.Cu" "B.Cu")
		(net "GND")
	)
	(via
		(at 10.8966 -72.263)
		(size 0.508)
		(drill 0.254)
		(layers "F.Cu" "B.Cu")
		(net "GND")
	)
	(via
		(at 38.203886 -163.546536)
		(size 0.508)
		(drill 0.254)
		(layers "F.Cu" "B.Cu")
		(net "GND")
	)
	(via
		(at 170.94708 -210.152996)
		(size 0.508)
		(drill 0.254)
		(layers "F.Cu" "B.Cu")
		(net "GND")
	)
	(via
		(at 227.10013 -54.499764)
		(size 0.4572)
		(drill 0.2032)
		(layers "F.Cu" "B.Cu")
		(net "GND")
	)
	(via
		(at 215.700102 -223.082104)
		(size 0.508)
		(drill 0.254)
		(layers "F.Cu" "B.Cu")
		(net "GND")
	)
	(via
		(at 84.963 -50.165)
		(size 0.7112)
		(drill 0.4064)
		(layers "F.Cu" "B.Cu")
		(net "GND")
	)
	(via
		(at 142.94739 -210.152996)
		(size 0.508)
		(drill 0.254)
		(layers "F.Cu" "B.Cu")
		(net "GND")
	)
	(via
		(at 71.922894 -185.443368)
		(size 0.508)
		(drill 0.254)
		(layers "F.Cu" "B.Cu")
		(net "GND")
	)
	(via
		(at 262.499856 -223.082104)
		(size 0.508)
		(drill 0.254)
		(layers "F.Cu" "B.Cu")
		(net "GND")
	)
	(via
		(at 36.568126 -156.779976)
		(size 0.4572)
		(drill 0.2032)
		(layers "F.Cu" "B.Cu")
		(net "GND")
	)
	(via
		(at 166.878 -181.483)
		(size 0.508)
		(drill 0.254)
		(layers "F.Cu" "B.Cu")
		(net "GND")
	)
	(via
		(at 194.900042 -223.082104)
		(size 0.508)
		(drill 0.254)
		(layers "F.Cu" "B.Cu")
		(net "GND")
	)
	(via
		(at 145.53946 -35.687254)
		(size 0.508)
		(drill 0.254)
		(layers "F.Cu" "B.Cu")
		(net "GND")
	)
	(via
		(at 248.099834 -58.499756)
		(size 0.4572)
		(drill 0.2032)
		(layers "F.Cu" "B.Cu")
		(net "GND")
	)
	(via
		(at 303.34712 -210.152996)
		(size 0.508)
		(drill 0.254)
		(layers "F.Cu" "B.Cu")
		(net "GND")
	)
	(via
		(at 178.7906 -219.9894)
		(size 0.508)
		(drill 0.254)
		(layers "F.Cu" "B.Cu")
		(net "GND")
	)
	(via
		(at 206.100172 -223.082104)
		(size 0.508)
		(drill 0.254)
		(layers "F.Cu" "B.Cu")
		(net "GND")
	)
	(via
		(at 247.099836 -54.499764)
		(size 0.4572)
		(drill 0.2032)
		(layers "F.Cu" "B.Cu")
		(net "GND")
	)
	(via
		(at 225.100134 -64.499744)
		(size 0.4572)
		(drill 0.2032)
		(layers "F.Cu" "B.Cu")
		(net "GND")
	)
	(via
		(at 257.099816 -58.499756)
		(size 0.4572)
		(drill 0.2032)
		(layers "F.Cu" "B.Cu")
		(net "GND")
	)
	(via
		(at 354.203 -131.985004)
		(size 0.508)
		(drill 0.254)
		(layers "F.Cu" "B.Cu")
		(net "GND")
	)
	(via
		(at 296.291 -14.2748)
		(size 0.508)
		(drill 0.254)
		(layers "F.Cu" "B.Cu")
		(net "GND")
	)
	(via
		(at 67.183 -36.2585)
		(size 0.508)
		(drill 0.254)
		(layers "F.Cu" "B.Cu")
		(net "GND")
	)
	(via
		(at 167.155622 -56.813958)
		(size 0.7112)
		(drill 0.4064)
		(layers "F.Cu" "B.Cu")
		(net "GND")
	)
	(via
		(at 223.100138 -41.500044)
		(size 0.4572)
		(drill 0.2032)
		(layers "F.Cu" "B.Cu")
		(net "GND")
	)
	(via
		(at 257.2004 -121.0818)
		(size 0.508)
		(drill 0.254)
		(layers "F.Cu" "B.Cu")
		(net "GND")
	)
	(via
		(at 319.6336 -11.6586)
		(size 0.508)
		(drill 0.254)
		(layers "F.Cu" "B.Cu")
		(net "GND")
	)
	(via
		(at 56.8325 -35.90798)
		(size 0.508)
		(drill 0.254)
		(layers "F.Cu" "B.Cu")
		(net "GND")
	)
	(via
		(at 259.099812 -32.500062)
		(size 0.4572)
		(drill 0.2032)
		(layers "F.Cu" "B.Cu")
		(net "GND")
	)
	(via
		(at 165.672516 -85.433662)
		(size 0.508)
		(drill 0.254)
		(layers "F.Cu" "B.Cu")
		(net "GND")
	)
	(via
		(at 347.134688 -53.419248)
		(size 0.7112)
		(drill 0.4064)
		(layers "F.Cu" "B.Cu")
		(net "GND")
	)
	(via
		(at 285.1912 -13.9954)
		(size 0.508)
		(drill 0.254)
		(layers "F.Cu" "B.Cu")
		(net "GND")
	)
	(via
		(at 340.7156 -174.4726)
		(size 0.508)
		(drill 0.254)
		(layers "F.Cu" "B.Cu")
		(net "GND")
	)
	(via
		(at 250.09983 -44.500038)
		(size 0.4572)
		(drill 0.2032)
		(layers "F.Cu" "B.Cu")
		(net "GND")
	)
	(via
		(at 229.100126 -45.500036)
		(size 0.4572)
		(drill 0.2032)
		(layers "F.Cu" "B.Cu")
		(net "GND")
	)
	(via
		(at 147.066 -18.3642)
		(size 0.508)
		(drill 0.254)
		(layers "F.Cu" "B.Cu")
		(net "GND")
	)
	(via
		(at 169.545 -19.304)
		(size 0.508)
		(drill 0.254)
		(layers "F.Cu" "B.Cu")
		(net "GND")
	)
	(via
		(at 242.099846 -30.500066)
		(size 0.4572)
		(drill 0.2032)
		(layers "F.Cu" "B.Cu")
		(net "GND")
	)
	(via
		(at 243.099844 -64.499744)
		(size 0.4572)
		(drill 0.2032)
		(layers "F.Cu" "B.Cu")
		(net "GND")
	)
	(via
		(at 340.868 -64.516)
		(size 0.508)
		(drill 0.254)
		(layers "F.Cu" "B.Cu")
		(net "GND")
	)
	(via
		(at 247.099836 -52.499768)
		(size 0.4572)
		(drill 0.2032)
		(layers "F.Cu" "B.Cu")
		(net "GND")
	)
	(via
		(at 229.100126 -58.499756)
		(size 0.4572)
		(drill 0.2032)
		(layers "F.Cu" "B.Cu")
		(net "GND")
	)
	(via
		(at 230.100124 -59.499754)
		(size 0.4572)
		(drill 0.2032)
		(layers "F.Cu" "B.Cu")
		(net "GND")
	)
	(via
		(at 247.099836 -55.499762)
		(size 0.4572)
		(drill 0.2032)
		(layers "F.Cu" "B.Cu")
		(net "GND")
	)
	(via
		(at 83.82 -191.516)
		(size 0.508)
		(drill 0.254)
		(layers "F.Cu" "B.Cu")
		(net "GND")
	)
	(via
		(at 309.6768 -22.098)
		(size 0.508)
		(drill 0.254)
		(layers "F.Cu" "B.Cu")
		(net "GND")
	)
	(via
		(at 174.01921 -53.511958)
		(size 0.508)
		(drill 0.254)
		(layers "F.Cu" "B.Cu")
		(net "GND")
	)
	(via
		(at 17.7038 -175.3362)
		(size 0.508)
		(drill 0.254)
		(layers "F.Cu" "B.Cu")
		(net "GND")
	)
	(via
		(at 323.1388 -14.7066)
		(size 0.508)
		(drill 0.254)
		(layers "F.Cu" "B.Cu")
		(net "GND")
	)
	(via
		(at 138.1506 -39.3192)
		(size 0.508)
		(drill 0.254)
		(layers "F.Cu" "B.Cu")
		(net "GND")
	)
	(via
		(at 238.100108 -55.499762)
		(size 0.4572)
		(drill 0.2032)
		(layers "F.Cu" "B.Cu")
		(net "GND")
	)
	(via
		(at 222.0722 -4.79425)
		(size 0.508)
		(drill 0.254)
		(layers "F.Cu" "B.Cu")
		(net "GND")
	)
	(via
		(at 245.999 -97.409)
		(size 0.7112)
		(drill 0.3556)
		(layers "F.Cu" "B.Cu")
		(net "GND")
	)
	(via
		(at 237.10011 -63.499746)
		(size 0.4572)
		(drill 0.2032)
		(layers "F.Cu" "B.Cu")
		(net "GND")
	)
	(via
		(at 5.4356 -89.916)
		(size 0.508)
		(drill 0.254)
		(layers "F.Cu" "B.Cu")
		(net "GND")
	)
	(via
		(at 40.856154 -160.185354)
		(size 0.508)
		(drill 0.254)
		(layers "F.Cu" "B.Cu")
		(net "GND")
	)
	(via
		(at 234.100116 -64.499744)
		(size 0.4572)
		(drill 0.2032)
		(layers "F.Cu" "B.Cu")
		(net "GND")
	)
	(via
		(at 37.452554 -140.750544)
		(size 0.4572)
		(drill 0.2032)
		(layers "F.Cu" "B.Cu")
		(net "GND")
	)
	(via
		(at 64.643 -39.0525)
		(size 0.508)
		(drill 0.254)
		(layers "F.Cu" "B.Cu")
		(net "GND")
	)
	(via
		(at 347.96095 -212.102954)
		(size 0.508)
		(drill 0.254)
		(layers "F.Cu" "B.Cu")
		(net "GND")
	)
	(via
		(at 248.099834 -59.499754)
		(size 0.4572)
		(drill 0.2032)
		(layers "F.Cu" "B.Cu")
		(net "GND")
	)
	(via
		(at 235.100114 -49.499774)
		(size 0.4572)
		(drill 0.2032)
		(layers "F.Cu" "B.Cu")
		(net "GND")
	)
	(via
		(at 202.66406 -50.525172)
		(size 0.508)
		(drill 0.254)
		(layers "F.Cu" "B.Cu")
		(net "GND")
	)
	(via
		(at 281.69997 -223.082104)
		(size 0.508)
		(drill 0.254)
		(layers "F.Cu" "B.Cu")
		(net "GND")
	)
	(via
		(at 70.1802 -156.8069)
		(size 0.508)
		(drill 0.254)
		(layers "F.Cu" "B.Cu")
		(net "GND")
	)
	(via
		(at 231.100122 -64.499744)
		(size 0.4572)
		(drill 0.2032)
		(layers "F.Cu" "B.Cu")
		(net "GND")
	)
	(via
		(at 220.3704 -0.635)
		(size 0.508)
		(drill 0.254)
		(layers "F.Cu" "B.Cu")
		(net "GND")
	)
	(via
		(at 102.547166 -210.152996)
		(size 0.508)
		(drill 0.254)
		(layers "F.Cu" "B.Cu")
		(net "GND")
	)
	(via
		(at 154.371802 -61.622432)
		(size 0.508)
		(drill 0.254)
		(layers "F.Cu" "B.Cu")
		(net "GND")
	)
	(via
		(at 64.262 -42.291)
		(size 0.7112)
		(drill 0.4064)
		(layers "F.Cu" "B.Cu")
		(net "GND")
	)
	(via
		(at 1.397 -111.651034)
		(size 0.508)
		(drill 0.254)
		(layers "F.Cu" "B.Cu")
		(net "GND")
	)
	(via
		(at 132.207 -131.9276)
		(size 0.508)
		(drill 0.254)
		(layers "F.Cu" "B.Cu")
		(net "GND")
	)
	(via
		(at 19.941032 -59.104022)
		(size 0.508)
		(drill 0.254)
		(layers "F.Cu" "B.Cu")
		(net "GND")
	)
	(via
		(at 250.09983 -48.499776)
		(size 0.4572)
		(drill 0.2032)
		(layers "F.Cu" "B.Cu")
		(net "GND")
	)
	(via
		(at 150.622 -38.8112)
		(size 0.508)
		(drill 0.254)
		(layers "F.Cu" "B.Cu")
		(net "GND")
	)
	(via
		(at 270.452596 -210.152996)
		(size 0.508)
		(drill 0.254)
		(layers "F.Cu" "B.Cu")
		(net "GND")
	)
	(via
		(at 185.5216 -59.3852)
		(size 0.7112)
		(drill 0.4064)
		(layers "F.Cu" "B.Cu")
		(net "GND")
	)
	(via
		(at 99.347274 -210.152996)
		(size 0.508)
		(drill 0.254)
		(layers "F.Cu" "B.Cu")
		(net "GND")
	)
	(via
		(at 235.100114 -58.499756)
		(size 0.4572)
		(drill 0.2032)
		(layers "F.Cu" "B.Cu")
		(net "GND")
	)
	(via
		(at 5.4356 -86.614)
		(size 0.508)
		(drill 0.254)
		(layers "F.Cu" "B.Cu")
		(net "GND")
	)
	(via
		(at 191.262 -91.186)
		(size 0.508)
		(drill 0.254)
		(layers "F.Cu" "B.Cu")
		(net "GND")
	)
	(via
		(at 36.322 -199.263)
		(size 0.508)
		(drill 0.254)
		(layers "F.Cu" "B.Cu")
		(net "GND")
	)
	(via
		(at 251.099828 -48.499776)
		(size 0.4572)
		(drill 0.2032)
		(layers "F.Cu" "B.Cu")
		(net "GND")
	)
	(via
		(at 170.899836 -223.082104)
		(size 0.508)
		(drill 0.254)
		(layers "F.Cu" "B.Cu")
		(net "GND")
	)
	(via
		(at 42.900092 -223.0628)
		(size 0.508)
		(drill 0.254)
		(layers "F.Cu" "B.Cu")
		(net "GND")
	)
	(via
		(at 193.252598 -210.152996)
		(size 0.508)
		(drill 0.254)
		(layers "F.Cu" "B.Cu")
		(net "GND")
	)
	(via
		(at 344.903044 -219.518484)
		(size 0.508)
		(drill 0.254)
		(layers "F.Cu" "B.Cu")
		(net "GND")
	)
	(via
		(at 266.512294 3.60299)
		(size 0.508)
		(drill 0.254)
		(layers "F.Cu" "B.Cu")
		(net "GND")
	)
	(via
		(at 248.099834 -46.500034)
		(size 0.4572)
		(drill 0.2032)
		(layers "F.Cu" "B.Cu")
		(net "GND")
	)
	(via
		(at 55.3212 -130.175)
		(size 0.508)
		(drill 0.254)
		(layers "F.Cu" "B.Cu")
		(net "GND")
	)
	(via
		(at 273.652488 -210.152996)
		(size 0.508)
		(drill 0.254)
		(layers "F.Cu" "B.Cu")
		(net "GND")
	)
	(via
		(at 278.547068 -210.152996)
		(size 0.508)
		(drill 0.254)
		(layers "F.Cu" "B.Cu")
		(net "GND")
	)
	(via
		(at 23.586186 -57.571386)
		(size 0.508)
		(drill 0.254)
		(layers "F.Cu" "B.Cu")
		(net "GND")
	)
	(via
		(at 4.572 -68.9864)
		(size 0.508)
		(drill 0.254)
		(layers "F.Cu" "B.Cu")
		(net "GND")
	)
	(via
		(at 1.397 -35.451034)
		(size 0.508)
		(drill 0.254)
		(layers "F.Cu" "B.Cu")
		(net "GND")
	)
	(via
		(at 251.099828 -58.499756)
		(size 0.4572)
		(drill 0.2032)
		(layers "F.Cu" "B.Cu")
		(net "GND")
	)
	(via
		(at 199.700134 -223.082104)
		(size 0.508)
		(drill 0.254)
		(layers "F.Cu" "B.Cu")
		(net "GND")
	)
	(via
		(at 236.100112 -45.500036)
		(size 0.4572)
		(drill 0.2032)
		(layers "F.Cu" "B.Cu")
		(net "GND")
	)
	(via
		(at 126.06909 -212.102954)
		(size 0.508)
		(drill 0.254)
		(layers "F.Cu" "B.Cu")
		(net "GND")
	)
	(via
		(at 1.397 -60.851034)
		(size 0.508)
		(drill 0.254)
		(layers "F.Cu" "B.Cu")
		(net "GND")
	)
	(via
		(at 142.692374 -87.955374)
		(size 0.508)
		(drill 0.254)
		(layers "F.Cu" "B.Cu")
		(net "GND")
	)
	(via
		(at 249.099832 -52.499768)
		(size 0.4572)
		(drill 0.2032)
		(layers "F.Cu" "B.Cu")
		(net "GND")
	)
	(via
		(at 251.099828 -59.499754)
		(size 0.4572)
		(drill 0.2032)
		(layers "F.Cu" "B.Cu")
		(net "GND")
	)
	(via
		(at 338.328 -69.215)
		(size 0.508)
		(drill 0.254)
		(layers "F.Cu" "B.Cu")
		(net "GND")
	)
	(via
		(at 244.099842 -42.500042)
		(size 0.4572)
		(drill 0.2032)
		(layers "F.Cu" "B.Cu")
		(net "GND")
	)
	(via
		(at 180.827426 -1.715516)
		(size 0.508)
		(drill 0.254)
		(layers "F.Cu" "B.Cu")
		(net "GND")
	)
	(via
		(at 1.397 -167.531034)
		(size 0.508)
		(drill 0.254)
		(layers "F.Cu" "B.Cu")
		(net "GND")
	)
	(via
		(at 296.099992 -223.082104)
		(size 0.508)
		(drill 0.254)
		(layers "F.Cu" "B.Cu")
		(net "GND")
	)
	(via
		(at 354.203 -65.945004)
		(size 0.508)
		(drill 0.254)
		(layers "F.Cu" "B.Cu")
		(net "GND")
	)
	(via
		(at 235.100114 -63.499746)
		(size 0.4572)
		(drill 0.2032)
		(layers "F.Cu" "B.Cu")
		(net "GND")
	)
	(via
		(at 79.248 -220.6244)
		(size 0.508)
		(drill 0.254)
		(layers "F.Cu" "B.Cu")
		(net "GND")
	)
	(via
		(at 103.251 -37.3126)
		(size 0.508)
		(drill 0.254)
		(layers "F.Cu" "B.Cu")
		(net "GND")
	)
	(via
		(at 51.300126 -223.082104)
		(size 0.508)
		(drill 0.254)
		(layers "F.Cu" "B.Cu")
		(net "GND")
	)
	(via
		(at 67.5894 -156.0576)
		(size 0.508)
		(drill 0.254)
		(layers "F.Cu" "B.Cu")
		(net "GND")
	)
	(via
		(at 68.326 -128.260348)
		(size 0.508)
		(drill 0.254)
		(layers "F.Cu" "B.Cu")
		(net "GND")
	)
	(via
		(at 49.784 -220.6498)
		(size 0.508)
		(drill 0.254)
		(layers "F.Cu" "B.Cu")
		(net "GND")
	)
	(via
		(at 252.538992 -194.517772)
		(size 0.508)
		(drill 0.254)
		(layers "F.Cu" "B.Cu")
		(net "GND")
	)
	(via
		(at 148.463 -23.6728)
		(size 0.508)
		(drill 0.254)
		(layers "F.Cu" "B.Cu")
		(net "GND")
	)
	(via
		(at 239.100106 -51.49977)
		(size 0.4572)
		(drill 0.2032)
		(layers "F.Cu" "B.Cu")
		(net "GND")
	)
	(via
		(at 177.299874 -223.082104)
		(size 0.508)
		(drill 0.254)
		(layers "F.Cu" "B.Cu")
		(net "GND")
	)
	(via
		(at 327.347072 -210.152996)
		(size 0.508)
		(drill 0.254)
		(layers "F.Cu" "B.Cu")
		(net "GND")
	)
	(via
		(at 12.322048 -90.547952)
		(size 0.508)
		(drill 0.254)
		(layers "F.Cu" "B.Cu")
		(net "GND")
	)
	(via
		(at 1.397 -81.171034)
		(size 0.508)
		(drill 0.254)
		(layers "F.Cu" "B.Cu")
		(net "GND")
	)
	(via
		(at 25.336246 -112.692434)
		(size 0.508)
		(drill 0.254)
		(layers "F.Cu" "B.Cu")
		(net "GND")
	)
	(via
		(at 202.6412 -26.543)
		(size 0.508)
		(drill 0.254)
		(layers "F.Cu" "B.Cu")
		(net "GND")
	)
	(via
		(at 1.397 -45.611034)
		(size 0.508)
		(drill 0.254)
		(layers "F.Cu" "B.Cu")
		(net "GND")
	)
	(via
		(at 183.652414 -210.152996)
		(size 0.508)
		(drill 0.254)
		(layers "F.Cu" "B.Cu")
		(net "GND")
	)
	(via
		(at 122.809 -199.3011)
		(size 0.508)
		(drill 0.254)
		(layers "F.Cu" "B.Cu")
		(net "GND")
	)
	(via
		(at 254.099822 -42.500042)
		(size 0.4572)
		(drill 0.2032)
		(layers "F.Cu" "B.Cu")
		(net "GND")
	)
	(via
		(at 20.3962 -151.4094)
		(size 0.508)
		(drill 0.254)
		(layers "F.Cu" "B.Cu")
		(net "GND")
	)
	(via
		(at 246.099838 -35.500056)
		(size 0.4572)
		(drill 0.2032)
		(layers "F.Cu" "B.Cu")
		(net "GND")
	)
	(via
		(at 298.4246 -207.8482)
		(size 0.508)
		(drill 0.254)
		(layers "F.Cu" "B.Cu")
		(net "GND")
	)
	(via
		(at 20.828 -150.495)
		(size 0.508)
		(drill 0.254)
		(layers "F.Cu" "B.Cu")
		(net "GND")
	)
	(via
		(at 271.018 -180.594)
		(size 0.508)
		(drill 0.254)
		(layers "F.Cu" "B.Cu")
		(net "GND")
	)
	(via
		(at 14.6812 -106.8578)
		(size 0.508)
		(drill 0.254)
		(layers "F.Cu" "B.Cu")
		(net "GND")
	)
	(via
		(at 225.100134 -31.500064)
		(size 0.4572)
		(drill 0.2032)
		(layers "F.Cu" "B.Cu")
		(net "GND")
	)
	(via
		(at 332.052676 -210.152996)
		(size 0.508)
		(drill 0.254)
		(layers "F.Cu" "B.Cu")
		(net "GND")
	)
	(via
		(at 268.899894 -223.082104)
		(size 0.508)
		(drill 0.254)
		(layers "F.Cu" "B.Cu")
		(net "GND")
	)
	(via
		(at 37.0586 -209.3976)
		(size 0.508)
		(drill 0.254)
		(layers "F.Cu" "B.Cu")
		(net "GND")
	)
	(via
		(at 157.318202 -57.177432)
		(size 0.508)
		(drill 0.254)
		(layers "F.Cu" "B.Cu")
		(net "GND")
	)
	(via
		(at 50.4444 -149.5425)
		(size 0.508)
		(drill 0.254)
		(layers "F.Cu" "B.Cu")
		(net "GND")
	)
	(via
		(at 241.099848 -45.500036)
		(size 0.4572)
		(drill 0.2032)
		(layers "F.Cu" "B.Cu")
		(net "GND")
	)
	(via
		(at 237.10011 -44.500038)
		(size 0.4572)
		(drill 0.2032)
		(layers "F.Cu" "B.Cu")
		(net "GND")
	)
	(via
		(at 28.642056 -67.111372)
		(size 0.508)
		(drill 0.254)
		(layers "F.Cu" "B.Cu")
		(net "GND")
	)
	(via
		(at 258.099814 -60.499752)
		(size 0.4572)
		(drill 0.2032)
		(layers "F.Cu" "B.Cu")
		(net "GND")
	)
	(via
		(at 231.100122 -42.500042)
		(size 0.4572)
		(drill 0.2032)
		(layers "F.Cu" "B.Cu")
		(net "GND")
	)
	(via
		(at 253.099824 -63.499746)
		(size 0.4572)
		(drill 0.2032)
		(layers "F.Cu" "B.Cu")
		(net "GND")
	)
	(via
		(at 308.5592 -54.7878)
		(size 0.7112)
		(drill 0.4064)
		(layers "F.Cu" "B.Cu")
		(net "GND")
	)
	(via
		(at 1.397 -172.611034)
		(size 0.508)
		(drill 0.254)
		(layers "F.Cu" "B.Cu")
		(net "GND")
	)
	(via
		(at 234.100116 -58.499756)
		(size 0.4572)
		(drill 0.2032)
		(layers "F.Cu" "B.Cu")
		(net "GND")
	)
	(via
		(at 67.183 -37.1475)
		(size 0.508)
		(drill 0.254)
		(layers "F.Cu" "B.Cu")
		(net "GND")
	)
	(via
		(at 49.149 -177.8)
		(size 0.508)
		(drill 0.254)
		(layers "F.Cu" "B.Cu")
		(net "GND")
	)
	(via
		(at 79.375 -181.991)
		(size 0.508)
		(drill 0.254)
		(layers "F.Cu" "B.Cu")
		(net "GND")
	)
	(via
		(at 162.433 -86.995)
		(size 0.508)
		(drill 0.254)
		(layers "F.Cu" "B.Cu")
		(net "GND")
	)
	(via
		(at 309.9054 -26.0858)
		(size 0.508)
		(drill 0.254)
		(layers "F.Cu" "B.Cu")
		(net "GND")
	)
	(via
		(at 250.09983 -63.499746)
		(size 0.4572)
		(drill 0.2032)
		(layers "F.Cu" "B.Cu")
		(net "GND")
	)
	(via
		(at 38.2524 -164.6682)
		(size 0.508)
		(drill 0.254)
		(layers "F.Cu" "B.Cu")
		(net "GND")
	)
	(via
		(at 135.15594 -35.1536)
		(size 0.508)
		(drill 0.254)
		(layers "F.Cu" "B.Cu")
		(net "GND")
	)
	(via
		(at 239.100106 -40.500046)
		(size 0.4572)
		(drill 0.2032)
		(layers "F.Cu" "B.Cu")
		(net "GND")
	)
	(via
		(at 23.51532 -104.333294)
		(size 0.508)
		(drill 0.254)
		(layers "F.Cu" "B.Cu")
		(net "GND")
	)
	(via
		(at 134.2898 -23.1394)
		(size 0.508)
		(drill 0.254)
		(layers "F.Cu" "B.Cu")
		(net "GND")
	)
	(via
		(at 341.652352 -210.152996)
		(size 0.508)
		(drill 0.254)
		(layers "F.Cu" "B.Cu")
		(net "GND")
	)
	(via
		(at 50.165 -146.6342)
		(size 0.508)
		(drill 0.254)
		(layers "F.Cu" "B.Cu")
		(net "GND")
	)
	(via
		(at 242.099846 -55.499762)
		(size 0.4572)
		(drill 0.2032)
		(layers "F.Cu" "B.Cu")
		(net "GND")
	)
	(via
		(at 333.747364 -210.152996)
		(size 0.508)
		(drill 0.254)
		(layers "F.Cu" "B.Cu")
		(net "GND")
	)
	(via
		(at 225.100134 -40.500046)
		(size 0.4572)
		(drill 0.2032)
		(layers "F.Cu" "B.Cu")
		(net "GND")
	)
	(via
		(at 47.897288 -211.375244)
		(size 0.508)
		(drill 0.254)
		(layers "F.Cu" "B.Cu")
		(net "GND")
	)
	(via
		(at 284.899862 -223.082104)
		(size 0.508)
		(drill 0.254)
		(layers "F.Cu" "B.Cu")
		(net "GND")
	)
	(via
		(at 237.10011 -46.500034)
		(size 0.4572)
		(drill 0.2032)
		(layers "F.Cu" "B.Cu")
		(net "GND")
	)
	(via
		(at 19.776186 -109.189266)
		(size 0.508)
		(drill 0.254)
		(layers "F.Cu" "B.Cu")
		(net "GND")
	)
	(via
		(at 158.0134 -18.3896)
		(size 0.508)
		(drill 0.254)
		(layers "F.Cu" "B.Cu")
		(net "GND")
	)
	(via
		(at 159.893 -90.551)
		(size 0.508)
		(drill 0.254)
		(layers "F.Cu" "B.Cu")
		(net "GND")
	)
	(via
		(at 189.23 -186.309)
		(size 0.7112)
		(drill 0.3556)
		(layers "F.Cu" "B.Cu")
		(net "GND")
	)
	(via
		(at 218.903042 -216.838784)
		(size 0.508)
		(drill 0.254)
		(layers "F.Cu" "B.Cu")
		(net "GND")
	)
	(via
		(at 256.099818 -31.500064)
		(size 0.4572)
		(drill 0.2032)
		(layers "F.Cu" "B.Cu")
		(net "GND")
	)
	(via
		(at 78.744064 -185.367422)
		(size 0.508)
		(drill 0.254)
		(layers "F.Cu" "B.Cu")
		(net "GND")
	)
	(via
		(at 233.100118 -63.499746)
		(size 0.4572)
		(drill 0.2032)
		(layers "F.Cu" "B.Cu")
		(net "GND")
	)
	(via
		(at 146.100038 -223.082104)
		(size 0.508)
		(drill 0.254)
		(layers "F.Cu" "B.Cu")
		(net "GND")
	)
	(via
		(at 187.022232 1.900682)
		(size 0.508)
		(drill 0.254)
		(layers "F.Cu" "B.Cu")
		(net "GND")
	)
	(via
		(at 322.6562 -23.1394)
		(size 0.508)
		(drill 0.254)
		(layers "F.Cu" "B.Cu")
		(net "GND")
	)
	(via
		(at 227.10013 -42.500042)
		(size 0.4572)
		(drill 0.2032)
		(layers "F.Cu" "B.Cu")
		(net "GND")
	)
	(via
		(at 29.464 -52.578)
		(size 0.508)
		(drill 0.254)
		(layers "F.Cu" "B.Cu")
		(net "GND")
	)
	(via
		(at 185.347102 -210.152996)
		(size 0.508)
		(drill 0.254)
		(layers "F.Cu" "B.Cu")
		(net "GND")
	)
	(via
		(at 180.6702 -58.0898)
		(size 0.7112)
		(drill 0.4064)
		(layers "F.Cu" "B.Cu")
		(net "GND")
	)
	(via
		(at 1.397 -106.571034)
		(size 0.508)
		(drill 0.254)
		(layers "F.Cu" "B.Cu")
		(net "GND")
	)
	(via
		(at 236.100112 -52.499768)
		(size 0.4572)
		(drill 0.2032)
		(layers "F.Cu" "B.Cu")
		(net "GND")
	)
	(via
		(at 20.107656 -108.260134)
		(size 0.508)
		(drill 0.254)
		(layers "F.Cu" "B.Cu")
		(net "GND")
	)
	(via
		(at 157.300168 -223.082104)
		(size 0.508)
		(drill 0.254)
		(layers "F.Cu" "B.Cu")
		(net "GND")
	)
	(via
		(at 341.700104 -223.082104)
		(size 0.508)
		(drill 0.254)
		(layers "F.Cu" "B.Cu")
		(net "GND")
	)
	(via
		(at 216.535 -182.372)
		(size 0.508)
		(drill 0.254)
		(layers "F.Cu" "B.Cu")
		(net "GND")
	)
	(via
		(at 150.852632 -210.152996)
		(size 0.508)
		(drill 0.254)
		(layers "F.Cu" "B.Cu")
		(net "GND")
	)
	(via
		(at 163.36264 -37.9984)
		(size 0.508)
		(drill 0.254)
		(layers "F.Cu" "B.Cu")
		(net "GND")
	)
	(via
		(at 224.8916 -188.8744)
		(size 0.508)
		(drill 0.254)
		(layers "F.Cu" "B.Cu")
		(net "GND")
	)
	(via
		(at 249.099832 -42.500042)
		(size 0.4572)
		(drill 0.2032)
		(layers "F.Cu" "B.Cu")
		(net "GND")
	)
	(via
		(at 8.001 -93.1926)
		(size 0.508)
		(drill 0.254)
		(layers "F.Cu" "B.Cu")
		(net "GND")
	)
	(via
		(at 242.099846 -44.500038)
		(size 0.4572)
		(drill 0.2032)
		(layers "F.Cu" "B.Cu")
		(net "GND")
	)
	(via
		(at 34.06648 -67.97802)
		(size 0.508)
		(drill 0.254)
		(layers "F.Cu" "B.Cu")
		(net "GND")
	)
	(via
		(at 68.199 -35.687)
		(size 0.7112)
		(drill 0.3556)
		(layers "F.Cu" "B.Cu")
		(net "GND")
	)
	(via
		(at 4.6355 -190.3095)
		(size 0.508)
		(drill 0.254)
		(layers "F.Cu" "B.Cu")
		(net "GND")
	)
	(via
		(at 37.94252 -44.70654)
		(size 0.508)
		(drill 0.254)
		(layers "F.Cu" "B.Cu")
		(net "GND")
	)
	(via
		(at 15.1892 -53.7972)
		(size 0.508)
		(drill 0.254)
		(layers "F.Cu" "B.Cu")
		(net "GND")
	)
	(via
		(at 233.100118 -44.500038)
		(size 0.4572)
		(drill 0.2032)
		(layers "F.Cu" "B.Cu")
		(net "GND")
	)
	(via
		(at 137.527284 -56.530748)
		(size 0.508)
		(drill 0.254)
		(layers "F.Cu" "B.Cu")
		(net "GND")
	)
	(via
		(at 227.10013 -37.500052)
		(size 0.4572)
		(drill 0.2032)
		(layers "F.Cu" "B.Cu")
		(net "GND")
	)
	(via
		(at 88.9 -136.5504)
		(size 0.508)
		(drill 0.254)
		(layers "F.Cu" "B.Cu")
		(net "GND")
	)
	(via
		(at 40.96512 -140.6652)
		(size 0.4572)
		(drill 0.2032)
		(layers "F.Cu" "B.Cu")
		(net "GND")
	)
	(via
		(at 111.300006 -223.082104)
		(size 0.508)
		(drill 0.254)
		(layers "F.Cu" "B.Cu")
		(net "GND")
	)
	(via
		(at 147.4978 -23.0886)
		(size 0.508)
		(drill 0.254)
		(layers "F.Cu" "B.Cu")
		(net "GND")
	)
	(via
		(at 169.314622 -57.575958)
		(size 0.7112)
		(drill 0.4064)
		(layers "F.Cu" "B.Cu")
		(net "GND")
	)
	(via
		(at 48.514 -62.611)
		(size 0.508)
		(drill 0.254)
		(layers "F.Cu" "B.Cu")
		(net "GND")
	)
	(via
		(at 24.09444 -159.7025)
		(size 0.508)
		(drill 0.254)
		(layers "F.Cu" "B.Cu")
		(net "GND")
	)
	(via
		(at 298.45254 -210.152996)
		(size 0.508)
		(drill 0.254)
		(layers "F.Cu" "B.Cu")
		(net "GND")
	)
	(via
		(at 158.334202 -57.177432)
		(size 0.508)
		(drill 0.254)
		(layers "F.Cu" "B.Cu")
		(net "GND")
	)
	(via
		(at 301.1932 -26.1366)
		(size 0.508)
		(drill 0.254)
		(layers "F.Cu" "B.Cu")
		(net "GND")
	)
	(via
		(at 325.247 -179.324)
		(size 0.508)
		(drill 0.254)
		(layers "F.Cu" "B.Cu")
		(net "GND")
	)
	(via
		(at 73.36409 -150.66391)
		(size 0.508)
		(drill 0.254)
		(layers "F.Cu" "B.Cu")
		(net "GND")
	)
	(via
		(at 128.983486 -85.430614)
		(size 0.508)
		(drill 0.254)
		(layers "F.Cu" "B.Cu")
		(net "GND")
	)
	(via
		(at 256.099818 -43.50004)
		(size 0.4572)
		(drill 0.2032)
		(layers "F.Cu" "B.Cu")
		(net "GND")
	)
	(via
		(at 83.693 -48.895)
		(size 0.7112)
		(drill 0.4064)
		(layers "F.Cu" "B.Cu")
		(net "GND")
	)
	(via
		(at 312.928 -49.403)
		(size 0.7112)
		(drill 0.4064)
		(layers "F.Cu" "B.Cu")
		(net "GND")
	)
	(via
		(at 1.397 -121.811034)
		(size 0.508)
		(drill 0.254)
		(layers "F.Cu" "B.Cu")
		(net "GND")
	)
	(via
		(at 19.842734 -82.77098)
		(size 0.508)
		(drill 0.254)
		(layers "F.Cu" "B.Cu")
		(net "GND")
	)
	(via
		(at 40.0558 -190.2206)
		(size 0.508)
		(drill 0.254)
		(layers "F.Cu" "B.Cu")
		(net "GND")
	)
	(via
		(at 86.233 -48.895)
		(size 0.7112)
		(drill 0.4064)
		(layers "F.Cu" "B.Cu")
		(net "GND")
	)
	(via
		(at 20.574 -147.066)
		(size 0.508)
		(drill 0.254)
		(layers "F.Cu" "B.Cu")
		(net "GND")
	)
	(via
		(at 142.374874 -90.95232)
		(size 0.508)
		(drill 0.254)
		(layers "F.Cu" "B.Cu")
		(net "GND")
	)
	(via
		(at 142.346172 -73.481946)
		(size 0.7112)
		(drill 0.4064)
		(layers "F.Cu" "B.Cu")
		(net "GND")
	)
	(via
		(at 236.100112 -48.499776)
		(size 0.4572)
		(drill 0.2032)
		(layers "F.Cu" "B.Cu")
		(net "GND")
	)
	(via
		(at 135.255 -15.9766)
		(size 0.508)
		(drill 0.254)
		(layers "F.Cu" "B.Cu")
		(net "GND")
	)
	(via
		(at 230.100124 -43.50004)
		(size 0.4572)
		(drill 0.2032)
		(layers "F.Cu" "B.Cu")
		(net "GND")
	)
	(via
		(at 115.7732 -52.9082)
		(size 0.508)
		(drill 0.254)
		(layers "F.Cu" "B.Cu")
		(net "GND")
	)
	(via
		(at 20.1295 -181.8767)
		(size 0.508)
		(drill 0.254)
		(layers "F.Cu" "B.Cu")
		(net "GND")
	)
	(via
		(at 299.085 -71.12)
		(size 0.7112)
		(drill 0.4064)
		(layers "F.Cu" "B.Cu")
		(net "GND")
	)
	(via
		(at 241.173 -26.162)
		(size 0.508)
		(drill 0.254)
		(layers "F.Cu" "B.Cu")
		(net "GND")
	)
	(via
		(at 250.09983 -58.499756)
		(size 0.4572)
		(drill 0.2032)
		(layers "F.Cu" "B.Cu")
		(net "GND")
	)
	(via
		(at 11.284204 -67.921632)
		(size 0.508)
		(drill 0.254)
		(layers "F.Cu" "B.Cu")
		(net "GND")
	)
	(via
		(at 250.09983 -43.50004)
		(size 0.4572)
		(drill 0.2032)
		(layers "F.Cu" "B.Cu")
		(net "GND")
	)
	(via
		(at 35.378644 -79.048356)
		(size 0.508)
		(drill 0.254)
		(layers "F.Cu" "B.Cu")
		(net "GND")
	)
	(via
		(at 30.167834 -156.779976)
		(size 0.4572)
		(drill 0.2032)
		(layers "F.Cu" "B.Cu")
		(net "GND")
	)
	(via
		(at 246.099838 -58.499756)
		(size 0.4572)
		(drill 0.2032)
		(layers "F.Cu" "B.Cu")
		(net "GND")
	)
	(via
		(at 142.899892 -223.082104)
		(size 0.508)
		(drill 0.254)
		(layers "F.Cu" "B.Cu")
		(net "GND")
	)
	(via
		(at 256.099818 -38.50005)
		(size 0.4572)
		(drill 0.2032)
		(layers "F.Cu" "B.Cu")
		(net "GND")
	)
	(via
		(at 314.119768 -34.98088)
		(size 0.508)
		(drill 0.254)
		(layers "F.Cu" "B.Cu")
		(net "GND")
	)
	(via
		(at 11.971528 -112.877346)
		(size 0.508)
		(drill 0.254)
		(layers "F.Cu" "B.Cu")
		(net "GND")
	)
	(via
		(at 295.873678 -35.18027)
		(size 0.508)
		(drill 0.254)
		(layers "F.Cu" "B.Cu")
		(net "GND")
	)
	(via
		(at 238.100108 -48.499776)
		(size 0.4572)
		(drill 0.2032)
		(layers "F.Cu" "B.Cu")
		(net "GND")
	)
	(via
		(at 144.500092 -223.082104)
		(size 0.508)
		(drill 0.254)
		(layers "F.Cu" "B.Cu")
		(net "GND")
	)
	(via
		(at 247.099836 -48.499776)
		(size 0.4572)
		(drill 0.2032)
		(layers "F.Cu" "B.Cu")
		(net "GND")
	)
	(via
		(at 225.100134 -61.49975)
		(size 0.4572)
		(drill 0.2032)
		(layers "F.Cu" "B.Cu")
		(net "GND")
	)
	(via
		(at 313.0042 -144.5006)
		(size 0.508)
		(drill 0.254)
		(layers "F.Cu" "B.Cu")
		(net "GND")
	)
	(via
		(at 249.099832 -58.499756)
		(size 0.4572)
		(drill 0.2032)
		(layers "F.Cu" "B.Cu")
		(net "GND")
	)
	(via
		(at 280.100024 -223.082104)
		(size 0.508)
		(drill 0.254)
		(layers "F.Cu" "B.Cu")
		(net "GND")
	)
	(via
		(at 153.101802 -58.955432)
		(size 0.508)
		(drill 0.254)
		(layers "F.Cu" "B.Cu")
		(net "GND")
	)
	(via
		(at 247.099836 -43.50004)
		(size 0.4572)
		(drill 0.2032)
		(layers "F.Cu" "B.Cu")
		(net "GND")
	)
	(via
		(at 8.8646 -55.0672)
		(size 0.508)
		(drill 0.254)
		(layers "F.Cu" "B.Cu")
		(net "GND")
	)
	(via
		(at 232.10012 -44.500038)
		(size 0.4572)
		(drill 0.2032)
		(layers "F.Cu" "B.Cu")
		(net "GND")
	)
	(via
		(at 232.10012 -53.499766)
		(size 0.4572)
		(drill 0.2032)
		(layers "F.Cu" "B.Cu")
		(net "GND")
	)
	(via
		(at 206.375 -126.8476)
		(size 0.508)
		(drill 0.254)
		(layers "F.Cu" "B.Cu")
		(net "GND")
	)
	(via
		(at 23.3172 -181.8894)
		(size 0.508)
		(drill 0.254)
		(layers "F.Cu" "B.Cu")
		(net "GND")
	)
	(via
		(at 186.020202 -75.160632)
		(size 0.7112)
		(drill 0.4064)
		(layers "F.Cu" "B.Cu")
		(net "GND")
	)
	(via
		(at 177.2158 -219.9894)
		(size 0.508)
		(drill 0.254)
		(layers "F.Cu" "B.Cu")
		(net "GND")
	)
	(via
		(at 38.605206 -140.344652)
		(size 0.4572)
		(drill 0.2032)
		(layers "F.Cu" "B.Cu")
		(net "GND")
	)
	(via
		(at 274.193 -160.274)
		(size 0.508)
		(drill 0.254)
		(layers "F.Cu" "B.Cu")
		(net "GND")
	)
	(via
		(at 88.9 -223.082104)
		(size 0.508)
		(drill 0.254)
		(layers "F.Cu" "B.Cu")
		(net "GND")
	)
	(via
		(at 288.2392 -23.6982)
		(size 0.508)
		(drill 0.254)
		(layers "F.Cu" "B.Cu")
		(net "GND")
	)
	(via
		(at 227.10013 -31.500064)
		(size 0.4572)
		(drill 0.2032)
		(layers "F.Cu" "B.Cu")
		(net "GND")
	)
	(via
		(at 228.100128 -52.499768)
		(size 0.4572)
		(drill 0.2032)
		(layers "F.Cu" "B.Cu")
		(net "GND")
	)
	(via
		(at 288.147252 -210.152996)
		(size 0.508)
		(drill 0.254)
		(layers "F.Cu" "B.Cu")
		(net "GND")
	)
	(via
		(at 319.278 -74.168)
		(size 0.7112)
		(drill 0.4064)
		(layers "F.Cu" "B.Cu")
		(net "GND")
	)
	(via
		(at 259.099812 -63.499746)
		(size 0.4572)
		(drill 0.2032)
		(layers "F.Cu" "B.Cu")
		(net "GND")
	)
	(via
		(at 283.252418 -210.152996)
		(size 0.508)
		(drill 0.254)
		(layers "F.Cu" "B.Cu")
		(net "GND")
	)
	(via
		(at 226.75723 -2.458974)
		(size 0.508)
		(drill 0.254)
		(layers "F.Cu" "B.Cu")
		(net "GND")
	)
	(via
		(at 154.295602 -68.734432)
		(size 0.7112)
		(drill 0.4064)
		(layers "F.Cu" "B.Cu")
		(net "GND")
	)
	(via
		(at 24.532336 -49.5554)
		(size 0.508)
		(drill 0.254)
		(layers "F.Cu" "B.Cu")
		(net "GND")
	)
	(via
		(at 64.899794 -223.082104)
		(size 0.508)
		(drill 0.254)
		(layers "F.Cu" "B.Cu")
		(net "GND")
	)
	(via
		(at 225.100134 -43.50004)
		(size 0.4572)
		(drill 0.2032)
		(layers "F.Cu" "B.Cu")
		(net "GND")
	)
	(via
		(at 87.376 -50.165)
		(size 0.7112)
		(drill 0.4064)
		(layers "F.Cu" "B.Cu")
		(net "GND")
	)
	(via
		(at 254.099822 -49.499774)
		(size 0.4572)
		(drill 0.2032)
		(layers "F.Cu" "B.Cu")
		(net "GND")
	)
	(via
		(at 238.100108 -45.500036)
		(size 0.4572)
		(drill 0.2032)
		(layers "F.Cu" "B.Cu")
		(net "GND")
	)
	(via
		(at 130.899916 -42.925492)
		(size 0.508)
		(drill 0.254)
		(layers "F.Cu" "B.Cu")
		(net "GND")
	)
	(via
		(at 45.9359 -72.5551)
		(size 0.508)
		(drill 0.254)
		(layers "F.Cu" "B.Cu")
		(net "GND")
	)
	(via
		(at 251.099828 -31.500064)
		(size 0.4572)
		(drill 0.2032)
		(layers "F.Cu" "B.Cu")
		(net "GND")
	)
	(via
		(at 246.099838 -44.500038)
		(size 0.4572)
		(drill 0.2032)
		(layers "F.Cu" "B.Cu")
		(net "GND")
	)
	(via
		(at 342.519 -181.102)
		(size 0.508)
		(drill 0.254)
		(layers "F.Cu" "B.Cu")
		(net "GND")
	)
	(via
		(at 234.100116 -56.49976)
		(size 0.4572)
		(drill 0.2032)
		(layers "F.Cu" "B.Cu")
		(net "GND")
	)
	(via
		(at 65.913 -35.179)
		(size 0.7112)
		(drill 0.4064)
		(layers "F.Cu" "B.Cu")
		(net "GND")
	)
	(via
		(at 227.838 -94.107)
		(size 0.508)
		(drill 0.254)
		(layers "F.Cu" "B.Cu")
		(net "GND")
	)
	(via
		(at 190.052198 -49.286668)
		(size 0.508)
		(drill 0.254)
		(layers "F.Cu" "B.Cu")
		(net "GND")
	)
	(via
		(at 21.7424 -53.5432)
		(size 0.508)
		(drill 0.254)
		(layers "F.Cu" "B.Cu")
		(net "GND")
	)
	(via
		(at 168.2242 -16.0782)
		(size 0.508)
		(drill 0.254)
		(layers "F.Cu" "B.Cu")
		(net "GND")
	)
	(via
		(at 102.65918 -82.983832)
		(size 0.508)
		(drill 0.254)
		(layers "F.Cu" "B.Cu")
		(net "GND")
	)
	(via
		(at 38.10508 -130.485134)
		(size 0.4572)
		(drill 0.2032)
		(layers "F.Cu" "B.Cu")
		(net "GND")
	)
	(via
		(at 249.063764 -6.751574)
		(size 0.7112)
		(drill 0.4064)
		(layers "F.Cu" "B.Cu")
		(net "GND")
	)
	(via
		(at 316.100206 -223.082104)
		(size 0.508)
		(drill 0.254)
		(layers "F.Cu" "B.Cu")
		(net "GND")
	)
	(via
		(at 224.100136 -56.49976)
		(size 0.4572)
		(drill 0.2032)
		(layers "F.Cu" "B.Cu")
		(net "GND")
	)
	(via
		(at 244.099842 -37.500052)
		(size 0.4572)
		(drill 0.2032)
		(layers "F.Cu" "B.Cu")
		(net "GND")
	)
	(via
		(at 257.099816 -49.499774)
		(size 0.4572)
		(drill 0.2032)
		(layers "F.Cu" "B.Cu")
		(net "GND")
	)
	(via
		(at 38.168326 -155.98013)
		(size 0.4572)
		(drill 0.2032)
		(layers "F.Cu" "B.Cu")
		(net "GND")
	)
	(via
		(at 65.913 -37.5285)
		(size 0.508)
		(drill 0.254)
		(layers "F.Cu" "B.Cu")
		(net "GND")
	)
	(via
		(at 225.100134 -50.499772)
		(size 0.4572)
		(drill 0.2032)
		(layers "F.Cu" "B.Cu")
		(net "GND")
	)
	(via
		(at 269.857982 -9.423146)
		(size 0.508)
		(drill 0.254)
		(layers "F.Cu" "B.Cu")
		(net "GND")
	)
	(via
		(at 237.10011 -42.500042)
		(size 0.4572)
		(drill 0.2032)
		(layers "F.Cu" "B.Cu")
		(net "GND")
	)
	(via
		(at 105.747312 -210.152996)
		(size 0.508)
		(drill 0.254)
		(layers "F.Cu" "B.Cu")
		(net "GND")
	)
	(via
		(at 218.2368 -11.9634)
		(size 0.508)
		(drill 0.254)
		(layers "F.Cu" "B.Cu")
		(net "GND")
	)
	(via
		(at 41.402 -53.721)
		(size 0.508)
		(drill 0.254)
		(layers "F.Cu" "B.Cu")
		(net "GND")
	)
	(via
		(at 249.099832 -64.499744)
		(size 0.4572)
		(drill 0.2032)
		(layers "F.Cu" "B.Cu")
		(net "GND")
	)
	(via
		(at 154.31008 -34.99612)
		(size 0.508)
		(drill 0.254)
		(layers "F.Cu" "B.Cu")
		(net "GND")
	)
	(via
		(at 44.196 -204.216)
		(size 0.508)
		(drill 0.254)
		(layers "F.Cu" "B.Cu")
		(net "GND")
	)
	(via
		(at 311.9882 -23.6474)
		(size 0.508)
		(drill 0.254)
		(layers "F.Cu" "B.Cu")
		(net "GND")
	)
	(via
		(at 245.09984 -52.499768)
		(size 0.4572)
		(drill 0.2032)
		(layers "F.Cu" "B.Cu")
		(net "GND")
	)
	(via
		(at 159.512 -23.622)
		(size 0.508)
		(drill 0.254)
		(layers "F.Cu" "B.Cu")
		(net "GND")
	)
	(via
		(at 160.782 -91.567)
		(size 0.508)
		(drill 0.254)
		(layers "F.Cu" "B.Cu")
		(net "GND")
	)
	(via
		(at 154.321002 -73.052432)
		(size 0.7112)
		(drill 0.4064)
		(layers "F.Cu" "B.Cu")
		(net "GND")
	)
	(via
		(at 242.099846 -42.500042)
		(size 0.4572)
		(drill 0.2032)
		(layers "F.Cu" "B.Cu")
		(net "GND")
	)
	(via
		(at 149.352 -14.5288)
		(size 0.508)
		(drill 0.254)
		(layers "F.Cu" "B.Cu")
		(net "GND")
	)
	(via
		(at 57.909206 -21.231606)
		(size 0.508)
		(drill 0.254)
		(layers "F.Cu" "B.Cu")
		(net "GND")
	)
	(via
		(at 224.100136 -37.500052)
		(size 0.4572)
		(drill 0.2032)
		(layers "F.Cu" "B.Cu")
		(net "GND")
	)
	(via
		(at 19.8882 -161.0995)
		(size 0.508)
		(drill 0.254)
		(layers "F.Cu" "B.Cu")
		(net "GND")
	)
	(via
		(at 286.500062 -223.082104)
		(size 0.508)
		(drill 0.254)
		(layers "F.Cu" "B.Cu")
		(net "GND")
	)
	(via
		(at 136.398 -177.927)
		(size 0.7112)
		(drill 0.3556)
		(layers "F.Cu" "B.Cu")
		(net "GND")
	)
	(via
		(at 252.099826 -43.50004)
		(size 0.4572)
		(drill 0.2032)
		(layers "F.Cu" "B.Cu")
		(net "GND")
	)
	(via
		(at 248.031 -1.143)
		(size 0.508)
		(drill 0.254)
		(layers "F.Cu" "B.Cu")
		(net "GND")
	)
	(via
		(at 198.501 -21.6154)
		(size 0.508)
		(drill 0.254)
		(layers "F.Cu" "B.Cu")
		(net "GND")
	)
	(via
		(at 320.947288 -210.152996)
		(size 0.508)
		(drill 0.254)
		(layers "F.Cu" "B.Cu")
		(net "GND")
	)
	(via
		(at 138.303 -14.5796)
		(size 0.508)
		(drill 0.254)
		(layers "F.Cu" "B.Cu")
		(net "GND")
	)
	(via
		(at 166.8018 -14.5796)
		(size 0.508)
		(drill 0.254)
		(layers "F.Cu" "B.Cu")
		(net "GND")
	)
	(via
		(at 42.126154 -160.185354)
		(size 0.508)
		(drill 0.254)
		(layers "F.Cu" "B.Cu")
		(net "GND")
	)
	(via
		(at 88.852502 -210.152996)
		(size 0.508)
		(drill 0.254)
		(layers "F.Cu" "B.Cu")
		(net "GND")
	)
	(via
		(at 54.229 -184.15)
		(size 0.508)
		(drill 0.254)
		(layers "F.Cu" "B.Cu")
		(net "GND")
	)
	(via
		(at 242.099846 -60.499752)
		(size 0.4572)
		(drill 0.2032)
		(layers "F.Cu" "B.Cu")
		(net "GND")
	)
	(via
		(at 227.400612 -192.75679)
		(size 0.508)
		(drill 0.254)
		(layers "F.Cu" "B.Cu")
		(net "GND")
	)
	(via
		(at 173.421802 -60.454032)
		(size 0.7112)
		(drill 0.4064)
		(layers "F.Cu" "B.Cu")
		(net "GND")
	)
	(via
		(at 22.81555 -175.99025)
		(size 0.508)
		(drill 0.254)
		(layers "F.Cu" "B.Cu")
		(net "GND")
	)
	(via
		(at 337.256628 -56.281066)
		(size 0.7112)
		(drill 0.4064)
		(layers "F.Cu" "B.Cu")
		(net "GND")
	)
	(via
		(at 84.147152 -210.152996)
		(size 0.508)
		(drill 0.254)
		(layers "F.Cu" "B.Cu")
		(net "GND")
	)
	(via
		(at 1.397 -40.531034)
		(size 0.508)
		(drill 0.254)
		(layers "F.Cu" "B.Cu")
		(net "GND")
	)
	(via
		(at 224.706434 -196.977)
		(size 0.508)
		(drill 0.254)
		(layers "F.Cu" "B.Cu")
		(net "GND")
	)
	(via
		(at 29.464 -53.721)
		(size 0.508)
		(drill 0.254)
		(layers "F.Cu" "B.Cu")
		(net "GND")
	)
	(via
		(at 48.26 -184.15)
		(size 0.508)
		(drill 0.254)
		(layers "F.Cu" "B.Cu")
		(net "GND")
	)
	(via
		(at 314.253626 -36.17468)
		(size 0.508)
		(drill 0.254)
		(layers "F.Cu" "B.Cu")
		(net "GND")
	)
	(via
		(at 139.747244 -210.152996)
		(size 0.508)
		(drill 0.254)
		(layers "F.Cu" "B.Cu")
		(net "GND")
	)
	(via
		(at 233.100118 -32.500062)
		(size 0.4572)
		(drill 0.2032)
		(layers "F.Cu" "B.Cu")
		(net "GND")
	)
	(via
		(at 310.2102 -19.9136)
		(size 0.508)
		(drill 0.254)
		(layers "F.Cu" "B.Cu")
		(net "GND")
	)
	(via
		(at 204.499972 -223.082104)
		(size 0.508)
		(drill 0.254)
		(layers "F.Cu" "B.Cu")
		(net "GND")
	)
	(via
		(at 38.117526 -162.687)
		(size 0.508)
		(drill 0.254)
		(layers "F.Cu" "B.Cu")
		(net "GND")
	)
	(via
		(at 151.831802 -60.733432)
		(size 0.508)
		(drill 0.254)
		(layers "F.Cu" "B.Cu")
		(net "GND")
	)
	(via
		(at 236.100112 -55.499762)
		(size 0.4572)
		(drill 0.2032)
		(layers "F.Cu" "B.Cu")
		(net "GND")
	)
	(via
		(at 32.568134 -156.779976)
		(size 0.4572)
		(drill 0.2032)
		(layers "F.Cu" "B.Cu")
		(net "GND")
	)
	(via
		(at 169.0116 -18.415)
		(size 0.508)
		(drill 0.254)
		(layers "F.Cu" "B.Cu")
		(net "GND")
	)
	(via
		(at 241.099848 -54.499764)
		(size 0.4572)
		(drill 0.2032)
		(layers "F.Cu" "B.Cu")
		(net "GND")
	)
	(via
		(at 5.8674 -57.023)
		(size 0.508)
		(drill 0.254)
		(layers "F.Cu" "B.Cu")
		(net "GND")
	)
	(via
		(at 182.76697 -8.4074)
		(size 0.508)
		(drill 0.254)
		(layers "F.Cu" "B.Cu")
		(net "GND")
	)
	(via
		(at 40.500046 -223.082104)
		(size 0.508)
		(drill 0.254)
		(layers "F.Cu" "B.Cu")
		(net "GND")
	)
	(via
		(at 331.756512 -171.196)
		(size 0.508)
		(drill 0.254)
		(layers "F.Cu" "B.Cu")
		(net "GND")
	)
	(via
		(at 1.397 -91.331034)
		(size 0.508)
		(drill 0.254)
		(layers "F.Cu" "B.Cu")
		(net "GND")
	)
	(via
		(at 318.643 -12.9794)
		(size 0.508)
		(drill 0.254)
		(layers "F.Cu" "B.Cu")
		(net "GND")
	)
	(via
		(at 57.827926 -1.397)
		(size 0.508)
		(drill 0.254)
		(layers "F.Cu" "B.Cu")
		(net "GND")
	)
	(via
		(at 242.099846 -58.499756)
		(size 0.4572)
		(drill 0.2032)
		(layers "F.Cu" "B.Cu")
		(net "GND")
	)
	(via
		(at 147.066 -22.1488)
		(size 0.508)
		(drill 0.254)
		(layers "F.Cu" "B.Cu")
		(net "GND")
	)
	(via
		(at 38.062154 -160.337754)
		(size 0.508)
		(drill 0.254)
		(layers "F.Cu" "B.Cu")
		(net "GND")
	)
	(via
		(at 245.09984 -41.500044)
		(size 0.4572)
		(drill 0.2032)
		(layers "F.Cu" "B.Cu")
		(net "GND")
	)
	(via
		(at 232.10012 -58.499756)
		(size 0.4572)
		(drill 0.2032)
		(layers "F.Cu" "B.Cu")
		(net "GND")
	)
	(via
		(at 340.868 -66.421)
		(size 0.508)
		(drill 0.254)
		(layers "F.Cu" "B.Cu")
		(net "GND")
	)
	(via
		(at 15.4051 -176.2887)
		(size 0.508)
		(drill 0.254)
		(layers "F.Cu" "B.Cu")
		(net "GND")
	)
	(via
		(at 248.285 -139.7)
		(size 0.508)
		(drill 0.254)
		(layers "F.Cu" "B.Cu")
		(net "GND")
	)
	(via
		(at 224.100136 -52.499768)
		(size 0.4572)
		(drill 0.2032)
		(layers "F.Cu" "B.Cu")
		(net "GND")
	)
	(via
		(at 257.099816 -60.499752)
		(size 0.4572)
		(drill 0.2032)
		(layers "F.Cu" "B.Cu")
		(net "GND")
	)
	(via
		(at 191.699896 -223.082104)
		(size 0.508)
		(drill 0.254)
		(layers "F.Cu" "B.Cu")
		(net "GND")
	)
	(via
		(at 239.100106 -44.500038)
		(size 0.4572)
		(drill 0.2032)
		(layers "F.Cu" "B.Cu")
		(net "GND")
	)
	(via
		(at 2.54508 -212.102954)
		(size 0.508)
		(drill 0.254)
		(layers "F.Cu" "B.Cu")
		(net "GND")
	)
	(via
		(at 245.09984 -64.499744)
		(size 0.4572)
		(drill 0.2032)
		(layers "F.Cu" "B.Cu")
		(net "GND")
	)
	(via
		(at 34.6456 -187.5282)
		(size 0.508)
		(drill 0.254)
		(layers "F.Cu" "B.Cu")
		(net "GND")
	)
	(via
		(at 349.758 -184.15)
		(size 0.508)
		(drill 0.254)
		(layers "F.Cu" "B.Cu")
		(net "GND")
	)
	(via
		(at 252.099826 -40.500046)
		(size 0.4572)
		(drill 0.2032)
		(layers "F.Cu" "B.Cu")
		(net "GND")
	)
	(via
		(at 237.10011 -53.499766)
		(size 0.4572)
		(drill 0.2032)
		(layers "F.Cu" "B.Cu")
		(net "GND")
	)
	(via
		(at 67.156838 -40.888158)
		(size 0.508)
		(drill 0.254)
		(layers "F.Cu" "B.Cu")
		(net "GND")
	)
	(via
		(at 38.10508 -129.685034)
		(size 0.4572)
		(drill 0.2032)
		(layers "F.Cu" "B.Cu")
		(net "GND")
	)
	(via
		(at 235.100114 -56.49976)
		(size 0.4572)
		(drill 0.2032)
		(layers "F.Cu" "B.Cu")
		(net "GND")
	)
	(via
		(at 239.100106 -60.499752)
		(size 0.4572)
		(drill 0.2032)
		(layers "F.Cu" "B.Cu")
		(net "GND")
	)
	(via
		(at 248.099834 -42.500042)
		(size 0.4572)
		(drill 0.2032)
		(layers "F.Cu" "B.Cu")
		(net "GND")
	)
	(via
		(at 45.1358 -183.8706)
		(size 0.508)
		(drill 0.254)
		(layers "F.Cu" "B.Cu")
		(net "GND")
	)
	(via
		(at 265.747246 -210.152996)
		(size 0.508)
		(drill 0.254)
		(layers "F.Cu" "B.Cu")
		(net "GND")
	)
	(via
		(at 35.310826 -112.566958)
		(size 0.508)
		(drill 0.254)
		(layers "F.Cu" "B.Cu")
		(net "GND")
	)
	(via
		(at 151.765 -89.4207)
		(size 0.508)
		(drill 0.254)
		(layers "F.Cu" "B.Cu")
		(net "GND")
	)
	(via
		(at 224.100136 -54.499764)
		(size 0.4572)
		(drill 0.2032)
		(layers "F.Cu" "B.Cu")
		(net "GND")
	)
	(via
		(at 68.147184 -210.152996)
		(size 0.508)
		(drill 0.254)
		(layers "F.Cu" "B.Cu")
		(net "GND")
	)
	(via
		(at 233.100118 -53.499766)
		(size 0.4572)
		(drill 0.2032)
		(layers "F.Cu" "B.Cu")
		(net "GND")
	)
	(via
		(at 306.197 -84.9376)
		(size 0.508)
		(drill 0.254)
		(layers "F.Cu" "B.Cu")
		(net "GND")
	)
	(via
		(at 154.052524 -210.152996)
		(size 0.508)
		(drill 0.254)
		(layers "F.Cu" "B.Cu")
		(net "GND")
	)
	(via
		(at 264.541 -173.228)
		(size 0.508)
		(drill 0.254)
		(layers "F.Cu" "B.Cu")
		(net "GND")
	)
	(via
		(at 113.8428 -134.9756)
		(size 0.508)
		(drill 0.254)
		(layers "F.Cu" "B.Cu")
		(net "GND")
	)
	(via
		(at 25.6286 -44.1452)
		(size 0.508)
		(drill 0.254)
		(layers "F.Cu" "B.Cu")
		(net "GND")
	)
	(via
		(at 350.012 -204.9526)
		(size 0.508)
		(drill 0.254)
		(layers "F.Cu" "B.Cu")
		(net "GND")
	)
	(via
		(at 177.347118 -210.152996)
		(size 0.508)
		(drill 0.254)
		(layers "F.Cu" "B.Cu")
		(net "GND")
	)
	(via
		(at 256.099818 -53.499766)
		(size 0.4572)
		(drill 0.2032)
		(layers "F.Cu" "B.Cu")
		(net "GND")
	)
	(via
		(at 201.34707 -210.152996)
		(size 0.508)
		(drill 0.254)
		(layers "F.Cu" "B.Cu")
		(net "GND")
	)
	(via
		(at 347.5482 -68.0212)
		(size 0.508)
		(drill 0.254)
		(layers "F.Cu" "B.Cu")
		(net "GND")
	)
	(via
		(at 260.5278 -1.9304)
		(size 0.508)
		(drill 0.254)
		(layers "F.Cu" "B.Cu")
		(net "GND")
	)
	(via
		(at 22.1488 -145.8595)
		(size 0.508)
		(drill 0.254)
		(layers "F.Cu" "B.Cu")
		(net "GND")
	)
	(via
		(at 169.252392 -210.152996)
		(size 0.508)
		(drill 0.254)
		(layers "F.Cu" "B.Cu")
		(net "GND")
	)
	(via
		(at 181.4322 -73.914)
		(size 0.7112)
		(drill 0.4064)
		(layers "F.Cu" "B.Cu")
		(net "GND")
	)
	(via
		(at 29.464 -51.308)
		(size 0.508)
		(drill 0.254)
		(layers "F.Cu" "B.Cu")
		(net "GND")
	)
	(via
		(at 315.595 -53.086)
		(size 0.7112)
		(drill 0.4064)
		(layers "F.Cu" "B.Cu")
		(net "GND")
	)
	(via
		(at 252.099826 -44.500038)
		(size 0.4572)
		(drill 0.2032)
		(layers "F.Cu" "B.Cu")
		(net "GND")
	)
	(via
		(at 158.947358 -210.152996)
		(size 0.508)
		(drill 0.254)
		(layers "F.Cu" "B.Cu")
		(net "GND")
	)
	(via
		(at 142.320772 -67.868546)
		(size 0.7112)
		(drill 0.4064)
		(layers "F.Cu" "B.Cu")
		(net "GND")
	)
	(via
		(at 1.397 -162.451034)
		(size 0.508)
		(drill 0.254)
		(layers "F.Cu" "B.Cu")
		(net "GND")
	)
	(via
		(at 354.203 -50.705004)
		(size 0.508)
		(drill 0.254)
		(layers "F.Cu" "B.Cu")
		(net "GND")
	)
	(via
		(at 230.100124 -55.499762)
		(size 0.4572)
		(drill 0.2032)
		(layers "F.Cu" "B.Cu")
		(net "GND")
	)
	(via
		(at 29.507942 -107.284266)
		(size 0.508)
		(drill 0.254)
		(layers "F.Cu" "B.Cu")
		(net "GND")
	)
	(via
		(at 241.099848 -66.49974)
		(size 0.4572)
		(drill 0.2032)
		(layers "F.Cu" "B.Cu")
		(net "GND")
	)
	(via
		(at 1.397 -55.771034)
		(size 0.508)
		(drill 0.254)
		(layers "F.Cu" "B.Cu")
		(net "GND")
	)
	(via
		(at 256.099818 -55.499762)
		(size 0.4572)
		(drill 0.2032)
		(layers "F.Cu" "B.Cu")
		(net "GND")
	)
	(via
		(at 222.10014 -41.500044)
		(size 0.4572)
		(drill 0.2032)
		(layers "F.Cu" "B.Cu")
		(net "GND")
	)
	(via
		(at 354.203 -101.505004)
		(size 0.508)
		(drill 0.254)
		(layers "F.Cu" "B.Cu")
		(net "GND")
	)
	(via
		(at 239.100106 -63.499746)
		(size 0.4572)
		(drill 0.2032)
		(layers "F.Cu" "B.Cu")
		(net "GND")
	)
	(via
		(at 61.272674 -60.672726)
		(size 0.508)
		(drill 0.254)
		(layers "F.Cu" "B.Cu")
		(net "GND")
	)
	(via
		(at 142.320772 -69.138546)
		(size 0.7112)
		(drill 0.4064)
		(layers "F.Cu" "B.Cu")
		(net "GND")
	)
	(via
		(at 146.5072 -93.7768)
		(size 0.508)
		(drill 0.254)
		(layers "F.Cu" "B.Cu")
		(net "GND")
	)
	(via
		(at 256.099818 -48.499776)
		(size 0.4572)
		(drill 0.2032)
		(layers "F.Cu" "B.Cu")
		(net "GND")
	)
	(via
		(at 36.195 -220.345)
		(size 0.508)
		(drill 0.254)
		(layers "F.Cu" "B.Cu")
		(net "GND")
	)
	(via
		(at 235.100114 -51.49977)
		(size 0.4572)
		(drill 0.2032)
		(layers "F.Cu" "B.Cu")
		(net "GND")
	)
	(via
		(at 223.100138 -61.49975)
		(size 0.4572)
		(drill 0.2032)
		(layers "F.Cu" "B.Cu")
		(net "GND")
	)
	(via
		(at 154.371802 -58.828432)
		(size 0.508)
		(drill 0.254)
		(layers "F.Cu" "B.Cu")
		(net "GND")
	)
	(via
		(at 114.935 -38.9382)
		(size 0.508)
		(drill 0.254)
		(layers "F.Cu" "B.Cu")
		(net "GND")
	)
	(via
		(at 38.209474 -106.757724)
		(size 0.508)
		(drill 0.254)
		(layers "F.Cu" "B.Cu")
		(net "GND")
	)
	(via
		(at 19.63166 -87.429848)
		(size 0.508)
		(drill 0.254)
		(layers "F.Cu" "B.Cu")
		(net "GND")
	)
	(via
		(at 105.699814 -223.082104)
		(size 0.508)
		(drill 0.254)
		(layers "F.Cu" "B.Cu")
		(net "GND")
	)
	(via
		(at 120.0404 -121.3358)
		(size 0.508)
		(drill 0.254)
		(layers "F.Cu" "B.Cu")
		(net "GND")
	)
	(via
		(at 208.28 -223.0628)
		(size 0.508)
		(drill 0.254)
		(layers "F.Cu" "B.Cu")
		(net "GND")
	)
	(via
		(at 227.10013 -56.49976)
		(size 0.4572)
		(drill 0.2032)
		(layers "F.Cu" "B.Cu")
		(net "GND")
	)
	(via
		(at 267.92809 -10.258044)
		(size 0.508)
		(drill 0.254)
		(layers "F.Cu" "B.Cu")
		(net "GND")
	)
	(via
		(at 224.100136 -35.500056)
		(size 0.4572)
		(drill 0.2032)
		(layers "F.Cu" "B.Cu")
		(net "GND")
	)
	(via
		(at 252.099826 -55.499762)
		(size 0.4572)
		(drill 0.2032)
		(layers "F.Cu" "B.Cu")
		(net "GND")
	)
	(via
		(at 246.099838 -42.500042)
		(size 0.4572)
		(drill 0.2032)
		(layers "F.Cu" "B.Cu")
		(net "GND")
	)
	(via
		(at 234.100116 -52.499768)
		(size 0.4572)
		(drill 0.2032)
		(layers "F.Cu" "B.Cu")
		(net "GND")
	)
	(via
		(at 68.541646 -78.337156)
		(size 0.508)
		(drill 0.254)
		(layers "F.Cu" "B.Cu")
		(net "GND")
	)
	(via
		(at 170.7134 -76.1492)
		(size 0.7112)
		(drill 0.4064)
		(layers "F.Cu" "B.Cu")
		(net "GND")
	)
	(via
		(at 185.4962 -58.0898)
		(size 0.7112)
		(drill 0.4064)
		(layers "F.Cu" "B.Cu")
		(net "GND")
	)
	(via
		(at 313.055 -23.0886)
		(size 0.508)
		(drill 0.254)
		(layers "F.Cu" "B.Cu")
		(net "GND")
	)
	(via
		(at 300.706536 -15.645892)
		(size 0.508)
		(drill 0.254)
		(layers "F.Cu" "B.Cu")
		(net "GND")
	)
	(via
		(at 66.7766 -42.291)
		(size 0.7112)
		(drill 0.4064)
		(layers "F.Cu" "B.Cu")
		(net "GND")
	)
	(via
		(at 245.09984 -55.499762)
		(size 0.4572)
		(drill 0.2032)
		(layers "F.Cu" "B.Cu")
		(net "GND")
	)
	(via
		(at 63.22822 -90.932)
		(size 0.508)
		(drill 0.254)
		(layers "F.Cu" "B.Cu")
		(net "GND")
	)
	(via
		(at 272.822162 -11.426952)
		(size 0.508)
		(drill 0.254)
		(layers "F.Cu" "B.Cu")
		(net "GND")
	)
	(via
		(at 232.10012 -48.499776)
		(size 0.4572)
		(drill 0.2032)
		(layers "F.Cu" "B.Cu")
		(net "GND")
	)
	(via
		(at 241.099848 -59.499754)
		(size 0.4572)
		(drill 0.2032)
		(layers "F.Cu" "B.Cu")
		(net "GND")
	)
	(via
		(at 85.652356 -210.152996)
		(size 0.508)
		(drill 0.254)
		(layers "F.Cu" "B.Cu")
		(net "GND")
	)
	(via
		(at 232.745026 -167.281352)
		(size 0.508)
		(drill 0.254)
		(layers "F.Cu" "B.Cu")
		(net "GND")
	)
	(via
		(at 218.059 -10.16)
		(size 0.508)
		(drill 0.254)
		(layers "F.Cu" "B.Cu")
		(net "GND")
	)
	(via
		(at 38.10508 -131.28498)
		(size 0.4572)
		(drill 0.2032)
		(layers "F.Cu" "B.Cu")
		(net "GND")
	)
	(via
		(at 154.371802 -63.527432)
		(size 0.508)
		(drill 0.254)
		(layers "F.Cu" "B.Cu")
		(net "GND")
	)
	(via
		(at 134.9756 -26.1366)
		(size 0.508)
		(drill 0.254)
		(layers "F.Cu" "B.Cu")
		(net "GND")
	)
	(via
		(at 249.099832 -55.499762)
		(size 0.4572)
		(drill 0.2032)
		(layers "F.Cu" "B.Cu")
		(net "GND")
	)
	(via
		(at 166.7256 -26.0604)
		(size 0.508)
		(drill 0.254)
		(layers "F.Cu" "B.Cu")
		(net "GND")
	)
	(via
		(at 117.5258 -93.8022)
		(size 0.508)
		(drill 0.254)
		(layers "F.Cu" "B.Cu")
		(net "GND")
	)
	(via
		(at 142.400782 -32.508952)
		(size 0.508)
		(drill 0.254)
		(layers "F.Cu" "B.Cu")
		(net "GND")
	)
	(via
		(at 225.100134 -41.500044)
		(size 0.4572)
		(drill 0.2032)
		(layers "F.Cu" "B.Cu")
		(net "GND")
	)
	(via
		(at 246.099838 -63.499746)
		(size 0.4572)
		(drill 0.2032)
		(layers "F.Cu" "B.Cu")
		(net "GND")
	)
	(via
		(at 304.900076 -223.082104)
		(size 0.508)
		(drill 0.254)
		(layers "F.Cu" "B.Cu")
		(net "GND")
	)
	(via
		(at 354.203 -162.465004)
		(size 0.508)
		(drill 0.254)
		(layers "F.Cu" "B.Cu")
		(net "GND")
	)
	(via
		(at 170.5102 -19.8374)
		(size 0.508)
		(drill 0.254)
		(layers "F.Cu" "B.Cu")
		(net "GND")
	)
	(via
		(at 36.195 -217.551)
		(size 0.508)
		(drill 0.254)
		(layers "F.Cu" "B.Cu")
		(net "GND")
	)
	(via
		(at 231.100122 -41.500044)
		(size 0.4572)
		(drill 0.2032)
		(layers "F.Cu" "B.Cu")
		(net "GND")
	)
	(via
		(at 128.2954 -41.8592)
		(size 0.508)
		(drill 0.254)
		(layers "F.Cu" "B.Cu")
		(net "GND")
	)
	(via
		(at 147.7518 -91.6178)
		(size 0.508)
		(drill 0.254)
		(layers "F.Cu" "B.Cu")
		(net "GND")
	)
	(via
		(at 17.591532 -153.162)
		(size 0.508)
		(drill 0.254)
		(layers "F.Cu" "B.Cu")
		(net "GND")
	)
	(via
		(at 65.913 -36.3855)
		(size 0.508)
		(drill 0.254)
		(layers "F.Cu" "B.Cu")
		(net "GND")
	)
	(via
		(at 38.967918 -155.98013)
		(size 0.4572)
		(drill 0.2032)
		(layers "F.Cu" "B.Cu")
		(net "GND")
	)
	(via
		(at 137.034778 -84.019898)
		(size 0.508)
		(drill 0.254)
		(layers "F.Cu" "B.Cu")
		(net "GND")
	)
	(via
		(at 37.30498 -130.485134)
		(size 0.4572)
		(drill 0.2032)
		(layers "F.Cu" "B.Cu")
		(net "GND")
	)
	(via
		(at 231.100122 -55.499762)
		(size 0.4572)
		(drill 0.2032)
		(layers "F.Cu" "B.Cu")
		(net "GND")
	)
	(via
		(at 40.96512 -142.6718)
		(size 0.4572)
		(drill 0.2032)
		(layers "F.Cu" "B.Cu")
		(net "GND")
	)
	(via
		(at 319.659 -85.217)
		(size 0.508)
		(drill 0.254)
		(layers "F.Cu" "B.Cu")
		(net "GND")
	)
	(via
		(at 350.918272 -45.867066)
		(size 0.508)
		(drill 0.254)
		(layers "F.Cu" "B.Cu")
		(net "GND")
	)
	(via
		(at 64.643 -39.9415)
		(size 0.508)
		(drill 0.254)
		(layers "F.Cu" "B.Cu")
		(net "GND")
	)
	(via
		(at 81.9658 -136.271)
		(size 0.508)
		(drill 0.254)
		(layers "F.Cu" "B.Cu")
		(net "GND")
	)
	(via
		(at 170.0276 -23.6728)
		(size 0.508)
		(drill 0.254)
		(layers "F.Cu" "B.Cu")
		(net "GND")
	)
	(via
		(at 307.439314 -39.80942)
		(size 0.508)
		(drill 0.254)
		(layers "F.Cu" "B.Cu")
		(net "GND")
	)
	(via
		(at 199.652382 -210.152996)
		(size 0.508)
		(drill 0.254)
		(layers "F.Cu" "B.Cu")
		(net "GND")
	)
	(via
		(at 69.922644 -128.115568)
		(size 0.508)
		(drill 0.254)
		(layers "F.Cu" "B.Cu")
		(net "GND")
	)
	(via
		(at 308.3814 -119.3292)
		(size 0.508)
		(drill 0.254)
		(layers "F.Cu" "B.Cu")
		(net "GND")
	)
	(via
		(at 243.560092 -162.602926)
		(size 0.508)
		(drill 0.254)
		(layers "F.Cu" "B.Cu")
		(net "GND")
	)
	(via
		(at 154.321002 -66.321432)
		(size 0.7112)
		(drill 0.4064)
		(layers "F.Cu" "B.Cu")
		(net "GND")
	)
	(via
		(at 157.25267 -210.152996)
		(size 0.508)
		(drill 0.254)
		(layers "F.Cu" "B.Cu")
		(net "GND")
	)
	(via
		(at 28.321 -115.4938)
		(size 0.508)
		(drill 0.254)
		(layers "F.Cu" "B.Cu")
		(net "GND")
	)
	(via
		(at 54.173628 -47.866808)
		(size 0.508)
		(drill 0.254)
		(layers "F.Cu" "B.Cu")
		(net "GND")
	)
	(via
		(at 191.74714 -210.152996)
		(size 0.508)
		(drill 0.254)
		(layers "F.Cu" "B.Cu")
		(net "GND")
	)
	(via
		(at 140.753846 -50.858166)
		(size 0.508)
		(drill 0.254)
		(layers "F.Cu" "B.Cu")
		(net "GND")
	)
	(via
		(at 312.928 -74.168)
		(size 0.7112)
		(drill 0.4064)
		(layers "F.Cu" "B.Cu")
		(net "GND")
	)
	(via
		(at 43.561 -51.435)
		(size 0.508)
		(drill 0.254)
		(layers "F.Cu" "B.Cu")
		(net "GND")
	)
	(via
		(at 280.269696 -17.19326)
		(size 0.508)
		(drill 0.254)
		(layers "F.Cu" "B.Cu")
		(net "GND")
	)
	(via
		(at 257.099816 -35.500056)
		(size 0.4572)
		(drill 0.2032)
		(layers "F.Cu" "B.Cu")
		(net "GND")
	)
	(via
		(at 308.2036 -90.2716)
		(size 0.508)
		(drill 0.254)
		(layers "F.Cu" "B.Cu")
		(net "GND")
	)
	(via
		(at 249.555 -69.977)
		(size 0.508)
		(drill 0.254)
		(layers "F.Cu" "B.Cu")
		(net "GND")
	)
	(via
		(at 249.099832 -43.50004)
		(size 0.4572)
		(drill 0.2032)
		(layers "F.Cu" "B.Cu")
		(net "GND")
	)
	(via
		(at 267.300202 -223.082104)
		(size 0.508)
		(drill 0.254)
		(layers "F.Cu" "B.Cu")
		(net "GND")
	)
	(via
		(at 251.099828 -54.499764)
		(size 0.4572)
		(drill 0.2032)
		(layers "F.Cu" "B.Cu")
		(net "GND")
	)
	(via
		(at 300.099984 -223.082104)
		(size 0.508)
		(drill 0.254)
		(layers "F.Cu" "B.Cu")
		(net "GND")
	)
	(via
		(at 229.100126 -49.499774)
		(size 0.4572)
		(drill 0.2032)
		(layers "F.Cu" "B.Cu")
		(net "GND")
	)
	(via
		(at 13.589 -175.3108)
		(size 0.508)
		(drill 0.254)
		(layers "F.Cu" "B.Cu")
		(net "GND")
	)
	(via
		(at 231.100122 -46.500034)
		(size 0.4572)
		(drill 0.2032)
		(layers "F.Cu" "B.Cu")
		(net "GND")
	)
	(via
		(at 340.868 -69.215)
		(size 0.508)
		(drill 0.254)
		(layers "F.Cu" "B.Cu")
		(net "GND")
	)
	(via
		(at 218.2622 -2.5146)
		(size 0.508)
		(drill 0.254)
		(layers "F.Cu" "B.Cu")
		(net "GND")
	)
	(via
		(at 354.203 -203.105004)
		(size 0.508)
		(drill 0.254)
		(layers "F.Cu" "B.Cu")
		(net "GND")
	)
	(via
		(at 234.100116 -37.500052)
		(size 0.4572)
		(drill 0.2032)
		(layers "F.Cu" "B.Cu")
		(net "GND")
	)
	(via
		(at 300.7614 -14.2494)
		(size 0.508)
		(drill 0.254)
		(layers "F.Cu" "B.Cu")
		(net "GND")
	)
	(via
		(at 64.643 -36.2585)
		(size 0.508)
		(drill 0.254)
		(layers "F.Cu" "B.Cu")
		(net "GND")
	)
	(via
		(at 239.100106 -30.500066)
		(size 0.4572)
		(drill 0.2032)
		(layers "F.Cu" "B.Cu")
		(net "GND")
	)
	(via
		(at 130.0734 -81.2038)
		(size 0.508)
		(drill 0.254)
		(layers "F.Cu" "B.Cu")
		(net "GND")
	)
	(via
		(at 227.10013 -46.500034)
		(size 0.4572)
		(drill 0.2032)
		(layers "F.Cu" "B.Cu")
		(net "GND")
	)
	(via
		(at 285.242 -25.1968)
		(size 0.508)
		(drill 0.254)
		(layers "F.Cu" "B.Cu")
		(net "GND")
	)
	(via
		(at 38.1508 -185.2676)
		(size 0.508)
		(drill 0.254)
		(layers "F.Cu" "B.Cu")
		(net "GND")
	)
	(via
		(at 55.55615 -35.09645)
		(size 0.508)
		(drill 0.254)
		(layers "F.Cu" "B.Cu")
		(net "GND")
	)
	(via
		(at 305.41214 -36.2839)
		(size 0.508)
		(drill 0.254)
		(layers "F.Cu" "B.Cu")
		(net "GND")
	)
	(via
		(at 269.532862 -6.981952)
		(size 0.508)
		(drill 0.254)
		(layers "F.Cu" "B.Cu")
		(net "GND")
	)
	(via
		(at 29.98724 -188.83884)
		(size 0.508)
		(drill 0.254)
		(layers "F.Cu" "B.Cu")
		(net "GND")
	)
	(via
		(at 286.131 -56.515)
		(size 0.508)
		(drill 0.254)
		(layers "F.Cu" "B.Cu")
		(net "GND")
	)
	(via
		(at 296.672 -71.12)
		(size 0.7112)
		(drill 0.4064)
		(layers "F.Cu" "B.Cu")
		(net "GND")
	)
	(via
		(at 211.016342 -2.286)
		(size 0.508)
		(drill 0.254)
		(layers "F.Cu" "B.Cu")
		(net "GND")
	)
	(via
		(at 239.100106 -56.49976)
		(size 0.4572)
		(drill 0.2032)
		(layers "F.Cu" "B.Cu")
		(net "GND")
	)
	(via
		(at 167.747188 -210.152996)
		(size 0.508)
		(drill 0.254)
		(layers "F.Cu" "B.Cu")
		(net "GND")
	)
	(via
		(at 246.099838 -55.499762)
		(size 0.4572)
		(drill 0.2032)
		(layers "F.Cu" "B.Cu")
		(net "GND")
	)
	(via
		(at 32.49295 -108.735622)
		(size 0.508)
		(drill 0.254)
		(layers "F.Cu" "B.Cu")
		(net "GND")
	)
	(via
		(at 184.3786 -59.3852)
		(size 0.7112)
		(drill 0.4064)
		(layers "F.Cu" "B.Cu")
		(net "GND")
	)
	(via
		(at 325.700136 -223.082104)
		(size 0.508)
		(drill 0.254)
		(layers "F.Cu" "B.Cu")
		(net "GND")
	)
	(via
		(at 241.099848 -65.499742)
		(size 0.4572)
		(drill 0.2032)
		(layers "F.Cu" "B.Cu")
		(net "GND")
	)
	(via
		(at 159.4104 -173.99)
		(size 0.508)
		(drill 0.254)
		(layers "F.Cu" "B.Cu")
		(net "GND")
	)
	(via
		(at 265.7348 -6.223)
		(size 0.508)
		(drill 0.254)
		(layers "F.Cu" "B.Cu")
		(net "GND")
	)
	(via
		(at 16.6116 -77.1652)
		(size 0.508)
		(drill 0.254)
		(layers "F.Cu" "B.Cu")
		(net "GND")
	)
	(via
		(at 171.2722 -26.0096)
		(size 0.508)
		(drill 0.254)
		(layers "F.Cu" "B.Cu")
		(net "GND")
	)
	(via
		(at 1.397 -71.011034)
		(size 0.508)
		(drill 0.254)
		(layers "F.Cu" "B.Cu")
		(net "GND")
	)
	(via
		(at 242.099846 -53.499766)
		(size 0.4572)
		(drill 0.2032)
		(layers "F.Cu" "B.Cu")
		(net "GND")
	)
	(via
		(at 4.718558 -27.407108)
		(size 0.508)
		(drill 0.254)
		(layers "F.Cu" "B.Cu")
		(net "GND")
	)
	(via
		(at 7.62508 -212.102954)
		(size 0.508)
		(drill 0.254)
		(layers "F.Cu" "B.Cu")
		(net "GND")
	)
	(via
		(at 5.5372 -47.7774)
		(size 0.508)
		(drill 0.254)
		(layers "F.Cu" "B.Cu")
		(net "GND")
	)
	(via
		(at 232.10012 -50.499772)
		(size 0.4572)
		(drill 0.2032)
		(layers "F.Cu" "B.Cu")
		(net "GND")
	)
	(via
		(at 18.034 -55.0164)
		(size 0.508)
		(drill 0.254)
		(layers "F.Cu" "B.Cu")
		(net "GND")
	)
	(via
		(at 226.100132 -41.500044)
		(size 0.4572)
		(drill 0.2032)
		(layers "F.Cu" "B.Cu")
		(net "GND")
	)
	(via
		(at 324.0532 -19.2786)
		(size 0.508)
		(drill 0.254)
		(layers "F.Cu" "B.Cu")
		(net "GND")
	)
	(via
		(at 79.375 -223.0628)
		(size 0.508)
		(drill 0.254)
		(layers "F.Cu" "B.Cu")
		(net "GND")
	)
	(via
		(at 239.100106 -31.500064)
		(size 0.4572)
		(drill 0.2032)
		(layers "F.Cu" "B.Cu")
		(net "GND")
	)
	(via
		(at 244.099842 -55.499762)
		(size 0.4572)
		(drill 0.2032)
		(layers "F.Cu" "B.Cu")
		(net "GND")
	)
	(via
		(at 309.65267 -210.152996)
		(size 0.508)
		(drill 0.254)
		(layers "F.Cu" "B.Cu")
		(net "GND")
	)
	(via
		(at 251.099828 -55.499762)
		(size 0.4572)
		(drill 0.2032)
		(layers "F.Cu" "B.Cu")
		(net "GND")
	)
	(via
		(at 154.371802 -60.733432)
		(size 0.508)
		(drill 0.254)
		(layers "F.Cu" "B.Cu")
		(net "GND")
	)
	(via
		(at 103.251 -35.9918)
		(size 0.508)
		(drill 0.254)
		(layers "F.Cu" "B.Cu")
		(net "GND")
	)
	(via
		(at 339.9028 -175.2092)
		(size 0.508)
		(drill 0.254)
		(layers "F.Cu" "B.Cu")
		(net "GND")
	)
	(via
		(at 71.3232 -219.329)
		(size 0.508)
		(drill 0.254)
		(layers "F.Cu" "B.Cu")
		(net "GND")
	)
	(via
		(at 64.947038 -210.152996)
		(size 0.508)
		(drill 0.254)
		(layers "F.Cu" "B.Cu")
		(net "GND")
	)
	(via
		(at 97.652586 -210.152996)
		(size 0.508)
		(drill 0.254)
		(layers "F.Cu" "B.Cu")
		(net "GND")
	)
	(via
		(at 247.099836 -41.500044)
		(size 0.4572)
		(drill 0.2032)
		(layers "F.Cu" "B.Cu")
		(net "GND")
	)
	(via
		(at 186.900058 -223.082104)
		(size 0.508)
		(drill 0.254)
		(layers "F.Cu" "B.Cu")
		(net "GND")
	)
	(via
		(at 251.099828 -43.50004)
		(size 0.4572)
		(drill 0.2032)
		(layers "F.Cu" "B.Cu")
		(net "GND")
	)
	(via
		(at 248.099834 -44.500038)
		(size 0.4572)
		(drill 0.2032)
		(layers "F.Cu" "B.Cu")
		(net "GND")
	)
	(via
		(at 36.567872 -155.98013)
		(size 0.4572)
		(drill 0.2032)
		(layers "F.Cu" "B.Cu")
		(net "GND")
	)
	(via
		(at 40.81018 -80.848708)
		(size 0.7112)
		(drill 0.4064)
		(layers "F.Cu" "B.Cu")
		(net "GND")
	)
	(via
		(at 87.347044 -210.152996)
		(size 0.508)
		(drill 0.254)
		(layers "F.Cu" "B.Cu")
		(net "GND")
	)
	(via
		(at 55.245 -132.0292)
		(size 0.508)
		(drill 0.254)
		(layers "F.Cu" "B.Cu")
		(net "GND")
	)
	(via
		(at 250.09983 -37.500052)
		(size 0.4572)
		(drill 0.2032)
		(layers "F.Cu" "B.Cu")
		(net "GND")
	)
	(via
		(at 311.658 -70.866)
		(size 0.7112)
		(drill 0.4064)
		(layers "F.Cu" "B.Cu")
		(net "GND")
	)
	(via
		(at 35.687 -99.187)
		(size 0.508)
		(drill 0.254)
		(layers "F.Cu" "B.Cu")
		(net "GND")
	)
	(via
		(at 232.745026 -197.761352)
		(size 0.508)
		(drill 0.254)
		(layers "F.Cu" "B.Cu")
		(net "GND")
	)
	(via
		(at 338.328 -68.199)
		(size 0.508)
		(drill 0.254)
		(layers "F.Cu" "B.Cu")
		(net "GND")
	)
	(via
		(at 332.100174 -223.082104)
		(size 0.508)
		(drill 0.254)
		(layers "F.Cu" "B.Cu")
		(net "GND")
	)
	(via
		(at 225.100134 -34.500058)
		(size 0.4572)
		(drill 0.2032)
		(layers "F.Cu" "B.Cu")
		(net "GND")
	)
	(via
		(at 337.256628 -52.725066)
		(size 0.7112)
		(drill 0.4064)
		(layers "F.Cu" "B.Cu")
		(net "GND")
	)
	(via
		(at 77.089 -124.714)
		(size 0.508)
		(drill 0.254)
		(layers "F.Cu" "B.Cu")
		(net "GND")
	)
	(via
		(at 78.189836 -60.443364)
		(size 0.508)
		(drill 0.254)
		(layers "F.Cu" "B.Cu")
		(net "GND")
	)
	(via
		(at 19.6215 -142.9385)
		(size 0.508)
		(drill 0.254)
		(layers "F.Cu" "B.Cu")
		(net "GND")
	)
	(via
		(at 295.0718 -207.899)
		(size 0.508)
		(drill 0.254)
		(layers "F.Cu" "B.Cu")
		(net "GND")
	)
	(via
		(at 345.8972 -151.5872)
		(size 0.508)
		(drill 0.254)
		(layers "F.Cu" "B.Cu")
		(net "GND")
	)
	(via
		(at 1.397 -187.851034)
		(size 0.508)
		(drill 0.254)
		(layers "F.Cu" "B.Cu")
		(net "GND")
	)
	(via
		(at 245.09984 -59.499754)
		(size 0.4572)
		(drill 0.2032)
		(layers "F.Cu" "B.Cu")
		(net "GND")
	)
	(via
		(at 18.25498 -65.30848)
		(size 0.508)
		(drill 0.254)
		(layers "F.Cu" "B.Cu")
		(net "GND")
	)
	(via
		(at 222.10014 -61.49975)
		(size 0.4572)
		(drill 0.2032)
		(layers "F.Cu" "B.Cu")
		(net "GND")
	)
	(via
		(at 314.54725 -210.152996)
		(size 0.508)
		(drill 0.254)
		(layers "F.Cu" "B.Cu")
		(net "GND")
	)
	(via
		(at 171.9072 -11.7602)
		(size 0.508)
		(drill 0.254)
		(layers "F.Cu" "B.Cu")
		(net "GND")
	)
	(via
		(at 232.10012 -59.499754)
		(size 0.4572)
		(drill 0.2032)
		(layers "F.Cu" "B.Cu")
		(net "GND")
	)
	(via
		(at 235.331 -15.2527)
		(size 0.7112)
		(drill 0.4064)
		(layers "F.Cu" "B.Cu")
		(net "GND")
	)
	(via
		(at 170.4594 -16.1036)
		(size 0.508)
		(drill 0.254)
		(layers "F.Cu" "B.Cu")
		(net "GND")
	)
	(via
		(at 30.099 -44.831)
		(size 0.508)
		(drill 0.254)
		(layers "F.Cu" "B.Cu")
		(net "GND")
	)
	(via
		(at 54.229 -198.247)
		(size 0.508)
		(drill 0.254)
		(layers "F.Cu" "B.Cu")
		(net "GND")
	)
	(via
		(at 321.691 -85.217)
		(size 0.508)
		(drill 0.254)
		(layers "F.Cu" "B.Cu")
		(net "GND")
	)
	(via
		(at 246.38 -15.5067)
		(size 0.7112)
		(drill 0.4064)
		(layers "F.Cu" "B.Cu")
		(net "GND")
	)
	(via
		(at 237.10011 -40.500046)
		(size 0.4572)
		(drill 0.2032)
		(layers "F.Cu" "B.Cu")
		(net "GND")
	)
	(via
		(at 247.920764 -6.751574)
		(size 0.7112)
		(drill 0.4064)
		(layers "F.Cu" "B.Cu")
		(net "GND")
	)
	(via
		(at 297.5102 -54.7878)
		(size 0.7112)
		(drill 0.4064)
		(layers "F.Cu" "B.Cu")
		(net "GND")
	)
	(via
		(at 98.7806 -139.8016)
		(size 0.508)
		(drill 0.254)
		(layers "F.Cu" "B.Cu")
		(net "GND")
	)
	(via
		(at 53.347112 -8.28167)
		(size 0.508)
		(drill 0.254)
		(layers "F.Cu" "B.Cu")
		(net "GND")
	)
	(via
		(at 38.967918 -156.779976)
		(size 0.4572)
		(drill 0.2032)
		(layers "F.Cu" "B.Cu")
		(net "GND")
	)
	(via
		(at 223.100138 -64.499744)
		(size 0.4572)
		(drill 0.2032)
		(layers "F.Cu" "B.Cu")
		(net "GND")
	)
	(via
		(at 259.099812 -64.499744)
		(size 0.4572)
		(drill 0.2032)
		(layers "F.Cu" "B.Cu")
		(net "GND")
	)
	(via
		(at 142.346172 -70.687946)
		(size 0.7112)
		(drill 0.4064)
		(layers "F.Cu" "B.Cu")
		(net "GND")
	)
	(via
		(at 339.598 -65.786)
		(size 0.508)
		(drill 0.254)
		(layers "F.Cu" "B.Cu")
		(net "GND")
	)
	(via
		(at 36.309554 -140.547344)
		(size 0.4572)
		(drill 0.2032)
		(layers "F.Cu" "B.Cu")
		(net "GND")
	)
	(via
		(at 157.9626 -22.2504)
		(size 0.508)
		(drill 0.254)
		(layers "F.Cu" "B.Cu")
		(net "GND")
	)
	(via
		(at 202.900026 -223.082104)
		(size 0.508)
		(drill 0.254)
		(layers "F.Cu" "B.Cu")
		(net "GND")
	)
	(via
		(at 254.099822 -44.500038)
		(size 0.4572)
		(drill 0.2032)
		(layers "F.Cu" "B.Cu")
		(net "GND")
	)
	(via
		(at 33.367726 -149.580092)
		(size 0.4572)
		(drill 0.2032)
		(layers "F.Cu" "B.Cu")
		(net "GND")
	)
	(via
		(at 316.103 -74.168)
		(size 0.7112)
		(drill 0.4064)
		(layers "F.Cu" "B.Cu")
		(net "GND")
	)
	(via
		(at 54.65064 -196.55536)
		(size 0.508)
		(drill 0.254)
		(layers "F.Cu" "B.Cu")
		(net "GND")
	)
	(via
		(at 230.100124 -56.49976)
		(size 0.4572)
		(drill 0.2032)
		(layers "F.Cu" "B.Cu")
		(net "GND")
	)
	(via
		(at 225.100134 -51.49977)
		(size 0.4572)
		(drill 0.2032)
		(layers "F.Cu" "B.Cu")
		(net "GND")
	)
	(via
		(at 172.500036 -223.082104)
		(size 0.508)
		(drill 0.254)
		(layers "F.Cu" "B.Cu")
		(net "GND")
	)
	(via
		(at 249.099832 -56.49976)
		(size 0.4572)
		(drill 0.2032)
		(layers "F.Cu" "B.Cu")
		(net "GND")
	)
	(via
		(at 172.193458 -55.797958)
		(size 0.7112)
		(drill 0.4064)
		(layers "F.Cu" "B.Cu")
		(net "GND")
	)
	(via
		(at 25.353772 -111.228632)
		(size 0.508)
		(drill 0.254)
		(layers "F.Cu" "B.Cu")
		(net "GND")
	)
	(via
		(at 354.203 -81.185004)
		(size 0.508)
		(drill 0.254)
		(layers "F.Cu" "B.Cu")
		(net "GND")
	)
	(via
		(at 138.3284 -22.1742)
		(size 0.508)
		(drill 0.254)
		(layers "F.Cu" "B.Cu")
		(net "GND")
	)
	(via
		(at 254.099822 -58.499756)
		(size 0.4572)
		(drill 0.2032)
		(layers "F.Cu" "B.Cu")
		(net "GND")
	)
	(via
		(at 174.498 -96.1898)
		(size 0.508)
		(drill 0.254)
		(layers "F.Cu" "B.Cu")
		(net "GND")
	)
	(via
		(at 19.5834 -77.1652)
		(size 0.508)
		(drill 0.254)
		(layers "F.Cu" "B.Cu")
		(net "GND")
	)
	(via
		(at 171.958 -76.1746)
		(size 0.7112)
		(drill 0.4064)
		(layers "F.Cu" "B.Cu")
		(net "GND")
	)
	(via
		(at 27.932888 -77.715872)
		(size 0.508)
		(drill 0.254)
		(layers "F.Cu" "B.Cu")
		(net "GND")
	)
	(via
		(at 225.5012 -10.1854)
		(size 0.508)
		(drill 0.254)
		(layers "F.Cu" "B.Cu")
		(net "GND")
	)
	(via
		(at 78.0796 -118.7704)
		(size 0.508)
		(drill 0.254)
		(layers "F.Cu" "B.Cu")
		(net "GND")
	)
	(via
		(at 36.195 -221.615)
		(size 0.508)
		(drill 0.254)
		(layers "F.Cu" "B.Cu")
		(net "GND")
	)
	(via
		(at 175.65243 -210.152996)
		(size 0.508)
		(drill 0.254)
		(layers "F.Cu" "B.Cu")
		(net "GND")
	)
	(via
		(at 35.198558 -27.407108)
		(size 0.508)
		(drill 0.254)
		(layers "F.Cu" "B.Cu")
		(net "GND")
	)
	(via
		(at 169.300144 -223.082104)
		(size 0.508)
		(drill 0.254)
		(layers "F.Cu" "B.Cu")
		(net "GND")
	)
	(via
		(at 214.6046 -21.6154)
		(size 0.508)
		(drill 0.254)
		(layers "F.Cu" "B.Cu")
		(net "GND")
	)
	(via
		(at 131.642358 -73.32472)
		(size 0.508)
		(drill 0.254)
		(layers "F.Cu" "B.Cu")
		(net "GND")
	)
	(via
		(at 236.100112 -41.500044)
		(size 0.4572)
		(drill 0.2032)
		(layers "F.Cu" "B.Cu")
		(net "GND")
	)
	(via
		(at 249.099832 -53.499766)
		(size 0.4572)
		(drill 0.2032)
		(layers "F.Cu" "B.Cu")
		(net "GND")
	)
	(via
		(at 328.835512 -186.182)
		(size 0.508)
		(drill 0.254)
		(layers "F.Cu" "B.Cu")
		(net "GND")
	)
	(via
		(at 241.935 -19.0754)
		(size 0.508)
		(drill 0.254)
		(layers "F.Cu" "B.Cu")
		(net "GND")
	)
	(via
		(at 6.88975 -176.59985)
		(size 0.508)
		(drill 0.254)
		(layers "F.Cu" "B.Cu")
		(net "GND")
	)
	(via
		(at 353.04095 -212.102954)
		(size 0.508)
		(drill 0.254)
		(layers "F.Cu" "B.Cu")
		(net "GND")
	)
	(via
		(at 336.296 -193.929)
		(size 0.7112)
		(drill 0.3556)
		(layers "F.Cu" "B.Cu")
		(net "GND")
	)
	(via
		(at 335.8515 -71.6915)
		(size 0.508)
		(drill 0.254)
		(layers "F.Cu" "B.Cu")
		(net "GND")
	)
	(via
		(at 19.2532 -173.2026)
		(size 0.508)
		(drill 0.254)
		(layers "F.Cu" "B.Cu")
		(net "GND")
	)
	(via
		(at 133.35 -35.1536)
		(size 0.508)
		(drill 0.254)
		(layers "F.Cu" "B.Cu")
		(net "GND")
	)
	(via
		(at 249.099832 -57.499758)
		(size 0.4572)
		(drill 0.2032)
		(layers "F.Cu" "B.Cu")
		(net "GND")
	)
	(via
		(at 311.531 -49.403)
		(size 0.7112)
		(drill 0.4064)
		(layers "F.Cu" "B.Cu")
		(net "GND")
	)
	(via
		(at 315.595 -163.83)
		(size 0.7112)
		(drill 0.3556)
		(layers "F.Cu" "B.Cu")
		(net "GND")
	)
	(via
		(at 49.149 -159.512)
		(size 0.7112)
		(drill 0.3556)
		(layers "F.Cu" "B.Cu")
		(net "GND")
	)
	(via
		(at 149.86 -11.7348)
		(size 0.508)
		(drill 0.254)
		(layers "F.Cu" "B.Cu")
		(net "GND")
	)
	(via
		(at 123.2662 -205.2955)
		(size 0.508)
		(drill 0.254)
		(layers "F.Cu" "B.Cu")
		(net "GND")
	)
	(via
		(at 34.965894 -155.980384)
		(size 0.4572)
		(drill 0.2032)
		(layers "F.Cu" "B.Cu")
		(net "GND")
	)
	(via
		(at 328.8538 -150.7236)
		(size 0.508)
		(drill 0.254)
		(layers "F.Cu" "B.Cu")
		(net "GND")
	)
	(via
		(at 172.228002 -60.479432)
		(size 0.7112)
		(drill 0.4064)
		(layers "F.Cu" "B.Cu")
		(net "GND")
	)
	(via
		(at 226.06 -24.8412)
		(size 0.508)
		(drill 0.254)
		(layers "F.Cu" "B.Cu")
		(net "GND")
	)
	(via
		(at 337.256628 -50.947066)
		(size 0.7112)
		(drill 0.4064)
		(layers "F.Cu" "B.Cu")
		(net "GND")
	)
	(via
		(at 56.099964 -223.082104)
		(size 0.508)
		(drill 0.254)
		(layers "F.Cu" "B.Cu")
		(net "GND")
	)
	(via
		(at 243.099844 -54.499764)
		(size 0.4572)
		(drill 0.2032)
		(layers "F.Cu" "B.Cu")
		(net "GND")
	)
	(via
		(at 166.116 -223.0628)
		(size 0.508)
		(drill 0.254)
		(layers "F.Cu" "B.Cu")
		(net "GND")
	)
	(via
		(at 247.099836 -45.500036)
		(size 0.4572)
		(drill 0.2032)
		(layers "F.Cu" "B.Cu")
		(net "GND")
	)
	(via
		(at 252.099826 -45.500036)
		(size 0.4572)
		(drill 0.2032)
		(layers "F.Cu" "B.Cu")
		(net "GND")
	)
	(via
		(at 230.100124 -58.499756)
		(size 0.4572)
		(drill 0.2032)
		(layers "F.Cu" "B.Cu")
		(net "GND")
	)
	(via
		(at 63.119 -148.082)
		(size 0.508)
		(drill 0.254)
		(layers "F.Cu" "B.Cu")
		(net "GND")
	)
	(via
		(at 90.8304 -162.1282)
		(size 0.508)
		(drill 0.254)
		(layers "F.Cu" "B.Cu")
		(net "GND")
	)
	(via
		(at 241.173 -24.765)
		(size 0.508)
		(drill 0.254)
		(layers "F.Cu" "B.Cu")
		(net "GND")
	)
	(via
		(at 51.593496 -209.31886)
		(size 0.508)
		(drill 0.254)
		(layers "F.Cu" "B.Cu")
		(net "GND")
	)
	(via
		(at 153.025602 -72.138032)
		(size 0.7112)
		(drill 0.3556)
		(layers "F.Cu" "B.Cu")
		(net "GND")
	)
	(via
		(at 243.099844 -31.500064)
		(size 0.4572)
		(drill 0.2032)
		(layers "F.Cu" "B.Cu")
		(net "GND")
	)
	(via
		(at 37.30498 -124.885196)
		(size 0.4572)
		(drill 0.2032)
		(layers "F.Cu" "B.Cu")
		(net "GND")
	)
	(via
		(at 52.073302 -48.919384)
		(size 0.508)
		(drill 0.254)
		(layers "F.Cu" "B.Cu")
		(net "GND")
	)
	(via
		(at 27.547062 -97.831656)
		(size 0.508)
		(drill 0.254)
		(layers "F.Cu" "B.Cu")
		(net "GND")
	)
	(via
		(at 38.904926 -130.485134)
		(size 0.4572)
		(drill 0.2032)
		(layers "F.Cu" "B.Cu")
		(net "GND")
	)
	(via
		(at 337.416394 -60.370466)
		(size 0.7112)
		(drill 0.4064)
		(layers "F.Cu" "B.Cu")
		(net "GND")
	)
	(via
		(at 147.652486 -210.152996)
		(size 0.508)
		(drill 0.254)
		(layers "F.Cu" "B.Cu")
		(net "GND")
	)
	(via
		(at 249.099832 -41.500044)
		(size 0.4572)
		(drill 0.2032)
		(layers "F.Cu" "B.Cu")
		(net "GND")
	)
	(via
		(at 324.8914 -11.7602)
		(size 0.508)
		(drill 0.254)
		(layers "F.Cu" "B.Cu")
		(net "GND")
	)
	(via
		(at 168.9354 -26.0858)
		(size 0.508)
		(drill 0.254)
		(layers "F.Cu" "B.Cu")
		(net "GND")
	)
	(via
		(at 22.987 -147.3454)
		(size 0.508)
		(drill 0.254)
		(layers "F.Cu" "B.Cu")
		(net "GND")
	)
	(via
		(at 232.745026 -172.361352)
		(size 0.508)
		(drill 0.254)
		(layers "F.Cu" "B.Cu")
		(net "GND")
	)
	(via
		(at 337.402424 -61.491114)
		(size 0.7112)
		(drill 0.4064)
		(layers "F.Cu" "B.Cu")
		(net "GND")
	)
	(via
		(at 312.003186 -35.04184)
		(size 0.508)
		(drill 0.254)
		(layers "F.Cu" "B.Cu")
		(net "GND")
	)
	(via
		(at 148.463 -117.475)
		(size 0.508)
		(drill 0.254)
		(layers "F.Cu" "B.Cu")
		(net "GND")
	)
	(via
		(at 269.558262 -4.441698)
		(size 0.508)
		(drill 0.254)
		(layers "F.Cu" "B.Cu")
		(net "GND")
	)
	(via
		(at 239.100106 -49.499774)
		(size 0.4572)
		(drill 0.2032)
		(layers "F.Cu" "B.Cu")
		(net "GND")
	)
	(via
		(at 308.5338 -11.684)
		(size 0.508)
		(drill 0.254)
		(layers "F.Cu" "B.Cu")
		(net "GND")
	)
	(via
		(at 251.099828 -42.500042)
		(size 0.4572)
		(drill 0.2032)
		(layers "F.Cu" "B.Cu")
		(net "GND")
	)
	(via
		(at 83.312 -168.402)
		(size 0.7112)
		(drill 0.3556)
		(layers "F.Cu" "B.Cu")
		(net "GND")
	)
	(via
		(at 252.099826 -42.500042)
		(size 0.4572)
		(drill 0.2032)
		(layers "F.Cu" "B.Cu")
		(net "GND")
	)
	(via
		(at 311.658 -72.517)
		(size 0.7112)
		(drill 0.4064)
		(layers "F.Cu" "B.Cu")
		(net "GND")
	)
	(via
		(at 328.08164 -35.625278)
		(size 0.508)
		(drill 0.254)
		(layers "F.Cu" "B.Cu")
		(net "GND")
	)
	(via
		(at 153.45918 -85.8266)
		(size 0.508)
		(drill 0.254)
		(layers "F.Cu" "B.Cu")
		(net "GND")
	)
	(via
		(at 229.100126 -59.499754)
		(size 0.4572)
		(drill 0.2032)
		(layers "F.Cu" "B.Cu")
		(net "GND")
	)
	(via
		(at 234.100116 -59.499754)
		(size 0.4572)
		(drill 0.2032)
		(layers "F.Cu" "B.Cu")
		(net "GND")
	)
	(via
		(at 231.013 -85.852)
		(size 0.508)
		(drill 0.254)
		(layers "F.Cu" "B.Cu")
		(net "GND")
	)
	(via
		(at 300.147228 -210.152996)
		(size 0.508)
		(drill 0.254)
		(layers "F.Cu" "B.Cu")
		(net "GND")
	)
	(via
		(at 245.09984 -45.500036)
		(size 0.4572)
		(drill 0.2032)
		(layers "F.Cu" "B.Cu")
		(net "GND")
	)
	(via
		(at 341.8459 -171.8945)
		(size 0.508)
		(drill 0.254)
		(layers "F.Cu" "B.Cu")
		(net "GND")
	)
	(via
		(at 321.437 -15.7226)
		(size 0.508)
		(drill 0.254)
		(layers "F.Cu" "B.Cu")
		(net "GND")
	)
	(via
		(at 231.100122 -32.500062)
		(size 0.4572)
		(drill 0.2032)
		(layers "F.Cu" "B.Cu")
		(net "GND")
	)
	(via
		(at 33.5788 -192.1002)
		(size 0.508)
		(drill 0.254)
		(layers "F.Cu" "B.Cu")
		(net "GND")
	)
	(via
		(at 230.759 -67.818)
		(size 0.508)
		(drill 0.254)
		(layers "F.Cu" "B.Cu")
		(net "GND")
	)
	(via
		(at 312.42 -20.0152)
		(size 0.508)
		(drill 0.254)
		(layers "F.Cu" "B.Cu")
		(net "GND")
	)
	(via
		(at 231.013 -71.882)
		(size 0.508)
		(drill 0.254)
		(layers "F.Cu" "B.Cu")
		(net "GND")
	)
	(via
		(at 220.218 -90.678)
		(size 0.7112)
		(drill 0.3556)
		(layers "F.Cu" "B.Cu")
		(net "GND")
	)
	(via
		(at 328.0664 -125.7808)
		(size 0.508)
		(drill 0.254)
		(layers "F.Cu" "B.Cu")
		(net "GND")
	)
	(via
		(at 226.100132 -51.49977)
		(size 0.4572)
		(drill 0.2032)
		(layers "F.Cu" "B.Cu")
		(net "GND")
	)
	(via
		(at 43.70451 -132.08508)
		(size 0.4572)
		(drill 0.2032)
		(layers "F.Cu" "B.Cu")
		(net "GND")
	)
	(via
		(at 312.4962 -16.0528)
		(size 0.508)
		(drill 0.254)
		(layers "F.Cu" "B.Cu")
		(net "GND")
	)
	(via
		(at 244.099842 -60.499752)
		(size 0.4572)
		(drill 0.2032)
		(layers "F.Cu" "B.Cu")
		(net "GND")
	)
	(via
		(at 252.099826 -49.499774)
		(size 0.4572)
		(drill 0.2032)
		(layers "F.Cu" "B.Cu")
		(net "GND")
	)
	(via
		(at 354.203 -187.865004)
		(size 0.508)
		(drill 0.254)
		(layers "F.Cu" "B.Cu")
		(net "GND")
	)
	(via
		(at 301.5234 -19.7866)
		(size 0.508)
		(drill 0.254)
		(layers "F.Cu" "B.Cu")
		(net "GND")
	)
	(via
		(at 246.099838 -53.499766)
		(size 0.4572)
		(drill 0.2032)
		(layers "F.Cu" "B.Cu")
		(net "GND")
	)
	(via
		(at 307.0352 -54.7878)
		(size 0.7112)
		(drill 0.4064)
		(layers "F.Cu" "B.Cu")
		(net "GND")
	)
	(via
		(at 146.147282 -210.152996)
		(size 0.508)
		(drill 0.254)
		(layers "F.Cu" "B.Cu")
		(net "GND")
	)
	(via
		(at 230.759 -69.85)
		(size 0.508)
		(drill 0.254)
		(layers "F.Cu" "B.Cu")
		(net "GND")
	)
	(via
		(at 66.294 -48.387)
		(size 0.7112)
		(drill 0.4064)
		(layers "F.Cu" "B.Cu")
		(net "GND")
	)
	(via
		(at 252.099826 -53.499766)
		(size 0.4572)
		(drill 0.2032)
		(layers "F.Cu" "B.Cu")
		(net "GND")
	)
	(via
		(at 124.93244 -97.06356)
		(size 0.508)
		(drill 0.254)
		(layers "F.Cu" "B.Cu")
		(net "GND")
	)
	(via
		(at 72.900032 -223.082104)
		(size 0.508)
		(drill 0.254)
		(layers "F.Cu" "B.Cu")
		(net "GND")
	)
	(via
		(at 91.313 -184.74309)
		(size 0.508)
		(drill 0.254)
		(layers "F.Cu" "B.Cu")
		(net "GND")
	)
	(via
		(at 314.4012 -133.223)
		(size 0.508)
		(drill 0.254)
		(layers "F.Cu" "B.Cu")
		(net "GND")
	)
	(via
		(at 66.499994 -223.082104)
		(size 0.508)
		(drill 0.254)
		(layers "F.Cu" "B.Cu")
		(net "GND")
	)
	(via
		(at 183.7182 -73.914)
		(size 0.7112)
		(drill 0.4064)
		(layers "F.Cu" "B.Cu")
		(net "GND")
	)
	(via
		(at 321.31 -170.688)
		(size 0.508)
		(drill 0.254)
		(layers "F.Cu" "B.Cu")
		(net "GND")
	)
	(via
		(at 183.750966 -23.287482)
		(size 0.508)
		(drill 0.254)
		(layers "F.Cu" "B.Cu")
		(net "GND")
	)
	(via
		(at 79.72425 -92.507054)
		(size 0.508)
		(drill 0.254)
		(layers "F.Cu" "B.Cu")
		(net "GND")
	)
	(via
		(at 255.5494 -134.2898)
		(size 0.508)
		(drill 0.254)
		(layers "F.Cu" "B.Cu")
		(net "GND")
	)
	(via
		(at 250.09983 -34.500058)
		(size 0.4572)
		(drill 0.2032)
		(layers "F.Cu" "B.Cu")
		(net "GND")
	)
	(via
		(at 157.0482 -22.352)
		(size 0.508)
		(drill 0.254)
		(layers "F.Cu" "B.Cu")
		(net "GND")
	)
	(via
		(at 232.745026 -187.601352)
		(size 0.508)
		(drill 0.254)
		(layers "F.Cu" "B.Cu")
		(net "GND")
	)
	(via
		(at 169.086784 -14.484858)
		(size 0.508)
		(drill 0.254)
		(layers "F.Cu" "B.Cu")
		(net "GND")
	)
	(via
		(at 44.504864 -132.084826)
		(size 0.4572)
		(drill 0.2032)
		(layers "F.Cu" "B.Cu")
		(net "GND")
	)
	(via
		(at 312.852562 -210.152996)
		(size 0.508)
		(drill 0.254)
		(layers "F.Cu" "B.Cu")
		(net "GND")
	)
	(via
		(at 225.100134 -48.499776)
		(size 0.4572)
		(drill 0.2032)
		(layers "F.Cu" "B.Cu")
		(net "GND")
	)
	(via
		(at 249.099832 -61.49975)
		(size 0.4572)
		(drill 0.2032)
		(layers "F.Cu" "B.Cu")
		(net "GND")
	)
	(via
		(at 74.041 -126.4158)
		(size 0.508)
		(drill 0.254)
		(layers "F.Cu" "B.Cu")
		(net "GND")
	)
	(via
		(at 8.9281 -72.2249)
		(size 0.508)
		(drill 0.254)
		(layers "F.Cu" "B.Cu")
		(net "GND")
	)
	(via
		(at 33.367726 -156.779976)
		(size 0.4572)
		(drill 0.2032)
		(layers "F.Cu" "B.Cu")
		(net "GND")
	)
	(via
		(at 43.8023 -53.6067)
		(size 0.508)
		(drill 0.254)
		(layers "F.Cu" "B.Cu")
		(net "GND")
	)
	(via
		(at 332.835504 -174.55007)
		(size 0.508)
		(drill 0.254)
		(layers "F.Cu" "B.Cu")
		(net "GND")
	)
	(via
		(at 337.244944 -68.924932)
		(size 0.7112)
		(drill 0.3556)
		(layers "F.Cu" "B.Cu")
		(net "GND")
	)
	(via
		(at 318.203072 -35.859974)
		(size 0.508)
		(drill 0.254)
		(layers "F.Cu" "B.Cu")
		(net "GND")
	)
	(via
		(at 254.099822 -64.499744)
		(size 0.4572)
		(drill 0.2032)
		(layers "F.Cu" "B.Cu")
		(net "GND")
	)
	(via
		(at 235.100114 -60.499752)
		(size 0.4572)
		(drill 0.2032)
		(layers "F.Cu" "B.Cu")
		(net "GND")
	)
	(via
		(at 67.8942 -83.47456)
		(size 0.508)
		(drill 0.254)
		(layers "F.Cu" "B.Cu")
		(net "GND")
	)
	(via
		(at 272.10004 -223.082104)
		(size 0.508)
		(drill 0.254)
		(layers "F.Cu" "B.Cu")
		(net "GND")
	)
	(via
		(at 238.100108 -54.499764)
		(size 0.4572)
		(drill 0.2032)
		(layers "F.Cu" "B.Cu")
		(net "GND")
	)
	(via
		(at 250.09983 -57.499758)
		(size 0.4572)
		(drill 0.2032)
		(layers "F.Cu" "B.Cu")
		(net "GND")
	)
	(via
		(at 151.831802 -59.717432)
		(size 0.508)
		(drill 0.254)
		(layers "F.Cu" "B.Cu")
		(net "GND")
	)
	(via
		(at 149.352 -22.1234)
		(size 0.508)
		(drill 0.254)
		(layers "F.Cu" "B.Cu")
		(net "GND")
	)
	(via
		(at 235.100114 -42.500042)
		(size 0.4572)
		(drill 0.2032)
		(layers "F.Cu" "B.Cu")
		(net "GND")
	)
	(via
		(at 257.099816 -44.500038)
		(size 0.4572)
		(drill 0.2032)
		(layers "F.Cu" "B.Cu")
		(net "GND")
	)
	(via
		(at 354.203 -45.625004)
		(size 0.508)
		(drill 0.254)
		(layers "F.Cu" "B.Cu")
		(net "GND")
	)
	(via
		(at 254.099822 -35.500056)
		(size 0.4572)
		(drill 0.2032)
		(layers "F.Cu" "B.Cu")
		(net "GND")
	)
	(via
		(at 302.3362 -54.7878)
		(size 0.7112)
		(drill 0.4064)
		(layers "F.Cu" "B.Cu")
		(net "GND")
	)
	(via
		(at 121.5136 -15.8242)
		(size 0.508)
		(drill 0.254)
		(layers "F.Cu" "B.Cu")
		(net "GND")
	)
	(via
		(at 329.565 -89.3572)
		(size 0.508)
		(drill 0.254)
		(layers "F.Cu" "B.Cu")
		(net "GND")
	)
	(via
		(at 41.36771 -155.18003)
		(size 0.4572)
		(drill 0.2032)
		(layers "F.Cu" "B.Cu")
		(net "GND")
	)
	(via
		(at 316.052708 -210.152996)
		(size 0.508)
		(drill 0.254)
		(layers "F.Cu" "B.Cu")
		(net "GND")
	)
	(via
		(at 229.100126 -64.499744)
		(size 0.4572)
		(drill 0.2032)
		(layers "F.Cu" "B.Cu")
		(net "GND")
	)
	(via
		(at 156.643324 -88.828372)
		(size 0.508)
		(drill 0.254)
		(layers "F.Cu" "B.Cu")
		(net "GND")
	)
	(via
		(at 199.761602 -50.550826)
		(size 0.508)
		(drill 0.254)
		(layers "F.Cu" "B.Cu")
		(net "GND")
	)
	(via
		(at 38.968172 -151.180038)
		(size 0.4572)
		(drill 0.2032)
		(layers "F.Cu" "B.Cu")
		(net "GND")
	)
	(via
		(at 42.418 -53.721)
		(size 0.508)
		(drill 0.254)
		(layers "F.Cu" "B.Cu")
		(net "GND")
	)
	(via
		(at 275.971 -71.12)
		(size 0.7112)
		(drill 0.3556)
		(layers "F.Cu" "B.Cu")
		(net "GND")
	)
	(via
		(at 288.4805 -58.1025)
		(size 0.508)
		(drill 0.254)
		(layers "F.Cu" "B.Cu")
		(net "GND")
	)
	(via
		(at 183.786526 -25.646126)
		(size 0.508)
		(drill 0.254)
		(layers "F.Cu" "B.Cu")
		(net "GND")
	)
	(via
		(at 316.103 -49.403)
		(size 0.7112)
		(drill 0.4064)
		(layers "F.Cu" "B.Cu")
		(net "GND")
	)
	(via
		(at 26.4414 -49.4284)
		(size 0.508)
		(drill 0.254)
		(layers "F.Cu" "B.Cu")
		(net "GND")
	)
	(via
		(at 159.893 -94.234)
		(size 0.508)
		(drill 0.254)
		(layers "F.Cu" "B.Cu")
		(net "GND")
	)
	(via
		(at 227.10013 -39.500048)
		(size 0.4572)
		(drill 0.2032)
		(layers "F.Cu" "B.Cu")
		(net "GND")
	)
	(via
		(at 158.6738 -15.5956)
		(size 0.508)
		(drill 0.254)
		(layers "F.Cu" "B.Cu")
		(net "GND")
	)
	(via
		(at 67.987926 -1.397)
		(size 0.508)
		(drill 0.254)
		(layers "F.Cu" "B.Cu")
		(net "GND")
	)
	(via
		(at 231.100122 -52.499768)
		(size 0.4572)
		(drill 0.2032)
		(layers "F.Cu" "B.Cu")
		(net "GND")
	)
	(via
		(at 40.278558 -27.407108)
		(size 0.508)
		(drill 0.254)
		(layers "F.Cu" "B.Cu")
		(net "GND")
	)
	(via
		(at 309.661052 -35.033712)
		(size 0.508)
		(drill 0.254)
		(layers "F.Cu" "B.Cu")
		(net "GND")
	)
	(via
		(at 251.099828 -30.500066)
		(size 0.4572)
		(drill 0.2032)
		(layers "F.Cu" "B.Cu")
		(net "GND")
	)
	(via
		(at 188.547248 -210.152996)
		(size 0.508)
		(drill 0.254)
		(layers "F.Cu" "B.Cu")
		(net "GND")
	)
	(via
		(at 60.4774 -163.4236)
		(size 0.508)
		(drill 0.254)
		(layers "F.Cu" "B.Cu")
		(net "GND")
	)
	(via
		(at 212.50021 -223.082104)
		(size 0.508)
		(drill 0.254)
		(layers "F.Cu" "B.Cu")
		(net "GND")
	)
	(via
		(at 209.677 -177.038)
		(size 0.7112)
		(drill 0.3556)
		(layers "F.Cu" "B.Cu")
		(net "GND")
	)
	(via
		(at 354.203 -182.785004)
		(size 0.508)
		(drill 0.254)
		(layers "F.Cu" "B.Cu")
		(net "GND")
	)
	(via
		(at 250.09983 -46.500034)
		(size 0.4572)
		(drill 0.2032)
		(layers "F.Cu" "B.Cu")
		(net "GND")
	)
	(via
		(at 155.337002 -73.687432)
		(size 0.7112)
		(drill 0.4064)
		(layers "F.Cu" "B.Cu")
		(net "GND")
	)
	(via
		(at 322.500244 -223.082104)
		(size 0.508)
		(drill 0.254)
		(layers "F.Cu" "B.Cu")
		(net "GND")
	)
	(via
		(at 239.100106 -42.500042)
		(size 0.4572)
		(drill 0.2032)
		(layers "F.Cu" "B.Cu")
		(net "GND")
	)
	(via
		(at 38.058852 -113.33226)
		(size 0.508)
		(drill 0.254)
		(layers "F.Cu" "B.Cu")
		(net "GND")
	)
	(via
		(at 44.899834 -223.082104)
		(size 0.508)
		(drill 0.254)
		(layers "F.Cu" "B.Cu")
		(net "GND")
	)
	(via
		(at 84.099908 -223.082104)
		(size 0.508)
		(drill 0.254)
		(layers "F.Cu" "B.Cu")
		(net "GND")
	)
	(via
		(at 243.099844 -45.500036)
		(size 0.4572)
		(drill 0.2032)
		(layers "F.Cu" "B.Cu")
		(net "GND")
	)
	(via
		(at 227.10013 -49.499774)
		(size 0.4572)
		(drill 0.2032)
		(layers "F.Cu" "B.Cu")
		(net "GND")
	)
	(via
		(at 154.005788 -89.286588)
		(size 0.508)
		(drill 0.254)
		(layers "F.Cu" "B.Cu")
		(net "GND")
	)
	(via
		(at 234.100116 -61.49975)
		(size 0.4572)
		(drill 0.2032)
		(layers "F.Cu" "B.Cu")
		(net "GND")
	)
	(via
		(at 246.099838 -49.499774)
		(size 0.4572)
		(drill 0.2032)
		(layers "F.Cu" "B.Cu")
		(net "GND")
	)
	(via
		(at 37.374322 -151.176736)
		(size 0.4572)
		(drill 0.2032)
		(layers "F.Cu" "B.Cu")
		(net "GND")
	)
	(via
		(at 225.100134 -32.500062)
		(size 0.4572)
		(drill 0.2032)
		(layers "F.Cu" "B.Cu")
		(net "GND")
	)
	(via
		(at 154.813 -91.622118)
		(size 0.508)
		(drill 0.254)
		(layers "F.Cu" "B.Cu")
		(net "GND")
	)
	(arc
		(start 37.9476 -223.7486)
		(mid 38.060429 -223.917461)
		(end 38.1 -224.116646)
		(width 0.508)
		(layer "F.Cu")
		(net "GND")
	)
	(segment
		(start 283.634434 0.08001)
		(end 284.447742 0.08001)
		(width 0.508)
		(layer "B.Cu")
		(net "GND")
	)
	(segment
		(start 241.8842 -59.99734)
		(end 241.8842 -60.284106)
		(width 0.3048)
		(layer "B.Cu")
		(net "GND")
	)
	(segment
		(start 169.700194 -223.482154)
		(end 169.300144 -223.082104)
		(width 0.508)
		(layer "B.Cu")
		(net "GND")
	)
	(segment
		(start 176.900078 -225.92538)
		(end 176.900078 -223.4819)
		(width 0.508)
		(layer "B.Cu")
		(net "GND")
	)
	(segment
		(start 241.935 -18.3515)
		(end 241.935 -19.0754)
		(width 0.508)
		(layer "B.Cu")
		(net "GND")
	)
	(segment
		(start 49.30013 -223.4819)
		(end 49.699926 -223.082104)
		(width 0.508)
		(layer "B.Cu")
		(net "GND")
	)
	(segment
		(start 299.700188 -223.4819)
		(end 300.099984 -223.082104)
		(width 0.508)
		(layer "B.Cu")
		(net "GND")
	)
	(segment
		(start 223.4692 -189.4586)
		(end 224.3074 -189.4586)
		(width 0.508)
		(layer "B.Cu")
		(net "GND")
	)
	(segment
		(start 70.10019 -223.482154)
		(end 69.70014 -223.082104)
		(width 0.508)
		(layer "B.Cu")
		(net "GND")
	)
	(segment
		(start 316.500002 -225.92538)
		(end 316.500002 -223.4819)
		(width 0.508)
		(layer "B.Cu")
		(net "GND")
	)
	(segment
		(start 22.7076 -119.4816)
		(end 23.19909 -119.4816)
		(width 0.508)
		(layer "B.Cu")
		(net "GND")
	)
	(segment
		(start 69.215 -192.017904)
		(end 69.117464 -191.920368)
		(width 0.508)
		(layer "B.Cu")
		(net "GND")
	)
	(segment
		(start 287.700212 -225.92538)
		(end 287.700212 -223.4819)
		(width 0.508)
		(layer "B.Cu")
		(net "GND")
	)
	(segment
		(start 179.300124 -223.482154)
		(end 178.900074 -223.082104)
		(width 0.508)
		(layer "B.Cu")
		(net "GND")
	)
	(segment
		(start 111.700056 -225.92538)
		(end 111.700056 -223.482154)
		(width 0.508)
		(layer "B.Cu")
		(net "GND")
	)
	(segment
		(start 216.374218 -200.468738)
		(end 216.38006 -200.47458)
		(width 0.508)
		(layer "B.Cu")
		(net "GND")
	)
	(segment
		(start 83.20024 -191.27724)
		(end 83.439 -191.516)
		(width 0.4064)
		(layer "B.Cu")
		(net "GND")
	)
	(segment
		(start 271.700244 -225.92538)
		(end 271.700244 -223.4819)
		(width 0.508)
		(layer "B.Cu")
		(net "GND")
	)
	(segment
		(start 133.23824 -203.6445)
		(end 133.23824 -204.288644)
		(width 0.4064)
		(layer "B.Cu")
		(net "GND")
	)
	(segment
		(start 278.100028 -225.92538)
		(end 278.100028 -223.4819)
		(width 0.508)
		(layer "B.Cu")
		(net "GND")
	)
	(segment
		(start 92.500196 -225.92538)
		(end 92.500196 -223.482154)
		(width 0.508)
		(layer "B.Cu")
		(net "GND")
	)
	(segment
		(start 237.3376 -59.99734)
		(end 237.3376 -60.262262)
		(width 0.3048)
		(layer "B.Cu")
		(net "GND")
	)
	(segment
		(start 56.134 -136.7155)
		(end 55.118 -136.7155)
		(width 0.508)
		(layer "B.Cu")
		(net "GND")
	)
	(segment
		(start 184.900062 -225.92538)
		(end 184.900062 -223.4819)
		(width 0.508)
		(layer "B.Cu")
		(net "GND")
	)
	(segment
		(start 262.10006 -225.92538)
		(end 262.10006 -223.4819)
		(width 0.508)
		(layer "B.Cu")
		(net "GND")
	)
	(segment
		(start 219.03055 -3.13055)
		(end 219.4941 -3.13055)
		(width 0.508)
		(layer "B.Cu")
		(net "GND")
	)
	(segment
		(start 253.873 -37.726874)
		(end 254.099822 -37.500052)
		(width 0.3048)
		(layer "B.Cu")
		(net "GND")
	)
	(segment
		(start 280.500074 -223.482154)
		(end 280.100024 -223.082104)
		(width 0.508)
		(layer "B.Cu")
		(net "GND")
	)
	(segment
		(start 265.300206 -223.4819)
		(end 265.700002 -223.082104)
		(width 0.508)
		(layer "B.Cu")
		(net "GND")
	)
	(segment
		(start 316.634368 0.08001)
		(end 316.634368 -0.733298)
		(width 0.508)
		(layer "B.Cu")
		(net "GND")
	)
	(segment
		(start 182.5752 -4.55168)
		(end 182.5752 -3.075686)
		(width 0.508)
		(layer "B.Cu")
		(net "GND")
	)
	(segment
		(start 226.2886 -59.9948)
		(end 226.2886 -60.311284)
		(width 0.3048)
		(layer "B.Cu")
		(net "GND")
	)
	(segment
		(start 220.853 -7.893558)
		(end 220.839538 -7.880096)
		(width 0.381)
		(layer "B.Cu")
		(net "GND")
	)
	(segment
		(start 335.700116 -223.482154)
		(end 335.300066 -223.082104)
		(width 0.508)
		(layer "B.Cu")
		(net "GND")
	)
	(segment
		(start 296.500042 -223.482154)
		(end 296.099992 -223.082104)
		(width 0.508)
		(layer "B.Cu")
		(net "GND")
	)
	(segment
		(start 109.30001 -223.4819)
		(end 109.699806 -223.082104)
		(width 0.508)
		(layer "B.Cu")
		(net "GND")
	)
	(segment
		(start 322.90004 -223.4819)
		(end 322.500244 -223.082104)
		(width 0.508)
		(layer "B.Cu")
		(net "GND")
	)
	(segment
		(start 326.100186 -223.482154)
		(end 325.700136 -223.082104)
		(width 0.508)
		(layer "B.Cu")
		(net "GND")
	)
	(segment
		(start 230.0351 -28.575)
		(end 230.0351 -29.435044)
		(width 0.508)
		(layer "B.Cu")
		(net "GND")
	)
	(segment
		(start 79.13624 -190.4365)
		(end 79.13624 -191.22644)
		(width 0.4064)
		(layer "B.Cu")
		(net "GND")
	)
	(segment
		(start 55.3212 -132.0292)
		(end 55.7149 -131.6355)
		(width 0.508)
		(layer "B.Cu")
		(net "GND")
	)
	(segment
		(start 243.8654 -57.995058)
		(end 243.8654 -58.265314)
		(width 0.3048)
		(layer "B.Cu")
		(net "GND")
	)
	(segment
		(start 140.13942 -35.49142)
		(end 140.13942 -34.934652)
		(width 0.508)
		(layer "B.Cu")
		(net "GND")
	)
	(segment
		(start 141.699996 -225.92538)
		(end 141.699996 -223.4819)
		(width 0.508)
		(layer "B.Cu")
		(net "GND")
	)
	(segment
		(start 226.2886 -60.311284)
		(end 226.100132 -60.499752)
		(width 0.3048)
		(layer "B.Cu")
		(net "GND")
	)
	(segment
		(start 243.7384 -32.004)
		(end 243.7384 -31.839154)
		(width 0.3048)
		(layer "B.Cu")
		(net "GND")
	)
	(segment
		(start 71.191374 -190.428626)
		(end 71.501 -190.119)
		(width 0.3048)
		(layer "B.Cu")
		(net "GND")
	)
	(segment
		(start 342.082628 -179.633626)
		(end 342.082628 -180.665628)
		(width 0.3048)
		(layer "B.Cu")
		(net "GND")
	)
	(segment
		(start 151.821134 0.08001)
		(end 152.634442 0.08001)
		(width 0.508)
		(layer "B.Cu")
		(net "GND")
	)
	(segment
		(start 184.900062 -223.4819)
		(end 185.299858 -223.082104)
		(width 0.508)
		(layer "B.Cu")
		(net "GND")
	)
	(segment
		(start 129.17424 -203.6445)
		(end 129.6035 -203.6445)
		(width 0.4064)
		(layer "B.Cu")
		(net "GND")
	)
	(segment
		(start 238.97082 -58.499756)
		(end 239.100106 -58.499756)
		(width 0.3048)
		(layer "B.Cu")
		(net "GND")
	)
	(segment
		(start 139.300204 -225.92538)
		(end 139.300204 -223.4819)
		(width 0.508)
		(layer "B.Cu")
		(net "GND")
	)
	(segment
		(start 37.12591 -112.998504)
		(end 37.12591 -113.43513)
		(width 0.508)
		(layer "B.Cu")
		(net "GND")
	)
	(segment
		(start 152.100026 -225.92538)
		(end 152.100026 -223.4819)
		(width 0.508)
		(layer "B.Cu")
		(net "GND")
	)
	(segment
		(start 283.634434 0.08001)
		(end 283.634434 -0.733298)
		(width 0.508)
		(layer "B.Cu")
		(net "GND")
	)
	(segment
		(start 342.082628 -180.665628)
		(end 342.519 -181.102)
		(width 0.3048)
		(layer "B.Cu")
		(net "GND")
	)
	(segment
		(start 241.9985 -18.288)
		(end 241.935 -18.3515)
		(width 0.508)
		(layer "B.Cu")
		(net "GND")
	)
	(segment
		(start 46.900084 -225.92538)
		(end 46.900084 -223.279716)
		(width 0.508)
		(layer "B.Cu")
		(net "GND")
	)
	(segment
		(start 176.900078 -223.4819)
		(end 177.299874 -223.082104)
		(width 0.508)
		(layer "B.Cu")
		(net "GND")
	)
	(segment
		(start 137.30224 -203.6445)
		(end 137.30224 -204.23124)
		(width 0.4064)
		(layer "B.Cu")
		(net "GND")
	)
	(segment
		(start 127.807212 -199.308974)
		(end 127.022606 -199.308974)
		(width 0.508)
		(layer "B.Cu")
		(net "GND")
	)
	(segment
		(start 262.10006 -223.4819)
		(end 262.499856 -223.082104)
		(width 0.508)
		(layer "B.Cu")
		(net "GND")
	)
	(segment
		(start 152.100026 -223.4819)
		(end 152.499822 -223.082104)
		(width 0.508)
		(layer "B.Cu")
		(net "GND")
	)
	(segment
		(start 41.099994 -38.999922)
		(end 41.099994 -40.04183)
		(width 0.508)
		(layer "B.Cu")
		(net "GND")
	)
	(segment
		(start 124.912628 -203.636626)
		(end 125.314202 -203.636626)
		(width 0.4064)
		(layer "B.Cu")
		(net "GND")
	)
	(segment
		(start 188.100208 -223.4819)
		(end 188.500004 -223.082104)
		(width 0.508)
		(layer "B.Cu")
		(net "GND")
	)
	(segment
		(start 264.033 -12.827)
		(end 263.336024 -12.827)
		(width 0.508)
		(layer "B.Cu")
		(net "GND")
	)
	(segment
		(start 54.1655 -139.827)
		(end 54.9402 -139.827)
		(width 0.508)
		(layer "B.Cu")
		(net "GND")
	)
	(segment
		(start 254.8382 -60.238132)
		(end 255.09982 -60.499752)
		(width 0.3048)
		(layer "B.Cu")
		(net "GND")
	)
	(segment
		(start 236.609128 -31.6992)
		(end 236.299248 -31.6992)
		(width 0.3048)
		(layer "B.Cu")
		(net "GND")
	)
	(segment
		(start 283.634434 0.893318)
		(end 283.634434 0.08001)
		(width 0.508)
		(layer "B.Cu")
		(net "GND")
	)
	(segment
		(start 295.302178 -208.129378)
		(end 295.0718 -207.899)
		(width 0.508)
		(layer "B.Cu")
		(net "GND")
	)
	(segment
		(start 257.830066 -5.215636)
		(end 257.634994 -5.020564)
		(width 0.3556)
		(layer "B.Cu")
		(net "GND")
	)
	(segment
		(start 188.100208 -225.92538)
		(end 188.100208 -223.4819)
		(width 0.508)
		(layer "B.Cu")
		(net "GND")
	)
	(segment
		(start 142.400782 -32.508952)
		(end 143.002508 -33.110678)
		(width 0.508)
		(layer "B.Cu")
		(net "GND")
	)
	(segment
		(start 45.14469 -131.445)
		(end 44.504864 -132.084826)
		(width 0.4064)
		(layer "B.Cu")
		(net "GND")
	)
	(segment
		(start 40.058086 -38.999922)
		(end 41.099994 -38.999922)
		(width 0.508)
		(layer "B.Cu")
		(net "GND")
	)
	(segment
		(start 129.4384 -195.9483)
		(end 129.4384 -195.71081)
		(width 0.508)
		(layer "B.Cu")
		(net "GND")
	)
	(segment
		(start 76.581 -198.1454)
		(end 76.581 -197.8152)
		(width 0.508)
		(layer "B.Cu")
		(net "GND")
	)
	(segment
		(start 174.634398 0.893318)
		(end 174.634398 0.08001)
		(width 0.508)
		(layer "B.Cu")
		(net "GND")
	)
	(segment
		(start 140.1445 -34.059876)
		(end 140.1445 -34.929572)
		(width 0.508)
		(layer "B.Cu")
		(net "GND")
	)
	(segment
		(start 123.698 -199.3011)
		(end 122.809 -199.3011)
		(width 0.508)
		(layer "B.Cu")
		(net "GND")
	)
	(segment
		(start 236.8423 -40.005)
		(end 236.8423 -40.242236)
		(width 0.3048)
		(layer "B.Cu")
		(net "GND")
	)
	(segment
		(start 290.100004 -223.4819)
		(end 289.700208 -223.082104)
		(width 0.508)
		(layer "B.Cu")
		(net "GND")
	)
	(segment
		(start 77.300074 -225.92538)
		(end 77.300074 -221.200726)
		(width 0.508)
		(layer "B.Cu")
		(net "GND")
	)
	(segment
		(start 140.821156 0.08001)
		(end 141.634464 0.08001)
		(width 0.508)
		(layer "B.Cu")
		(net "GND")
	)
	(segment
		(start 128.525524 -32.50565)
		(end 128.525524 -32.050482)
		(width 0.508)
		(layer "B.Cu")
		(net "GND")
	)
	(segment
		(start 130.634486 0.08001)
		(end 131.447794 0.08001)
		(width 0.508)
		(layer "B.Cu")
		(net "GND")
	)
	(segment
		(start 253.873 -38.002972)
		(end 253.873 -37.726874)
		(width 0.3048)
		(layer "B.Cu")
		(net "GND")
	)
	(segment
		(start 283.70022 -223.482154)
		(end 283.30017 -223.082104)
		(width 0.508)
		(layer "B.Cu")
		(net "GND")
	)
	(segment
		(start 337.891628 -179.633626)
		(end 338.129626 -179.633626)
		(width 0.3048)
		(layer "B.Cu")
		(net "GND")
	)
	(segment
		(start 16.4338 -135.89)
		(end 16.3068 -135.763)
		(width 0.508)
		(layer "B.Cu")
		(net "GND")
	)
	(segment
		(start 333.30007 -225.92538)
		(end 333.30007 -223.4819)
		(width 0.508)
		(layer "B.Cu")
		(net "GND")
	)
	(segment
		(start 234.5944 -31.6992)
		(end 234.299252 -31.6992)
		(width 0.3048)
		(layer "B.Cu")
		(net "GND")
	)
	(segment
		(start 254.347472 -41.012872)
		(end 254.612648 -41.012872)
		(width 0.3048)
		(layer "B.Cu")
		(net "GND")
	)
	(segment
		(start 235.8644 -59.0042)
		(end 235.8644 -59.264042)
		(width 0.3048)
		(layer "B.Cu")
		(net "GND")
	)
	(segment
		(start 79.70012 -225.92538)
		(end 79.70012 -223.38792)
		(width 0.508)
		(layer "B.Cu")
		(net "GND")
	)
	(segment
		(start 237.3376 -57.995058)
		(end 237.3376 -58.262266)
		(width 0.3048)
		(layer "B.Cu")
		(net "GND")
	)
	(segment
		(start 176.53 -207.899)
		(end 177.3174 -208.6864)
		(width 0.508)
		(layer "B.Cu")
		(net "GND")
	)
	(segment
		(start 242.062 -34.537904)
		(end 242.099846 -34.500058)
		(width 0.3048)
		(layer "B.Cu")
		(net "GND")
	)
	(segment
		(start 253.873 -37.27323)
		(end 254.099822 -37.500052)
		(width 0.3048)
		(layer "B.Cu")
		(net "GND")
	)
	(segment
		(start 136.100058 -223.614742)
		(end 136.652 -223.0628)
		(width 0.508)
		(layer "B.Cu")
		(net "GND")
	)
	(segment
		(start 264.500106 -225.92538)
		(end 264.500106 -223.482154)
		(width 0.508)
		(layer "B.Cu")
		(net "GND")
	)
	(segment
		(start 81.833212 -186.100974)
		(end 81.833212 -185.211212)
		(width 0.508)
		(layer "B.Cu")
		(net "GND")
	)
	(segment
		(start 82.900012 -225.92538)
		(end 82.900012 -223.482154)
		(width 0.508)
		(layer "B.Cu")
		(net "GND")
	)
	(segment
		(start 232.611422 -31.6992)
		(end 232.299256 -31.6992)
		(width 0.3048)
		(layer "B.Cu")
		(net "GND")
	)
	(segment
		(start 346.329 -68.0212)
		(end 347.5482 -68.0212)
		(width 0.508)
		(layer "B.Cu")
		(net "GND")
	)
	(segment
		(start 313.30011 -223.482154)
		(end 312.90006 -223.082104)
		(width 0.508)
		(layer "B.Cu")
		(net "GND")
	)
	(segment
		(start 339.700108 -225.92538)
		(end 339.700108 -223.4819)
		(width 0.508)
		(layer "B.Cu")
		(net "GND")
	)
	(segment
		(start 240.538 -23.6855)
		(end 239.395 -23.6855)
		(width 0.508)
		(layer "B.Cu")
		(net "GND")
	)
	(segment
		(start 225.425 -10.2616)
		(end 225.5012 -10.1854)
		(width 0.508)
		(layer "B.Cu")
		(net "GND")
	)
	(segment
		(start 274.900136 -223.4819)
		(end 275.299932 -223.082104)
		(width 0.508)
		(layer "B.Cu")
		(net "GND")
	)
	(segment
		(start 326.100186 -225.92538)
		(end 326.100186 -223.482154)
		(width 0.508)
		(layer "B.Cu")
		(net "GND")
	)
	(segment
		(start 154.500072 -225.92538)
		(end 154.500072 -223.482154)
		(width 0.508)
		(layer "B.Cu")
		(net "GND")
	)
	(segment
		(start 217.297 -197.188328)
		(end 217.297 -196.977)
		(width 0.381)
		(layer "B.Cu")
		(net "GND")
	)
	(segment
		(start 348.389956 -44.63923)
		(end 347.479112 -44.63923)
		(width 0.508)
		(layer "B.Cu")
		(net "GND")
	)
	(segment
		(start 237.2614 -32.661352)
		(end 237.10011 -32.500062)
		(width 0.3048)
		(layer "B.Cu")
		(net "GND")
	)
	(segment
		(start 231.0638 -34.53638)
		(end 231.100122 -34.500058)
		(width 0.3048)
		(layer "B.Cu")
		(net "GND")
	)
	(segment
		(start 143.002508 -33.110678)
		(end 143.002508 -33.99663)
		(width 0.508)
		(layer "B.Cu")
		(net "GND")
	)
	(segment
		(start 124.079 -205.2955)
		(end 123.2662 -205.2955)
		(width 0.508)
		(layer "B.Cu")
		(net "GND")
	)
	(segment
		(start 228.10724 -197.8025)
		(end 228.10724 -197.806818)
		(width 0.3048)
		(layer "B.Cu")
		(net "GND")
	)
	(segment
		(start 230.29926 -31.6992)
		(end 230.100124 -31.500064)
		(width 0.3048)
		(layer "B.Cu")
		(net "GND")
	)
	(segment
		(start 237.8964 -59.296046)
		(end 238.100108 -59.499754)
		(width 0.3048)
		(layer "B.Cu")
		(net "GND")
	)
	(segment
		(start 280.500074 -225.92538)
		(end 280.500074 -223.482154)
		(width 0.508)
		(layer "B.Cu")
		(net "GND")
	)
	(segment
		(start 250.1138 -34.514028)
		(end 250.09983 -34.500058)
		(width 0.3048)
		(layer "B.Cu")
		(net "GND")
	)
	(segment
		(start 56.134 -137.4902)
		(end 56.134 -136.7155)
		(width 0.508)
		(layer "B.Cu")
		(net "GND")
	)
	(segment
		(start 38.1381 -113.431828)
		(end 38.058852 -113.35258)
		(width 0.508)
		(layer "B.Cu")
		(net "GND")
	)
	(segment
		(start 320.500248 -223.4819)
		(end 320.900044 -223.082104)
		(width 0.508)
		(layer "B.Cu")
		(net "GND")
	)
	(segment
		(start 187.300108 -225.92538)
		(end 187.300108 -223.482154)
		(width 0.508)
		(layer "B.Cu")
		(net "GND")
	)
	(segment
		(start 315.82106 0.08001)
		(end 316.634368 0.08001)
		(width 0.508)
		(layer "B.Cu")
		(net "GND")
	)
	(segment
		(start 57.15 -134.4295)
		(end 56.134 -134.4295)
		(width 0.508)
		(layer "B.Cu")
		(net "GND")
	)
	(segment
		(start 24.0284 -70.3834)
		(end 24.44496 -69.96684)
		(width 0.508)
		(layer "B.Cu")
		(net "GND")
	)
	(segment
		(start 241.8842 -58.28411)
		(end 242.099846 -58.499756)
		(width 0.3048)
		(layer "B.Cu")
		(net "GND")
	)
	(segment
		(start 194.500246 -223.4819)
		(end 194.900042 -223.082104)
		(width 0.508)
		(layer "B.Cu")
		(net "GND")
	)
	(segment
		(start 277.300182 -223.482154)
		(end 276.900132 -223.082104)
		(width 0.508)
		(layer "B.Cu")
		(net "GND")
	)
	(segment
		(start 127.972058 -33.059116)
		(end 128.525524 -32.50565)
		(width 0.508)
		(layer "B.Cu")
		(net "GND")
	)
	(segment
		(start 58.90006 -223.4819)
		(end 59.299856 -223.082104)
		(width 0.508)
		(layer "B.Cu")
		(net "GND")
	)
	(segment
		(start 255.387348 -9.123426)
		(end 255.387348 -9.430004)
		(width 0.508)
		(layer "B.Cu")
		(net "GND")
	)
	(segment
		(start 319.700148 -225.92538)
		(end 319.700148 -223.482154)
		(width 0.508)
		(layer "B.Cu")
		(net "GND")
	)
	(segment
		(start 222.8088 -190.119)
		(end 223.4692 -189.4586)
		(width 0.508)
		(layer "B.Cu")
		(net "GND")
	)
	(segment
		(start 245.872 -59.9948)
		(end 245.872 -60.271914)
		(width 0.3048)
		(layer "B.Cu")
		(net "GND")
	)
	(segment
		(start 157.700218 -225.92538)
		(end 157.700218 -223.482154)
		(width 0.508)
		(layer "B.Cu")
		(net "GND")
	)
	(segment
		(start 220.45676 -9.4869)
		(end 220.45676 -8.77824)
		(width 0.381)
		(layer "B.Cu")
		(net "GND")
	)
	(segment
		(start 330.100178 -224.280222)
		(end 330.6572 -223.7232)
		(width 0.508)
		(layer "B.Cu")
		(net "GND")
	)
	(segment
		(start 42.126154 -159.432244)
		(end 42.126154 -160.185354)
		(width 0.508)
		(layer "B.Cu")
		(net "GND")
	)
	(segment
		(start 44.500038 -223.4819)
		(end 44.899834 -223.082104)
		(width 0.508)
		(layer "B.Cu")
		(net "GND")
	)
	(segment
		(start 222.28683 -193.554858)
		(end 222.28683 -192.915794)
		(width 0.508)
		(layer "B.Cu")
		(net "GND")
	)
	(segment
		(start 137.8712 -204.8002)
		(end 137.795 -204.724)
		(width 0.508)
		(layer "B.Cu")
		(net "GND")
	)
	(segment
		(start 179.300124 -225.92538)
		(end 179.300124 -223.482154)
		(width 0.508)
		(layer "B.Cu")
		(net "GND")
	)
	(segment
		(start 46.900084 -223.279716)
		(end 47.117 -223.0628)
		(width 0.508)
		(layer "B.Cu")
		(net "GND")
	)
	(segment
		(start 314.10021 -223.4819)
		(end 314.500006 -223.082104)
		(width 0.508)
		(layer "B.Cu")
		(net "GND")
	)
	(segment
		(start 125.314202 -203.636626)
		(end 125.623828 -203.327)
		(width 0.4064)
		(layer "B.Cu")
		(net "GND")
	)
	(segment
		(start 95.700088 -225.92538)
		(end 95.700088 -223.4819)
		(width 0.508)
		(layer "B.Cu")
		(net "GND")
	)
	(segment
		(start 338.129626 -179.633626)
		(end 338.709 -180.213)
		(width 0.3048)
		(layer "B.Cu")
		(net "GND")
	)
	(segment
		(start 243.401088 -31.500064)
		(end 243.099844 -31.500064)
		(width 0.3048)
		(layer "B.Cu")
		(net "GND")
	)
	(segment
		(start 235.3056 -59.99734)
		(end 235.3056 -60.294266)
		(width 0.3048)
		(layer "B.Cu")
		(net "GND")
	)
	(segment
		(start 223.744282 -7.488682)
		(end 223.1771 -6.9215)
		(width 0.508)
		(layer "B.Cu")
		(net "GND")
	)
	(segment
		(start 216.100152 -225.92538)
		(end 216.100152 -223.482154)
		(width 0.508)
		(layer "B.Cu")
		(net "GND")
	)
	(segment
		(start 310.900064 -223.4819)
		(end 311.29986 -223.082104)
		(width 0.508)
		(layer "B.Cu")
		(net "GND")
	)
	(segment
		(start 213.700106 -225.92538)
		(end 213.700106 -223.4819)
		(width 0.508)
		(layer "B.Cu")
		(net "GND")
	)
	(segment
		(start 66.900044 -223.482154)
		(end 66.499994 -223.082104)
		(width 0.508)
		(layer "B.Cu")
		(net "GND")
	)
	(segment
		(start 287.700212 -223.4819)
		(end 288.100008 -223.082104)
		(width 0.508)
		(layer "B.Cu")
		(net "GND")
	)
	(segment
		(start 129.6035 -203.6445)
		(end 129.921 -203.962)
		(width 0.4064)
		(layer "B.Cu")
		(net "GND")
	)
	(segment
		(start 206.500222 -223.482154)
		(end 206.100172 -223.082104)
		(width 0.508)
		(layer "B.Cu")
		(net "GND")
	)
	(segment
		(start 151.30018 -223.482154)
		(end 150.90013 -223.082104)
		(width 0.508)
		(layer "B.Cu")
		(net "GND")
	)
	(segment
		(start 170.50004 -223.4819)
		(end 170.899836 -223.082104)
		(width 0.508)
		(layer "B.Cu")
		(net "GND")
	)
	(segment
		(start 160.90011 -223.482154)
		(end 160.50006 -223.082104)
		(width 0.508)
		(layer "B.Cu")
		(net "GND")
	)
	(segment
		(start 220.48724 -197.8025)
		(end 220.9292 -197.8025)
		(width 0.3048)
		(layer "B.Cu")
		(net "GND")
	)
	(segment
		(start 148.900134 -223.4819)
		(end 149.29993 -223.082104)
		(width 0.508)
		(layer "B.Cu")
		(net "GND")
	)
	(segment
		(start 50.165 -146.6342)
		(end 50.165 -145.8595)
		(width 0.508)
		(layer "B.Cu")
		(net "GND")
	)
	(segment
		(start 124.832364 -32.177482)
		(end 125.28423 -32.629348)
		(width 0.508)
		(layer "B.Cu")
		(net "GND")
	)
	(segment
		(start 222.2627 -13.3858)
		(end 222.2627 -14.2875)
		(width 0.508)
		(layer "B.Cu")
		(net "GND")
	)
	(segment
		(start 154.500072 -223.482154)
		(end 154.100022 -223.082104)
		(width 0.508)
		(layer "B.Cu")
		(net "GND")
	)
	(segment
		(start 52.500022 -225.92538)
		(end 52.500022 -223.4819)
		(width 0.508)
		(layer "B.Cu")
		(net "GND")
	)
	(segment
		(start 54.798976 -125.918976)
		(end 55.0037 -126.1237)
		(width 0.508)
		(layer "B.Cu")
		(net "GND")
	)
	(segment
		(start 70.900036 -223.4819)
		(end 71.299832 -223.082104)
		(width 0.508)
		(layer "B.Cu")
		(net "GND")
	)
	(segment
		(start 215.55964 -200.46696)
		(end 216.374218 -200.468738)
		(width 0.508)
		(layer "B.Cu")
		(net "GND")
	)
	(segment
		(start 55.700168 -223.4819)
		(end 56.099964 -223.082104)
		(width 0.508)
		(layer "B.Cu")
		(net "GND")
	)
	(segment
		(start 237.8964 -56.9976)
		(end 237.8964 -57.29605)
		(width 0.3048)
		(layer "B.Cu")
		(net "GND")
	)
	(segment
		(start 33.070038 -109.31271)
		(end 33.441132 -109.31271)
		(width 0.508)
		(layer "B.Cu")
		(net "GND")
	)
	(segment
		(start 295.302178 -209.04454)
		(end 295.302178 -208.129378)
		(width 0.508)
		(layer "B.Cu")
		(net "GND")
	)
	(segment
		(start 284.500066 -223.4819)
		(end 284.899862 -223.082104)
		(width 0.508)
		(layer "B.Cu")
		(net "GND")
	)
	(segment
		(start 281.300174 -223.4819)
		(end 281.69997 -223.082104)
		(width 0.508)
		(layer "B.Cu")
		(net "GND")
	)
	(segment
		(start 86.900004 -223.4819)
		(end 87.2998 -223.082104)
		(width 0.508)
		(layer "B.Cu")
		(net "GND")
	)
	(segment
		(start 262.694674 -0.721868)
		(end 261.736332 -0.721868)
		(width 0.508)
		(layer "B.Cu")
		(net "GND")
	)
	(segment
		(start 323.70014 -225.92538)
		(end 323.70014 -223.4819)
		(width 0.508)
		(layer "B.Cu")
		(net "GND")
	)
	(segment
		(start 238.8616 -35.738562)
		(end 239.100106 -35.500056)
		(width 0.3048)
		(layer "B.Cu")
		(net "GND")
	)
	(segment
		(start 253.873 -32.726884)
		(end 254.099822 -32.500062)
		(width 0.3048)
		(layer "B.Cu")
		(net "GND")
	)
	(segment
		(start 61.300106 -223.562164)
		(end 61.204094 -223.466152)
		(width 0.508)
		(layer "B.Cu")
		(net "GND")
	)
	(segment
		(start 331.724 -181.1655)
		(end 331.2033 -180.6448)
		(width 0.508)
		(layer "B.Cu")
		(net "GND")
	)
	(segment
		(start 55.700168 -225.92538)
		(end 55.700168 -223.4819)
		(width 0.508)
		(layer "B.Cu")
		(net "GND")
	)
	(segment
		(start 102.100126 -225.92538)
		(end 102.100126 -223.4819)
		(width 0.508)
		(layer "B.Cu")
		(net "GND")
	)
	(segment
		(start 294.634412 0.08001)
		(end 295.44772 0.08001)
		(width 0.508)
		(layer "B.Cu")
		(net "GND")
	)
	(segment
		(start 257.830066 -5.95249)
		(end 257.830066 -5.215636)
		(width 0.3556)
		(layer "B.Cu")
		(net "GND")
	)
	(segment
		(start 51.700176 -225.92538)
		(end 51.700176 -223.482154)
		(width 0.508)
		(layer "B.Cu")
		(net "GND")
	)
	(segment
		(start 55.0037 -126.1237)
		(end 55.0164 -126.1237)
		(width 0.508)
		(layer "B.Cu")
		(net "GND")
	)
	(segment
		(start 167.300148 -225.92538)
		(end 167.300148 -223.4819)
		(width 0.508)
		(layer "B.Cu")
		(net "GND")
	)
	(segment
		(start 101.300026 -223.482154)
		(end 100.899976 -223.082104)
		(width 0.508)
		(layer "B.Cu")
		(net "GND")
	)
	(segment
		(start 163.63442 0.893318)
		(end 163.63442 0.08001)
		(width 0.508)
		(layer "B.Cu")
		(net "GND")
	)
	(segment
		(start 338.900008 -223.4819)
		(end 338.500212 -223.082104)
		(width 0.508)
		(layer "B.Cu")
		(net "GND")
	)
	(segment
		(start 174.634398 0.08001)
		(end 175.447706 0.08001)
		(width 0.508)
		(layer "B.Cu")
		(net "GND")
	)
	(segment
		(start 30.569154 -160.067244)
		(end 30.569154 -160.909)
		(width 0.508)
		(layer "B.Cu")
		(net "GND")
	)
	(segment
		(start 35.545776 -112.801908)
		(end 35.545776 -113.965736)
		(width 0.508)
		(layer "B.Cu")
		(net "GND")
	)
	(segment
		(start 237.2614 -32.9946)
		(end 237.2614 -32.661352)
		(width 0.3048)
		(layer "B.Cu")
		(net "GND")
	)
	(segment
		(start 38.062154 -159.432244)
		(end 38.062154 -160.337754)
		(width 0.508)
		(layer "B.Cu")
		(net "GND")
	)
	(segment
		(start 95.700088 -223.4819)
		(end 96.099884 -223.082104)
		(width 0.508)
		(layer "B.Cu")
		(net "GND")
	)
	(segment
		(start 151.649176 -33.100772)
		(end 151.649176 -32.11195)
		(width 0.508)
		(layer "B.Cu")
		(net "GND")
	)
	(segment
		(start 37.1221 -113.43894)
		(end 37.1221 -114.10696)
		(width 0.508)
		(layer "B.Cu")
		(net "GND")
	)
	(segment
		(start 39.586154 -159.432244)
		(end 39.586154 -160.286954)
		(width 0.508)
		(layer "B.Cu")
		(net "GND")
	)
	(segment
		(start 243.8654 -58.265314)
		(end 244.099842 -58.499756)
		(width 0.3048)
		(layer "B.Cu")
		(net "GND")
	)
	(segment
		(start 304.821082 0.08001)
		(end 305.63439 0.08001)
		(width 0.508)
		(layer "B.Cu")
		(net "GND")
	)
	(segment
		(start 224.04324 -197.640194)
		(end 224.706434 -196.977)
		(width 0.3048)
		(layer "B.Cu")
		(net "GND")
	)
	(segment
		(start 245.324376 -31.7246)
		(end 245.09984 -31.500064)
		(width 0.3048)
		(layer "B.Cu")
		(net "GND")
	)
	(segment
		(start 64.499998 -225.92538)
		(end 64.499998 -223.4819)
		(width 0.508)
		(layer "B.Cu")
		(net "GND")
	)
	(segment
		(start 187.300108 -223.482154)
		(end 186.900058 -223.082104)
		(width 0.508)
		(layer "B.Cu")
		(net "GND")
	)
	(segment
		(start 226.740212 -193.41719)
		(end 227.400612 -192.75679)
		(width 0.508)
		(layer "B.Cu")
		(net "GND")
	)
	(segment
		(start 264.500106 -223.482154)
		(end 264.100056 -223.082104)
		(width 0.508)
		(layer "B.Cu")
		(net "GND")
	)
	(segment
		(start 45.2755 -131.445)
		(end 45.14469 -131.445)
		(width 0.4064)
		(layer "B.Cu")
		(net "GND")
	)
	(segment
		(start 98.89998 -223.4819)
		(end 99.299776 -223.082104)
		(width 0.508)
		(layer "B.Cu")
		(net "GND")
	)
	(segment
		(start 224.3074 -189.4586)
		(end 224.8916 -188.8744)
		(width 0.508)
		(layer "B.Cu")
		(net "GND")
	)
	(segment
		(start 162.821112 0.08001)
		(end 163.63442 0.08001)
		(width 0.508)
		(layer "B.Cu")
		(net "GND")
	)
	(segment
		(start 215.4174 -21.3741)
		(end 214.8459 -21.3741)
		(width 0.508)
		(layer "B.Cu")
		(net "GND")
	)
	(segment
		(start 58.09996 -225.92538)
		(end 58.09996 -223.4819)
		(width 0.508)
		(layer "B.Cu")
		(net "GND")
	)
	(segment
		(start 176.100232 -225.92538)
		(end 176.100232 -223.482154)
		(width 0.508)
		(layer "B.Cu")
		(net "GND")
	)
	(segment
		(start 35.545776 -113.965736)
		(end 35.687 -114.10696)
		(width 0.508)
		(layer "B.Cu")
		(net "GND")
	)
	(segment
		(start 38.1381 -114.10696)
		(end 38.1381 -113.431828)
		(width 0.508)
		(layer "B.Cu")
		(net "GND")
	)
	(segment
		(start 61.204094 -223.386142)
		(end 60.900056 -223.082104)
		(width 0.508)
		(layer "B.Cu")
		(net "GND")
	)
	(segment
		(start 102.100126 -223.4819)
		(end 102.499922 -223.082104)
		(width 0.508)
		(layer "B.Cu")
		(net "GND")
	)
	(segment
		(start 64.499998 -223.4819)
		(end 64.899794 -223.082104)
		(width 0.508)
		(layer "B.Cu")
		(net "GND")
	)
	(segment
		(start 294.634412 0.08001)
		(end 294.634412 -0.733298)
		(width 0.508)
		(layer "B.Cu")
		(net "GND")
	)
	(segment
		(start 294.099996 -225.92538)
		(end 294.099996 -223.4819)
		(width 0.508)
		(layer "B.Cu")
		(net "GND")
	)
	(segment
		(start 222.8088 -190.1317)
		(end 222.8088 -190.119)
		(width 0.508)
		(layer "B.Cu")
		(net "GND")
	)
	(segment
		(start 157.700218 -223.482154)
		(end 157.300168 -223.082104)
		(width 0.508)
		(layer "B.Cu")
		(net "GND")
	)
	(segment
		(start 129.821178 0.08001)
		(end 130.634486 0.08001)
		(width 0.508)
		(layer "B.Cu")
		(net "GND")
	)
	(segment
		(start 222.097092 -194.284092)
		(end 222.097092 -193.744596)
		(width 0.508)
		(layer "B.Cu")
		(net "GND")
	)
	(segment
		(start 105.300018 -223.4819)
		(end 105.699814 -223.082104)
		(width 0.508)
		(layer "B.Cu")
		(net "GND")
	)
	(segment
		(start 274.100036 -225.92538)
		(end 274.100036 -223.4819)
		(width 0.508)
		(layer "B.Cu")
		(net "GND")
	)
	(segment
		(start 262.60425 -13.701268)
		(end 263.088882 -13.216636)
		(width 0.508)
		(layer "B.Cu")
		(net "GND")
	)
	(segment
		(start 36.500054 -223.683576)
		(end 36.500054 -225.92538)
		(width 0.508)
		(layer "B.Cu")
		(net "GND")
	)
	(segment
		(start 98.100134 -223.482154)
		(end 97.700084 -223.082104)
		(width 0.508)
		(layer "B.Cu")
		(net "GND")
	)
	(segment
		(start 79.389224 -191.479424)
		(end 79.616808 -191.479424)
		(width 0.4064)
		(layer "B.Cu")
		(net "GND")
	)
	(segment
		(start 164.100002 -223.967802)
		(end 163.1188 -222.9866)
		(width 0.508)
		(layer "B.Cu")
		(net "GND")
	)
	(segment
		(start 40.856154 -159.432244)
		(end 40.856154 -160.185354)
		(width 0.508)
		(layer "B.Cu")
		(net "GND")
	)
	(segment
		(start 191.3001 -225.92538)
		(end 191.3001 -223.4819)
		(width 0.508)
		(layer "B.Cu")
		(net "GND")
	)
	(segment
		(start 193.700146 -223.482154)
		(end 193.300096 -223.082104)
		(width 0.508)
		(layer "B.Cu")
		(net "GND")
	)
	(segment
		(start 213.700106 -223.4819)
		(end 214.099902 -223.082104)
		(width 0.508)
		(layer "B.Cu")
		(net "GND")
	)
	(segment
		(start 230.0351 -29.435044)
		(end 230.100124 -29.500068)
		(width 0.508)
		(layer "B.Cu")
		(net "GND")
	)
	(segment
		(start 317.300102 -225.92538)
		(end 317.300102 -223.4819)
		(width 0.508)
		(layer "B.Cu")
		(net "GND")
	)
	(segment
		(start 38.1 -225.92538)
		(end 38.1 -223.012)
		(width 0.508)
		(layer "B.Cu")
		(net "GND")
	)
	(segment
		(start 136.100058 -225.92538)
		(end 136.100058 -223.614742)
		(width 0.508)
		(layer "B.Cu")
		(net "GND")
	)
	(segment
		(start 138.500104 -223.386904)
		(end 138.176 -223.0628)
		(width 0.508)
		(layer "B.Cu")
		(net "GND")
	)
	(segment
		(start 148.100034 -223.4819)
		(end 147.700238 -223.082104)
		(width 0.508)
		(layer "B.Cu")
		(net "GND")
	)
	(segment
		(start 236.8423 -40.242236)
		(end 237.10011 -40.500046)
		(width 0.3048)
		(layer "B.Cu")
		(net "GND")
	)
	(segment
		(start 223.1771 -6.9215)
		(end 222.8342 -6.9215)
		(width 0.508)
		(layer "B.Cu")
		(net "GND")
	)
	(segment
		(start 217.2081 -197.277228)
		(end 217.297 -197.188328)
		(width 0.381)
		(layer "B.Cu")
		(net "GND")
	)
	(segment
		(start 73.705212 -186.100974)
		(end 72.5805 -186.100974)
		(width 0.508)
		(layer "B.Cu")
		(net "GND")
	)
	(segment
		(start 163.63442 0.08001)
		(end 164.447728 0.08001)
		(width 0.508)
		(layer "B.Cu")
		(net "GND")
	)
	(segment
		(start 28.503118 -75.29449)
		(end 28.317698 -75.29449)
		(width 0.508)
		(layer "B.Cu")
		(net "GND")
	)
	(segment
		(start 226.740212 -193.466974)
		(end 226.740212 -193.41719)
		(width 0.508)
		(layer "B.Cu")
		(net "GND")
	)
	(segment
		(start 80.499966 -223.4819)
		(end 80.899762 -223.082104)
		(width 0.508)
		(layer "B.Cu")
		(net "GND")
	)
	(segment
		(start 225.425 -11.4046)
		(end 225.425 -10.2616)
		(width 0.508)
		(layer "B.Cu")
		(net "GND")
	)
	(segment
		(start 73.300082 -223.482154)
		(end 72.900032 -223.082104)
		(width 0.508)
		(layer "B.Cu")
		(net "GND")
	)
	(segment
		(start 333.30007 -223.4819)
		(end 333.699866 -223.082104)
		(width 0.508)
		(layer "B.Cu")
		(net "GND")
	)
	(segment
		(start 330.100178 -225.92538)
		(end 330.100178 -224.280222)
		(width 0.508)
		(layer "B.Cu")
		(net "GND")
	)
	(segment
		(start 50.165 -145.8595)
		(end 51.181 -145.8595)
		(width 0.508)
		(layer "B.Cu")
		(net "GND")
	)
	(segment
		(start 61.300106 -225.92538)
		(end 61.300106 -223.562164)
		(width 0.508)
		(layer "B.Cu")
		(net "GND")
	)
	(segment
		(start 327.634346 0.08001)
		(end 328.447654 0.08001)
		(width 0.508)
		(layer "B.Cu")
		(net "GND")
	)
	(segment
		(start 234.299252 -31.6992)
		(end 234.100116 -31.500064)
		(width 0.3048)
		(layer "B.Cu")
		(net "GND")
	)
	(segment
		(start 132.607812 -199.04202)
		(end 132.607812 -198.884286)
		(width 0.508)
		(layer "B.Cu")
		(net "GND")
	)
	(segment
		(start 155.300172 -225.92538)
		(end 155.300172 -223.4819)
		(width 0.508)
		(layer "B.Cu")
		(net "GND")
	)
	(segment
		(start 334.01 -180.074316)
		(end 334.148684 -180.213)
		(width 0.3048)
		(layer "B.Cu")
		(net "GND")
	)
	(segment
		(start 32.220154 -160.067244)
		(end 32.220154 -160.896046)
		(width 0.508)
		(layer "B.Cu")
		(net "GND")
	)
	(segment
		(start 18.8595 -126.619)
		(end 19.595592 -126.619)
		(width 0.508)
		(layer "B.Cu")
		(net "GND")
	)
	(segment
		(start 336.5246 -175.2981)
		(end 336.5246 -175.232314)
		(width 0.508)
		(layer "B.Cu")
		(net "GND")
	)
	(segment
		(start 176.53 -207.5942)
		(end 176.53 -207.899)
		(width 0.508)
		(layer "B.Cu")
		(net "GND")
	)
	(segment
		(start 158.500064 -225.92538)
		(end 158.500064 -223.4819)
		(width 0.508)
		(layer "B.Cu")
		(net "GND")
	)
	(segment
		(start 152.532588 -32.416242)
		(end 152.024588 -31.908242)
		(width 0.508)
		(layer "B.Cu")
		(net "GND")
	)
	(segment
		(start 193.700146 -225.92538)
		(end 193.700146 -223.482154)
		(width 0.508)
		(layer "B.Cu")
		(net "GND")
	)
	(segment
		(start 34.100008 -223.836992)
		(end 34.100008 -225.92538)
		(width 0.508)
		(layer "B.Cu")
		(net "GND")
	)
	(segment
		(start 132.204714 -199.445118)
		(end 132.607812 -199.04202)
		(width 0.508)
		(layer "B.Cu")
		(net "GND")
	)
	(segment
		(start 203.300076 -225.92538)
		(end 203.300076 -223.482154)
		(width 0.508)
		(layer "B.Cu")
		(net "GND")
	)
	(segment
		(start 56.134 -134.4295)
		(end 55.245 -134.4295)
		(width 0.508)
		(layer "B.Cu")
		(net "GND")
	)
	(segment
		(start 330.6572 -223.7232)
		(end 330.6572 -223.0374)
		(width 0.508)
		(layer "B.Cu")
		(net "GND")
	)
	(segment
		(start 129.668524 -195.476876)
		(end 129.9972 -195.1482)
		(width 0.508)
		(layer "B.Cu")
		(net "GND")
	)
	(segment
		(start 338.900008 -225.92538)
		(end 338.900008 -223.4819)
		(width 0.508)
		(layer "B.Cu")
		(net "GND")
	)
	(segment
		(start 243.3066 -57.293002)
		(end 243.099844 -57.499758)
		(width 0.3048)
		(layer "B.Cu")
		(net "GND")
	)
	(segment
		(start 38.1 -223.012)
		(end 38.0238 -222.9358)
		(width 0.508)
		(layer "B.Cu")
		(net "GND")
	)
	(segment
		(start 139.300204 -223.4819)
		(end 139.7 -223.082104)
		(width 0.508)
		(layer "B.Cu")
		(net "GND")
	)
	(segment
		(start 218.540838 -193.0146)
		(end 218.10853 -193.0146)
		(width 0.508)
		(layer "B.Cu")
		(net "GND")
	)
	(segment
		(start 267.699998 -223.4819)
		(end 267.300202 -223.082104)
		(width 0.508)
		(layer "B.Cu")
		(net "GND")
	)
	(segment
		(start 89.30005 -225.92538)
		(end 89.30005 -223.482154)
		(width 0.508)
		(layer "B.Cu")
		(net "GND")
	)
	(segment
		(start 336.061304 -174.769018)
		(end 336.061304 -174.497746)
		(width 0.508)
		(layer "B.Cu")
		(net "GND")
	)
	(segment
		(start 235.3056 -60.294266)
		(end 235.100114 -60.499752)
		(width 0.3048)
		(layer "B.Cu")
		(net "GND")
	)
	(segment
		(start 265.69416 -3.51536)
		(end 266.046966 -3.868166)
		(width 0.508)
		(layer "B.Cu")
		(net "GND")
	)
	(segment
		(start 302.100234 -225.92538)
		(end 302.100234 -223.482154)
		(width 0.508)
		(layer "B.Cu")
		(net "GND")
	)
	(segment
		(start 172.900086 -225.92538)
		(end 172.900086 -223.482154)
		(width 0.508)
		(layer "B.Cu")
		(net "GND")
	)
	(segment
		(start 160.90011 -225.92538)
		(end 160.90011 -223.482154)
		(width 0.508)
		(layer "B.Cu")
		(net "GND")
	)
	(segment
		(start 109.30001 -225.92538)
		(end 109.30001 -223.4819)
		(width 0.508)
		(layer "B.Cu")
		(net "GND")
	)
	(segment
		(start 196.900038 -225.92538)
		(end 196.900038 -223.4819)
		(width 0.508)
		(layer "B.Cu")
		(net "GND")
	)
	(segment
		(start 37.12591 -113.43513)
		(end 37.1221 -113.43894)
		(width 0.508)
		(layer "B.Cu")
		(net "GND")
	)
	(segment
		(start 137.8712 -205.4987)
		(end 137.8712 -204.8002)
		(width 0.508)
		(layer "B.Cu")
		(net "GND")
	)
	(segment
		(start 73.300082 -225.92538)
		(end 73.300082 -223.482154)
		(width 0.508)
		(layer "B.Cu")
		(net "GND")
	)
	(segment
		(start 142.500096 -223.4819)
		(end 142.899892 -223.082104)
		(width 0.508)
		(layer "B.Cu")
		(net "GND")
	)
	(segment
		(start 277.300182 -225.92538)
		(end 277.300182 -223.482154)
		(width 0.508)
		(layer "B.Cu")
		(net "GND")
	)
	(segment
		(start 142.136114 -33.99663)
		(end 142.136114 -32.77362)
		(width 0.508)
		(layer "B.Cu")
		(net "GND")
	)
	(segment
		(start 294.099996 -223.4819)
		(end 294.499792 -223.082104)
		(width 0.508)
		(layer "B.Cu")
		(net "GND")
	)
	(segment
		(start 39.54272 -113.6523)
		(end 39.989252 -113.205768)
		(width 0.508)
		(layer "B.Cu")
		(net "GND")
	)
	(segment
		(start 167.300148 -223.4819)
		(end 167.699944 -223.082104)
		(width 0.508)
		(layer "B.Cu")
		(net "GND")
	)
	(segment
		(start 133.23824 -204.288644)
		(end 133.673596 -204.724)
		(width 0.4064)
		(layer "B.Cu")
		(net "GND")
	)
	(segment
		(start 293.30015 -225.92538)
		(end 293.30015 -223.482154)
		(width 0.508)
		(layer "B.Cu")
		(net "GND")
	)
	(segment
		(start 197.700138 -225.92538)
		(end 197.700138 -223.4819)
		(width 0.508)
		(layer "B.Cu")
		(net "GND")
	)
	(segment
		(start 39.54272 -114.09172)
		(end 39.54272 -113.6523)
		(width 0.508)
		(layer "B.Cu")
		(net "GND")
	)
	(segment
		(start 245.3132 -57.286398)
		(end 245.09984 -57.499758)
		(width 0.3048)
		(layer "B.Cu")
		(net "GND")
	)
	(segment
		(start 132.607812 -198.884286)
		(end 132.715 -198.777098)
		(width 0.508)
		(layer "B.Cu")
		(net "GND")
	)
	(segment
		(start 262.60425 -14.6431)
		(end 262.60425 -13.701268)
		(width 0.508)
		(layer "B.Cu")
		(net "GND")
	)
	(segment
		(start 336.5246 -175.232314)
		(end 336.061304 -174.769018)
		(width 0.508)
		(layer "B.Cu")
		(net "GND")
	)
	(segment
		(start 223.744282 -7.768082)
		(end 223.744282 -7.488682)
		(width 0.508)
		(layer "B.Cu")
		(net "GND")
	)
	(segment
		(start 322.90004 -225.92538)
		(end 322.90004 -223.4819)
		(width 0.508)
		(layer "B.Cu")
		(net "GND")
	)
	(segment
		(start 342.100154 -223.482154)
		(end 341.700104 -223.082104)
		(width 0.508)
		(layer "B.Cu")
		(net "GND")
	)
	(segment
		(start 286.900112 -223.482154)
		(end 286.500062 -223.082104)
		(width 0.508)
		(layer "B.Cu")
		(net "GND")
	)
	(segment
		(start 293.30015 -223.482154)
		(end 292.9001 -223.082104)
		(width 0.508)
		(layer "B.Cu")
		(net "GND")
	)
	(segment
		(start 253.873 -32.9946)
		(end 253.873 -32.726884)
		(width 0.3048)
		(layer "B.Cu")
		(net "GND")
	)
	(segment
		(start 34.900108 -223.798892)
		(end 34.900108 -225.92538)
		(width 0.508)
		(layer "B.Cu")
		(net "GND")
	)
	(segment
		(start 234.603544 -38.00348)
		(end 234.100116 -37.500052)
		(width 0.3048)
		(layer "B.Cu")
		(net "GND")
	)
	(segment
		(start 293.821104 0.08001)
		(end 294.634412 0.08001)
		(width 0.508)
		(layer "B.Cu")
		(net "GND")
	)
	(segment
		(start 90.10015 -225.92538)
		(end 90.10015 -223.4819)
		(width 0.508)
		(layer "B.Cu")
		(net "GND")
	)
	(segment
		(start 138.500104 -225.92538)
		(end 138.500104 -223.386904)
		(width 0.508)
		(layer "B.Cu")
		(net "GND")
	)
	(segment
		(start 150.783544 -32.526224)
		(end 150.209758 -31.952438)
		(width 0.508)
		(layer "B.Cu")
		(net "GND")
	)
	(segment
		(start 235.8644 -57.264046)
		(end 236.100112 -57.499758)
		(width 0.3048)
		(layer "B.Cu")
		(net "GND")
	)
	(segment
		(start 243.604542 -31.703518)
		(end 243.401088 -31.500064)
		(width 0.3048)
		(layer "B.Cu")
		(net "GND")
	)
	(segment
		(start 124.37872 -33.03397)
		(end 124.37872 -32.631126)
		(width 0.508)
		(layer "B.Cu")
		(net "GND")
	)
	(segment
		(start 169.700194 -225.92538)
		(end 169.700194 -223.482154)
		(width 0.508)
		(layer "B.Cu")
		(net "GND")
	)
	(segment
		(start 302.90008 -223.4819)
		(end 303.299876 -223.082104)
		(width 0.508)
		(layer "B.Cu")
		(net "GND")
	)
	(segment
		(start 339.700108 -223.4819)
		(end 340.099904 -223.082104)
		(width 0.508)
		(layer "B.Cu")
		(net "GND")
	)
	(segment
		(start 104.500172 -223.482154)
		(end 104.100122 -223.082104)
		(width 0.508)
		(layer "B.Cu")
		(net "GND")
	)
	(segment
		(start 137.30224 -204.23124)
		(end 137.795 -204.724)
		(width 0.4064)
		(layer "B.Cu")
		(net "GND")
	)
	(segment
		(start 238.964216 -56.49976)
		(end 239.100106 -56.49976)
		(width 0.3048)
		(layer "B.Cu")
		(net "GND")
	)
	(segment
		(start 243.3066 -56.9976)
		(end 243.3066 -57.293002)
		(width 0.3048)
		(layer "B.Cu")
		(net "GND")
	)
	(segment
		(start 111.700056 -223.482154)
		(end 111.300006 -223.082104)
		(width 0.508)
		(layer "B.Cu")
		(net "GND")
	)
	(segment
		(start 101.300026 -225.92538)
		(end 101.300026 -223.482154)
		(width 0.508)
		(layer "B.Cu")
		(net "GND")
	)
	(segment
		(start 148.900134 -225.92538)
		(end 148.900134 -223.4819)
		(width 0.508)
		(layer "B.Cu")
		(net "GND")
	)
	(segment
		(start 255.387348 -9.430004)
		(end 256.011934 -10.05459)
		(width 0.508)
		(layer "B.Cu")
		(net "GND")
	)
	(segment
		(start 80.499966 -225.92538)
		(end 80.499966 -223.4819)
		(width 0.508)
		(layer "B.Cu")
		(net "GND")
	)
	(segment
		(start 267.699998 -225.92538)
		(end 267.699998 -223.4819)
		(width 0.508)
		(layer "B.Cu")
		(net "GND")
	)
	(segment
		(start 241.3254 -57.274206)
		(end 241.099848 -57.499758)
		(width 0.3048)
		(layer "B.Cu")
		(net "GND")
	)
	(segment
		(start 181.21503 -1.715516)
		(end 180.827426 -1.715516)
		(width 0.508)
		(layer "B.Cu")
		(net "GND")
	)
	(segment
		(start 131.843526 -199.445118)
		(end 132.204714 -199.445118)
		(width 0.508)
		(layer "B.Cu")
		(net "GND")
	)
	(segment
		(start 221.234 -197.4977)
		(end 221.234 -197.231)
		(width 0.3048)
		(layer "B.Cu")
		(net "GND")
	)
	(segment
		(start 151.649176 -32.11195)
		(end 151.852884 -31.908242)
		(width 0.508)
		(layer "B.Cu")
		(net "GND")
	)
	(segment
		(start 86.100158 -223.482154)
		(end 85.700108 -223.082104)
		(width 0.508)
		(layer "B.Cu")
		(net "GND")
	)
	(segment
		(start 327.634346 0.08001)
		(end 327.634346 -0.733298)
		(width 0.508)
		(layer "B.Cu")
		(net "GND")
	)
	(segment
		(start 144.900142 -223.482154)
		(end 144.500092 -223.082104)
		(width 0.508)
		(layer "B.Cu")
		(net "GND")
	)
	(segment
		(start 86.100158 -225.92538)
		(end 86.100158 -223.482154)
		(width 0.508)
		(layer "B.Cu")
		(net "GND")
	)
	(segment
		(start 34.937954 -158.924244)
		(end 34.937954 -159.981646)
		(width 0.508)
		(layer "B.Cu")
		(net "GND")
	)
	(segment
		(start 141.634464 0.08001)
		(end 142.447772 0.08001)
		(width 0.508)
		(layer "B.Cu")
		(net "GND")
	)
	(segment
		(start 243.604542 -31.705296)
		(end 243.604542 -31.703518)
		(width 0.3048)
		(layer "B.Cu")
		(net "GND")
	)
	(segment
		(start 253.873 -36.999672)
		(end 253.873 -37.27323)
		(width 0.3048)
		(layer "B.Cu")
		(net "GND")
	)
	(segment
		(start 69.215 -192.7225)
		(end 69.215 -192.017904)
		(width 0.508)
		(layer "B.Cu")
		(net "GND")
	)
	(segment
		(start 41.099994 -37.958014)
		(end 41.099994 -38.999922)
		(width 0.508)
		(layer "B.Cu")
		(net "GND")
	)
	(segment
		(start 305.300126 -223.482154)
		(end 304.900076 -223.082104)
		(width 0.508)
		(layer "B.Cu")
		(net "GND")
	)
	(segment
		(start 247.1674 -37.567616)
		(end 247.099836 -37.500052)
		(width 0.3048)
		(layer "B.Cu")
		(net "GND")
	)
	(segment
		(start 235.8644 -56.9976)
		(end 235.8644 -57.264046)
		(width 0.3048)
		(layer "B.Cu")
		(net "GND")
	)
	(segment
		(start 46.1645 -112.5982)
		(end 44.996862 -112.5982)
		(width 0.508)
		(layer "B.Cu")
		(net "GND")
	)
	(segment
		(start 144.900142 -225.92538)
		(end 144.900142 -223.482154)
		(width 0.508)
		(layer "B.Cu")
		(net "GND")
	)
	(segment
		(start 61.204094 -223.466152)
		(end 61.204094 -223.386142)
		(width 0.508)
		(layer "B.Cu")
		(net "GND")
	)
	(segment
		(start 326.900032 -225.92538)
		(end 326.900032 -223.4819)
		(width 0.508)
		(layer "B.Cu")
		(net "GND")
	)
	(segment
		(start 35.699954 -225.92538)
		(end 35.699954 -223.049846)
		(width 0.508)
		(layer "B.Cu")
		(net "GND")
	)
	(segment
		(start 92.500196 -223.482154)
		(end 92.100146 -223.082104)
		(width 0.508)
		(layer "B.Cu")
		(net "GND")
	)
	(segment
		(start 107.700064 -225.92538)
		(end 107.700064 -223.482154)
		(width 0.508)
		(layer "B.Cu")
		(net "GND")
	)
	(segment
		(start 34.925 -223.774)
		(end 34.900108 -223.798892)
		(width 0.508)
		(layer "B.Cu")
		(net "GND")
	)
	(segment
		(start 35.310826 -112.566958)
		(end 35.545776 -112.801908)
		(width 0.508)
		(layer "B.Cu")
		(net "GND")
	)
	(segment
		(start 212.900006 -225.92538)
		(end 212.900006 -223.4819)
		(width 0.508)
		(layer "B.Cu")
		(net "GND")
	)
	(segment
		(start 316.500002 -223.4819)
		(end 316.100206 -223.082104)
		(width 0.508)
		(layer "B.Cu")
		(net "GND")
	)
	(segment
		(start 67.700144 -223.4819)
		(end 68.09994 -223.082104)
		(width 0.508)
		(layer "B.Cu")
		(net "GND")
	)
	(segment
		(start 129.4384 -195.71081)
		(end 129.668524 -195.480686)
		(width 0.508)
		(layer "B.Cu")
		(net "GND")
	)
	(segment
		(start 166.500048 -223.446848)
		(end 166.116 -223.0628)
		(width 0.508)
		(layer "B.Cu")
		(net "GND")
	)
	(segment
		(start 236.299248 -31.6992)
		(end 236.100112 -31.500064)
		(width 0.3048)
		(layer "B.Cu")
		(net "GND")
	)
	(segment
		(start 265.300206 -225.92538)
		(end 265.300206 -223.4819)
		(width 0.508)
		(layer "B.Cu")
		(net "GND")
	)
	(segment
		(start 220.9292 -197.8025)
		(end 221.234 -197.4977)
		(width 0.3048)
		(layer "B.Cu")
		(net "GND")
	)
	(segment
		(start 245.872 -60.271914)
		(end 246.099838 -60.499752)
		(width 0.3048)
		(layer "B.Cu")
		(net "GND")
	)
	(segment
		(start 153.396696 -32.613092)
		(end 153.904696 -32.105092)
		(width 0.508)
		(layer "B.Cu")
		(net "GND")
	)
	(segment
		(start 33.441386 -108.289598)
		(end 32.938974 -108.289598)
		(width 0.508)
		(layer "B.Cu")
		(net "GND")
	)
	(segment
		(start 147.920202 -58.436002)
		(end 149.1234 -59.6392)
		(width 0.508)
		(layer "B.Cu")
		(net "GND")
	)
	(segment
		(start 86.900004 -225.92538)
		(end 86.900004 -223.4819)
		(width 0.508)
		(layer "B.Cu")
		(net "GND")
	)
	(segment
		(start 242.062 -35.0012)
		(end 242.062 -34.537904)
		(width 0.3048)
		(layer "B.Cu")
		(net "GND")
	)
	(segment
		(start 135.935212 -199.308974)
		(end 135.935212 -198.374)
		(width 0.508)
		(layer "B.Cu")
		(net "GND")
	)
	(segment
		(start 286.900112 -225.92538)
		(end 286.900112 -223.482154)
		(width 0.508)
		(layer "B.Cu")
		(net "GND")
	)
	(segment
		(start 216.565226 -197.921626)
		(end 217.2081 -197.278752)
		(width 0.381)
		(layer "B.Cu")
		(net "GND")
	)
	(segment
		(start 130.634486 0.893318)
		(end 130.634486 0.08001)
		(width 0.508)
		(layer "B.Cu")
		(net "GND")
	)
	(segment
		(start 235.8644 -59.264042)
		(end 236.100112 -59.499754)
		(width 0.3048)
		(layer "B.Cu")
		(net "GND")
	)
	(segment
		(start 228.10724 -197.806818)
		(end 228.809296 -198.508874)
		(width 0.3048)
		(layer "B.Cu")
		(net "GND")
	)
	(segment
		(start 73.787 -182.753)
		(end 74.676 -181.864)
		(width 0.508)
		(layer "B.Cu")
		(net "GND")
	)
	(segment
		(start 238.633 -56.9976)
		(end 238.633 -56.830976)
		(width 0.3048)
		(layer "B.Cu")
		(net "GND")
	)
	(segment
		(start 329.300078 -225.92538)
		(end 329.300078 -223.759522)
		(width 0.508)
		(layer "B.Cu")
		(net "GND")
	)
	(segment
		(start 238.633 -56.830976)
		(end 238.964216 -56.49976)
		(width 0.3048)
		(layer "B.Cu")
		(net "GND")
	)
	(segment
		(start 320.500248 -225.92538)
		(end 320.500248 -223.4819)
		(width 0.508)
		(layer "B.Cu")
		(net "GND")
	)
	(segment
		(start 98.100134 -225.92538)
		(end 98.100134 -223.482154)
		(width 0.508)
		(layer "B.Cu")
		(net "GND")
	)
	(segment
		(start 128.525524 -32.050482)
		(end 127.589788 -32.050482)
		(width 0.508)
		(layer "B.Cu")
		(net "GND")
	)
	(segment
		(start 203.300076 -223.482154)
		(end 202.900026 -223.082104)
		(width 0.508)
		(layer "B.Cu")
		(net "GND")
	)
	(segment
		(start 26.289 -116.2685)
		(end 26.289 -115.4938)
		(width 0.508)
		(layer "B.Cu")
		(net "GND")
	)
	(segment
		(start 79.70012 -223.38792)
		(end 79.375 -223.0628)
		(width 0.508)
		(layer "B.Cu")
		(net "GND")
	)
	(segment
		(start 173.82109 0.08001)
		(end 174.634398 0.08001)
		(width 0.508)
		(layer "B.Cu")
		(net "GND")
	)
	(segment
		(start 240.538 -23.6855)
		(end 240.538 -24.13)
		(width 0.508)
		(layer "B.Cu")
		(net "GND")
	)
	(segment
		(start 281.300174 -225.92538)
		(end 281.300174 -223.4819)
		(width 0.508)
		(layer "B.Cu")
		(net "GND")
	)
	(segment
		(start 125.28423 -32.629348)
		(end 125.28423 -33.03905)
		(width 0.508)
		(layer "B.Cu")
		(net "GND")
	)
	(segment
		(start 176.100232 -223.482154)
		(end 175.700182 -223.082104)
		(width 0.508)
		(layer "B.Cu")
		(net "GND")
	)
	(segment
		(start 54.229 -125.918976)
		(end 54.798976 -125.918976)
		(width 0.508)
		(layer "B.Cu")
		(net "GND")
	)
	(segment
		(start 147.920202 -58.371232)
		(end 147.920202 -58.436002)
		(width 0.508)
		(layer "B.Cu")
		(net "GND")
	)
	(segment
		(start 83.700112 -223.4819)
		(end 84.099908 -223.082104)
		(width 0.508)
		(layer "B.Cu")
		(net "GND")
	)
	(segment
		(start 278.100028 -223.4819)
		(end 278.499824 -223.082104)
		(width 0.508)
		(layer "B.Cu")
		(net "GND")
	)
	(segment
		(start 336.500216 -223.4819)
		(end 336.900012 -223.082104)
		(width 0.508)
		(layer "B.Cu")
		(net "GND")
	)
	(segment
		(start 58.90006 -225.92538)
		(end 58.90006 -223.4819)
		(width 0.508)
		(layer "B.Cu")
		(net "GND")
	)
	(segment
		(start 200.100184 -225.92538)
		(end 200.100184 -223.482154)
		(width 0.508)
		(layer "B.Cu")
		(net "GND")
	)
	(segment
		(start 152.634442 0.08001)
		(end 153.44775 0.08001)
		(width 0.508)
		(layer "B.Cu")
		(net "GND")
	)
	(segment
		(start 310.900064 -225.92538)
		(end 310.900064 -223.4819)
		(width 0.508)
		(layer "B.Cu")
		(net "GND")
	)
	(segment
		(start 83.439 -191.516)
		(end 83.82 -191.516)
		(width 0.4064)
		(layer "B.Cu")
		(net "GND")
	)
	(segment
		(start 173.700186 -225.92538)
		(end 173.700186 -223.4819)
		(width 0.508)
		(layer "B.Cu")
		(net "GND")
	)
	(segment
		(start 333.684626 -179.506626)
		(end 334.01 -179.832)
		(width 0.3048)
		(layer "B.Cu")
		(net "GND")
	)
	(segment
		(start 210.500214 -225.92538)
		(end 210.500214 -223.4819)
		(width 0.508)
		(layer "B.Cu")
		(net "GND")
	)
	(segment
		(start 241.8842 -57.995058)
		(end 241.8842 -58.28411)
		(width 0.3048)
		(layer "B.Cu")
		(net "GND")
	)
	(segment
		(start 132.715 -198.777098)
		(end 132.715 -198.635874)
		(width 0.508)
		(layer "B.Cu")
		(net "GND")
	)
	(segment
		(start 333.446628 -179.506626)
		(end 333.684626 -179.506626)
		(width 0.3048)
		(layer "B.Cu")
		(net "GND")
	)
	(segment
		(start 78.538578 -185.367422)
		(end 78.744064 -185.367422)
		(width 0.508)
		(layer "B.Cu")
		(net "GND")
	)
	(segment
		(start 37.300154 -223.736154)
		(end 37.300154 -225.92538)
		(width 0.508)
		(layer "B.Cu")
		(net "GND")
	)
	(segment
		(start 222.097092 -193.744596)
		(end 222.28683 -193.554858)
		(width 0.508)
		(layer "B.Cu")
		(net "GND")
	)
	(segment
		(start 263.088882 -13.216636)
		(end 263.088882 -13.074142)
		(width 0.508)
		(layer "B.Cu")
		(net "GND")
	)
	(segment
		(start 257.634994 -5.020564)
		(end 256.787142 -5.020564)
		(width 0.3556)
		(layer "B.Cu")
		(net "GND")
	)
	(segment
		(start 72.5805 -186.100974)
		(end 71.922894 -185.443368)
		(width 0.508)
		(layer "B.Cu")
		(net "GND")
	)
	(segment
		(start 290.100004 -225.92538)
		(end 290.100004 -223.4819)
		(width 0.508)
		(layer "B.Cu")
		(net "GND")
	)
	(segment
		(start 152.532588 -33.096962)
		(end 152.532588 -32.416242)
		(width 0.508)
		(layer "B.Cu")
		(net "GND")
	)
	(segment
		(start 70.900036 -225.92538)
		(end 70.900036 -223.4819)
		(width 0.508)
		(layer "B.Cu")
		(net "GND")
	)
	(segment
		(start 200.90003 -225.92538)
		(end 200.90003 -223.4819)
		(width 0.508)
		(layer "B.Cu")
		(net "GND")
	)
	(segment
		(start 327.634346 0.893318)
		(end 327.634346 0.08001)
		(width 0.508)
		(layer "B.Cu")
		(net "GND")
	)
	(segment
		(start 243.3066 -59.292998)
		(end 243.099844 -59.499754)
		(width 0.254)
		(layer "B.Cu")
		(net "GND")
	)
	(segment
		(start 73.787 -182.8165)
		(end 73.787 -182.753)
		(width 0.508)
		(layer "B.Cu")
		(net "GND")
	)
	(segment
		(start 238.8616 -35.9918)
		(end 238.8616 -35.738562)
		(width 0.3048)
		(layer "B.Cu")
		(net "GND")
	)
	(segment
		(start 141.699996 -223.4819)
		(end 141.3002 -223.082104)
		(width 0.508)
		(layer "B.Cu")
		(net "GND")
	)
	(segment
		(start 210.500214 -223.4819)
		(end 210.90001 -223.082104)
		(width 0.508)
		(layer "B.Cu")
		(net "GND")
	)
	(segment
		(start 240.538 -24.13)
		(end 241.173 -24.765)
		(width 0.508)
		(layer "B.Cu")
		(net "GND")
	)
	(segment
		(start 197.700138 -223.4819)
		(end 198.099934 -223.082104)
		(width 0.508)
		(layer "B.Cu")
		(net "GND")
	)
	(segment
		(start 44.996862 -112.5982)
		(end 44.728892 -112.86617)
		(width 0.508)
		(layer "B.Cu")
		(net "GND")
	)
	(segment
		(start 263.336024 -12.827)
		(end 263.088882 -13.074142)
		(width 0.508)
		(layer "B.Cu")
		(net "GND")
	)
	(segment
		(start 332.500224 -225.92538)
		(end 332.500224 -223.482154)
		(width 0.508)
		(layer "B.Cu")
		(net "GND")
	)
	(segment
		(start 54.900068 -225.92538)
		(end 54.900068 -223.482154)
		(width 0.508)
		(layer "B.Cu")
		(net "GND")
	)
	(segment
		(start 342.100154 -225.92538)
		(end 342.100154 -223.482154)
		(width 0.508)
		(layer "B.Cu")
		(net "GND")
	)
	(segment
		(start 165.8112 -199.7456)
		(end 164.8206 -198.755)
		(width 0.508)
		(layer "B.Cu")
		(net "GND")
	)
	(segment
		(start 75.07224 -190.4365)
		(end 75.43673 -190.4365)
		(width 0.4064)
		(layer "B.Cu")
		(net "GND")
	)
	(segment
		(start 241.8842 -60.284106)
		(end 242.099846 -60.499752)
		(width 0.3048)
		(layer "B.Cu")
		(net "GND")
	)
	(segment
		(start 145.700242 -225.92538)
		(end 145.700242 -223.4819)
		(width 0.508)
		(layer "B.Cu")
		(net "GND")
	)
	(segment
		(start 283.70022 -225.92538)
		(end 283.70022 -223.482154)
		(width 0.508)
		(layer "B.Cu")
		(net "GND")
	)
	(segment
		(start 17.0815 -135.89)
		(end 16.4338 -135.89)
		(width 0.508)
		(layer "B.Cu")
		(net "GND")
	)
	(segment
		(start 172.900086 -223.482154)
		(end 172.500036 -223.082104)
		(width 0.508)
		(layer "B.Cu")
		(net "GND")
	)
	(segment
		(start 27.94 -74.916792)
		(end 27.94 -73.9775)
		(width 0.508)
		(layer "B.Cu")
		(net "GND")
	)
	(segment
		(start 98.89998 -225.92538)
		(end 98.89998 -223.4819)
		(width 0.508)
		(layer "B.Cu")
		(net "GND")
	)
	(segment
		(start 238.633 -58.837576)
		(end 238.97082 -58.499756)
		(width 0.3048)
		(layer "B.Cu")
		(net "GND")
	)
	(segment
		(start 222.28683 -192.915794)
		(end 222.221298 -192.850262)
		(width 0.508)
		(layer "B.Cu")
		(net "GND")
	)
	(segment
		(start 254.8382 -59.9948)
		(end 254.8382 -60.238132)
		(width 0.3048)
		(layer "B.Cu")
		(net "GND")
	)
	(segment
		(start 284.500066 -225.92538)
		(end 284.500066 -223.4819)
		(width 0.508)
		(layer "B.Cu")
		(net "GND")
	)
	(segment
		(start 55.7149 -131.6355)
		(end 56.134 -131.6355)
		(width 0.508)
		(layer "B.Cu")
		(net "GND")
	)
	(segment
		(start 142.136114 -32.77362)
		(end 142.400782 -32.508952)
		(width 0.508)
		(layer "B.Cu")
		(net "GND")
	)
	(segment
		(start 243.8654 -60.26531)
		(end 244.099842 -60.499752)
		(width 0.3048)
		(layer "B.Cu")
		(net "GND")
	)
	(segment
		(start 127.589788 -32.050482)
		(end 127.084328 -32.555942)
		(width 0.508)
		(layer "B.Cu")
		(net "GND")
	)
	(segment
		(start 216.352628 -197.921626)
		(end 216.565226 -197.921626)
		(width 0.381)
		(layer "B.Cu")
		(net "GND")
	)
	(segment
		(start 150.783544 -33.100772)
		(end 150.783544 -32.526224)
		(width 0.508)
		(layer "B.Cu")
		(net "GND")
	)
	(segment
		(start 220.45676 -8.77824)
		(end 220.853 -8.382)
		(width 0.381)
		(layer "B.Cu")
		(net "GND")
	)
	(segment
		(start 204.100176 -225.92538)
		(end 204.100176 -223.4819)
		(width 0.508)
		(layer "B.Cu")
		(net "GND")
	)
	(segment
		(start 218.4146 -2.5146)
		(end 219.03055 -3.13055)
		(width 0.508)
		(layer "B.Cu")
		(net "GND")
	)
	(segment
		(start 51.700176 -223.482154)
		(end 51.300126 -223.082104)
		(width 0.508)
		(layer "B.Cu")
		(net "GND")
	)
	(segment
		(start 191.3001 -223.4819)
		(end 191.699896 -223.082104)
		(width 0.508)
		(layer "B.Cu")
		(net "GND")
	)
	(segment
		(start 166.500048 -225.92538)
		(end 166.500048 -223.446848)
		(width 0.508)
		(layer "B.Cu")
		(net "GND")
	)
	(segment
		(start 245.3132 -59.0042)
		(end 245.3132 -59.286394)
		(width 0.3048)
		(layer "B.Cu")
		(net "GND")
	)
	(segment
		(start 200.90003 -223.4819)
		(end 201.299826 -223.082104)
		(width 0.508)
		(layer "B.Cu")
		(net "GND")
	)
	(segment
		(start 152.634442 0.893318)
		(end 152.634442 0.08001)
		(width 0.508)
		(layer "B.Cu")
		(net "GND")
	)
	(segment
		(start 313.30011 -225.92538)
		(end 313.30011 -223.482154)
		(width 0.508)
		(layer "B.Cu")
		(net "GND")
	)
	(segment
		(start 296.500042 -225.92538)
		(end 296.500042 -223.482154)
		(width 0.508)
		(layer "B.Cu")
		(net "GND")
	)
	(segment
		(start 247.324372 -31.7246)
		(end 247.099836 -31.500064)
		(width 0.3048)
		(layer "B.Cu")
		(net "GND")
	)
	(segment
		(start 330.0222 -223.0374)
		(end 330.6572 -223.0374)
		(width 0.508)
		(layer "B.Cu")
		(net "GND")
	)
	(segment
		(start 145.700242 -223.4819)
		(end 146.100038 -223.082104)
		(width 0.508)
		(layer "B.Cu")
		(net "GND")
	)
	(segment
		(start 214.8459 -21.3741)
		(end 214.6046 -21.6154)
		(width 0.508)
		(layer "B.Cu")
		(net "GND")
	)
	(segment
		(start 316.634368 0.08001)
		(end 317.447676 0.08001)
		(width 0.508)
		(layer "B.Cu")
		(net "GND")
	)
	(segment
		(start 250.1138 -35.0012)
		(end 250.1138 -34.514028)
		(width 0.3048)
		(layer "B.Cu")
		(net "GND")
	)
	(segment
		(start 148.100034 -225.92538)
		(end 148.100034 -223.4819)
		(width 0.508)
		(layer "B.Cu")
		(net "GND")
	)
	(segment
		(start 66.900044 -225.92538)
		(end 66.900044 -223.482154)
		(width 0.508)
		(layer "B.Cu")
		(net "GND")
	)
	(segment
		(start 237.8964 -57.29605)
		(end 238.100108 -57.499758)
		(width 0.3048)
		(layer "B.Cu")
		(net "GND")
	)
	(segment
		(start 142.500096 -225.92538)
		(end 142.500096 -223.4819)
		(width 0.508)
		(layer "B.Cu")
		(net "GND")
	)
	(segment
		(start 267.259054 -4.672584)
		(end 268.236446 -4.672584)
		(width 0.508)
		(layer "B.Cu")
		(net "GND")
	)
	(segment
		(start 217.2081 -197.278752)
		(end 217.2081 -197.277228)
		(width 0.381)
		(layer "B.Cu")
		(net "GND")
	)
	(segment
		(start 231.0638 -35.0012)
		(end 231.0638 -34.53638)
		(width 0.3048)
		(layer "B.Cu")
		(net "GND")
	)
	(segment
		(start 76.581 -197.8152)
		(end 75.7936 -197.0278)
		(width 0.508)
		(layer "B.Cu")
		(net "GND")
	)
	(segment
		(start 180.435504 -9.457944)
		(end 180.11648 -9.13892)
		(width 0.508)
		(layer "B.Cu")
		(net "GND")
	)
	(segment
		(start 130.634486 0.08001)
		(end 130.634486 -0.733298)
		(width 0.508)
		(layer "B.Cu")
		(net "GND")
	)
	(segment
		(start 241.681 -23.6855)
		(end 240.538 -23.6855)
		(width 0.508)
		(layer "B.Cu")
		(net "GND")
	)
	(segment
		(start 340.7156 -175.2981)
		(end 340.7156 -174.4726)
		(width 0.508)
		(layer "B.Cu")
		(net "GND")
	)
	(segment
		(start 212.900006 -223.4819)
		(end 212.50021 -223.082104)
		(width 0.508)
		(layer "B.Cu")
		(net "GND")
	)
	(segment
		(start 180.876702 -9.457944)
		(end 180.435504 -9.457944)
		(width 0.508)
		(layer "B.Cu")
		(net "GND")
	)
	(segment
		(start 23.19909 -119.4816)
		(end 23.6855 -119.96801)
		(width 0.508)
		(layer "B.Cu")
		(net "GND")
	)
	(segment
		(start 241.3254 -59.274202)
		(end 241.099848 -59.499754)
		(width 0.3048)
		(layer "B.Cu")
		(net "GND")
	)
	(segment
		(start 141.634464 0.893318)
		(end 141.634464 0.08001)
		(width 0.508)
		(layer "B.Cu")
		(net "GND")
	)
	(segment
		(start 245.3132 -56.9976)
		(end 245.3132 -57.286398)
		(width 0.3048)
		(layer "B.Cu")
		(net "GND")
	)
	(segment
		(start 302.100234 -223.482154)
		(end 301.700184 -223.082104)
		(width 0.508)
		(layer "B.Cu")
		(net "GND")
	)
	(segment
		(start 224.04324 -197.8025)
		(end 224.04324 -197.640194)
		(width 0.3048)
		(layer "B.Cu")
		(net "GND")
	)
	(segment
		(start 282.821126 0.08001)
		(end 283.634434 0.08001)
		(width 0.508)
		(layer "B.Cu")
		(net "GND")
	)
	(segment
		(start 190.5 -223.4819)
		(end 190.100204 -223.082104)
		(width 0.508)
		(layer "B.Cu")
		(net "GND")
	)
	(segment
		(start 104.500172 -225.92538)
		(end 104.500172 -223.482154)
		(width 0.508)
		(layer "B.Cu")
		(net "GND")
	)
	(segment
		(start 331.2033 -180.6448)
		(end 330.638912 -180.6448)
		(width 0.508)
		(layer "B.Cu")
		(net "GND")
	)
	(segment
		(start 237.8964 -59.0042)
		(end 237.8964 -59.296046)
		(width 0.3048)
		(layer "B.Cu")
		(net "GND")
	)
	(segment
		(start 79.13624 -191.22644)
		(end 79.389224 -191.479424)
		(width 0.4064)
		(layer "B.Cu")
		(net "GND")
	)
	(segment
		(start 253.873 -36.009072)
		(end 253.873 -35.726878)
		(width 0.3048)
		(layer "B.Cu")
		(net "GND")
	)
	(segment
		(start 28.317698 -75.29449)
		(end 27.94 -74.916792)
		(width 0.508)
		(layer "B.Cu")
		(net "GND")
	)
	(segment
		(start 206.500222 -225.92538)
		(end 206.500222 -223.482154)
		(width 0.508)
		(layer "B.Cu")
		(net "GND")
	)
	(segment
		(start 90.10015 -223.4819)
		(end 90.499946 -223.082104)
		(width 0.508)
		(layer "B.Cu")
		(net "GND")
	)
	(segment
		(start 247.591072 -31.7246)
		(end 247.324372 -31.7246)
		(width 0.3048)
		(layer "B.Cu")
		(net "GND")
	)
	(segment
		(start 253.873 -35.273234)
		(end 254.099822 -35.500056)
		(width 0.3048)
		(layer "B.Cu")
		(net "GND")
	)
	(segment
		(start 58.039 -36.2458)
		(end 58.039 -35.0774)
		(width 0.508)
		(layer "B.Cu")
		(net "GND")
	)
	(segment
		(start 243.3066 -59.0042)
		(end 243.3066 -59.292998)
		(width 0.254)
		(layer "B.Cu")
		(net "GND")
	)
	(segment
		(start 54.900068 -223.482154)
		(end 54.500018 -223.082104)
		(width 0.508)
		(layer "B.Cu")
		(net "GND")
	)
	(segment
		(start 219.120212 -193.593974)
		(end 218.540838 -193.0146)
		(width 0.508)
		(layer "B.Cu")
		(net "GND")
	)
	(segment
		(start 124.37872 -32.631126)
		(end 124.832364 -32.177482)
		(width 0.508)
		(layer "B.Cu")
		(net "GND")
	)
	(segment
		(start 32.938974 -108.289598)
		(end 32.49295 -108.735622)
		(width 0.508)
		(layer "B.Cu")
		(net "GND")
	)
	(segment
		(start 82.900012 -223.482154)
		(end 82.499962 -223.082104)
		(width 0.508)
		(layer "B.Cu")
		(net "GND")
	)
	(segment
		(start 241.3254 -56.9976)
		(end 241.3254 -57.274206)
		(width 0.3048)
		(layer "B.Cu")
		(net "GND")
	)
	(segment
		(start 44.500038 -225.92538)
		(end 44.500038 -223.4819)
		(width 0.508)
		(layer "B.Cu")
		(net "GND")
	)
	(segment
		(start 245.3132 -59.286394)
		(end 245.09984 -59.499754)
		(width 0.3048)
		(layer "B.Cu")
		(net "GND")
	)
	(segment
		(start 107.700064 -223.482154)
		(end 107.300014 -223.082104)
		(width 0.508)
		(layer "B.Cu")
		(net "GND")
	)
	(segment
		(start 70.10019 -225.92538)
		(end 70.10019 -223.482154)
		(width 0.508)
		(layer "B.Cu")
		(net "GND")
	)
	(segment
		(start 290.900104 -225.92538)
		(end 290.900104 -223.4819)
		(width 0.508)
		(layer "B.Cu")
		(net "GND")
	)
	(segment
		(start 274.100036 -223.4819)
		(end 273.70024 -223.082104)
		(width 0.508)
		(layer "B.Cu")
		(net "GND")
	)
	(segment
		(start 67.700144 -225.92538)
		(end 67.700144 -223.4819)
		(width 0.508)
		(layer "B.Cu")
		(net "GND")
	)
	(segment
		(start 58.09996 -223.4819)
		(end 57.700164 -223.082104)
		(width 0.508)
		(layer "B.Cu")
		(net "GND")
	)
	(segment
		(start 274.900136 -225.92538)
		(end 274.900136 -223.4819)
		(width 0.508)
		(layer "B.Cu")
		(net "GND")
	)
	(segment
		(start 241.3254 -59.0042)
		(end 241.3254 -59.274202)
		(width 0.3048)
		(layer "B.Cu")
		(net "GND")
	)
	(segment
		(start 261.736332 -0.721868)
		(end 260.5278 -1.9304)
		(width 0.508)
		(layer "B.Cu")
		(net "GND")
	)
	(segment
		(start 77.300074 -221.200726)
		(end 77.851 -220.6498)
		(width 0.508)
		(layer "B.Cu")
		(net "GND")
	)
	(segment
		(start 237.3376 -58.262266)
		(end 237.10011 -58.499756)
		(width 0.3048)
		(layer "B.Cu")
		(net "GND")
	)
	(segment
		(start 83.700112 -225.92538)
		(end 83.700112 -223.4819)
		(width 0.508)
		(layer "B.Cu")
		(net "GND")
	)
	(segment
		(start 190.5 -225.92538)
		(end 190.5 -223.4819)
		(width 0.508)
		(layer "B.Cu")
		(net "GND")
	)
	(segment
		(start 127.022606 -199.308974)
		(end 126.259844 -198.546212)
		(width 0.508)
		(layer "B.Cu")
		(net "GND")
	)
	(segment
		(start 316.634368 0.893318)
		(end 316.634368 0.08001)
		(width 0.508)
		(layer "B.Cu")
		(net "GND")
	)
	(segment
		(start 237.3376 -60.262262)
		(end 237.10011 -60.499752)
		(width 0.3048)
		(layer "B.Cu")
		(net "GND")
	)
	(segment
		(start 329.300078 -223.759522)
		(end 330.0222 -223.0374)
		(width 0.508)
		(layer "B.Cu")
		(net "GND")
	)
	(segment
		(start 127.084328 -32.555942)
		(end 127.084328 -33.074356)
		(width 0.508)
		(layer "B.Cu")
		(net "GND")
	)
	(segment
		(start 271.700244 -223.4819)
		(end 272.10004 -223.082104)
		(width 0.508)
		(layer "B.Cu")
		(net "GND")
	)
	(segment
		(start 305.300126 -225.92538)
		(end 305.300126 -223.482154)
		(width 0.508)
		(layer "B.Cu")
		(net "GND")
	)
	(segment
		(start 265.213338 -3.51536)
		(end 265.69416 -3.51536)
		(width 0.508)
		(layer "B.Cu")
		(net "GND")
	)
	(segment
		(start 256.787142 -5.020564)
		(end 256.598166 -4.831588)
		(width 0.3556)
		(layer "B.Cu")
		(net "GND")
	)
	(segment
		(start 70.683628 -190.428626)
		(end 71.191374 -190.428626)
		(width 0.3048)
		(layer "B.Cu")
		(net "GND")
	)
	(segment
		(start 215.265 -193.5861)
		(end 214.4141 -193.5861)
		(width 0.508)
		(layer "B.Cu")
		(net "GND")
	)
	(segment
		(start 253.873 -39.273226)
		(end 254.099822 -39.500048)
		(width 0.3048)
		(layer "B.Cu")
		(net "GND")
	)
	(segment
		(start 234.6071 -38.00348)
		(end 234.603544 -38.00348)
		(width 0.3048)
		(layer "B.Cu")
		(net "GND")
	)
	(segment
		(start 332.087474 -175.2981)
		(end 332.835504 -174.55007)
		(width 0.508)
		(layer "B.Cu")
		(net "GND")
	)
	(segment
		(start 335.700116 -225.92538)
		(end 335.700116 -223.482154)
		(width 0.508)
		(layer "B.Cu")
		(net "GND")
	)
	(segment
		(start 317.300102 -223.4819)
		(end 317.699898 -223.082104)
		(width 0.508)
		(layer "B.Cu")
		(net "GND")
	)
	(segment
		(start 314.10021 -225.92538)
		(end 314.10021 -223.4819)
		(width 0.508)
		(layer "B.Cu")
		(net "GND")
	)
	(segment
		(start 173.700186 -223.4819)
		(end 174.099982 -223.082104)
		(width 0.508)
		(layer "B.Cu")
		(net "GND")
	)
	(segment
		(start 218.2622 -2.5146)
		(end 218.4146 -2.5146)
		(width 0.508)
		(layer "B.Cu")
		(net "GND")
	)
	(segment
		(start 230.6066 -31.6992)
		(end 230.29926 -31.6992)
		(width 0.3048)
		(layer "B.Cu")
		(net "GND")
	)
	(segment
		(start 240.9952 -37.9984)
		(end 240.9952 -38.395402)
		(width 0.3048)
		(layer "B.Cu")
		(net "GND")
	)
	(segment
		(start 23.6855 -119.96801)
		(end 23.6855 -119.9896)
		(width 0.508)
		(layer "B.Cu")
		(net "GND")
	)
	(segment
		(start 39.989252 -113.205768)
		(end 40.52316 -113.205768)
		(width 0.508)
		(layer "B.Cu")
		(net "GND")
	)
	(segment
		(start 152.024588 -31.908242)
		(end 151.852884 -31.908242)
		(width 0.508)
		(layer "B.Cu")
		(net "GND")
	)
	(segment
		(start 290.900104 -223.4819)
		(end 291.2999 -223.082104)
		(width 0.508)
		(layer "B.Cu")
		(net "GND")
	)
	(segment
		(start 305.63439 0.08001)
		(end 306.447698 0.08001)
		(width 0.508)
		(layer "B.Cu")
		(net "GND")
	)
	(segment
		(start 151.30018 -225.92538)
		(end 151.30018 -223.482154)
		(width 0.508)
		(layer "B.Cu")
		(net "GND")
	)
	(segment
		(start 253.873 -35.726878)
		(end 254.099822 -35.500056)
		(width 0.3048)
		(layer "B.Cu")
		(net "GND")
	)
	(segment
		(start 19.595592 -126.619)
		(end 19.730974 -126.754382)
		(width 0.508)
		(layer "B.Cu")
		(net "GND")
	)
	(segment
		(start 294.634412 0.893318)
		(end 294.634412 0.08001)
		(width 0.508)
		(layer "B.Cu")
		(net "GND")
	)
	(segment
		(start 89.30005 -223.482154)
		(end 88.9 -223.082104)
		(width 0.508)
		(layer "B.Cu")
		(net "GND")
	)
	(segment
		(start 302.90008 -225.92538)
		(end 302.90008 -223.4819)
		(width 0.508)
		(layer "B.Cu")
		(net "GND")
	)
	(segment
		(start 129.668524 -195.480686)
		(end 129.668524 -195.476876)
		(width 0.508)
		(layer "B.Cu")
		(net "GND")
	)
	(segment
		(start 38.058852 -113.35258)
		(end 38.058852 -113.33226)
		(width 0.508)
		(layer "B.Cu")
		(net "GND")
	)
	(segment
		(start 56.134 -131.6355)
		(end 57.15 -131.6355)
		(width 0.508)
		(layer "B.Cu")
		(net "GND")
	)
	(segment
		(start 105.300018 -225.92538)
		(end 105.300018 -223.4819)
		(width 0.508)
		(layer "B.Cu")
		(net "GND")
	)
	(segment
		(start 336.500216 -225.92538)
		(end 336.500216 -223.4819)
		(width 0.508)
		(layer "B.Cu")
		(net "GND")
	)
	(segment
		(start 243.8654 -59.99734)
		(end 243.8654 -60.26531)
		(width 0.3048)
		(layer "B.Cu")
		(net "GND")
	)
	(segment
		(start 49.30013 -225.92538)
		(end 49.30013 -223.4819)
		(width 0.508)
		(layer "B.Cu")
		(net "GND")
	)
	(segment
		(start 247.1674 -37.9984)
		(end 247.1674 -37.567616)
		(width 0.3048)
		(layer "B.Cu")
		(net "GND")
	)
	(segment
		(start 35.699954 -223.049846)
		(end 35.814 -222.9358)
		(width 0.508)
		(layer "B.Cu")
		(net "GND")
	)
	(segment
		(start 69.469 -186.0931)
		(end 68.58 -186.0931)
		(width 0.508)
		(layer "B.Cu")
		(net "GND")
	)
	(segment
		(start 204.100176 -223.4819)
		(end 204.499972 -223.082104)
		(width 0.508)
		(layer "B.Cu")
		(net "GND")
	)
	(segment
		(start 69.2785 -192.786)
		(end 69.215 -192.7225)
		(width 0.508)
		(layer "B.Cu")
		(net "GND")
	)
	(segment
		(start 253.873 -34.993072)
		(end 253.873 -35.273234)
		(width 0.3048)
		(layer "B.Cu")
		(net "GND")
	)
	(segment
		(start 165.8112 -200.2028)
		(end 165.8112 -199.7456)
		(width 0.508)
		(layer "B.Cu")
		(net "GND")
	)
	(segment
		(start 249.324368 -31.7246)
		(end 249.099832 -31.500064)
		(width 0.3048)
		(layer "B.Cu")
		(net "GND")
	)
	(segment
		(start 140.4112 -35.7632)
		(end 140.13942 -35.49142)
		(width 0.508)
		(layer "B.Cu")
		(net "GND")
	)
	(segment
		(start 200.100184 -223.482154)
		(end 199.700134 -223.082104)
		(width 0.508)
		(layer "B.Cu")
		(net "GND")
	)
	(segment
		(start 77.805026 -186.100974)
		(end 78.538578 -185.367422)
		(width 0.508)
		(layer "B.Cu")
		(net "GND")
	)
	(segment
		(start 196.900038 -223.4819)
		(end 196.500242 -223.082104)
		(width 0.508)
		(layer "B.Cu")
		(net "GND")
	)
	(segment
		(start 229.328472 -40.728392)
		(end 229.100126 -40.500046)
		(width 0.3048)
		(layer "B.Cu")
		(net "GND")
	)
	(segment
		(start 24.44496 -69.96684)
		(end 25.0063 -69.96684)
		(width 0.508)
		(layer "B.Cu")
		(net "GND")
	)
	(segment
		(start 170.50004 -225.92538)
		(end 170.50004 -223.4819)
		(width 0.508)
		(layer "B.Cu")
		(net "GND")
	)
	(segment
		(start 155.300172 -223.4819)
		(end 155.699968 -223.082104)
		(width 0.508)
		(layer "B.Cu")
		(net "GND")
	)
	(segment
		(start 32.49295 -108.735622)
		(end 33.070038 -109.31271)
		(width 0.508)
		(layer "B.Cu")
		(net "GND")
	)
	(segment
		(start 243.7384 -31.839154)
		(end 243.604542 -31.705296)
		(width 0.3048)
		(layer "B.Cu")
		(net "GND")
	)
	(segment
		(start 164.100002 -225.92538)
		(end 164.100002 -223.967802)
		(width 0.508)
		(layer "B.Cu")
		(net "GND")
	)
	(segment
		(start 240.9952 -38.395402)
		(end 241.099848 -38.50005)
		(width 0.3048)
		(layer "B.Cu")
		(net "GND")
	)
	(segment
		(start 153.396696 -33.096962)
		(end 153.396696 -32.613092)
		(width 0.508)
		(layer "B.Cu")
		(net "GND")
	)
	(segment
		(start 158.500064 -223.4819)
		(end 158.89986 -223.082104)
		(width 0.508)
		(layer "B.Cu")
		(net "GND")
	)
	(segment
		(start 238.633 -59.0042)
		(end 238.633 -58.837576)
		(width 0.3048)
		(layer "B.Cu")
		(net "GND")
	)
	(segment
		(start 253.873 -39.0144)
		(end 253.873 -39.273226)
		(width 0.3048)
		(layer "B.Cu")
		(net "GND")
	)
	(segment
		(start 323.70014 -223.4819)
		(end 324.099936 -223.082104)
		(width 0.508)
		(layer "B.Cu")
		(net "GND")
	)
	(segment
		(start 126.259844 -198.546212)
		(end 125.999494 -198.546212)
		(width 0.508)
		(layer "B.Cu")
		(net "GND")
	)
	(segment
		(start 305.63439 0.893318)
		(end 305.63439 0.08001)
		(width 0.508)
		(layer "B.Cu")
		(net "GND")
	)
	(segment
		(start 249.612912 -31.7246)
		(end 249.324368 -31.7246)
		(width 0.3048)
		(layer "B.Cu")
		(net "GND")
	)
	(segment
		(start 140.1445 -34.929572)
		(end 140.13942 -34.934652)
		(width 0.508)
		(layer "B.Cu")
		(net "GND")
	)
	(segment
		(start 216.100152 -223.482154)
		(end 215.700102 -223.082104)
		(width 0.508)
		(layer "B.Cu")
		(net "GND")
	)
	(segment
		(start 326.900032 -223.4819)
		(end 327.299828 -223.082104)
		(width 0.508)
		(layer "B.Cu")
		(net "GND")
	)
	(segment
		(start 232.299256 -31.6992)
		(end 232.10012 -31.500064)
		(width 0.3048)
		(layer "B.Cu")
		(net "GND")
	)
	(segment
		(start 334.01 -179.832)
		(end 334.01 -180.074316)
		(width 0.3048)
		(layer "B.Cu")
		(net "GND")
	)
	(segment
		(start 34.163 -223.774)
		(end 34.100008 -223.836992)
		(width 0.508)
		(layer "B.Cu")
		(net "GND")
	)
	(segment
		(start 77.769212 -186.100974)
		(end 77.805026 -186.100974)
		(width 0.508)
		(layer "B.Cu")
		(net "GND")
	)
	(segment
		(start 245.5926 -31.7246)
		(end 245.324376 -31.7246)
		(width 0.3048)
		(layer "B.Cu")
		(net "GND")
	)
	(segment
		(start 75.819 -190.81877)
		(end 75.819 -191.008)
		(width 0.4064)
		(layer "B.Cu")
		(net "GND")
	)
	(segment
		(start 229.328472 -41.012872)
		(end 229.328472 -40.728392)
		(width 0.3048)
		(layer "B.Cu")
		(net "GND")
	)
	(segment
		(start 254.612648 -41.012872)
		(end 255.09982 -41.500044)
		(width 0.3048)
		(layer "B.Cu")
		(net "GND")
	)
	(segment
		(start 332.0796 -175.2981)
		(end 332.087474 -175.2981)
		(width 0.508)
		(layer "B.Cu")
		(net "GND")
	)
	(segment
		(start 267.249148 -4.662678)
		(end 267.259054 -4.672584)
		(width 0.508)
		(layer "B.Cu")
		(net "GND")
	)
	(segment
		(start 55.245 -132.0292)
		(end 55.3212 -132.0292)
		(width 0.508)
		(layer "B.Cu")
		(net "GND")
	)
	(segment
		(start 75.43673 -190.4365)
		(end 75.819 -190.81877)
		(width 0.4064)
		(layer "B.Cu")
		(net "GND")
	)
	(segment
		(start 332.500224 -223.482154)
		(end 332.100174 -223.082104)
		(width 0.508)
		(layer "B.Cu")
		(net "GND")
	)
	(segment
		(start 319.700148 -223.482154)
		(end 319.300098 -223.082104)
		(width 0.508)
		(layer "B.Cu")
		(net "GND")
	)
	(segment
		(start 305.63439 0.08001)
		(end 305.63439 -0.733298)
		(width 0.508)
		(layer "B.Cu")
		(net "GND")
	)
	(segment
		(start 220.853 -8.382)
		(end 220.853 -7.893558)
		(width 0.381)
		(layer "B.Cu")
		(net "GND")
	)
	(segment
		(start 182.5752 -3.075686)
		(end 181.21503 -1.715516)
		(width 0.508)
		(layer "B.Cu")
		(net "GND")
	)
	(segment
		(start 194.500246 -225.92538)
		(end 194.500246 -223.4819)
		(width 0.508)
		(layer "B.Cu")
		(net "GND")
	)
	(segment
		(start 83.20024 -190.4365)
		(end 83.20024 -191.27724)
		(width 0.4064)
		(layer "B.Cu")
		(net "GND")
	)
	(segment
		(start 326.821038 0.08001)
		(end 327.634346 0.08001)
		(width 0.508)
		(layer "B.Cu")
		(net "GND")
	)
	(segment
		(start 299.700188 -225.92538)
		(end 299.700188 -223.4819)
		(width 0.508)
		(layer "B.Cu")
		(net "GND")
	)
	(segment
		(start 52.500022 -223.4819)
		(end 52.899818 -223.082104)
		(width 0.508)
		(layer "B.Cu")
		(net "GND")
	)
	(segment
		(start 305.63439 0.08001)
		(end 305.63439 -0.733298)
		(width 0.508)
		(layer "In5.Cu")
		(net "GND")
	)
	(segment
		(start 294.634412 0.893318)
		(end 294.634412 0.08001)
		(width 0.508)
		(layer "In5.Cu")
		(net "GND")
	)
	(segment
		(start 300.134274 -7.865872)
		(end 300.134274 -9.53008)
		(width 0.508)
		(layer "In5.Cu")
		(net "GND")
	)
	(segment
		(start 283.634434 0.08001)
		(end 283.634434 -0.733298)
		(width 0.508)
		(layer "In5.Cu")
		(net "GND")
	)
	(segment
		(start 326.821038 0.08001)
		(end 327.634346 0.08001)
		(width 0.508)
		(layer "In5.Cu")
		(net "GND")
	)
	(segment
		(start 287.470088 -9.53008)
		(end 289.134296 -9.53008)
		(width 0.508)
		(layer "In5.Cu")
		(net "GND")
	)
	(segment
		(start 293.821104 0.08001)
		(end 294.634412 0.08001)
		(width 0.508)
		(layer "In5.Cu")
		(net "GND")
	)
	(segment
		(start 311.134506 -7.865872)
		(end 311.134506 -9.53008)
		(width 0.508)
		(layer "In5.Cu")
		(net "GND")
	)
	(segment
		(start 294.634412 0.08001)
		(end 294.634412 -0.733298)
		(width 0.508)
		(layer "In5.Cu")
		(net "GND")
	)
	(segment
		(start 327.634346 0.08001)
		(end 327.634346 -0.733298)
		(width 0.508)
		(layer "In5.Cu")
		(net "GND")
	)
	(segment
		(start 322.134484 -7.865872)
		(end 322.134484 -9.53008)
		(width 0.508)
		(layer "In5.Cu")
		(net "GND")
	)
	(segment
		(start 305.63439 0.893318)
		(end 305.63439 0.08001)
		(width 0.508)
		(layer "In5.Cu")
		(net "GND")
	)
	(segment
		(start 327.634346 0.08001)
		(end 328.447654 0.08001)
		(width 0.508)
		(layer "In5.Cu")
		(net "GND")
	)
	(segment
		(start 33.770062 -156.37764)
		(end 33.367726 -156.779976)
		(width 0.13462)
		(layer "In5.Cu")
		(net "GND")
	)
	(segment
		(start 315.82106 0.08001)
		(end 316.634368 0.08001)
		(width 0.508)
		(layer "In5.Cu")
		(net "GND")
	)
	(segment
		(start 320.470276 -9.53008)
		(end 322.134484 -9.53008)
		(width 0.508)
		(layer "In5.Cu")
		(net "GND")
	)
	(segment
		(start 309.470298 -9.53008)
		(end 311.134506 -9.53008)
		(width 0.508)
		(layer "In5.Cu")
		(net "GND")
	)
	(segment
		(start 316.634368 0.08001)
		(end 317.447676 0.08001)
		(width 0.508)
		(layer "In5.Cu")
		(net "GND")
	)
	(segment
		(start 327.634346 0.893318)
		(end 327.634346 0.08001)
		(width 0.508)
		(layer "In5.Cu")
		(net "GND")
	)
	(segment
		(start 283.634434 0.893318)
		(end 283.634434 0.08001)
		(width 0.508)
		(layer "In5.Cu")
		(net "GND")
	)
	(segment
		(start 305.63439 0.08001)
		(end 306.447698 0.08001)
		(width 0.508)
		(layer "In5.Cu")
		(net "GND")
	)
	(segment
		(start 282.821126 0.08001)
		(end 283.634434 0.08001)
		(width 0.508)
		(layer "In5.Cu")
		(net "GND")
	)
	(segment
		(start 322.134484 -9.53008)
		(end 323.798692 -9.53008)
		(width 0.508)
		(layer "In5.Cu")
		(net "GND")
	)
	(segment
		(start 316.634368 0.893318)
		(end 316.634368 0.08001)
		(width 0.508)
		(layer "In5.Cu")
		(net "GND")
	)
	(segment
		(start 289.134296 -9.53008)
		(end 290.798504 -9.53008)
		(width 0.508)
		(layer "In5.Cu")
		(net "GND")
	)
	(segment
		(start 298.470066 -9.53008)
		(end 300.134274 -9.53008)
		(width 0.508)
		(layer "In5.Cu")
		(net "GND")
	)
	(segment
		(start 34.965894 -155.980384)
		(end 34.568638 -156.37764)
		(width 0.13462)
		(layer "In5.Cu")
		(net "GND")
	)
	(segment
		(start 300.134274 -9.53008)
		(end 301.798482 -9.53008)
		(width 0.508)
		(layer "In5.Cu")
		(net "GND")
	)
	(segment
		(start 294.634412 0.08001)
		(end 295.44772 0.08001)
		(width 0.508)
		(layer "In5.Cu")
		(net "GND")
	)
	(segment
		(start 289.134296 -7.865872)
		(end 289.134296 -9.53008)
		(width 0.508)
		(layer "In5.Cu")
		(net "GND")
	)
	(segment
		(start 34.568638 -156.37764)
		(end 33.770062 -156.37764)
		(width 0.13462)
		(layer "In5.Cu")
		(net "GND")
	)
	(segment
		(start 316.634368 0.08001)
		(end 316.634368 -0.733298)
		(width 0.508)
		(layer "In5.Cu")
		(net "GND")
	)
	(segment
		(start 311.134506 -9.53008)
		(end 312.798714 -9.53008)
		(width 0.508)
		(layer "In5.Cu")
		(net "GND")
	)
	(segment
		(start 283.634434 0.08001)
		(end 284.447742 0.08001)
		(width 0.508)
		(layer "In5.Cu")
		(net "GND")
	)
	(segment
		(start 304.821082 0.08001)
		(end 305.63439 0.08001)
		(width 0.508)
		(layer "In5.Cu")
		(net "GND")
	)
	(segment
		(start 10.988548 -82.889852)
		(end 11.4427 -82.4357)
		(width 0.12065)
		(layer "F.Cu")
		(net "FM_OSC_50M_EN")
	)
	(segment
		(start 11.4427 -82.4357)
		(end 11.4427 -81.6356)
		(width 0.12065)
		(layer "F.Cu")
		(net "FM_OSC_50M_EN")
	)
	(segment
		(start 10.988548 -83.897978)
		(end 10.988548 -82.889852)
		(width 0.12065)
		(layer "F.Cu")
		(net "FM_OSC_50M_EN")
	)
	(segment
		(start 18.864326 -148.975826)
		(end 18.864326 -152.26538)
		(width 0.12065)
		(layer "F.Cu")
		(net "FM_BMC_RESET_N")
	)
	(segment
		(start 26.621232 -104.315514)
		(end 26.002742 -104.934004)
		(width 0.12065)
		(layer "F.Cu")
		(net "FM_BMC_RESET_N")
	)
	(segment
		(start 29.208984 -100.496878)
		(end 27.495246 -102.210616)
		(width 0.12065)
		(layer "F.Cu")
		(net "FM_BMC_RESET_N")
	)
	(segment
		(start 60.3758 -110.9472)
		(end 59.817 -111.506)
		(width 0.12065)
		(layer "F.Cu")
		(net "FM_BMC_RESET_N")
	)
	(segment
		(start 76.626466 -78.57744)
		(end 75.590654 -79.613252)
		(width 0.12065)
		(layer "F.Cu")
		(net "FM_BMC_RESET_N")
	)
	(segment
		(start 18.7325 -148.844)
		(end 18.7325 -147.828)
		(width 0.12065)
		(layer "F.Cu")
		(net "FM_BMC_RESET_N")
	)
	(segment
		(start 17.15135 -103.419402)
		(end 6.924294 -103.419402)
		(width 0.12065)
		(layer "F.Cu")
		(net "FM_BMC_RESET_N")
	)
	(segment
		(start 67.852798 -79.613252)
		(end 65.7606 -77.521054)
		(width 0.12065)
		(layer "F.Cu")
		(net "FM_BMC_RESET_N")
	)
	(segment
		(start 76.626466 -78.331568)
		(end 76.626466 -78.57744)
		(width 0.12065)
		(layer "F.Cu")
		(net "FM_BMC_RESET_N")
	)
	(segment
		(start 60.3758 -105.8926)
		(end 60.3758 -110.9472)
		(width 0.12065)
		(layer "F.Cu")
		(net "FM_BMC_RESET_N")
	)
	(segment
		(start 18.121884 -141.456664)
		(end 16.889476 -141.456664)
		(width 0.12065)
		(layer "F.Cu")
		(net "FM_BMC_RESET_N")
	)
	(segment
		(start 3.972052 -106.371644)
		(end 3.972052 -124.749052)
		(width 0.12065)
		(layer "F.Cu")
		(net "FM_BMC_RESET_N")
	)
	(segment
		(start 60.5536 -105.7148)
		(end 60.3758 -105.8926)
		(width 0.12065)
		(layer "F.Cu")
		(net "FM_BMC_RESET_N")
	)
	(segment
		(start 27.249628 -95.127064)
		(end 28.525978 -95.127064)
		(width 0.12065)
		(layer "F.Cu")
		(net "FM_BMC_RESET_N")
	)
	(segment
		(start 29.208984 -99.682046)
		(end 29.208984 -100.496878)
		(width 0.12065)
		(layer "F.Cu")
		(net "FM_BMC_RESET_N")
	)
	(segment
		(start 27.495246 -102.210616)
		(end 26.961592 -102.210616)
		(width 0.12065)
		(layer "F.Cu")
		(net "FM_BMC_RESET_N")
	)
	(segment
		(start 17.653 -148.844)
		(end 18.7325 -148.844)
		(width 0.12065)
		(layer "F.Cu")
		(net "FM_BMC_RESET_N")
	)
	(segment
		(start 12.3698 -136.29386)
		(end 16.369792 -140.293852)
		(width 0.12065)
		(layer "F.Cu")
		(net "FM_BMC_RESET_N")
	)
	(segment
		(start 75.590654 -79.613252)
		(end 67.852798 -79.613252)
		(width 0.12065)
		(layer "F.Cu")
		(net "FM_BMC_RESET_N")
	)
	(segment
		(start 29.956252 -96.557338)
		(end 29.956252 -98.934778)
		(width 0.12065)
		(layer "F.Cu")
		(net "FM_BMC_RESET_N")
	)
	(segment
		(start 16.889476 -141.456664)
		(end 15.007336 -141.456664)
		(width 0.12065)
		(layer "F.Cu")
		(net "FM_BMC_RESET_N")
	)
	(segment
		(start 79.513684 -75.44435)
		(end 76.626466 -78.331568)
		(width 0.12065)
		(layer "F.Cu")
		(net "FM_BMC_RESET_N")
	)
	(segment
		(start 26.897584 -91.964256)
		(end 26.88209 -91.97975)
		(width 0.12065)
		(layer "F.Cu")
		(net "FM_BMC_RESET_N")
	)
	(segment
		(start 19.135852 -140.293852)
		(end 19.685 -140.843)
		(width 0.12065)
		(layer "F.Cu")
		(net "FM_BMC_RESET_N")
	)
	(segment
		(start 23.3045 -150.495)
		(end 23.368 -150.4315)
		(width 0.12065)
		(layer "F.Cu")
		(net "FM_BMC_RESET_N")
	)
	(segment
		(start 14.986 -147.828)
		(end 18.7325 -147.828)
		(width 0.12065)
		(layer "F.Cu")
		(net "FM_BMC_RESET_N")
	)
	(segment
		(start 26.621232 -102.550976)
		(end 26.621232 -103.007668)
		(width 0.12065)
		(layer "F.Cu")
		(net "FM_BMC_RESET_N")
	)
	(segment
		(start 25.908 -92.6338)
		(end 26.22804 -92.6338)
		(width 0.12065)
		(layer "F.Cu")
		(net "FM_BMC_RESET_N")
	)
	(segment
		(start 28.525978 -95.127064)
		(end 29.956252 -96.557338)
		(width 0.12065)
		(layer "F.Cu")
		(net "FM_BMC_RESET_N")
	)
	(segment
		(start 16.369792 -140.293852)
		(end 19.135852 -140.293852)
		(width 0.12065)
		(layer "F.Cu")
		(net "FM_BMC_RESET_N")
	)
	(segment
		(start 19.685 -140.843)
		(end 19.620484 -140.907516)
		(width 0.12065)
		(layer "F.Cu")
		(net "FM_BMC_RESET_N")
	)
	(segment
		(start 26.88209 -91.97975)
		(end 26.88209 -94.759526)
		(width 0.12065)
		(layer "F.Cu")
		(net "FM_BMC_RESET_N")
	)
	(segment
		(start 26.961592 -102.210616)
		(end 26.621232 -102.550976)
		(width 0.12065)
		(layer "F.Cu")
		(net "FM_BMC_RESET_N")
	)
	(segment
		(start 65.7606 -77.521054)
		(end 65.7606 -75.4507)
		(width 0.12065)
		(layer "F.Cu")
		(net "FM_BMC_RESET_N")
	)
	(segment
		(start 26.621232 -103.007668)
		(end 26.621232 -104.315514)
		(width 0.12065)
		(layer "F.Cu")
		(net "FM_BMC_RESET_N")
	)
	(segment
		(start 62.4713 -75.4507)
		(end 62.3316 -75.311)
		(width 0.12065)
		(layer "F.Cu")
		(net "FM_BMC_RESET_N")
	)
	(segment
		(start 18.671032 -140.907516)
		(end 18.121884 -141.456664)
		(width 0.12065)
		(layer "F.Cu")
		(net "FM_BMC_RESET_N")
	)
	(segment
		(start 6.924294 -103.419402)
		(end 3.972052 -106.371644)
		(width 0.12065)
		(layer "F.Cu")
		(net "FM_BMC_RESET_N")
	)
	(segment
		(start 23.368 -150.4315)
		(end 23.368 -150.1648)
		(width 0.12065)
		(layer "F.Cu")
		(net "FM_BMC_RESET_N")
	)
	(segment
		(start 18.7325 -148.844)
		(end 18.864326 -148.975826)
		(width 0.12065)
		(layer "F.Cu")
		(net "FM_BMC_RESET_N")
	)
	(segment
		(start 15.007336 -141.456664)
		(end 13.744448 -142.719552)
		(width 0.12065)
		(layer "F.Cu")
		(net "FM_BMC_RESET_N")
	)
	(segment
		(start 29.956252 -98.934778)
		(end 29.208984 -99.682046)
		(width 0.12065)
		(layer "F.Cu")
		(net "FM_BMC_RESET_N")
	)
	(segment
		(start 12.3698 -133.1468)
		(end 12.3698 -136.29386)
		(width 0.12065)
		(layer "F.Cu")
		(net "FM_BMC_RESET_N")
	)
	(segment
		(start 23.3045 -151.24176)
		(end 23.3045 -150.495)
		(width 0.12065)
		(layer "F.Cu")
		(net "FM_BMC_RESET_N")
	)
	(segment
		(start 26.88209 -94.759526)
		(end 27.249628 -95.127064)
		(width 0.12065)
		(layer "F.Cu")
		(net "FM_BMC_RESET_N")
	)
	(segment
		(start 13.744448 -146.586448)
		(end 14.986 -147.828)
		(width 0.12065)
		(layer "F.Cu")
		(net "FM_BMC_RESET_N")
	)
	(segment
		(start 65.7606 -75.4507)
		(end 62.4713 -75.4507)
		(width 0.12065)
		(layer "F.Cu")
		(net "FM_BMC_RESET_N")
	)
	(segment
		(start 80.428084 -75.44435)
		(end 79.513684 -75.44435)
		(width 0.12065)
		(layer "F.Cu")
		(net "FM_BMC_RESET_N")
	)
	(segment
		(start 3.972052 -124.749052)
		(end 12.3698 -133.1468)
		(width 0.12065)
		(layer "F.Cu")
		(net "FM_BMC_RESET_N")
	)
	(segment
		(start 19.620484 -140.907516)
		(end 18.671032 -140.907516)
		(width 0.12065)
		(layer "F.Cu")
		(net "FM_BMC_RESET_N")
	)
	(segment
		(start 26.22804 -92.6338)
		(end 26.88209 -91.97975)
		(width 0.12065)
		(layer "F.Cu")
		(net "FM_BMC_RESET_N")
	)
	(segment
		(start 18.665952 -104.934004)
		(end 17.15135 -103.419402)
		(width 0.12065)
		(layer "F.Cu")
		(net "FM_BMC_RESET_N")
	)
	(segment
		(start 26.002742 -104.934004)
		(end 18.665952 -104.934004)
		(width 0.12065)
		(layer "F.Cu")
		(net "FM_BMC_RESET_N")
	)
	(segment
		(start 13.744448 -142.719552)
		(end 13.744448 -146.586448)
		(width 0.12065)
		(layer "F.Cu")
		(net "FM_BMC_RESET_N")
	)
	(via
		(at 60.7314 -101.3968)
		(size 0.508)
		(drill 0.254)
		(layers "F.Cu" "B.Cu")
		(net "FM_BMC_RESET_N")
	)
	(via
		(at 23.368 -150.1648)
		(size 0.508)
		(drill 0.254)
		(layers "F.Cu" "B.Cu")
		(net "FM_BMC_RESET_N")
	)
	(via
		(at 60.5536 -105.7148)
		(size 0.508)
		(drill 0.254)
		(layers "F.Cu" "B.Cu")
		(net "FM_BMC_RESET_N")
	)
	(via
		(at 43.544236 -101.115622)
		(size 0.508)
		(drill 0.254)
		(layers "F.Cu" "B.Cu")
		(net "FM_BMC_RESET_N")
	)
	(via
		(at 19.685 -140.843)
		(size 0.508)
		(drill 0.254)
		(layers "F.Cu" "B.Cu")
		(net "FM_BMC_RESET_N")
	)
	(via
		(at 17.653 -148.844)
		(size 0.508)
		(drill 0.254)
		(layers "F.Cu" "B.Cu")
		(net "FM_BMC_RESET_N")
	)
	(via
		(at 25.908 -92.6338)
		(size 0.508)
		(drill 0.254)
		(layers "F.Cu" "B.Cu")
		(net "FM_BMC_RESET_N")
	)
	(via
		(at 62.3316 -75.311)
		(size 0.508)
		(drill 0.254)
		(layers "F.Cu" "B.Cu")
		(net "FM_BMC_RESET_N")
	)
	(segment
		(start 43.544236 -101.115622)
		(end 43.694858 -100.965)
		(width 0.12065)
		(layer "B.Cu")
		(net "FM_BMC_RESET_N")
	)
	(segment
		(start 60.2996 -100.965)
		(end 60.7314 -101.3968)
		(width 0.12065)
		(layer "B.Cu")
		(net "FM_BMC_RESET_N")
	)
	(segment
		(start 43.694858 -100.965)
		(end 60.2996 -100.965)
		(width 0.12065)
		(layer "B.Cu")
		(net "FM_BMC_RESET_N")
	)
	(segment
		(start 20.5105 -140.843)
		(end 19.685 -140.843)
		(width 0.12065)
		(layer "B.Cu")
		(net "FM_BMC_RESET_N")
	)
	(segment
		(start 17.653 -148.844)
		(end 17.7038 -148.8948)
		(width 0.127)
		(layer "In2.Cu")
		(net "FM_BMC_RESET_N")
	)
	(segment
		(start 17.7038 -148.8948)
		(end 22.098 -148.8948)
		(width 0.127)
		(layer "In2.Cu")
		(net "FM_BMC_RESET_N")
	)
	(segment
		(start 22.098 -148.8948)
		(end 23.368 -150.1648)
		(width 0.127)
		(layer "In2.Cu")
		(net "FM_BMC_RESET_N")
	)
	(segment
		(start 62.3316 -75.311)
		(end 62.169548 -75.311)
		(width 0.127)
		(layer "In5.Cu")
		(net "FM_BMC_RESET_N")
	)
	(segment
		(start 62.169548 -75.311)
		(end 60.5536 -76.926948)
		(width 0.127)
		(layer "In5.Cu")
		(net "FM_BMC_RESET_N")
	)
	(segment
		(start 60.7314 -105.438956)
		(end 60.7314 -101.3968)
		(width 0.127)
		(layer "In5.Cu")
		(net "FM_BMC_RESET_N")
	)
	(segment
		(start 60.5536 -105.616756)
		(end 60.7314 -105.438956)
		(width 0.127)
		(layer "In5.Cu")
		(net "FM_BMC_RESET_N")
	)
	(segment
		(start 40.94734 -98.518726)
		(end 43.544236 -101.115622)
		(width 0.127)
		(layer "In5.Cu")
		(net "FM_BMC_RESET_N")
	)
	(segment
		(start 60.5536 -105.7148)
		(end 60.5536 -105.616756)
		(width 0.127)
		(layer "In5.Cu")
		(net "FM_BMC_RESET_N")
	)
	(segment
		(start 60.5536 -98.4123)
		(end 60.7314 -98.5901)
		(width 0.127)
		(layer "In5.Cu")
		(net "FM_BMC_RESET_N")
	)
	(segment
		(start 36.570666 -94.817946)
		(end 36.570666 -95.74911)
		(width 0.127)
		(layer "In5.Cu")
		(net "FM_BMC_RESET_N")
	)
	(segment
		(start 36.570666 -95.74911)
		(end 39.340282 -98.518726)
		(width 0.127)
		(layer "In5.Cu")
		(net "FM_BMC_RESET_N")
	)
	(segment
		(start 25.908 -92.6338)
		(end 28.7401 -89.8017)
		(width 0.127)
		(layer "In5.Cu")
		(net "FM_BMC_RESET_N")
	)
	(segment
		(start 31.55442 -89.8017)
		(end 36.570666 -94.817946)
		(width 0.127)
		(layer "In5.Cu")
		(net "FM_BMC_RESET_N")
	)
	(segment
		(start 60.7314 -98.5901)
		(end 60.7314 -101.3968)
		(width 0.127)
		(layer "In5.Cu")
		(net "FM_BMC_RESET_N")
	)
	(segment
		(start 39.340282 -98.518726)
		(end 40.94734 -98.518726)
		(width 0.127)
		(layer "In5.Cu")
		(net "FM_BMC_RESET_N")
	)
	(segment
		(start 28.7401 -89.8017)
		(end 31.55442 -89.8017)
		(width 0.127)
		(layer "In5.Cu")
		(net "FM_BMC_RESET_N")
	)
	(segment
		(start 60.5536 -76.926948)
		(end 60.5536 -98.4123)
		(width 0.127)
		(layer "In5.Cu")
		(net "FM_BMC_RESET_N")
	)
	(segment
		(start 263.053068 -2.813304)
		(end 263.053068 -2.169668)
		(width 0.12065)
		(layer "F.Cu")
		(net "FM_BMC_RESET#_BTN")
	)
	(segment
		(start 262.387588 -3.743452)
		(end 262.387588 -3.702812)
		(width 0.12065)
		(layer "F.Cu")
		(net "FM_BMC_RESET#_BTN")
	)
	(segment
		(start 124.97562 -89.56802)
		(end 135.763 -100.3554)
		(width 0.12065)
		(layer "F.Cu")
		(net "FM_BMC_RESET#_BTN")
	)
	(segment
		(start 94.33941 -79.54899)
		(end 109.60735 -79.54899)
		(width 0.12065)
		(layer "F.Cu")
		(net "FM_BMC_RESET#_BTN")
	)
	(segment
		(start 109.60735 -79.54899)
		(end 119.62638 -89.56802)
		(width 0.12065)
		(layer "F.Cu")
		(net "FM_BMC_RESET#_BTN")
	)
	(segment
		(start 93.7006 -80.1878)
		(end 94.33941 -79.54899)
		(width 0.12065)
		(layer "F.Cu")
		(net "FM_BMC_RESET#_BTN")
	)
	(segment
		(start 263.053068 -3.037332)
		(end 263.053068 -2.813304)
		(width 0.12065)
		(layer "F.Cu")
		(net "FM_BMC_RESET#_BTN")
	)
	(segment
		(start 17.78 -158.623)
		(end 15.8496 -158.623)
		(width 0.12065)
		(layer "F.Cu")
		(net "FM_BMC_RESET#_BTN")
	)
	(segment
		(start 263.053068 -2.169668)
		(end 261.94131 -1.05791)
		(width 0.12065)
		(layer "F.Cu")
		(net "FM_BMC_RESET#_BTN")
	)
	(segment
		(start 261.94131 -1.05791)
		(end 261.94131 -0.432308)
		(width 0.12065)
		(layer "F.Cu")
		(net "FM_BMC_RESET#_BTN")
	)
	(segment
		(start 262.386318 -3.744722)
		(end 262.387588 -3.743452)
		(width 0.12065)
		(layer "F.Cu")
		(net "FM_BMC_RESET#_BTN")
	)
	(segment
		(start 119.62638 -89.56802)
		(end 124.97562 -89.56802)
		(width 0.12065)
		(layer "F.Cu")
		(net "FM_BMC_RESET#_BTN")
	)
	(segment
		(start 262.387588 -3.702812)
		(end 263.053068 -3.037332)
		(width 0.12065)
		(layer "F.Cu")
		(net "FM_BMC_RESET#_BTN")
	)
	(via
		(at 15.8496 -158.623)
		(size 0.508)
		(drill 0.254)
		(layers "F.Cu" "B.Cu")
		(net "FM_BMC_RESET#_BTN")
	)
	(via
		(at 93.7006 -80.1878)
		(size 0.508)
		(drill 0.254)
		(layers "F.Cu" "B.Cu")
		(net "FM_BMC_RESET#_BTN")
	)
	(via
		(at 262.386318 -3.744722)
		(size 0.508)
		(drill 0.254)
		(layers "F.Cu" "B.Cu")
		(net "FM_BMC_RESET#_BTN")
	)
	(via
		(at 135.763 -100.3554)
		(size 0.508)
		(drill 0.254)
		(layers "F.Cu" "B.Cu")
		(net "FM_BMC_RESET#_BTN")
	)
	(via
		(at 269.4432 -2.5654)
		(size 0.508)
		(drill 0.254)
		(layers "F.Cu" "B.Cu")
		(net "FM_BMC_RESET#_BTN")
	)
	(via
		(at 350.386142 -41.536112)
		(size 0.7112)
		(drill 0.3556)
		(layers "F.Cu" "B.Cu")
		(net "FM_BMC_RESET#_BTN")
	)
	(segment
		(start 352.571812 -46.85792)
		(end 352.571812 -45.576998)
		(width 0.12065)
		(layer "B.Cu")
		(net "FM_BMC_RESET#_BTN")
	)
	(segment
		(start 351.749868 -47.679864)
		(end 352.571812 -46.85792)
		(width 0.12065)
		(layer "B.Cu")
		(net "FM_BMC_RESET#_BTN")
	)
	(segment
		(start 137.1473 -101.7397)
		(end 137.1981 -101.7397)
		(width 0.12065)
		(layer "B.Cu")
		(net "FM_BMC_RESET#_BTN")
	)
	(segment
		(start 351.892108 -42.354754)
		(end 351.073466 -41.536112)
		(width 0.12065)
		(layer "B.Cu")
		(net "FM_BMC_RESET#_BTN")
	)
	(segment
		(start 347.764354 -41.536112)
		(end 347.41358 -41.886886)
		(width 0.12065)
		(layer "B.Cu")
		(net "FM_BMC_RESET#_BTN")
	)
	(segment
		(start 267.650468 0.123444)
		(end 267.650468 -2.619502)
		(width 0.12065)
		(layer "B.Cu")
		(net "FM_BMC_RESET#_BTN")
	)
	(segment
		(start 331.48905 -30.762448)
		(end 331.139546 -30.412944)
		(width 0.12065)
		(layer "B.Cu")
		(net "FM_BMC_RESET#_BTN")
	)
	(segment
		(start 141.39545 -105.93705)
		(end 142.865856 -105.93705)
		(width 0.12065)
		(layer "B.Cu")
		(net "FM_BMC_RESET#_BTN")
	)
	(segment
		(start 351.892108 -43.14698)
		(end 351.892108 -42.354754)
		(width 0.12065)
		(layer "B.Cu")
		(net "FM_BMC_RESET#_BTN")
	)
	(segment
		(start 268.063218 -3.032252)
		(end 268.976348 -3.032252)
		(width 0.12065)
		(layer "B.Cu")
		(net "FM_BMC_RESET#_BTN")
	)
	(segment
		(start 142.865856 -105.93705)
		(end 149.606762 -112.677956)
		(width 0.12065)
		(layer "B.Cu")
		(net "FM_BMC_RESET#_BTN")
	)
	(segment
		(start 149.606762 -112.677956)
		(end 334.517238 -112.677956)
		(width 0.12065)
		(layer "B.Cu")
		(net "FM_BMC_RESET#_BTN")
	)
	(segment
		(start 351.749868 -95.445326)
		(end 351.749868 -47.679864)
		(width 0.12065)
		(layer "B.Cu")
		(net "FM_BMC_RESET#_BTN")
	)
	(segment
		(start 351.749868 -43.28922)
		(end 351.892108 -43.14698)
		(width 0.12065)
		(layer "B.Cu")
		(net "FM_BMC_RESET#_BTN")
	)
	(segment
		(start 347.41358 -41.886886)
		(end 344.13444 -41.886886)
		(width 0.12065)
		(layer "B.Cu")
		(net "FM_BMC_RESET#_BTN")
	)
	(segment
		(start 137.1981 -101.7397)
		(end 141.39545 -105.93705)
		(width 0.12065)
		(layer "B.Cu")
		(net "FM_BMC_RESET#_BTN")
	)
	(segment
		(start 269.426944 1.888744)
		(end 269.415768 1.888744)
		(width 0.12065)
		(layer "B.Cu")
		(net "FM_BMC_RESET#_BTN")
	)
	(segment
		(start 344.13444 -41.886886)
		(end 343.405714 -42.615612)
		(width 0.12065)
		(layer "B.Cu")
		(net "FM_BMC_RESET#_BTN")
	)
	(segment
		(start 331.139546 -30.412944)
		(end 331.139546 -25.068276)
		(width 0.12065)
		(layer "B.Cu")
		(net "FM_BMC_RESET#_BTN")
	)
	(segment
		(start 330.22413 -24.15286)
		(end 330.22413 -6.081268)
		(width 0.12065)
		(layer "B.Cu")
		(net "FM_BMC_RESET#_BTN")
	)
	(segment
		(start 330.22413 -6.081268)
		(end 326.579992 -2.43713)
		(width 0.12065)
		(layer "B.Cu")
		(net "FM_BMC_RESET#_BTN")
	)
	(segment
		(start 350.386142 -41.536112)
		(end 347.764354 -41.536112)
		(width 0.12065)
		(layer "B.Cu")
		(net "FM_BMC_RESET#_BTN")
	)
	(segment
		(start 331.139546 -25.068276)
		(end 330.22413 -24.15286)
		(width 0.12065)
		(layer "B.Cu")
		(net "FM_BMC_RESET#_BTN")
	)
	(segment
		(start 282.531058 -2.43713)
		(end 277.92172 2.172208)
		(width 0.12065)
		(layer "B.Cu")
		(net "FM_BMC_RESET#_BTN")
	)
	(segment
		(start 331.48905 -39.015162)
		(end 331.48905 -30.762448)
		(width 0.12065)
		(layer "B.Cu")
		(net "FM_BMC_RESET#_BTN")
	)
	(segment
		(start 351.749868 -44.755054)
		(end 351.749868 -43.28922)
		(width 0.12065)
		(layer "B.Cu")
		(net "FM_BMC_RESET#_BTN")
	)
	(segment
		(start 268.976348 -3.032252)
		(end 269.4432 -2.5654)
		(width 0.12065)
		(layer "B.Cu")
		(net "FM_BMC_RESET#_BTN")
	)
	(segment
		(start 269.415768 1.888744)
		(end 267.650468 0.123444)
		(width 0.12065)
		(layer "B.Cu")
		(net "FM_BMC_RESET#_BTN")
	)
	(segment
		(start 343.405714 -42.615612)
		(end 335.0895 -42.615612)
		(width 0.12065)
		(layer "B.Cu")
		(net "FM_BMC_RESET#_BTN")
	)
	(segment
		(start 352.571812 -45.576998)
		(end 351.749868 -44.755054)
		(width 0.12065)
		(layer "B.Cu")
		(net "FM_BMC_RESET#_BTN")
	)
	(segment
		(start 326.579992 -2.43713)
		(end 282.531058 -2.43713)
		(width 0.12065)
		(layer "B.Cu")
		(net "FM_BMC_RESET#_BTN")
	)
	(segment
		(start 135.763 -100.3554)
		(end 137.1473 -101.7397)
		(width 0.12065)
		(layer "B.Cu")
		(net "FM_BMC_RESET#_BTN")
	)
	(segment
		(start 277.92172 2.172208)
		(end 269.710408 2.172208)
		(width 0.12065)
		(layer "B.Cu")
		(net "FM_BMC_RESET#_BTN")
	)
	(segment
		(start 267.650468 -2.619502)
		(end 268.063218 -3.032252)
		(width 0.12065)
		(layer "B.Cu")
		(net "FM_BMC_RESET#_BTN")
	)
	(segment
		(start 269.710408 2.172208)
		(end 269.426944 1.888744)
		(width 0.12065)
		(layer "B.Cu")
		(net "FM_BMC_RESET#_BTN")
	)
	(segment
		(start 335.0895 -42.615612)
		(end 331.48905 -39.015162)
		(width 0.12065)
		(layer "B.Cu")
		(net "FM_BMC_RESET#_BTN")
	)
	(segment
		(start 334.517238 -112.677956)
		(end 351.749868 -95.445326)
		(width 0.12065)
		(layer "B.Cu")
		(net "FM_BMC_RESET#_BTN")
	)
	(segment
		(start 351.073466 -41.536112)
		(end 350.386142 -41.536112)
		(width 0.12065)
		(layer "B.Cu")
		(net "FM_BMC_RESET#_BTN")
	)
	(segment
		(start 88.282272 -80.1878)
		(end 93.7006 -80.1878)
		(width 0.127)
		(layer "In2.Cu")
		(net "FM_BMC_RESET#_BTN")
	)
	(segment
		(start 43.126914 -84.527136)
		(end 54.0512 -84.527136)
		(width 0.127)
		(layer "In2.Cu")
		(net "FM_BMC_RESET#_BTN")
	)
	(segment
		(start 15.8496 -158.623)
		(end 15.8496 -158.196788)
		(width 0.127)
		(layer "In2.Cu")
		(net "FM_BMC_RESET#_BTN")
	)
	(segment
		(start 29.692854 -85.0646)
		(end 42.58945 -85.0646)
		(width 0.127)
		(layer "In2.Cu")
		(net "FM_BMC_RESET#_BTN")
	)
	(segment
		(start 54.0512 -84.527136)
		(end 54.42458 -84.153756)
		(width 0.127)
		(layer "In2.Cu")
		(net "FM_BMC_RESET#_BTN")
	)
	(segment
		(start 22.21611 -89.103454)
		(end 23.035006 -89.103454)
		(width 0.127)
		(layer "In2.Cu")
		(net "FM_BMC_RESET#_BTN")
	)
	(segment
		(start 6.127242 -103.901494)
		(end 6.126988 -103.90124)
		(width 0.127)
		(layer "In2.Cu")
		(net "FM_BMC_RESET#_BTN")
	)
	(segment
		(start 75.82916 -81.79816)
		(end 76.68514 -82.65414)
		(width 0.127)
		(layer "In2.Cu")
		(net "FM_BMC_RESET#_BTN")
	)
	(segment
		(start 6.126988 -103.585772)
		(end 12.585446 -97.127314)
		(width 0.127)
		(layer "In2.Cu")
		(net "FM_BMC_RESET#_BTN")
	)
	(segment
		(start 12.585446 -97.127314)
		(end 12.5857 -97.028254)
		(width 0.127)
		(layer "In2.Cu")
		(net "FM_BMC_RESET#_BTN")
	)
	(segment
		(start 72.793606 -81.79816)
		(end 75.82916 -81.79816)
		(width 0.127)
		(layer "In2.Cu")
		(net "FM_BMC_RESET#_BTN")
	)
	(segment
		(start 2.88036 -110.23346)
		(end 6.127242 -106.986578)
		(width 0.127)
		(layer "In2.Cu")
		(net "FM_BMC_RESET#_BTN")
	)
	(segment
		(start 76.68514 -82.65414)
		(end 81.27746 -82.65414)
		(width 0.127)
		(layer "In2.Cu")
		(net "FM_BMC_RESET#_BTN")
	)
	(segment
		(start 27.300936 -85.7123)
		(end 28.139136 -84.8741)
		(width 0.127)
		(layer "In2.Cu")
		(net "FM_BMC_RESET#_BTN")
	)
	(segment
		(start 69.585586 -85.00618)
		(end 72.793606 -81.79816)
		(width 0.127)
		(layer "In2.Cu")
		(net "FM_BMC_RESET#_BTN")
	)
	(segment
		(start 6.126988 -103.90124)
		(end 6.126988 -103.585772)
		(width 0.127)
		(layer "In2.Cu")
		(net "FM_BMC_RESET#_BTN")
	)
	(segment
		(start 28.139136 -84.8741)
		(end 29.502354 -84.8741)
		(width 0.127)
		(layer "In2.Cu")
		(net "FM_BMC_RESET#_BTN")
	)
	(segment
		(start 65.09639 -84.153756)
		(end 65.948814 -85.00618)
		(width 0.127)
		(layer "In2.Cu")
		(net "FM_BMC_RESET#_BTN")
	)
	(segment
		(start 21.528024 -89.79154)
		(end 22.21611 -89.103454)
		(width 0.127)
		(layer "In2.Cu")
		(net "FM_BMC_RESET#_BTN")
	)
	(segment
		(start 54.42458 -84.153756)
		(end 65.09639 -84.153756)
		(width 0.127)
		(layer "In2.Cu")
		(net "FM_BMC_RESET#_BTN")
	)
	(segment
		(start 42.58945 -85.0646)
		(end 43.126914 -84.527136)
		(width 0.127)
		(layer "In2.Cu")
		(net "FM_BMC_RESET#_BTN")
	)
	(segment
		(start 65.948814 -85.00618)
		(end 69.585586 -85.00618)
		(width 0.127)
		(layer "In2.Cu")
		(net "FM_BMC_RESET#_BTN")
	)
	(segment
		(start 6.127242 -106.986578)
		(end 6.127242 -103.901494)
		(width 0.127)
		(layer "In2.Cu")
		(net "FM_BMC_RESET#_BTN")
	)
	(segment
		(start 12.5857 -95.944182)
		(end 18.738342 -89.79154)
		(width 0.127)
		(layer "In2.Cu")
		(net "FM_BMC_RESET#_BTN")
	)
	(segment
		(start 12.5857 -97.028254)
		(end 12.5857 -95.944182)
		(width 0.127)
		(layer "In2.Cu")
		(net "FM_BMC_RESET#_BTN")
	)
	(segment
		(start 23.035006 -89.103454)
		(end 26.42616 -85.7123)
		(width 0.127)
		(layer "In2.Cu")
		(net "FM_BMC_RESET#_BTN")
	)
	(segment
		(start 82.677508 -81.254092)
		(end 87.21598 -81.254092)
		(width 0.127)
		(layer "In2.Cu")
		(net "FM_BMC_RESET#_BTN")
	)
	(segment
		(start 15.8496 -158.196788)
		(end 2.88036 -145.227548)
		(width 0.127)
		(layer "In2.Cu")
		(net "FM_BMC_RESET#_BTN")
	)
	(segment
		(start 2.88036 -145.227548)
		(end 2.88036 -110.23346)
		(width 0.127)
		(layer "In2.Cu")
		(net "FM_BMC_RESET#_BTN")
	)
	(segment
		(start 29.502354 -84.8741)
		(end 29.692854 -85.0646)
		(width 0.127)
		(layer "In2.Cu")
		(net "FM_BMC_RESET#_BTN")
	)
	(segment
		(start 81.27746 -82.65414)
		(end 82.677508 -81.254092)
		(width 0.127)
		(layer "In2.Cu")
		(net "FM_BMC_RESET#_BTN")
	)
	(segment
		(start 26.42616 -85.7123)
		(end 27.300936 -85.7123)
		(width 0.127)
		(layer "In2.Cu")
		(net "FM_BMC_RESET#_BTN")
	)
	(segment
		(start 87.21598 -81.254092)
		(end 88.282272 -80.1878)
		(width 0.127)
		(layer "In2.Cu")
		(net "FM_BMC_RESET#_BTN")
	)
	(segment
		(start 18.738342 -89.79154)
		(end 21.528024 -89.79154)
		(width 0.127)
		(layer "In2.Cu")
		(net "FM_BMC_RESET#_BTN")
	)
	(segment
		(start 265.852148 -3.398266)
		(end 266.955016 -3.398266)
		(width 0.127)
		(layer "In5.Cu")
		(net "FM_BMC_RESET#_BTN")
	)
	(segment
		(start 262.427466 -3.7846)
		(end 265.465814 -3.7846)
		(width 0.127)
		(layer "In5.Cu")
		(net "FM_BMC_RESET#_BTN")
	)
	(segment
		(start 262.386318 -3.744722)
		(end 262.387588 -3.744722)
		(width 0.127)
		(layer "In5.Cu")
		(net "FM_BMC_RESET#_BTN")
	)
	(segment
		(start 268.8209 -3.1877)
		(end 269.4432 -2.5654)
		(width 0.127)
		(layer "In5.Cu")
		(net "FM_BMC_RESET#_BTN")
	)
	(segment
		(start 267.165582 -3.1877)
		(end 268.8209 -3.1877)
		(width 0.127)
		(layer "In5.Cu")
		(net "FM_BMC_RESET#_BTN")
	)
	(segment
		(start 262.387588 -3.744722)
		(end 262.427466 -3.7846)
		(width 0.127)
		(layer "In5.Cu")
		(net "FM_BMC_RESET#_BTN")
	)
	(segment
		(start 265.465814 -3.7846)
		(end 265.852148 -3.398266)
		(width 0.127)
		(layer "In5.Cu")
		(net "FM_BMC_RESET#_BTN")
	)
	(segment
		(start 266.955016 -3.398266)
		(end 267.165582 -3.1877)
		(width 0.127)
		(layer "In5.Cu")
		(net "FM_BMC_RESET#_BTN")
	)
	(segment
		(start 61.05652 -59.39282)
		(end 61.0616 -59.3979)
		(width 0.12065)
		(layer "F.Cu")
		(net "FLA_WPN")
	)
	(segment
		(start 60.002674 -62.230254)
		(end 60.002674 -59.41822)
		(width 0.12065)
		(layer "F.Cu")
		(net "FLA_WPN")
	)
	(segment
		(start 60.002674 -59.41822)
		(end 60.028074 -59.39282)
		(width 0.12065)
		(layer "F.Cu")
		(net "FLA_WPN")
	)
	(segment
		(start 60.028074 -59.39282)
		(end 61.05652 -59.39282)
		(width 0.12065)
		(layer "F.Cu")
		(net "FLA_WPN")
	)
	(segment
		(start 78.189836 -71.827644)
		(end 78.189836 -72.00646)
		(width 0.12065)
		(layer "F.Cu")
		(net "FLA_CS_R")
	)
	(segment
		(start 78.189836 -68.969636)
		(end 78.189836 -71.827644)
		(width 0.12065)
		(layer "F.Cu")
		(net "FLA_CS_R")
	)
	(segment
		(start 77.9526 -63.754)
		(end 77.9526 -68.7324)
		(width 0.12065)
		(layer "F.Cu")
		(net "FLA_CS_R")
	)
	(segment
		(start 18.793968 -132.715)
		(end 18.741898 -132.76707)
		(width 0.12065)
		(layer "F.Cu")
		(net "FLA_CS_R")
	)
	(segment
		(start 77.9272 -73.787)
		(end 77.9272 -73.994772)
		(width 0.12065)
		(layer "F.Cu")
		(net "FLA_CS_R")
	)
	(segment
		(start 77.9272 -73.787)
		(end 78.069186 -73.787)
		(width 0.12065)
		(layer "F.Cu")
		(net "FLA_CS_R")
	)
	(segment
		(start 19.7358 -132.715)
		(end 18.793968 -132.715)
		(width 0.12065)
		(layer "F.Cu")
		(net "FLA_CS_R")
	)
	(segment
		(start 78.069186 -73.787)
		(end 78.189836 -73.66635)
		(width 0.12065)
		(layer "F.Cu")
		(net "FLA_CS_R")
	)
	(segment
		(start 78.189836 -73.66635)
		(end 78.189836 -72.00646)
		(width 0.12065)
		(layer "F.Cu")
		(net "FLA_CS_R")
	)
	(segment
		(start 77.9526 -68.7324)
		(end 78.189836 -68.969636)
		(width 0.12065)
		(layer "F.Cu")
		(net "FLA_CS_R")
	)
	(segment
		(start 77.9272 -73.994772)
		(end 78.494128 -74.5617)
		(width 0.12065)
		(layer "F.Cu")
		(net "FLA_CS_R")
	)
	(via
		(at 76.53528 -92.075)
		(size 0.508)
		(drill 0.254)
		(layers "F.Cu" "B.Cu")
		(net "FLA_CS_R")
	)
	(via
		(at 19.7358 -132.715)
		(size 0.508)
		(drill 0.254)
		(layers "F.Cu" "B.Cu")
		(net "FLA_CS_R")
	)
	(via
		(at 18.741898 -132.76707)
		(size 0.7112)
		(drill 0.3556)
		(layers "F.Cu" "B.Cu")
		(net "FLA_CS_R")
	)
	(via
		(at 77.9526 -63.754)
		(size 0.508)
		(drill 0.254)
		(layers "F.Cu" "B.Cu")
		(net "FLA_CS_R")
	)
	(via
		(at 77.9272 -73.787)
		(size 0.508)
		(drill 0.254)
		(layers "F.Cu" "B.Cu")
		(net "FLA_CS_R")
	)
	(segment
		(start 20.5105 -132.715)
		(end 19.7358 -132.715)
		(width 0.12065)
		(layer "B.Cu")
		(net "FLA_CS_R")
	)
	(segment
		(start 14.228826 -122.67692)
		(end 13.226034 -123.679712)
		(width 0.127)
		(layer "In2.Cu")
		(net "FLA_CS_R")
	)
	(segment
		(start 15.9131 -119.411496)
		(end 15.352522 -119.972074)
		(width 0.127)
		(layer "In2.Cu")
		(net "FLA_CS_R")
	)
	(segment
		(start 77.9526 -62.9666)
		(end 77.9526 -63.754)
		(width 0.127)
		(layer "In2.Cu")
		(net "FLA_CS_R")
	)
	(segment
		(start 17.922748 -132.715)
		(end 19.7358 -132.715)
		(width 0.127)
		(layer "In2.Cu")
		(net "FLA_CS_R")
	)
	(segment
		(start 15.654274 -132.840984)
		(end 15.654528 -132.841238)
		(width 0.127)
		(layer "In2.Cu")
		(net "FLA_CS_R")
	)
	(segment
		(start 58.50509 -93.0783)
		(end 52.734972 -93.0783)
		(width 0.127)
		(layer "In2.Cu")
		(net "FLA_CS_R")
	)
	(segment
		(start 24.001476 -100.733098)
		(end 23.749 -100.985574)
		(width 0.127)
		(layer "In2.Cu")
		(net "FLA_CS_R")
	)
	(segment
		(start 14.675612 -132.342636)
		(end 14.675612 -132.34289)
		(width 0.127)
		(layer "In2.Cu")
		(net "FLA_CS_R")
	)
	(segment
		(start 20.894294 -104.352852)
		(end 16.565626 -108.68152)
		(width 0.127)
		(layer "In2.Cu")
		(net "FLA_CS_R")
	)
	(segment
		(start 15.352522 -121.008902)
		(end 14.228826 -122.132852)
		(width 0.127)
		(layer "In2.Cu")
		(net "FLA_CS_R")
	)
	(segment
		(start 24.809704 -100.733098)
		(end 24.001476 -100.733098)
		(width 0.127)
		(layer "In2.Cu")
		(net "FLA_CS_R")
	)
	(segment
		(start 12.930378 -125.1204)
		(end 12.568428 -125.1204)
		(width 0.127)
		(layer "In2.Cu")
		(net "FLA_CS_R")
	)
	(segment
		(start 15.744444 -132.9309)
		(end 17.706848 -132.9309)
		(width 0.127)
		(layer "In2.Cu")
		(net "FLA_CS_R")
	)
	(segment
		(start 15.654782 -132.841238)
		(end 15.744444 -132.9309)
		(width 0.127)
		(layer "In2.Cu")
		(net "FLA_CS_R")
	)
	(segment
		(start 73.941178 -92.30106)
		(end 71.72198 -92.30106)
		(width 0.127)
		(layer "In2.Cu")
		(net "FLA_CS_R")
	)
	(segment
		(start 36.225226 -94.387924)
		(end 35.375342 -95.237808)
		(width 0.127)
		(layer "In2.Cu")
		(net "FLA_CS_R")
	)
	(segment
		(start 21.430488 -103.30561)
		(end 20.935188 -103.801418)
		(width 0.127)
		(layer "In2.Cu")
		(net "FLA_CS_R")
	)
	(segment
		(start 13.226034 -123.679712)
		(end 13.226034 -124.824744)
		(width 0.127)
		(layer "In2.Cu")
		(net "FLA_CS_R")
	)
	(segment
		(start 75.922378 -92.687902)
		(end 74.32802 -92.687902)
		(width 0.127)
		(layer "In2.Cu")
		(net "FLA_CS_R")
	)
	(segment
		(start 12.26566 -125.423168)
		(end 12.26566 -129.932684)
		(width 0.127)
		(layer "In2.Cu")
		(net "FLA_CS_R")
	)
	(segment
		(start 21.928328 -102.807516)
		(end 21.430488 -103.30561)
		(width 0.127)
		(layer "In2.Cu")
		(net "FLA_CS_R")
	)
	(segment
		(start 20.935188 -103.801418)
		(end 20.894294 -103.842312)
		(width 0.127)
		(layer "In2.Cu")
		(net "FLA_CS_R")
	)
	(segment
		(start 14.675612 -132.34289)
		(end 15.173706 -132.840984)
		(width 0.127)
		(layer "In2.Cu")
		(net "FLA_CS_R")
	)
	(segment
		(start 41.720262 -94.425262)
		(end 41.167812 -93.872812)
		(width 0.127)
		(layer "In2.Cu")
		(net "FLA_CS_R")
	)
	(segment
		(start 76.835 -52.6288)
		(end 76.835 -61.849)
		(width 0.127)
		(layer "In2.Cu")
		(net "FLA_CS_R")
	)
	(segment
		(start 76.835 -61.849)
		(end 77.9526 -62.9666)
		(width 0.127)
		(layer "In2.Cu")
		(net "FLA_CS_R")
	)
	(segment
		(start 12.568428 -125.1204)
		(end 12.26566 -125.423168)
		(width 0.127)
		(layer "In2.Cu")
		(net "FLA_CS_R")
	)
	(segment
		(start 16.565626 -108.68152)
		(end 16.565626 -112.979962)
		(width 0.127)
		(layer "In2.Cu")
		(net "FLA_CS_R")
	)
	(segment
		(start 51.38801 -94.425262)
		(end 41.720262 -94.425262)
		(width 0.127)
		(layer "In2.Cu")
		(net "FLA_CS_R")
	)
	(segment
		(start 15.173706 -132.840984)
		(end 15.654274 -132.840984)
		(width 0.127)
		(layer "In2.Cu")
		(net "FLA_CS_R")
	)
	(segment
		(start 26.812494 -99.230942)
		(end 26.31186 -99.230942)
		(width 0.127)
		(layer "In2.Cu")
		(net "FLA_CS_R")
	)
	(segment
		(start 16.565372 -113.025428)
		(end 15.9131 -113.6777)
		(width 0.127)
		(layer "In2.Cu")
		(net "FLA_CS_R")
	)
	(segment
		(start 30.805628 -95.237808)
		(end 26.812494 -99.230942)
		(width 0.127)
		(layer "In2.Cu")
		(net "FLA_CS_R")
	)
	(segment
		(start 71.28764 -92.7354)
		(end 58.84799 -92.7354)
		(width 0.127)
		(layer "In2.Cu")
		(net "FLA_CS_R")
	)
	(segment
		(start 14.228826 -122.132852)
		(end 14.228826 -122.67692)
		(width 0.127)
		(layer "In2.Cu")
		(net "FLA_CS_R")
	)
	(segment
		(start 15.352522 -119.972074)
		(end 15.352522 -121.008902)
		(width 0.127)
		(layer "In2.Cu")
		(net "FLA_CS_R")
	)
	(segment
		(start 13.226034 -124.824744)
		(end 12.930378 -125.1204)
		(width 0.127)
		(layer "In2.Cu")
		(net "FLA_CS_R")
	)
	(segment
		(start 15.654528 -132.841238)
		(end 15.654782 -132.841238)
		(width 0.127)
		(layer "In2.Cu")
		(net "FLA_CS_R")
	)
	(segment
		(start 17.706848 -132.9309)
		(end 17.922748 -132.715)
		(width 0.127)
		(layer "In2.Cu")
		(net "FLA_CS_R")
	)
	(segment
		(start 38.774878 -93.872812)
		(end 38.259766 -94.387924)
		(width 0.127)
		(layer "In2.Cu")
		(net "FLA_CS_R")
	)
	(segment
		(start 20.894294 -103.842312)
		(end 20.894294 -104.352852)
		(width 0.127)
		(layer "In2.Cu")
		(net "FLA_CS_R")
	)
	(segment
		(start 52.734972 -93.0783)
		(end 51.38801 -94.425262)
		(width 0.127)
		(layer "In2.Cu")
		(net "FLA_CS_R")
	)
	(segment
		(start 15.9131 -113.6777)
		(end 15.9131 -119.411496)
		(width 0.127)
		(layer "In2.Cu")
		(net "FLA_CS_R")
	)
	(segment
		(start 41.167812 -93.872812)
		(end 38.774878 -93.872812)
		(width 0.127)
		(layer "In2.Cu")
		(net "FLA_CS_R")
	)
	(segment
		(start 35.375342 -95.237808)
		(end 30.805628 -95.237808)
		(width 0.127)
		(layer "In2.Cu")
		(net "FLA_CS_R")
	)
	(segment
		(start 76.53528 -92.075)
		(end 75.922378 -92.687902)
		(width 0.127)
		(layer "In2.Cu")
		(net "FLA_CS_R")
	)
	(segment
		(start 26.31186 -99.230942)
		(end 24.809704 -100.733098)
		(width 0.127)
		(layer "In2.Cu")
		(net "FLA_CS_R")
	)
	(segment
		(start 12.26566 -129.932684)
		(end 14.675612 -132.342636)
		(width 0.127)
		(layer "In2.Cu")
		(net "FLA_CS_R")
	)
	(segment
		(start 23.749 -100.985574)
		(end 21.928328 -102.807516)
		(width 0.127)
		(layer "In2.Cu")
		(net "FLA_CS_R")
	)
	(segment
		(start 74.32802 -92.687902)
		(end 73.941178 -92.30106)
		(width 0.127)
		(layer "In2.Cu")
		(net "FLA_CS_R")
	)
	(segment
		(start 58.84799 -92.7354)
		(end 58.50509 -93.0783)
		(width 0.127)
		(layer "In2.Cu")
		(net "FLA_CS_R")
	)
	(segment
		(start 71.72198 -92.30106)
		(end 71.28764 -92.7354)
		(width 0.127)
		(layer "In2.Cu")
		(net "FLA_CS_R")
	)
	(segment
		(start 16.565626 -112.979962)
		(end 16.565372 -113.025428)
		(width 0.127)
		(layer "In2.Cu")
		(net "FLA_CS_R")
	)
	(segment
		(start 38.259766 -94.387924)
		(end 36.225226 -94.387924)
		(width 0.127)
		(layer "In2.Cu")
		(net "FLA_CS_R")
	)
	(segment
		(start 77.69352 -75.495404)
		(end 77.69352 -74.02068)
		(width 0.127)
		(layer "In5.Cu")
		(net "FLA_CS_R")
	)
	(segment
		(start 77.69352 -74.02068)
		(end 77.9272 -73.787)
		(width 0.127)
		(layer "In5.Cu")
		(net "FLA_CS_R")
	)
	(segment
		(start 76.53528 -91.74988)
		(end 74.5617 -89.7763)
		(width 0.127)
		(layer "In5.Cu")
		(net "FLA_CS_R")
	)
	(segment
		(start 74.5617 -78.627224)
		(end 77.69352 -75.495404)
		(width 0.127)
		(layer "In5.Cu")
		(net "FLA_CS_R")
	)
	(segment
		(start 74.5617 -89.7763)
		(end 74.5617 -78.627224)
		(width 0.127)
		(layer "In5.Cu")
		(net "FLA_CS_R")
	)
	(segment
		(start 76.53528 -92.075)
		(end 76.53528 -91.74988)
		(width 0.127)
		(layer "In5.Cu")
		(net "FLA_CS_R")
	)
	(segment
		(start 15.526512 -131.990084)
		(end 15.245842 -131.709414)
		(width 0.12065)
		(layer "F.Cu")
		(net "FLA_CS")
	)
	(segment
		(start 15.05712 -129.766314)
		(end 15.135098 -129.844292)
		(width 0.12065)
		(layer "F.Cu")
		(net "FLA_CS")
	)
	(segment
		(start 32.104838 -133.284976)
		(end 31.705042 -132.88518)
		(width 0.12065)
		(layer "F.Cu")
		(net "FLA_CS")
	)
	(segment
		(start 15.245842 -131.709414)
		(end 15.245842 -129.955036)
		(width 0.12065)
		(layer "F.Cu")
		(net "FLA_CS")
	)
	(segment
		(start 15.245842 -129.955036)
		(end 15.135098 -129.844292)
		(width 0.12065)
		(layer "F.Cu")
		(net "FLA_CS")
	)
	(segment
		(start 14.036294 -129.766314)
		(end 15.05712 -129.766314)
		(width 0.12065)
		(layer "F.Cu")
		(net "FLA_CS")
	)
	(via
		(at 15.526512 -131.990084)
		(size 0.508)
		(drill 0.254)
		(layers "F.Cu" "B.Cu")
		(net "FLA_CS")
	)
	(via
		(at 31.705042 -132.88518)
		(size 0.4572)
		(drill 0.2032)
		(layers "F.Cu" "B.Cu")
		(net "FLA_CS")
	)
	(via
		(at 15.135098 -129.844292)
		(size 0.7112)
		(drill 0.3556)
		(layers "F.Cu" "B.Cu")
		(net "FLA_CS")
	)
	(segment
		(start 31.31439 -132.494528)
		(end 30.743144 -132.494528)
		(width 0.12065)
		(layer "B.Cu")
		(net "FLA_CS")
	)
	(segment
		(start 31.705042 -132.88518)
		(end 31.31439 -132.494528)
		(width 0.12065)
		(layer "B.Cu")
		(net "FLA_CS")
	)
	(segment
		(start 25.40254 -133.138164)
		(end 24.953468 -132.689092)
		(width 0.12065)
		(layer "B.Cu")
		(net "FLA_CS")
	)
	(segment
		(start 27.430984 -132.878068)
		(end 27.170888 -133.138164)
		(width 0.12065)
		(layer "B.Cu")
		(net "FLA_CS")
	)
	(segment
		(start 24.953468 -132.689092)
		(end 21.425408 -132.689092)
		(width 0.12065)
		(layer "B.Cu")
		(net "FLA_CS")
	)
	(segment
		(start 30.743144 -132.494528)
		(end 30.359604 -132.878068)
		(width 0.12065)
		(layer "B.Cu")
		(net "FLA_CS")
	)
	(segment
		(start 21.425408 -132.689092)
		(end 21.3995 -132.715)
		(width 0.12065)
		(layer "B.Cu")
		(net "FLA_CS")
	)
	(segment
		(start 27.170888 -133.138164)
		(end 25.40254 -133.138164)
		(width 0.12065)
		(layer "B.Cu")
		(net "FLA_CS")
	)
	(segment
		(start 30.359604 -132.878068)
		(end 27.430984 -132.878068)
		(width 0.12065)
		(layer "B.Cu")
		(net "FLA_CS")
	)
	(segment
		(start 18.330418 -131.2291)
		(end 19.930618 -131.2291)
		(width 0.127)
		(layer "In2.Cu")
		(net "FLA_CS")
	)
	(segment
		(start 17.390618 -132.1689)
		(end 18.330418 -131.2291)
		(width 0.127)
		(layer "In2.Cu")
		(net "FLA_CS")
	)
	(segment
		(start 16.0655 -132.1689)
		(end 17.390618 -132.1689)
		(width 0.127)
		(layer "In2.Cu")
		(net "FLA_CS")
	)
	(segment
		(start 15.9258 -132.0292)
		(end 16.0655 -132.1689)
		(width 0.127)
		(layer "In2.Cu")
		(net "FLA_CS")
	)
	(segment
		(start 21.192998 -132.49148)
		(end 31.068264 -132.49148)
		(width 0.127)
		(layer "In2.Cu")
		(net "FLA_CS")
	)
	(segment
		(start 31.461964 -132.88518)
		(end 31.705042 -132.88518)
		(width 0.127)
		(layer "In2.Cu")
		(net "FLA_CS")
	)
	(segment
		(start 19.930618 -131.2291)
		(end 21.192998 -132.49148)
		(width 0.127)
		(layer "In2.Cu")
		(net "FLA_CS")
	)
	(segment
		(start 15.526512 -131.990084)
		(end 15.565628 -132.0292)
		(width 0.127)
		(layer "In2.Cu")
		(net "FLA_CS")
	)
	(segment
		(start 15.565628 -132.0292)
		(end 15.9258 -132.0292)
		(width 0.127)
		(layer "In2.Cu")
		(net "FLA_CS")
	)
	(segment
		(start 31.068264 -132.49148)
		(end 31.461964 -132.88518)
		(width 0.127)
		(layer "In2.Cu")
		(net "FLA_CS")
	)
	(segment
		(start 31.304738 -126.084838)
		(end 31.304738 -126.084584)
		(width 0.12065)
		(layer "F.Cu")
		(net "FCB_HW_REVISION")
	)
	(segment
		(start 31.304738 -126.084584)
		(end 30.904942 -125.684788)
		(width 0.12065)
		(layer "F.Cu")
		(net "FCB_HW_REVISION")
	)
	(via
		(at 30.904942 -125.684788)
		(size 0.4572)
		(drill 0.2032)
		(layers "F.Cu" "B.Cu")
		(net "FCB_HW_REVISION")
	)
	(via
		(at 10.6934 -173.736)
		(size 0.508)
		(drill 0.254)
		(layers "F.Cu" "B.Cu")
		(net "FCB_HW_REVISION")
	)
	(via
		(at 54.061614 -205.145386)
		(size 0.7112)
		(drill 0.3556)
		(layers "F.Cu" "B.Cu")
		(net "FCB_HW_REVISION")
	)
	(segment
		(start 42.450766 -175.415702)
		(end 49.124362 -175.415702)
		(width 0.12065)
		(layer "B.Cu")
		(net "FCB_HW_REVISION")
	)
	(segment
		(start 41.171114 -174.13605)
		(end 42.450766 -175.415702)
		(width 0.12065)
		(layer "B.Cu")
		(net "FCB_HW_REVISION")
	)
	(segment
		(start 12.2174 -173.48835)
		(end 12.8651 -174.13605)
		(width 0.12065)
		(layer "B.Cu")
		(net "FCB_HW_REVISION")
	)
	(segment
		(start 41.17086 -174.13605)
		(end 41.171114 -174.13605)
		(width 0.12065)
		(layer "B.Cu")
		(net "FCB_HW_REVISION")
	)
	(segment
		(start 10.94105 -173.48835)
		(end 12.2174 -173.48835)
		(width 0.12065)
		(layer "B.Cu")
		(net "FCB_HW_REVISION")
	)
	(segment
		(start 41.300146 -225.92538)
		(end 41.300146 -211.937854)
		(width 0.12065)
		(layer "B.Cu")
		(net "FCB_HW_REVISION")
	)
	(segment
		(start 41.300146 -211.937854)
		(end 47.68215 -205.55585)
		(width 0.12065)
		(layer "B.Cu")
		(net "FCB_HW_REVISION")
	)
	(segment
		(start 25.135078 -174.13605)
		(end 26.589228 -172.6819)
		(width 0.12065)
		(layer "B.Cu")
		(net "FCB_HW_REVISION")
	)
	(segment
		(start 49.124362 -175.415702)
		(end 50.041556 -174.498508)
		(width 0.12065)
		(layer "B.Cu")
		(net "FCB_HW_REVISION")
	)
	(segment
		(start 27.397202 -123.5456)
		(end 29.367988 -125.516386)
		(width 0.12065)
		(layer "B.Cu")
		(net "FCB_HW_REVISION")
	)
	(segment
		(start 29.367988 -125.516386)
		(end 30.73654 -125.516386)
		(width 0.12065)
		(layer "B.Cu")
		(net "FCB_HW_REVISION")
	)
	(segment
		(start 53.65115 -205.55585)
		(end 54.061614 -205.145386)
		(width 0.12065)
		(layer "B.Cu")
		(net "FCB_HW_REVISION")
	)
	(segment
		(start 24.5745 -122.0216)
		(end 25.247854 -122.0216)
		(width 0.12065)
		(layer "B.Cu")
		(net "FCB_HW_REVISION")
	)
	(segment
		(start 25.247854 -122.0216)
		(end 26.771854 -123.5456)
		(width 0.12065)
		(layer "B.Cu")
		(net "FCB_HW_REVISION")
	)
	(segment
		(start 57.023 -176.276)
		(end 57.023 -202.184)
		(width 0.12065)
		(layer "B.Cu")
		(net "FCB_HW_REVISION")
	)
	(segment
		(start 10.6934 -173.736)
		(end 10.94105 -173.48835)
		(width 0.12065)
		(layer "B.Cu")
		(net "FCB_HW_REVISION")
	)
	(segment
		(start 39.71671 -172.6819)
		(end 41.17086 -174.13605)
		(width 0.12065)
		(layer "B.Cu")
		(net "FCB_HW_REVISION")
	)
	(segment
		(start 55.245508 -174.498508)
		(end 57.023 -176.276)
		(width 0.12065)
		(layer "B.Cu")
		(net "FCB_HW_REVISION")
	)
	(segment
		(start 30.73654 -125.516386)
		(end 30.904942 -125.684788)
		(width 0.12065)
		(layer "B.Cu")
		(net "FCB_HW_REVISION")
	)
	(segment
		(start 47.68215 -205.55585)
		(end 53.65115 -205.55585)
		(width 0.12065)
		(layer "B.Cu")
		(net "FCB_HW_REVISION")
	)
	(segment
		(start 57.023 -202.184)
		(end 54.061614 -205.145386)
		(width 0.12065)
		(layer "B.Cu")
		(net "FCB_HW_REVISION")
	)
	(segment
		(start 26.589228 -172.6819)
		(end 39.71671 -172.6819)
		(width 0.12065)
		(layer "B.Cu")
		(net "FCB_HW_REVISION")
	)
	(segment
		(start 50.041556 -174.498508)
		(end 55.245508 -174.498508)
		(width 0.12065)
		(layer "B.Cu")
		(net "FCB_HW_REVISION")
	)
	(segment
		(start 26.771854 -123.5456)
		(end 27.397202 -123.5456)
		(width 0.12065)
		(layer "B.Cu")
		(net "FCB_HW_REVISION")
	)
	(segment
		(start 12.8651 -174.13605)
		(end 25.135078 -174.13605)
		(width 0.12065)
		(layer "B.Cu")
		(net "FCB_HW_REVISION")
	)
	(segment
		(start 11.5443 -137.491724)
		(end 15.406624 -133.6294)
		(width 0.127)
		(layer "In5.Cu")
		(net "FCB_HW_REVISION")
	)
	(segment
		(start 24.576786 -130.9624)
		(end 29.854398 -125.684788)
		(width 0.127)
		(layer "In5.Cu")
		(net "FCB_HW_REVISION")
	)
	(segment
		(start 29.854398 -125.684788)
		(end 30.904942 -125.684788)
		(width 0.127)
		(layer "In5.Cu")
		(net "FCB_HW_REVISION")
	)
	(segment
		(start 15.406624 -133.6294)
		(end 16.5862 -133.6294)
		(width 0.127)
		(layer "In5.Cu")
		(net "FCB_HW_REVISION")
	)
	(segment
		(start 11.5443 -172.8851)
		(end 11.5443 -137.491724)
		(width 0.127)
		(layer "In5.Cu")
		(net "FCB_HW_REVISION")
	)
	(segment
		(start 24.297132 -131.2418)
		(end 24.576786 -130.9624)
		(width 0.127)
		(layer "In5.Cu")
		(net "FCB_HW_REVISION")
	)
	(segment
		(start 16.5862 -133.6294)
		(end 18.9738 -131.2418)
		(width 0.127)
		(layer "In5.Cu")
		(net "FCB_HW_REVISION")
	)
	(segment
		(start 10.6934 -173.736)
		(end 11.5443 -172.8851)
		(width 0.127)
		(layer "In5.Cu")
		(net "FCB_HW_REVISION")
	)
	(segment
		(start 18.9738 -131.2418)
		(end 24.297132 -131.2418)
		(width 0.127)
		(layer "In5.Cu")
		(net "FCB_HW_REVISION")
	)
	(segment
		(start 44.104814 -136.484868)
		(end 44.504864 -136.084818)
		(width 0.12065)
		(layer "F.Cu")
		(net "FAN_PWM_PCIE_BMC")
	)
	(via
		(at 44.504864 -136.084818)
		(size 0.4572)
		(drill 0.2032)
		(layers "F.Cu" "B.Cu")
		(net "FAN_PWM_PCIE_BMC")
	)
	(via
		(at 47.08017 -136.619996)
		(size 0.7112)
		(drill 0.3556)
		(layers "F.Cu" "B.Cu")
		(net "FAN_PWM_PCIE_BMC")
	)
	(segment
		(start 46.863 -138.4935)
		(end 47.08017 -138.27633)
		(width 0.12065)
		(layer "B.Cu")
		(net "FAN_PWM_PCIE_BMC")
	)
	(segment
		(start 46.935898 -136.475724)
		(end 45.035724 -136.475724)
		(width 0.12065)
		(layer "B.Cu")
		(net "FAN_PWM_PCIE_BMC")
	)
	(segment
		(start 47.08017 -138.27633)
		(end 47.08017 -136.619996)
		(width 0.12065)
		(layer "B.Cu")
		(net "FAN_PWM_PCIE_BMC")
	)
	(segment
		(start 44.644818 -136.084818)
		(end 44.504864 -136.084818)
		(width 0.12065)
		(layer "B.Cu")
		(net "FAN_PWM_PCIE_BMC")
	)
	(segment
		(start 45.035724 -136.475724)
		(end 44.644818 -136.084818)
		(width 0.12065)
		(layer "B.Cu")
		(net "FAN_PWM_PCIE_BMC")
	)
	(segment
		(start 47.08017 -136.619996)
		(end 46.935898 -136.475724)
		(width 0.12065)
		(layer "B.Cu")
		(net "FAN_PWM_PCIE_BMC")
	)
	(segment
		(start 220.79712 -1.13538)
		(end 221.7039 -1.13538)
		(width 0.12065)
		(layer "F.Cu")
		(net "EXP_UART_TX_R")
	)
	(segment
		(start 219.9005 -2.032)
		(end 220.79712 -1.13538)
		(width 0.12065)
		(layer "F.Cu")
		(net "EXP_UART_TX_R")
	)
	(segment
		(start 220.93682 -0.13462)
		(end 221.7039 -0.13462)
		(width 0.12065)
		(layer "F.Cu")
		(net "EXP_UART_RX_R")
	)
	(segment
		(start 219.837 0.209296)
		(end 220.592904 0.209296)
		(width 0.12065)
		(layer "F.Cu")
		(net "EXP_UART_RX_R")
	)
	(segment
		(start 219.4433 -0.9906)
		(end 219.4433 0.088646)
		(width 0.12065)
		(layer "F.Cu")
		(net "EXP_UART_RX_R")
	)
	(segment
		(start 219.56395 0.209296)
		(end 219.837 0.209296)
		(width 0.12065)
		(layer "F.Cu")
		(net "EXP_UART_RX_R")
	)
	(segment
		(start 219.4433 0.088646)
		(end 219.56395 0.209296)
		(width 0.12065)
		(layer "F.Cu")
		(net "EXP_UART_RX_R")
	)
	(segment
		(start 220.592904 0.209296)
		(end 220.93682 -0.13462)
		(width 0.12065)
		(layer "F.Cu")
		(net "EXP_UART_RX_R")
	)
	(via
		(at 219.837 0.209296)
		(size 0.7112)
		(drill 0.3556)
		(layers "F.Cu" "B.Cu")
		(net "EXP_UART_RX_R")
	)
	(segment
		(start 32.904938 -134.884922)
		(end 32.505142 -134.485126)
		(width 0.12065)
		(layer "F.Cu")
		(net "EXP_TRAY_ID_BMC")
	)
	(via
		(at 32.505142 -134.485126)
		(size 0.4572)
		(drill 0.2032)
		(layers "F.Cu" "B.Cu")
		(net "EXP_TRAY_ID_BMC")
	)
	(via
		(at 22.49551 -135.23214)
		(size 0.7112)
		(drill 0.3556)
		(layers "F.Cu" "B.Cu")
		(net "EXP_TRAY_ID_BMC")
	)
	(segment
		(start 32.113982 -134.093966)
		(end 32.505142 -134.485126)
		(width 0.12065)
		(layer "B.Cu")
		(net "EXP_TRAY_ID_BMC")
	)
	(segment
		(start 22.01037 -134.747)
		(end 21.3995 -134.747)
		(width 0.12065)
		(layer "B.Cu")
		(net "EXP_TRAY_ID_BMC")
	)
	(segment
		(start 22.49551 -135.23214)
		(end 22.553168 -135.289798)
		(width 0.12065)
		(layer "B.Cu")
		(net "EXP_TRAY_ID_BMC")
	)
	(segment
		(start 22.49551 -135.23214)
		(end 22.01037 -134.747)
		(width 0.12065)
		(layer "B.Cu")
		(net "EXP_TRAY_ID_BMC")
	)
	(segment
		(start 22.553168 -135.289798)
		(end 27.883104 -135.289798)
		(width 0.12065)
		(layer "B.Cu")
		(net "EXP_TRAY_ID_BMC")
	)
	(segment
		(start 29.078936 -134.093966)
		(end 32.113982 -134.093966)
		(width 0.12065)
		(layer "B.Cu")
		(net "EXP_TRAY_ID_BMC")
	)
	(segment
		(start 27.883104 -135.289798)
		(end 29.078936 -134.093966)
		(width 0.12065)
		(layer "B.Cu")
		(net "EXP_TRAY_ID_BMC")
	)
	(segment
		(start 262.90016 -225.54438)
		(end 262.90016 -224.607882)
		(width 0.12065)
		(layer "F.Cu")
		(net "EXP_TRAY_ID")
	)
	(segment
		(start 262.033004 -223.740726)
		(end 262.033004 -209.590132)
		(width 0.12065)
		(layer "F.Cu")
		(net "EXP_TRAY_ID")
	)
	(segment
		(start 262.90016 -224.607882)
		(end 262.033004 -223.740726)
		(width 0.12065)
		(layer "F.Cu")
		(net "EXP_TRAY_ID")
	)
	(segment
		(start 262.033004 -209.590132)
		(end 262.1026 -209.520536)
		(width 0.12065)
		(layer "F.Cu")
		(net "EXP_TRAY_ID")
	)
	(segment
		(start 254.508 -154.178)
		(end 243.967 -154.178)
		(width 0.12065)
		(layer "F.Cu")
		(net "EXP_TRAY_ID")
	)
	(segment
		(start 262.1026 -161.7726)
		(end 254.508 -154.178)
		(width 0.12065)
		(layer "F.Cu")
		(net "EXP_TRAY_ID")
	)
	(segment
		(start 262.1026 -209.520536)
		(end 262.1026 -161.7726)
		(width 0.12065)
		(layer "F.Cu")
		(net "EXP_TRAY_ID")
	)
	(via
		(at 13.7668 -169.3672)
		(size 0.508)
		(drill 0.254)
		(layers "F.Cu" "B.Cu")
		(net "EXP_TRAY_ID")
	)
	(via
		(at 223.745806 -155.857194)
		(size 0.7112)
		(drill 0.3556)
		(layers "F.Cu" "B.Cu")
		(net "EXP_TRAY_ID")
	)
	(via
		(at 15.3162 -135.6106)
		(size 0.508)
		(drill 0.254)
		(layers "F.Cu" "B.Cu")
		(net "EXP_TRAY_ID")
	)
	(via
		(at 243.967 -154.178)
		(size 0.508)
		(drill 0.254)
		(layers "F.Cu" "B.Cu")
		(net "EXP_TRAY_ID")
	)
	(segment
		(start 210.8962 -168.7068)
		(end 223.745806 -155.857194)
		(width 0.12065)
		(layer "B.Cu")
		(net "EXP_TRAY_ID")
	)
	(segment
		(start 53.285136 -168.7068)
		(end 73.55967 -168.706546)
		(width 0.12065)
		(layer "B.Cu")
		(net "EXP_TRAY_ID")
	)
	(segment
		(start 35.782758 -168.195498)
		(end 52.764436 -168.195498)
		(width 0.12065)
		(layer "B.Cu")
		(net "EXP_TRAY_ID")
	)
	(segment
		(start 225.891852 -153.711148)
		(end 223.745806 -155.857194)
		(width 0.12065)
		(layer "B.Cu")
		(net "EXP_TRAY_ID")
	)
	(segment
		(start 76.561188 -168.706292)
		(end 76.561696 -168.7068)
		(width 0.12065)
		(layer "B.Cu")
		(net "EXP_TRAY_ID")
	)
	(segment
		(start 243.844064 -154.178)
		(end 243.377212 -153.711148)
		(width 0.12065)
		(layer "B.Cu")
		(net "EXP_TRAY_ID")
	)
	(segment
		(start 52.764436 -168.195498)
		(end 53.275738 -168.7068)
		(width 0.12065)
		(layer "B.Cu")
		(net "EXP_TRAY_ID")
	)
	(segment
		(start 20.5105 -134.747)
		(end 20.171918 -134.408418)
		(width 0.12065)
		(layer "B.Cu")
		(net "EXP_TRAY_ID")
	)
	(segment
		(start 16.0274 -169.3672)
		(end 34.611056 -169.3672)
		(width 0.12065)
		(layer "B.Cu")
		(net "EXP_TRAY_ID")
	)
	(segment
		(start 243.377212 -153.711148)
		(end 225.891852 -153.711148)
		(width 0.12065)
		(layer "B.Cu")
		(net "EXP_TRAY_ID")
	)
	(segment
		(start 16.9799 -133.8326)
		(end 15.5829 -135.2296)
		(width 0.12065)
		(layer "B.Cu")
		(net "EXP_TRAY_ID")
	)
	(segment
		(start 13.7668 -169.3672)
		(end 14.52626 -169.3672)
		(width 0.12065)
		(layer "B.Cu")
		(net "EXP_TRAY_ID")
	)
	(segment
		(start 73.55967 -168.706546)
		(end 73.85939 -168.706546)
		(width 0.12065)
		(layer "B.Cu")
		(net "EXP_TRAY_ID")
	)
	(segment
		(start 15.5829 -135.2296)
		(end 15.5829 -135.3439)
		(width 0.12065)
		(layer "B.Cu")
		(net "EXP_TRAY_ID")
	)
	(segment
		(start 73.85939 -168.706546)
		(end 73.859644 -168.706292)
		(width 0.12065)
		(layer "B.Cu")
		(net "EXP_TRAY_ID")
	)
	(segment
		(start 76.561696 -168.7068)
		(end 210.8962 -168.7068)
		(width 0.12065)
		(layer "B.Cu")
		(net "EXP_TRAY_ID")
	)
	(segment
		(start 16.027146 -169.366946)
		(end 16.0274 -169.3672)
		(width 0.12065)
		(layer "B.Cu")
		(net "EXP_TRAY_ID")
	)
	(segment
		(start 20.171918 -134.408418)
		(end 17.555718 -134.408418)
		(width 0.12065)
		(layer "B.Cu")
		(net "EXP_TRAY_ID")
	)
	(segment
		(start 14.52626 -169.3672)
		(end 14.526514 -169.366946)
		(width 0.12065)
		(layer "B.Cu")
		(net "EXP_TRAY_ID")
	)
	(segment
		(start 14.526514 -169.366946)
		(end 16.027146 -169.366946)
		(width 0.12065)
		(layer "B.Cu")
		(net "EXP_TRAY_ID")
	)
	(segment
		(start 53.275738 -168.7068)
		(end 53.285136 -168.7068)
		(width 0.12065)
		(layer "B.Cu")
		(net "EXP_TRAY_ID")
	)
	(segment
		(start 17.555718 -134.408418)
		(end 16.9799 -133.8326)
		(width 0.12065)
		(layer "B.Cu")
		(net "EXP_TRAY_ID")
	)
	(segment
		(start 34.611056 -169.3672)
		(end 35.782758 -168.195498)
		(width 0.12065)
		(layer "B.Cu")
		(net "EXP_TRAY_ID")
	)
	(segment
		(start 73.859644 -168.706292)
		(end 76.561188 -168.706292)
		(width 0.12065)
		(layer "B.Cu")
		(net "EXP_TRAY_ID")
	)
	(segment
		(start 243.967 -154.178)
		(end 243.844064 -154.178)
		(width 0.12065)
		(layer "B.Cu")
		(net "EXP_TRAY_ID")
	)
	(segment
		(start 15.5829 -135.3439)
		(end 15.3162 -135.6106)
		(width 0.12065)
		(layer "B.Cu")
		(net "EXP_TRAY_ID")
	)
	(segment
		(start 13.9319 -164.024818)
		(end 13.7414 -164.215318)
		(width 0.127)
		(layer "In5.Cu")
		(net "EXP_TRAY_ID")
	)
	(segment
		(start 13.7414 -164.215318)
		(end 13.7414 -169.3418)
		(width 0.127)
		(layer "In5.Cu")
		(net "EXP_TRAY_ID")
	)
	(segment
		(start 13.9319 -163.635182)
		(end 13.9319 -164.024818)
		(width 0.127)
		(layer "In5.Cu")
		(net "EXP_TRAY_ID")
	)
	(segment
		(start 13.7414 -163.444682)
		(end 13.9319 -163.635182)
		(width 0.127)
		(layer "In5.Cu")
		(net "EXP_TRAY_ID")
	)
	(segment
		(start 15.3162 -135.6106)
		(end 13.7414 -137.1854)
		(width 0.127)
		(layer "In5.Cu")
		(net "EXP_TRAY_ID")
	)
	(segment
		(start 13.7414 -137.1854)
		(end 13.7414 -163.444682)
		(width 0.127)
		(layer "In5.Cu")
		(net "EXP_TRAY_ID")
	)
	(segment
		(start 13.7414 -169.3418)
		(end 13.7668 -169.3672)
		(width 0.127)
		(layer "In5.Cu")
		(net "EXP_TRAY_ID")
	)
	(segment
		(start 89.30767 -85.06968)
		(end 89.30767 -84.432648)
		(width 0.12065)
		(layer "F.Cu")
		(net "EXP_SMART_TX_R")
	)
	(segment
		(start 89.30767 -84.432648)
		(end 88.665812 -83.79079)
		(width 0.12065)
		(layer "F.Cu")
		(net "EXP_SMART_TX_R")
	)
	(segment
		(start 88.2523 -85.2424)
		(end 89.13495 -85.2424)
		(width 0.12065)
		(layer "F.Cu")
		(net "EXP_SMART_TX_R")
	)
	(segment
		(start 89.13495 -85.2424)
		(end 89.30767 -85.06968)
		(width 0.12065)
		(layer "F.Cu")
		(net "EXP_SMART_TX_R")
	)
	(segment
		(start 88.665812 -83.79079)
		(end 87.716614 -83.79079)
		(width 0.12065)
		(layer "F.Cu")
		(net "EXP_SMART_TX_R")
	)
	(via
		(at 89.30767 -85.06968)
		(size 0.7112)
		(drill 0.3556)
		(layers "F.Cu" "B.Cu")
		(net "EXP_SMART_TX_R")
	)
	(segment
		(start 92.15755 -80.311498)
		(end 92.15755 -85.344)
		(width 0.12065)
		(layer "F.Cu")
		(net "EXP_SMART_TX")
	)
	(segment
		(start 130.977386 -51.326288)
		(end 130.420872 -50.769774)
		(width 0.12065)
		(layer "F.Cu")
		(net "EXP_SMART_TX")
	)
	(segment
		(start 218.784678 -2.032)
		(end 217.793062 -1.040384)
		(width 0.12065)
		(layer "F.Cu")
		(net "EXP_SMART_TX")
	)
	(segment
		(start 87.70112 -86.2203)
		(end 87.3633 -85.88248)
		(width 0.12065)
		(layer "F.Cu")
		(net "EXP_SMART_TX")
	)
	(segment
		(start 128.326388 -50.868326)
		(end 128.326388 -52.417218)
		(width 0.12065)
		(layer "F.Cu")
		(net "EXP_SMART_TX")
	)
	(segment
		(start 127.662686 -53.08092)
		(end 126.167642 -53.08092)
		(width 0.12065)
		(layer "F.Cu")
		(net "EXP_SMART_TX")
	)
	(segment
		(start 123.731782 -55.51678)
		(end 116.952268 -55.51678)
		(width 0.12065)
		(layer "F.Cu")
		(net "EXP_SMART_TX")
	)
	(segment
		(start 130.420872 -50.769774)
		(end 128.42494 -50.769774)
		(width 0.12065)
		(layer "F.Cu")
		(net "EXP_SMART_TX")
	)
	(segment
		(start 91.28125 -86.2203)
		(end 87.70112 -86.2203)
		(width 0.12065)
		(layer "F.Cu")
		(net "EXP_SMART_TX")
	)
	(segment
		(start 128.326388 -52.417218)
		(end 127.662686 -53.08092)
		(width 0.12065)
		(layer "F.Cu")
		(net "EXP_SMART_TX")
	)
	(segment
		(start 219.0115 -2.032)
		(end 218.784678 -2.032)
		(width 0.12065)
		(layer "F.Cu")
		(net "EXP_SMART_TX")
	)
	(segment
		(start 92.15755 -85.344)
		(end 91.28125 -86.2203)
		(width 0.12065)
		(layer "F.Cu")
		(net "EXP_SMART_TX")
	)
	(segment
		(start 217.793062 -1.040384)
		(end 217.793062 -0.076962)
		(width 0.12065)
		(layer "F.Cu")
		(net "EXP_SMART_TX")
	)
	(segment
		(start 126.167642 -53.08092)
		(end 123.731782 -55.51678)
		(width 0.12065)
		(layer "F.Cu")
		(net "EXP_SMART_TX")
	)
	(segment
		(start 128.42494 -50.769774)
		(end 128.326388 -50.868326)
		(width 0.12065)
		(layer "F.Cu")
		(net "EXP_SMART_TX")
	)
	(segment
		(start 116.952268 -55.51678)
		(end 92.15755 -80.311498)
		(width 0.12065)
		(layer "F.Cu")
		(net "EXP_SMART_TX")
	)
	(segment
		(start 87.3633 -85.88248)
		(end 87.3633 -85.2424)
		(width 0.12065)
		(layer "F.Cu")
		(net "EXP_SMART_TX")
	)
	(via
		(at 92.15755 -85.344)
		(size 0.508)
		(drill 0.254)
		(layers "F.Cu" "B.Cu")
		(net "EXP_SMART_TX")
	)
	(via
		(at 217.793062 -0.076962)
		(size 0.508)
		(drill 0.254)
		(layers "F.Cu" "B.Cu")
		(net "EXP_SMART_TX")
	)
	(via
		(at 216.789 0.5334)
		(size 0.7112)
		(drill 0.3556)
		(layers "F.Cu" "B.Cu")
		(net "EXP_SMART_TX")
	)
	(segment
		(start 217.793062 -0.076962)
		(end 217.399362 -0.076962)
		(width 0.12065)
		(layer "B.Cu")
		(net "EXP_SMART_TX")
	)
	(segment
		(start 217.399362 -0.076962)
		(end 216.789 0.5334)
		(width 0.12065)
		(layer "B.Cu")
		(net "EXP_SMART_TX")
	)
	(segment
		(start 188.622432 -3.339592)
		(end 188.62294 -3.339846)
		(width 0.127)
		(layer "In2.Cu")
		(net "EXP_SMART_TX")
	)
	(segment
		(start 117.011196 -17.841722)
		(end 118.9609 -15.892018)
		(width 0.127)
		(layer "In2.Cu")
		(net "EXP_SMART_TX")
	)
	(segment
		(start 133.01853 -3.661156)
		(end 181.343046 -3.661156)
		(width 0.127)
		(layer "In2.Cu")
		(net "EXP_SMART_TX")
	)
	(segment
		(start 196.9516 -5.588)
		(end 204.322934 -5.588)
		(width 0.127)
		(layer "In2.Cu")
		(net "EXP_SMART_TX")
	)
	(segment
		(start 188.62294 -3.339846)
		(end 189.033912 -3.339846)
		(width 0.127)
		(layer "In2.Cu")
		(net "EXP_SMART_TX")
	)
	(segment
		(start 100.050346 -74.544428)
		(end 100.0506 -71.626222)
		(width 0.127)
		(layer "In2.Cu")
		(net "EXP_SMART_TX")
	)
	(segment
		(start 205.919578 -2.716022)
		(end 208.4324 -0.2032)
		(width 0.127)
		(layer "In2.Cu")
		(net "EXP_SMART_TX")
	)
	(segment
		(start 189.033912 -3.339846)
		(end 190.710566 -5.0165)
		(width 0.127)
		(layer "In2.Cu")
		(net "EXP_SMART_TX")
	)
	(segment
		(start 118.9609 -15.892018)
		(end 118.9609 -15.629382)
		(width 0.127)
		(layer "In2.Cu")
		(net "EXP_SMART_TX")
	)
	(segment
		(start 93.35135 -84.1502)
		(end 93.998034 -84.1502)
		(width 0.127)
		(layer "In2.Cu")
		(net "EXP_SMART_TX")
	)
	(segment
		(start 97.40519 -35.062922)
		(end 114.62639 -17.841722)
		(width 0.127)
		(layer "In2.Cu")
		(net "EXP_SMART_TX")
	)
	(segment
		(start 185.15203 -3.339846)
		(end 185.152284 -3.339592)
		(width 0.127)
		(layer "In2.Cu")
		(net "EXP_SMART_TX")
	)
	(segment
		(start 92.15755 -85.344)
		(end 93.35135 -84.1502)
		(width 0.127)
		(layer "In2.Cu")
		(net "EXP_SMART_TX")
	)
	(segment
		(start 217.666824 -0.2032)
		(end 217.793062 -0.076962)
		(width 0.127)
		(layer "In2.Cu")
		(net "EXP_SMART_TX")
	)
	(segment
		(start 196.3801 -5.0165)
		(end 196.9516 -5.588)
		(width 0.127)
		(layer "In2.Cu")
		(net "EXP_SMART_TX")
	)
	(segment
		(start 181.343046 -3.661156)
		(end 181.664356 -3.339846)
		(width 0.127)
		(layer "In2.Cu")
		(net "EXP_SMART_TX")
	)
	(segment
		(start 185.152284 -3.339592)
		(end 188.622432 -3.339592)
		(width 0.127)
		(layer "In2.Cu")
		(net "EXP_SMART_TX")
	)
	(segment
		(start 100.0506 -50.37455)
		(end 97.40519 -47.72914)
		(width 0.127)
		(layer "In2.Cu")
		(net "EXP_SMART_TX")
	)
	(segment
		(start 114.62639 -17.841722)
		(end 117.011196 -17.841722)
		(width 0.127)
		(layer "In2.Cu")
		(net "EXP_SMART_TX")
	)
	(segment
		(start 118.9609 -15.629382)
		(end 121.162064 -13.428218)
		(width 0.127)
		(layer "In2.Cu")
		(net "EXP_SMART_TX")
	)
	(segment
		(start 123.246896 -13.428218)
		(end 133.01853 -3.661156)
		(width 0.127)
		(layer "In2.Cu")
		(net "EXP_SMART_TX")
	)
	(segment
		(start 100.050346 -75.536552)
		(end 100.050346 -74.544428)
		(width 0.127)
		(layer "In2.Cu")
		(net "EXP_SMART_TX")
	)
	(segment
		(start 100.0506 -71.626222)
		(end 100.0506 -50.37455)
		(width 0.127)
		(layer "In2.Cu")
		(net "EXP_SMART_TX")
	)
	(segment
		(start 121.162064 -13.428218)
		(end 123.246896 -13.428218)
		(width 0.127)
		(layer "In2.Cu")
		(net "EXP_SMART_TX")
	)
	(segment
		(start 205.919578 -3.991356)
		(end 205.919578 -2.716022)
		(width 0.127)
		(layer "In2.Cu")
		(net "EXP_SMART_TX")
	)
	(segment
		(start 204.322934 -5.588)
		(end 205.919578 -3.991356)
		(width 0.127)
		(layer "In2.Cu")
		(net "EXP_SMART_TX")
	)
	(segment
		(start 208.4324 -0.2032)
		(end 217.666824 -0.2032)
		(width 0.127)
		(layer "In2.Cu")
		(net "EXP_SMART_TX")
	)
	(segment
		(start 190.710566 -5.0165)
		(end 196.3801 -5.0165)
		(width 0.127)
		(layer "In2.Cu")
		(net "EXP_SMART_TX")
	)
	(segment
		(start 97.4344 -80.713834)
		(end 97.4344 -78.153514)
		(width 0.127)
		(layer "In2.Cu")
		(net "EXP_SMART_TX")
	)
	(segment
		(start 181.664356 -3.339846)
		(end 185.15203 -3.339846)
		(width 0.127)
		(layer "In2.Cu")
		(net "EXP_SMART_TX")
	)
	(segment
		(start 97.4344 -78.153514)
		(end 100.050346 -75.536552)
		(width 0.127)
		(layer "In2.Cu")
		(net "EXP_SMART_TX")
	)
	(segment
		(start 93.998034 -84.1502)
		(end 97.4344 -80.713834)
		(width 0.127)
		(layer "In2.Cu")
		(net "EXP_SMART_TX")
	)
	(segment
		(start 97.40519 -47.72914)
		(end 97.40519 -35.062922)
		(width 0.127)
		(layer "In2.Cu")
		(net "EXP_SMART_TX")
	)
	(segment
		(start 83.9724 -85.217)
		(end 83.793076 -85.037676)
		(width 0.12065)
		(layer "F.Cu")
		(net "EXP_SMART_RX_R")
	)
	(segment
		(start 85.0519 -85.217)
		(end 83.9724 -85.217)
		(width 0.12065)
		(layer "F.Cu")
		(net "EXP_SMART_RX_R")
	)
	(segment
		(start 83.793076 -85.037676)
		(end 83.793076 -84.658454)
		(width 0.12065)
		(layer "F.Cu")
		(net "EXP_SMART_RX_R")
	)
	(segment
		(start 84.66074 -83.79079)
		(end 85.379814 -83.79079)
		(width 0.12065)
		(layer "F.Cu")
		(net "EXP_SMART_RX_R")
	)
	(segment
		(start 83.793076 -84.658454)
		(end 84.66074 -83.79079)
		(width 0.12065)
		(layer "F.Cu")
		(net "EXP_SMART_RX_R")
	)
	(via
		(at 83.793076 -85.037676)
		(size 0.7112)
		(drill 0.3556)
		(layers "F.Cu" "B.Cu")
		(net "EXP_SMART_RX_R")
	)
	(segment
		(start 85.9409 -86.3727)
		(end 85.9409 -85.217)
		(width 0.12065)
		(layer "F.Cu")
		(net "EXP_SMART_RX")
	)
	(segment
		(start 92.6592 -86.2076)
		(end 92.075 -86.7918)
		(width 0.12065)
		(layer "F.Cu")
		(net "EXP_SMART_RX")
	)
	(segment
		(start 92.6592 -80.519524)
		(end 92.6592 -86.2076)
		(width 0.12065)
		(layer "F.Cu")
		(net "EXP_SMART_RX")
	)
	(segment
		(start 128.363726 -53.58257)
		(end 126.553976 -53.58257)
		(width 0.12065)
		(layer "F.Cu")
		(net "EXP_SMART_RX")
	)
	(segment
		(start 129.021586 -51.351688)
		(end 129.021586 -52.92471)
		(width 0.12065)
		(layer "F.Cu")
		(net "EXP_SMART_RX")
	)
	(segment
		(start 218.694 -0.8509)
		(end 218.694 -0.0889)
		(width 0.12065)
		(layer "F.Cu")
		(net "EXP_SMART_RX")
	)
	(segment
		(start 129.021586 -52.92471)
		(end 128.363726 -53.58257)
		(width 0.12065)
		(layer "F.Cu")
		(net "EXP_SMART_RX")
	)
	(segment
		(start 86.36 -86.7918)
		(end 85.9409 -86.3727)
		(width 0.12065)
		(layer "F.Cu")
		(net "EXP_SMART_RX")
	)
	(segment
		(start 218.5543 -0.9906)
		(end 218.694 -0.8509)
		(width 0.12065)
		(layer "F.Cu")
		(net "EXP_SMART_RX")
	)
	(segment
		(start 124.118116 -56.01843)
		(end 117.160294 -56.01843)
		(width 0.12065)
		(layer "F.Cu")
		(net "EXP_SMART_RX")
	)
	(segment
		(start 92.075 -86.7918)
		(end 86.36 -86.7918)
		(width 0.12065)
		(layer "F.Cu")
		(net "EXP_SMART_RX")
	)
	(segment
		(start 117.160294 -56.01843)
		(end 92.6592 -80.519524)
		(width 0.12065)
		(layer "F.Cu")
		(net "EXP_SMART_RX")
	)
	(segment
		(start 126.553976 -53.58257)
		(end 124.118116 -56.01843)
		(width 0.12065)
		(layer "F.Cu")
		(net "EXP_SMART_RX")
	)
	(via
		(at 92.075 -86.7918)
		(size 0.508)
		(drill 0.254)
		(layers "F.Cu" "B.Cu")
		(net "EXP_SMART_RX")
	)
	(via
		(at 218.694 -0.0889)
		(size 0.508)
		(drill 0.254)
		(layers "F.Cu" "B.Cu")
		(net "EXP_SMART_RX")
	)
	(via
		(at 219.8624 0.4318)
		(size 0.7112)
		(drill 0.3556)
		(layers "F.Cu" "B.Cu")
		(net "EXP_SMART_RX")
	)
	(segment
		(start 218.694 -0.0889)
		(end 219.3417 -0.0889)
		(width 0.12065)
		(layer "B.Cu")
		(net "EXP_SMART_RX")
	)
	(segment
		(start 219.3417 -0.0889)
		(end 219.8624 0.4318)
		(width 0.12065)
		(layer "B.Cu")
		(net "EXP_SMART_RX")
	)
	(segment
		(start 100.558346 -74.544682)
		(end 100.5586 -71.626476)
		(width 0.127)
		(layer "In2.Cu")
		(net "EXP_SMART_RX")
	)
	(segment
		(start 114.836956 -18.349722)
		(end 117.569996 -18.349722)
		(width 0.127)
		(layer "In2.Cu")
		(net "EXP_SMART_RX")
	)
	(segment
		(start 119.9007 -16.019018)
		(end 119.9007 -15.756382)
		(width 0.127)
		(layer "In2.Cu")
		(net "EXP_SMART_RX")
	)
	(segment
		(start 181.874922 -3.847846)
		(end 185.362596 -3.847846)
		(width 0.127)
		(layer "In2.Cu")
		(net "EXP_SMART_RX")
	)
	(segment
		(start 100.5586 -50.163984)
		(end 97.91319 -47.518574)
		(width 0.127)
		(layer "In2.Cu")
		(net "EXP_SMART_RX")
	)
	(segment
		(start 196.741034 -6.096)
		(end 204.575918 -6.096)
		(width 0.127)
		(layer "In2.Cu")
		(net "EXP_SMART_RX")
	)
	(segment
		(start 218.0717 -0.7112)
		(end 218.694 -0.0889)
		(width 0.127)
		(layer "In2.Cu")
		(net "EXP_SMART_RX")
	)
	(segment
		(start 185.362596 -3.847846)
		(end 185.36285 -3.847592)
		(width 0.127)
		(layer "In2.Cu")
		(net "EXP_SMART_RX")
	)
	(segment
		(start 204.575918 -6.096)
		(end 209.960718 -0.7112)
		(width 0.127)
		(layer "In2.Cu")
		(net "EXP_SMART_RX")
	)
	(segment
		(start 117.569996 -18.349722)
		(end 119.9007 -16.019018)
		(width 0.127)
		(layer "In2.Cu")
		(net "EXP_SMART_RX")
	)
	(segment
		(start 133.228588 -4.169664)
		(end 133.229096 -4.169156)
		(width 0.127)
		(layer "In2.Cu")
		(net "EXP_SMART_RX")
	)
	(segment
		(start 119.9007 -15.756382)
		(end 121.720864 -13.936218)
		(width 0.127)
		(layer "In2.Cu")
		(net "EXP_SMART_RX")
	)
	(segment
		(start 97.91319 -47.518574)
		(end 97.91319 -35.273488)
		(width 0.127)
		(layer "In2.Cu")
		(net "EXP_SMART_RX")
	)
	(segment
		(start 100.5586 -71.626476)
		(end 100.5586 -50.163984)
		(width 0.127)
		(layer "In2.Cu")
		(net "EXP_SMART_RX")
	)
	(segment
		(start 100.558346 -75.747118)
		(end 100.558346 -74.544682)
		(width 0.127)
		(layer "In2.Cu")
		(net "EXP_SMART_RX")
	)
	(segment
		(start 185.36285 -3.847592)
		(end 188.411866 -3.847592)
		(width 0.127)
		(layer "In2.Cu")
		(net "EXP_SMART_RX")
	)
	(segment
		(start 196.30898 -5.6642)
		(end 196.741034 -6.096)
		(width 0.127)
		(layer "In2.Cu")
		(net "EXP_SMART_RX")
	)
	(segment
		(start 97.91319 -35.273488)
		(end 114.836956 -18.349722)
		(width 0.127)
		(layer "In2.Cu")
		(net "EXP_SMART_RX")
	)
	(segment
		(start 123.457462 -13.936218)
		(end 133.228588 -4.169664)
		(width 0.127)
		(layer "In2.Cu")
		(net "EXP_SMART_RX")
	)
	(segment
		(start 135.545576 -4.16941)
		(end 181.553358 -4.16941)
		(width 0.127)
		(layer "In2.Cu")
		(net "EXP_SMART_RX")
	)
	(segment
		(start 121.720864 -13.936218)
		(end 123.457462 -13.936218)
		(width 0.127)
		(layer "In2.Cu")
		(net "EXP_SMART_RX")
	)
	(segment
		(start 188.411866 -3.847592)
		(end 189.583822 -5.019294)
		(width 0.127)
		(layer "In2.Cu")
		(net "EXP_SMART_RX")
	)
	(segment
		(start 209.960718 -0.7112)
		(end 218.0717 -0.7112)
		(width 0.127)
		(layer "In2.Cu")
		(net "EXP_SMART_RX")
	)
	(segment
		(start 189.583822 -5.019294)
		(end 190.228982 -5.6642)
		(width 0.127)
		(layer "In2.Cu")
		(net "EXP_SMART_RX")
	)
	(segment
		(start 190.228982 -5.6642)
		(end 196.30898 -5.6642)
		(width 0.127)
		(layer "In2.Cu")
		(net "EXP_SMART_RX")
	)
	(segment
		(start 133.229096 -4.169156)
		(end 135.545322 -4.169156)
		(width 0.127)
		(layer "In2.Cu")
		(net "EXP_SMART_RX")
	)
	(segment
		(start 97.9424 -78.36408)
		(end 100.558346 -75.747118)
		(width 0.127)
		(layer "In2.Cu")
		(net "EXP_SMART_RX")
	)
	(segment
		(start 181.553358 -4.16941)
		(end 181.874922 -3.847846)
		(width 0.127)
		(layer "In2.Cu")
		(net "EXP_SMART_RX")
	)
	(segment
		(start 92.075 -86.7918)
		(end 97.9424 -80.9244)
		(width 0.127)
		(layer "In2.Cu")
		(net "EXP_SMART_RX")
	)
	(segment
		(start 97.9424 -80.9244)
		(end 97.9424 -78.36408)
		(width 0.127)
		(layer "In2.Cu")
		(net "EXP_SMART_RX")
	)
	(segment
		(start 135.545322 -4.169156)
		(end 135.545576 -4.16941)
		(width 0.127)
		(layer "In2.Cu")
		(net "EXP_SMART_RX")
	)
	(segment
		(start 78.31074 -91.05646)
		(end 76.689966 -91.05646)
		(width 0.12065)
		(layer "F.Cu")
		(net "EXP_BMC_HB_LED_R")
	)
	(segment
		(start 83.5152 -80.2386)
		(end 82.2198 -81.534)
		(width 0.12065)
		(layer "F.Cu")
		(net "EXP_BMC_HB_LED_R")
	)
	(segment
		(start 82.2198 -87.1474)
		(end 79.87919 -89.48801)
		(width 0.12065)
		(layer "F.Cu")
		(net "EXP_BMC_HB_LED_R")
	)
	(segment
		(start 79.87919 -89.48801)
		(end 78.31074 -91.05646)
		(width 0.12065)
		(layer "F.Cu")
		(net "EXP_BMC_HB_LED_R")
	)
	(segment
		(start 182.311802 0.9271)
		(end 181.38267 0.9271)
		(width 0.12065)
		(layer "F.Cu")
		(net "EXP_BMC_HB_LED_R")
	)
	(segment
		(start 82.2198 -81.534)
		(end 82.2198 -87.1474)
		(width 0.12065)
		(layer "F.Cu")
		(net "EXP_BMC_HB_LED_R")
	)
	(segment
		(start 181.38267 0.9271)
		(end 181.219094 0.763524)
		(width 0.12065)
		(layer "F.Cu")
		(net "EXP_BMC_HB_LED_R")
	)
	(via
		(at 79.87919 -89.48801)
		(size 0.7112)
		(drill 0.3556)
		(layers "F.Cu" "B.Cu")
		(net "EXP_BMC_HB_LED_R")
	)
	(via
		(at 181.219094 0.763524)
		(size 0.508)
		(drill 0.254)
		(layers "F.Cu" "B.Cu")
		(net "EXP_BMC_HB_LED_R")
	)
	(via
		(at 83.5152 -80.2386)
		(size 0.508)
		(drill 0.254)
		(layers "F.Cu" "B.Cu")
		(net "EXP_BMC_HB_LED_R")
	)
	(segment
		(start 181.047136 0.935482)
		(end 132.581396 0.935482)
		(width 0.127)
		(layer "In2.Cu")
		(net "EXP_BMC_HB_LED_R")
	)
	(segment
		(start 181.219094 0.763524)
		(end 181.047136 0.935482)
		(width 0.127)
		(layer "In2.Cu")
		(net "EXP_BMC_HB_LED_R")
	)
	(segment
		(start 86.709758 -80.2386)
		(end 83.5152 -80.2386)
		(width 0.127)
		(layer "In2.Cu")
		(net "EXP_BMC_HB_LED_R")
	)
	(segment
		(start 120.493536 -7.530592)
		(end 94.35719 -33.666938)
		(width 0.127)
		(layer "In2.Cu")
		(net "EXP_BMC_HB_LED_R")
	)
	(segment
		(start 96.2914 -70.656958)
		(end 86.709758 -80.2386)
		(width 0.127)
		(layer "In2.Cu")
		(net "EXP_BMC_HB_LED_R")
	)
	(segment
		(start 94.35719 -33.666938)
		(end 94.35719 -50.117756)
		(width 0.127)
		(layer "In2.Cu")
		(net "EXP_BMC_HB_LED_R")
	)
	(segment
		(start 132.581396 0.935482)
		(end 124.110496 -7.530592)
		(width 0.127)
		(layer "In2.Cu")
		(net "EXP_BMC_HB_LED_R")
	)
	(segment
		(start 94.35719 -50.117756)
		(end 96.2914 -52.051966)
		(width 0.127)
		(layer "In2.Cu")
		(net "EXP_BMC_HB_LED_R")
	)
	(segment
		(start 124.110496 -7.530592)
		(end 120.493536 -7.530592)
		(width 0.127)
		(layer "In2.Cu")
		(net "EXP_BMC_HB_LED_R")
	)
	(segment
		(start 96.2914 -52.051966)
		(end 96.2914 -70.656958)
		(width 0.127)
		(layer "In2.Cu")
		(net "EXP_BMC_HB_LED_R")
	)
	(segment
		(start 188.184028 -0.001524)
		(end 188.168788 -0.016764)
		(width 0.12065)
		(layer "F.Cu")
		(net "EXP_BMC_HB_LED_D")
	)
	(segment
		(start 188.168788 -0.016764)
		(end 184.779666 -0.016764)
		(width 0.12065)
		(layer "F.Cu")
		(net "EXP_BMC_HB_LED_D")
	)
	(segment
		(start 184.779666 -0.016764)
		(end 183.835802 0.9271)
		(width 0.12065)
		(layer "F.Cu")
		(net "EXP_BMC_HB_LED_D")
	)
	(segment
		(start 198.9582 -1.0414)
		(end 197.68185 -2.31775)
		(width 0.12065)
		(layer "F.Cu")
		(net "ENCLO_LED_RED_R")
	)
	(segment
		(start 194.233292 -0.937006)
		(end 194.233292 0)
		(width 0.12065)
		(layer "F.Cu")
		(net "ENCLO_LED_RED_R")
	)
	(segment
		(start 195.614036 -2.31775)
		(end 194.233292 -0.937006)
		(width 0.12065)
		(layer "F.Cu")
		(net "ENCLO_LED_RED_R")
	)
	(segment
		(start 197.68185 -2.31775)
		(end 195.614036 -2.31775)
		(width 0.12065)
		(layer "F.Cu")
		(net "ENCLO_LED_RED_R")
	)
	(segment
		(start 198.9582 -0.2794)
		(end 198.9582 -1.0414)
		(width 0.12065)
		(layer "F.Cu")
		(net "ENCLO_LED_RED_R")
	)
	(segment
		(start 190.388748 -9.688576)
		(end 186.661298 -9.688576)
		(width 0.12065)
		(layer "F.Cu")
		(net "ENCLO_LED_RED_G")
	)
	(segment
		(start 193.9036 -10.02665)
		(end 193.9036 -8.9408)
		(width 0.12065)
		(layer "F.Cu")
		(net "ENCLO_LED_RED_G")
	)
	(segment
		(start 186.661298 -9.688576)
		(end 186.185302 -9.21258)
		(width 0.12065)
		(layer "F.Cu")
		(net "ENCLO_LED_RED_G")
	)
	(segment
		(start 186.185302 -8.098028)
		(end 186.185302 -7.934198)
		(width 0.12065)
		(layer "F.Cu")
		(net "ENCLO_LED_RED_G")
	)
	(segment
		(start 186.185302 -7.934198)
		(end 187.071 -7.0485)
		(width 0.12065)
		(layer "F.Cu")
		(net "ENCLO_LED_RED_G")
	)
	(segment
		(start 191.018922 -10.31875)
		(end 190.388748 -9.688576)
		(width 0.12065)
		(layer "F.Cu")
		(net "ENCLO_LED_RED_G")
	)
	(segment
		(start 193.6115 -10.31875)
		(end 191.018922 -10.31875)
		(width 0.12065)
		(layer "F.Cu")
		(net "ENCLO_LED_RED_G")
	)
	(segment
		(start 193.6115 -10.31875)
		(end 193.9036 -10.02665)
		(width 0.12065)
		(layer "F.Cu")
		(net "ENCLO_LED_RED_G")
	)
	(segment
		(start 186.185302 -9.21258)
		(end 186.185302 -8.098028)
		(width 0.12065)
		(layer "F.Cu")
		(net "ENCLO_LED_RED_G")
	)
	(via
		(at 193.9036 -8.9408)
		(size 0.7112)
		(drill 0.3556)
		(layers "F.Cu" "B.Cu")
		(net "ENCLO_LED_RED_G")
	)
	(segment
		(start 192.0367 -13.6652)
		(end 193.061336 -13.6652)
		(width 0.12065)
		(layer "F.Cu")
		(net "ENCLO_LED_RED_D")
	)
	(segment
		(start 192.0367 -11.6332)
		(end 191.7065 -11.303)
		(width 0.12065)
		(layer "F.Cu")
		(net "ENCLO_LED_RED_D")
	)
	(segment
		(start 190.78575 -11.303)
		(end 189.8015 -10.31875)
		(width 0.12065)
		(layer "F.Cu")
		(net "ENCLO_LED_RED_D")
	)
	(segment
		(start 192.0367 -13.6652)
		(end 192.0367 -11.6332)
		(width 0.12065)
		(layer "F.Cu")
		(net "ENCLO_LED_RED_D")
	)
	(segment
		(start 191.7065 -11.303)
		(end 190.78575 -11.303)
		(width 0.12065)
		(layer "F.Cu")
		(net "ENCLO_LED_RED_D")
	)
	(via
		(at 193.061336 -13.6652)
		(size 0.7112)
		(drill 0.3556)
		(layers "F.Cu" "B.Cu")
		(net "ENCLO_LED_RED_D")
	)
	(segment
		(start 187.024518 -9.120124)
		(end 187.024518 -8.147812)
		(width 0.12065)
		(layer "F.Cu")
		(net "ENCLO_LED_BLUE_OUT")
	)
	(segment
		(start 187.024518 -8.147812)
		(end 187.074302 -8.098028)
		(width 0.12065)
		(layer "F.Cu")
		(net "ENCLO_LED_BLUE_OUT")
	)
	(segment
		(start 187.110116 -9.205722)
		(end 187.024518 -9.120124)
		(width 0.12065)
		(layer "F.Cu")
		(net "ENCLO_LED_BLUE_OUT")
	)
	(segment
		(start 188.7855 -8.57504)
		(end 188.154818 -9.205722)
		(width 0.12065)
		(layer "F.Cu")
		(net "ENCLO_LED_BLUE_OUT")
	)
	(segment
		(start 188.154818 -9.205722)
		(end 187.110116 -9.205722)
		(width 0.12065)
		(layer "F.Cu")
		(net "ENCLO_LED_BLUE_OUT")
	)
	(via
		(at 187.024518 -9.120124)
		(size 0.7112)
		(drill 0.3556)
		(layers "F.Cu" "B.Cu")
		(net "ENCLO_LED_BLUE_OUT")
	)
	(segment
		(start 128.8542 -45.4533)
		(end 128.8542 -44.577)
		(width 0.12065)
		(layer "F.Cu")
		(net "EJTAG_TRSTB_R")
	)
	(segment
		(start 232.599992 -38.999922)
		(end 232.10012 -38.50005)
		(width 0.12065)
		(layer "F.Cu")
		(net "EJTAG_TRSTB_R")
	)
	(via
		(at 232.10012 -38.50005)
		(size 0.4572)
		(drill 0.2032)
		(layers "F.Cu" "B.Cu")
		(net "EJTAG_TRSTB_R")
	)
	(via
		(at 128.8542 -44.577)
		(size 0.508)
		(drill 0.254)
		(layers "F.Cu" "B.Cu")
		(net "EJTAG_TRSTB_R")
	)
	(segment
		(start 215.542114 -19.167856)
		(end 219.691204 -19.167856)
		(width 0.127)
		(layer "In5.Cu")
		(net "EJTAG_TRSTB_R")
	)
	(segment
		(start 181.016402 -15.310358)
		(end 191.219582 -15.310358)
		(width 0.127)
		(layer "In5.Cu")
		(net "EJTAG_TRSTB_R")
	)
	(segment
		(start 219.830904 -19.028156)
		(end 228.023928 -19.028156)
		(width 0.127)
		(layer "In5.Cu")
		(net "EJTAG_TRSTB_R")
	)
	(segment
		(start 203.15936 -18.4531)
		(end 214.827358 -18.4531)
		(width 0.127)
		(layer "In5.Cu")
		(net "EJTAG_TRSTB_R")
	)
	(segment
		(start 219.691204 -19.167856)
		(end 219.830904 -19.028156)
		(width 0.127)
		(layer "In5.Cu")
		(net "EJTAG_TRSTB_R")
	)
	(segment
		(start 233.1085 -25.207722)
		(end 233.1085 -25.964388)
		(width 0.127)
		(layer "In5.Cu")
		(net "EJTAG_TRSTB_R")
	)
	(segment
		(start 233.1085 -25.964388)
		(end 233.426 -26.281888)
		(width 0.127)
		(layer "In5.Cu")
		(net "EJTAG_TRSTB_R")
	)
	(segment
		(start 195.18884 -19.2405)
		(end 195.19138 -19.241008)
		(width 0.127)
		(layer "In5.Cu")
		(net "EJTAG_TRSTB_R")
	)
	(segment
		(start 127.2159 -16.392398)
		(end 127.2159 -13.204698)
		(width 0.127)
		(layer "In5.Cu")
		(net "EJTAG_TRSTB_R")
	)
	(segment
		(start 134.600188 -5.82041)
		(end 173.662594 -5.82041)
		(width 0.127)
		(layer "In5.Cu")
		(net "EJTAG_TRSTB_R")
	)
	(segment
		(start 233.426 -26.281888)
		(end 233.426 -29.295852)
		(width 0.127)
		(layer "In5.Cu")
		(net "EJTAG_TRSTB_R")
	)
	(segment
		(start 123.600464 -34.498026)
		(end 123.600464 -20.007834)
		(width 0.127)
		(layer "In5.Cu")
		(net "EJTAG_TRSTB_R")
	)
	(segment
		(start 179.17541 -12.280646)
		(end 179.175156 -12.2809)
		(width 0.127)
		(layer "In5.Cu")
		(net "EJTAG_TRSTB_R")
	)
	(segment
		(start 195.149724 -19.2405)
		(end 195.18884 -19.2405)
		(width 0.127)
		(layer "In5.Cu")
		(net "EJTAG_TRSTB_R")
	)
	(segment
		(start 228.023928 -19.028156)
		(end 230.608632 -21.61286)
		(width 0.127)
		(layer "In5.Cu")
		(net "EJTAG_TRSTB_R")
	)
	(segment
		(start 199.485758 -19.2405)
		(end 199.942958 -19.6977)
		(width 0.127)
		(layer "In5.Cu")
		(net "EJTAG_TRSTB_R")
	)
	(segment
		(start 195.781676 -19.2405)
		(end 199.485758 -19.2405)
		(width 0.127)
		(layer "In5.Cu")
		(net "EJTAG_TRSTB_R")
	)
	(segment
		(start 230.608632 -22.707854)
		(end 233.1085 -25.207722)
		(width 0.127)
		(layer "In5.Cu")
		(net "EJTAG_TRSTB_R")
	)
	(segment
		(start 179.17541 -11.333226)
		(end 179.17541 -12.280646)
		(width 0.127)
		(layer "In5.Cu")
		(net "EJTAG_TRSTB_R")
	)
	(segment
		(start 128.8542 -44.577)
		(end 128.8542 -39.752016)
		(width 0.127)
		(layer "In5.Cu")
		(net "EJTAG_TRSTB_R")
	)
	(segment
		(start 233.697018 -29.56687)
		(end 233.697018 -37.0586)
		(width 0.1016)
		(layer "In5.Cu")
		(net "EJTAG_TRSTB_R")
	)
	(segment
		(start 232.36555 -38.50005)
		(end 232.10012 -38.50005)
		(width 0.1016)
		(layer "In5.Cu")
		(net "EJTAG_TRSTB_R")
	)
	(segment
		(start 179.175156 -12.2809)
		(end 179.175156 -13.469112)
		(width 0.127)
		(layer "In5.Cu")
		(net "EJTAG_TRSTB_R")
	)
	(segment
		(start 195.781422 -19.240754)
		(end 195.781676 -19.2405)
		(width 0.127)
		(layer "In5.Cu")
		(net "EJTAG_TRSTB_R")
	)
	(segment
		(start 191.219582 -15.310358)
		(end 195.149724 -19.2405)
		(width 0.127)
		(layer "In5.Cu")
		(net "EJTAG_TRSTB_R")
	)
	(segment
		(start 195.19138 -19.241008)
		(end 195.4657 -19.241008)
		(width 0.127)
		(layer "In5.Cu")
		(net "EJTAG_TRSTB_R")
	)
	(segment
		(start 230.608632 -21.61286)
		(end 230.608632 -22.707854)
		(width 0.127)
		(layer "In5.Cu")
		(net "EJTAG_TRSTB_R")
	)
	(segment
		(start 214.827358 -18.4531)
		(end 215.542114 -19.167856)
		(width 0.127)
		(layer "In5.Cu")
		(net "EJTAG_TRSTB_R")
	)
	(segment
		(start 233.503216 -37.653976)
		(end 233.133392 -38.0238)
		(width 0.1016)
		(layer "In5.Cu")
		(net "EJTAG_TRSTB_R")
	)
	(segment
		(start 233.426 -29.295852)
		(end 233.697018 -29.56687)
		(width 0.1016)
		(layer "In5.Cu")
		(net "EJTAG_TRSTB_R")
	)
	(segment
		(start 195.4657 -19.241008)
		(end 195.465954 -19.240754)
		(width 0.127)
		(layer "In5.Cu")
		(net "EJTAG_TRSTB_R")
	)
	(segment
		(start 199.942958 -19.6977)
		(end 201.91476 -19.6977)
		(width 0.127)
		(layer "In5.Cu")
		(net "EJTAG_TRSTB_R")
	)
	(segment
		(start 201.91476 -19.6977)
		(end 203.15936 -18.4531)
		(width 0.127)
		(layer "In5.Cu")
		(net "EJTAG_TRSTB_R")
	)
	(segment
		(start 195.465954 -19.240754)
		(end 195.781422 -19.240754)
		(width 0.127)
		(layer "In5.Cu")
		(net "EJTAG_TRSTB_R")
	)
	(segment
		(start 179.175156 -13.469112)
		(end 181.016402 -15.310358)
		(width 0.127)
		(layer "In5.Cu")
		(net "EJTAG_TRSTB_R")
	)
	(segment
		(start 233.503216 -37.252402)
		(end 233.503216 -37.653976)
		(width 0.1016)
		(layer "In5.Cu")
		(net "EJTAG_TRSTB_R")
	)
	(segment
		(start 123.600464 -20.007834)
		(end 127.2159 -16.392398)
		(width 0.127)
		(layer "In5.Cu")
		(net "EJTAG_TRSTB_R")
	)
	(segment
		(start 128.8542 -39.752016)
		(end 123.600464 -34.498026)
		(width 0.127)
		(layer "In5.Cu")
		(net "EJTAG_TRSTB_R")
	)
	(segment
		(start 127.2159 -13.204698)
		(end 134.600188 -5.82041)
		(width 0.127)
		(layer "In5.Cu")
		(net "EJTAG_TRSTB_R")
	)
	(segment
		(start 233.133392 -38.0238)
		(end 232.8418 -38.0238)
		(width 0.1016)
		(layer "In5.Cu")
		(net "EJTAG_TRSTB_R")
	)
	(segment
		(start 233.697018 -37.0586)
		(end 233.503216 -37.252402)
		(width 0.1016)
		(layer "In5.Cu")
		(net "EJTAG_TRSTB_R")
	)
	(segment
		(start 173.662594 -5.82041)
		(end 179.17541 -11.333226)
		(width 0.127)
		(layer "In5.Cu")
		(net "EJTAG_TRSTB_R")
	)
	(segment
		(start 232.8418 -38.0238)
		(end 232.36555 -38.50005)
		(width 0.1016)
		(layer "In5.Cu")
		(net "EJTAG_TRSTB_R")
	)
	(segment
		(start 131.295394 -44.611036)
		(end 129.56413 -46.3423)
		(width 0.12065)
		(layer "F.Cu")
		(net "EJTAG_TRSTB")
	)
	(segment
		(start 128.2827 -46.9138)
		(end 128.8542 -46.3423)
		(width 0.12065)
		(layer "F.Cu")
		(net "EJTAG_TRSTB")
	)
	(segment
		(start 129.56413 -46.3423)
		(end 128.8542 -46.3423)
		(width 0.12065)
		(layer "F.Cu")
		(net "EJTAG_TRSTB")
	)
	(segment
		(start 128.2827 -47.371)
		(end 128.2827 -46.9138)
		(width 0.12065)
		(layer "F.Cu")
		(net "EJTAG_TRSTB")
	)
	(segment
		(start 132.658612 -44.611036)
		(end 131.295394 -44.611036)
		(width 0.12065)
		(layer "F.Cu")
		(net "EJTAG_TRSTB")
	)
	(segment
		(start 136.13384 -38.607746)
		(end 136.13384 -38.69944)
		(width 0.12065)
		(layer "F.Cu")
		(net "EJTAG_TMS_R")
	)
	(segment
		(start 232.599992 -39.99992)
		(end 232.10012 -39.500048)
		(width 0.12065)
		(layer "F.Cu")
		(net "EJTAG_TMS_R")
	)
	(segment
		(start 136.13384 -38.69944)
		(end 136.779 -39.3446)
		(width 0.12065)
		(layer "F.Cu")
		(net "EJTAG_TMS_R")
	)
	(segment
		(start 140.2461 -40.4368)
		(end 140.843 -41.0337)
		(width 0.12065)
		(layer "F.Cu")
		(net "EJTAG_TMS_R")
	)
	(segment
		(start 137.423398 -39.3446)
		(end 138.515598 -40.4368)
		(width 0.12065)
		(layer "F.Cu")
		(net "EJTAG_TMS_R")
	)
	(segment
		(start 136.779 -39.3446)
		(end 137.423398 -39.3446)
		(width 0.12065)
		(layer "F.Cu")
		(net "EJTAG_TMS_R")
	)
	(segment
		(start 138.515598 -40.4368)
		(end 140.2461 -40.4368)
		(width 0.12065)
		(layer "F.Cu")
		(net "EJTAG_TMS_R")
	)
	(via
		(at 232.10012 -39.500048)
		(size 0.4572)
		(drill 0.2032)
		(layers "F.Cu" "B.Cu")
		(net "EJTAG_TMS_R")
	)
	(via
		(at 136.13384 -38.607746)
		(size 0.508)
		(drill 0.254)
		(layers "F.Cu" "B.Cu")
		(net "EJTAG_TMS_R")
	)
	(via
		(at 136.779 -39.3446)
		(size 0.7112)
		(drill 0.3556)
		(layers "F.Cu" "B.Cu")
		(net "EJTAG_TMS_R")
	)
	(segment
		(start 194.833748 -20.0025)
		(end 195.113148 -20.0025)
		(width 0.127)
		(layer "In5.Cu")
		(net "EJTAG_TMS_R")
	)
	(segment
		(start 208.099406 -19.7993)
		(end 208.670652 -19.228054)
		(width 0.127)
		(layer "In5.Cu")
		(net "EJTAG_TMS_R")
	)
	(segment
		(start 199.626982 -20.4597)
		(end 203.599288 -20.4597)
		(width 0.127)
		(layer "In5.Cu")
		(net "EJTAG_TMS_R")
	)
	(segment
		(start 195.78193 -20.002754)
		(end 196.097398 -20.002754)
		(width 0.127)
		(layer "In5.Cu")
		(net "EJTAG_TMS_R")
	)
	(segment
		(start 178.41341 -11.96467)
		(end 178.413156 -11.964924)
		(width 0.127)
		(layer "In5.Cu")
		(net "EJTAG_TMS_R")
	)
	(segment
		(start 232.49382 -35.261804)
		(end 232.49382 -36.663376)
		(width 0.1016)
		(layer "In5.Cu")
		(net "EJTAG_TMS_R")
	)
	(segment
		(start 195.115688 -20.003008)
		(end 195.781676 -20.003008)
		(width 0.127)
		(layer "In5.Cu")
		(net "EJTAG_TMS_R")
	)
	(segment
		(start 189.12967 -16.072358)
		(end 191.370712 -18.3134)
		(width 0.127)
		(layer "In5.Cu")
		(net "EJTAG_TMS_R")
	)
	(segment
		(start 178.41341 -11.649202)
		(end 178.41341 -11.96467)
		(width 0.127)
		(layer "In5.Cu")
		(net "EJTAG_TMS_R")
	)
	(segment
		(start 203.599288 -20.4597)
		(end 204.259688 -19.7993)
		(width 0.127)
		(layer "In5.Cu")
		(net "EJTAG_TMS_R")
	)
	(segment
		(start 204.259688 -19.7993)
		(end 208.099406 -19.7993)
		(width 0.127)
		(layer "In5.Cu")
		(net "EJTAG_TMS_R")
	)
	(segment
		(start 220.00718 -19.929856)
		(end 220.14688 -19.790156)
		(width 0.127)
		(layer "In5.Cu")
		(net "EJTAG_TMS_R")
	)
	(segment
		(start 129.753614 -39.5732)
		(end 124.362464 -34.18205)
		(width 0.127)
		(layer "In5.Cu")
		(net "EJTAG_TMS_R")
	)
	(segment
		(start 215.226138 -19.929856)
		(end 220.00718 -19.929856)
		(width 0.127)
		(layer "In5.Cu")
		(net "EJTAG_TMS_R")
	)
	(segment
		(start 208.670652 -19.228054)
		(end 214.524336 -19.228054)
		(width 0.127)
		(layer "In5.Cu")
		(net "EJTAG_TMS_R")
	)
	(segment
		(start 136.13384 -38.607746)
		(end 135.168386 -39.5732)
		(width 0.127)
		(layer "In5.Cu")
		(net "EJTAG_TMS_R")
	)
	(segment
		(start 193.144648 -18.3134)
		(end 194.833748 -20.0025)
		(width 0.127)
		(layer "In5.Cu")
		(net "EJTAG_TMS_R")
	)
	(segment
		(start 135.168386 -39.5732)
		(end 129.753614 -39.5732)
		(width 0.127)
		(layer "In5.Cu")
		(net "EJTAG_TMS_R")
	)
	(segment
		(start 232.706418 -28.8925)
		(end 232.706418 -35.049206)
		(width 0.1016)
		(layer "In5.Cu")
		(net "EJTAG_TMS_R")
	)
	(segment
		(start 199.169782 -20.0025)
		(end 199.626982 -20.4597)
		(width 0.127)
		(layer "In5.Cu")
		(net "EJTAG_TMS_R")
	)
	(segment
		(start 173.346618 -6.58241)
		(end 178.41341 -11.649202)
		(width 0.127)
		(layer "In5.Cu")
		(net "EJTAG_TMS_R")
	)
	(segment
		(start 232.149396 -36.893754)
		(end 231.70642 -37.33673)
		(width 0.1016)
		(layer "In5.Cu")
		(net "EJTAG_TMS_R")
	)
	(segment
		(start 231.70642 -37.33673)
		(end 231.70642 -39.106348)
		(width 0.1016)
		(layer "In5.Cu")
		(net "EJTAG_TMS_R")
	)
	(segment
		(start 232.3465 -25.964388)
		(end 232.719118 -26.337006)
		(width 0.127)
		(layer "In5.Cu")
		(net "EJTAG_TMS_R")
	)
	(segment
		(start 124.362464 -20.32381)
		(end 127.9779 -16.708374)
		(width 0.127)
		(layer "In5.Cu")
		(net "EJTAG_TMS_R")
	)
	(segment
		(start 196.097398 -20.002754)
		(end 196.097652 -20.0025)
		(width 0.127)
		(layer "In5.Cu")
		(net "EJTAG_TMS_R")
	)
	(segment
		(start 232.719118 -28.8798)
		(end 232.706418 -28.8925)
		(width 0.1016)
		(layer "In5.Cu")
		(net "EJTAG_TMS_R")
	)
	(segment
		(start 127.9779 -13.520674)
		(end 134.916164 -6.58241)
		(width 0.127)
		(layer "In5.Cu")
		(net "EJTAG_TMS_R")
	)
	(segment
		(start 134.916164 -6.58241)
		(end 173.346618 -6.58241)
		(width 0.127)
		(layer "In5.Cu")
		(net "EJTAG_TMS_R")
	)
	(segment
		(start 178.413156 -11.964924)
		(end 178.413156 -13.785088)
		(width 0.127)
		(layer "In5.Cu")
		(net "EJTAG_TMS_R")
	)
	(segment
		(start 220.14688 -19.790156)
		(end 227.707952 -19.790156)
		(width 0.127)
		(layer "In5.Cu")
		(net "EJTAG_TMS_R")
	)
	(segment
		(start 232.3465 -25.759156)
		(end 232.3465 -25.964388)
		(width 0.127)
		(layer "In5.Cu")
		(net "EJTAG_TMS_R")
	)
	(segment
		(start 232.719118 -26.337006)
		(end 232.719118 -28.8798)
		(width 0.127)
		(layer "In5.Cu")
		(net "EJTAG_TMS_R")
	)
	(segment
		(start 229.5779 -22.990556)
		(end 232.3465 -25.759156)
		(width 0.127)
		(layer "In5.Cu")
		(net "EJTAG_TMS_R")
	)
	(segment
		(start 180.700426 -16.072358)
		(end 189.12967 -16.072358)
		(width 0.127)
		(layer "In5.Cu")
		(net "EJTAG_TMS_R")
	)
	(segment
		(start 195.781676 -20.003008)
		(end 195.78193 -20.002754)
		(width 0.127)
		(layer "In5.Cu")
		(net "EJTAG_TMS_R")
	)
	(segment
		(start 229.5779 -21.660104)
		(end 229.5779 -22.990556)
		(width 0.127)
		(layer "In5.Cu")
		(net "EJTAG_TMS_R")
	)
	(segment
		(start 127.9779 -16.708374)
		(end 127.9779 -13.520674)
		(width 0.127)
		(layer "In5.Cu")
		(net "EJTAG_TMS_R")
	)
	(segment
		(start 195.113148 -20.0025)
		(end 195.115688 -20.003008)
		(width 0.127)
		(layer "In5.Cu")
		(net "EJTAG_TMS_R")
	)
	(segment
		(start 232.706418 -35.049206)
		(end 232.49382 -35.261804)
		(width 0.1016)
		(layer "In5.Cu")
		(net "EJTAG_TMS_R")
	)
	(segment
		(start 196.097652 -20.0025)
		(end 199.169782 -20.0025)
		(width 0.127)
		(layer "In5.Cu")
		(net "EJTAG_TMS_R")
	)
	(segment
		(start 232.49382 -36.663376)
		(end 232.263442 -36.893754)
		(width 0.1016)
		(layer "In5.Cu")
		(net "EJTAG_TMS_R")
	)
	(segment
		(start 231.70642 -39.106348)
		(end 232.10012 -39.500048)
		(width 0.1016)
		(layer "In5.Cu")
		(net "EJTAG_TMS_R")
	)
	(segment
		(start 124.362464 -34.18205)
		(end 124.362464 -20.32381)
		(width 0.127)
		(layer "In5.Cu")
		(net "EJTAG_TMS_R")
	)
	(segment
		(start 232.263442 -36.893754)
		(end 232.149396 -36.893754)
		(width 0.1016)
		(layer "In5.Cu")
		(net "EJTAG_TMS_R")
	)
	(segment
		(start 191.370712 -18.3134)
		(end 193.144648 -18.3134)
		(width 0.127)
		(layer "In5.Cu")
		(net "EJTAG_TMS_R")
	)
	(segment
		(start 214.524336 -19.228054)
		(end 215.226138 -19.929856)
		(width 0.127)
		(layer "In5.Cu")
		(net "EJTAG_TMS_R")
	)
	(segment
		(start 178.413156 -13.785088)
		(end 180.700426 -16.072358)
		(width 0.127)
		(layer "In5.Cu")
		(net "EJTAG_TMS_R")
	)
	(segment
		(start 227.707952 -19.790156)
		(end 229.5779 -21.660104)
		(width 0.127)
		(layer "In5.Cu")
		(net "EJTAG_TMS_R")
	)
	(segment
		(start 138.6586 -43.8912)
		(end 139.7508 -42.799)
		(width 0.12065)
		(layer "F.Cu")
		(net "EJTAG_TMS")
	)
	(segment
		(start 139.7508 -41.9735)
		(end 139.8016 -41.9227)
		(width 0.12065)
		(layer "F.Cu")
		(net "EJTAG_TMS")
	)
	(segment
		(start 138.6586 -44.611036)
		(end 138.6586 -43.8912)
		(width 0.12065)
		(layer "F.Cu")
		(net "EJTAG_TMS")
	)
	(segment
		(start 140.843 -41.9227)
		(end 141.1097 -41.9227)
		(width 0.12065)
		(layer "F.Cu")
		(net "EJTAG_TMS")
	)
	(segment
		(start 141.386052 -40.655748)
		(end 141.7574 -40.2844)
		(width 0.12065)
		(layer "F.Cu")
		(net "EJTAG_TMS")
	)
	(segment
		(start 141.1097 -41.9227)
		(end 141.386052 -41.646348)
		(width 0.12065)
		(layer "F.Cu")
		(net "EJTAG_TMS")
	)
	(segment
		(start 141.386052 -41.646348)
		(end 141.386052 -40.655748)
		(width 0.12065)
		(layer "F.Cu")
		(net "EJTAG_TMS")
	)
	(segment
		(start 139.8016 -41.9227)
		(end 140.843 -41.9227)
		(width 0.12065)
		(layer "F.Cu")
		(net "EJTAG_TMS")
	)
	(segment
		(start 139.7508 -42.799)
		(end 139.7508 -41.9735)
		(width 0.12065)
		(layer "F.Cu")
		(net "EJTAG_TMS")
	)
	(via
		(at 141.7574 -40.2844)
		(size 0.7112)
		(drill 0.3556)
		(layers "F.Cu" "B.Cu")
		(net "EJTAG_TMS")
	)
	(segment
		(start 136.658604 -43.030648)
		(end 137.79246 -41.896792)
		(width 0.12065)
		(layer "F.Cu")
		(net "EJTAG_TDO")
	)
	(segment
		(start 137.79246 -41.896792)
		(end 137.79246 -41.618154)
		(width 0.12065)
		(layer "F.Cu")
		(net "EJTAG_TDO")
	)
	(segment
		(start 136.658604 -44.611036)
		(end 136.658604 -43.030648)
		(width 0.12065)
		(layer "F.Cu")
		(net "EJTAG_TDO")
	)
	(segment
		(start 133.7437 -41.10101)
		(end 133.7437 -42.11701)
		(width 0.12065)
		(layer "F.Cu")
		(net "EJTAG_TDI")
	)
	(segment
		(start 133.7437 -42.410126)
		(end 133.7437 -42.11701)
		(width 0.12065)
		(layer "F.Cu")
		(net "EJTAG_TDI")
	)
	(segment
		(start 134.658608 -43.325034)
		(end 133.7437 -42.410126)
		(width 0.12065)
		(layer "F.Cu")
		(net "EJTAG_TDI")
	)
	(segment
		(start 134.658608 -44.611036)
		(end 134.658608 -43.325034)
		(width 0.12065)
		(layer "F.Cu")
		(net "EJTAG_TDI")
	)
	(segment
		(start 142.6464 -39.3954)
		(end 143.0274 -39.7764)
		(width 0.12065)
		(layer "F.Cu")
		(net "EJTAG_TCK_R")
	)
	(segment
		(start 143.0274 -39.7764)
		(end 143.0274 -40.9575)
		(width 0.12065)
		(layer "F.Cu")
		(net "EJTAG_TCK_R")
	)
	(segment
		(start 141.8844 -42.1005)
		(end 141.8844 -42.35958)
		(width 0.12065)
		(layer "F.Cu")
		(net "EJTAG_TCK_R")
	)
	(segment
		(start 141.8844 -42.35958)
		(end 141.762734 -42.481246)
		(width 0.12065)
		(layer "F.Cu")
		(net "EJTAG_TCK_R")
	)
	(segment
		(start 143.0274 -40.9575)
		(end 141.8844 -42.1005)
		(width 0.12065)
		(layer "F.Cu")
		(net "EJTAG_TCK_R")
	)
	(segment
		(start 142.6464 -39.3192)
		(end 142.6464 -39.3954)
		(width 0.12065)
		(layer "F.Cu")
		(net "EJTAG_TCK_R")
	)
	(segment
		(start 233.59999 -40.999918)
		(end 233.100118 -40.500046)
		(width 0.12065)
		(layer "F.Cu")
		(net "EJTAG_TCK_R")
	)
	(via
		(at 233.100118 -40.500046)
		(size 0.4572)
		(drill 0.2032)
		(layers "F.Cu" "B.Cu")
		(net "EJTAG_TCK_R")
	)
	(via
		(at 141.762734 -42.481246)
		(size 0.508)
		(drill 0.254)
		(layers "F.Cu" "B.Cu")
		(net "EJTAG_TCK_R")
	)
	(via
		(at 142.6464 -39.3192)
		(size 0.7112)
		(drill 0.3556)
		(layers "F.Cu" "B.Cu")
		(net "EJTAG_TCK_R")
	)
	(segment
		(start 123.219464 -19.849846)
		(end 123.219464 -35.157664)
		(width 0.127)
		(layer "In5.Cu")
		(net "EJTAG_TCK_R")
	)
	(segment
		(start 219.366084 -18.647156)
		(end 219.226384 -18.786856)
		(width 0.127)
		(layer "In5.Cu")
		(net "EJTAG_TCK_R")
	)
	(segment
		(start 127.53975 -39.47795)
		(end 127.53975 -43.977306)
		(width 0.127)
		(layer "In5.Cu")
		(net "EJTAG_TCK_R")
	)
	(segment
		(start 199.643746 -18.8595)
		(end 195.623688 -18.8595)
		(width 0.127)
		(layer "In5.Cu")
		(net "EJTAG_TCK_R")
	)
	(segment
		(start 214.985346 -18.0721)
		(end 203.001372 -18.0721)
		(width 0.127)
		(layer "In5.Cu")
		(net "EJTAG_TCK_R")
	)
	(segment
		(start 233.7816 -28.5496)
		(end 233.7816 -26.256488)
		(width 0.127)
		(layer "In5.Cu")
		(net "EJTAG_TCK_R")
	)
	(segment
		(start 231.6099 -23.170134)
		(end 231.6099 -21.471382)
		(width 0.127)
		(layer "In5.Cu")
		(net "EJTAG_TCK_R")
	)
	(segment
		(start 233.706416 -37.33673)
		(end 233.900218 -37.142928)
		(width 0.1016)
		(layer "In5.Cu")
		(net "EJTAG_TCK_R")
	)
	(segment
		(start 181.17439 -14.929358)
		(end 179.556156 -13.311124)
		(width 0.127)
		(layer "In5.Cu")
		(net "EJTAG_TCK_R")
	)
	(segment
		(start 234.493816 -29.261816)
		(end 234.315 -29.083)
		(width 0.1016)
		(layer "In5.Cu")
		(net "EJTAG_TCK_R")
	)
	(segment
		(start 233.100118 -40.500046)
		(end 233.100118 -40.256968)
		(width 0.1016)
		(layer "In5.Cu")
		(net "EJTAG_TCK_R")
	)
	(segment
		(start 179.556156 -13.311124)
		(end 179.556156 -12.438888)
		(width 0.127)
		(layer "In5.Cu")
		(net "EJTAG_TCK_R")
	)
	(segment
		(start 233.4895 -25.964388)
		(end 233.4895 -25.049734)
		(width 0.127)
		(layer "In5.Cu")
		(net "EJTAG_TCK_R")
	)
	(segment
		(start 126.8349 -16.23441)
		(end 123.219464 -19.849846)
		(width 0.127)
		(layer "In5.Cu")
		(net "EJTAG_TCK_R")
	)
	(segment
		(start 233.900218 -37.142928)
		(end 233.900218 -36.256976)
		(width 0.1016)
		(layer "In5.Cu")
		(net "EJTAG_TCK_R")
	)
	(segment
		(start 127.53975 -43.977306)
		(end 128.609344 -45.0469)
		(width 0.127)
		(layer "In5.Cu")
		(net "EJTAG_TCK_R")
	)
	(segment
		(start 233.100118 -40.256968)
		(end 233.706416 -39.65067)
		(width 0.1016)
		(layer "In5.Cu")
		(net "EJTAG_TCK_R")
	)
	(segment
		(start 179.55641 -11.175238)
		(end 173.820582 -5.43941)
		(width 0.127)
		(layer "In5.Cu")
		(net "EJTAG_TCK_R")
	)
	(segment
		(start 195.623688 -18.8595)
		(end 195.307966 -18.859754)
		(width 0.127)
		(layer "In5.Cu")
		(net "EJTAG_TCK_R")
	)
	(segment
		(start 195.307966 -18.859754)
		(end 191.37757 -14.929358)
		(width 0.127)
		(layer "In5.Cu")
		(net "EJTAG_TCK_R")
	)
	(segment
		(start 231.6099 -21.471382)
		(end 228.785674 -18.647156)
		(width 0.127)
		(layer "In5.Cu")
		(net "EJTAG_TCK_R")
	)
	(segment
		(start 215.700102 -18.786856)
		(end 214.985346 -18.0721)
		(width 0.127)
		(layer "In5.Cu")
		(net "EJTAG_TCK_R")
	)
	(segment
		(start 233.706416 -39.65067)
		(end 233.706416 -37.33673)
		(width 0.1016)
		(layer "In5.Cu")
		(net "EJTAG_TCK_R")
	)
	(segment
		(start 191.37757 -14.929358)
		(end 181.17439 -14.929358)
		(width 0.127)
		(layer "In5.Cu")
		(net "EJTAG_TCK_R")
	)
	(segment
		(start 134.4422 -5.43941)
		(end 126.8349 -13.04671)
		(width 0.127)
		(layer "In5.Cu")
		(net "EJTAG_TCK_R")
	)
	(segment
		(start 201.756772 -19.3167)
		(end 200.100946 -19.3167)
		(width 0.127)
		(layer "In5.Cu")
		(net "EJTAG_TCK_R")
	)
	(segment
		(start 179.55641 -12.438634)
		(end 179.55641 -11.175238)
		(width 0.127)
		(layer "In5.Cu")
		(net "EJTAG_TCK_R")
	)
	(segment
		(start 179.556156 -12.438888)
		(end 179.55641 -12.438634)
		(width 0.127)
		(layer "In5.Cu")
		(net "EJTAG_TCK_R")
	)
	(segment
		(start 126.8349 -13.04671)
		(end 126.8349 -16.23441)
		(width 0.127)
		(layer "In5.Cu")
		(net "EJTAG_TCK_R")
	)
	(segment
		(start 233.7816 -26.256488)
		(end 233.4895 -25.964388)
		(width 0.127)
		(layer "In5.Cu")
		(net "EJTAG_TCK_R")
	)
	(segment
		(start 139.19708 -45.0469)
		(end 141.762734 -42.481246)
		(width 0.127)
		(layer "In5.Cu")
		(net "EJTAG_TCK_R")
	)
	(segment
		(start 234.493816 -35.663378)
		(end 234.493816 -29.261816)
		(width 0.1016)
		(layer "In5.Cu")
		(net "EJTAG_TCK_R")
	)
	(segment
		(start 203.001372 -18.0721)
		(end 201.756772 -19.3167)
		(width 0.127)
		(layer "In5.Cu")
		(net "EJTAG_TCK_R")
	)
	(segment
		(start 123.219464 -35.157664)
		(end 127.53975 -39.47795)
		(width 0.127)
		(layer "In5.Cu")
		(net "EJTAG_TCK_R")
	)
	(segment
		(start 219.226384 -18.786856)
		(end 215.700102 -18.786856)
		(width 0.127)
		(layer "In5.Cu")
		(net "EJTAG_TCK_R")
	)
	(segment
		(start 233.4895 -25.049734)
		(end 231.6099 -23.170134)
		(width 0.127)
		(layer "In5.Cu")
		(net "EJTAG_TCK_R")
	)
	(segment
		(start 173.820582 -5.43941)
		(end 134.4422 -5.43941)
		(width 0.127)
		(layer "In5.Cu")
		(net "EJTAG_TCK_R")
	)
	(segment
		(start 233.900218 -36.256976)
		(end 234.493816 -35.663378)
		(width 0.1016)
		(layer "In5.Cu")
		(net "EJTAG_TCK_R")
	)
	(segment
		(start 128.609344 -45.0469)
		(end 139.19708 -45.0469)
		(width 0.127)
		(layer "In5.Cu")
		(net "EJTAG_TCK_R")
	)
	(segment
		(start 234.315 -29.083)
		(end 233.7816 -28.5496)
		(width 0.127)
		(layer "In5.Cu")
		(net "EJTAG_TCK_R")
	)
	(segment
		(start 200.100946 -19.3167)
		(end 199.643746 -18.8595)
		(width 0.127)
		(layer "In5.Cu")
		(net "EJTAG_TCK_R")
	)
	(segment
		(start 228.785674 -18.647156)
		(end 219.366084 -18.647156)
		(width 0.127)
		(layer "In5.Cu")
		(net "EJTAG_TCK_R")
	)
	(segment
		(start 141.877288 -43.073574)
		(end 143.0274 -41.923462)
		(width 0.12065)
		(layer "F.Cu")
		(net "EJTAG_TCK")
	)
	(segment
		(start 140.658596 -43.456606)
		(end 141.041628 -43.073574)
		(width 0.12065)
		(layer "F.Cu")
		(net "EJTAG_TCK")
	)
	(segment
		(start 144.0688 -41.8465)
		(end 143.0274 -41.8465)
		(width 0.12065)
		(layer "F.Cu")
		(net "EJTAG_TCK")
	)
	(segment
		(start 140.658596 -44.611036)
		(end 140.658596 -43.456606)
		(width 0.12065)
		(layer "F.Cu")
		(net "EJTAG_TCK")
	)
	(segment
		(start 143.0274 -41.923462)
		(end 143.0274 -41.8465)
		(width 0.12065)
		(layer "F.Cu")
		(net "EJTAG_TCK")
	)
	(segment
		(start 141.041628 -43.073574)
		(end 141.877288 -43.073574)
		(width 0.12065)
		(layer "F.Cu")
		(net "EJTAG_TCK")
	)
	(segment
		(start 142.658592 -44.611036)
		(end 142.658592 -43.37558)
		(width 0.12065)
		(layer "F.Cu")
		(net "EJTAG_RSTB")
	)
	(segment
		(start 142.658592 -43.37558)
		(end 143.378682 -42.65549)
		(width 0.12065)
		(layer "F.Cu")
		(net "EJTAG_RSTB")
	)
	(segment
		(start 144.32661 -42.65549)
		(end 143.378682 -42.65549)
		(width 0.12065)
		(layer "F.Cu")
		(net "EJTAG_RSTB")
	)
	(segment
		(start 145.1356 -41.8465)
		(end 144.32661 -42.65549)
		(width 0.12065)
		(layer "F.Cu")
		(net "EJTAG_RSTB")
	)
	(segment
		(start 232.599992 -37.999924)
		(end 232.10012 -37.500052)
		(width 0.12065)
		(layer "F.Cu")
		(net "EJTAG_RSTB")
	)
	(via
		(at 232.10012 -37.500052)
		(size 0.4572)
		(drill 0.2032)
		(layers "F.Cu" "B.Cu")
		(net "EJTAG_RSTB")
	)
	(via
		(at 143.378682 -42.65549)
		(size 0.508)
		(drill 0.254)
		(layers "F.Cu" "B.Cu")
		(net "EJTAG_RSTB")
	)
	(segment
		(start 123.981464 -34.340038)
		(end 129.875026 -40.2336)
		(width 0.127)
		(layer "In5.Cu")
		(net "EJTAG_RSTB")
	)
	(segment
		(start 199.32777 -19.6215)
		(end 195.939664 -19.6215)
		(width 0.127)
		(layer "In5.Cu")
		(net "EJTAG_RSTB")
	)
	(segment
		(start 233.493818 -29.967174)
		(end 233.39806 -29.871416)
		(width 0.1016)
		(layer "In5.Cu")
		(net "EJTAG_RSTB")
	)
	(segment
		(start 232.936796 -35.106356)
		(end 233.050842 -35.106356)
		(width 0.1016)
		(layer "In5.Cu")
		(net "EJTAG_RSTB")
	)
	(segment
		(start 141.519148 -41.52138)
		(end 142.653258 -42.65549)
		(width 0.127)
		(layer "In5.Cu")
		(net "EJTAG_RSTB")
	)
	(segment
		(start 233.045 -26.22423)
		(end 232.7275 -25.90673)
		(width 0.127)
		(layer "In5.Cu")
		(net "EJTAG_RSTB")
	)
	(segment
		(start 219.988892 -19.409156)
		(end 219.849192 -19.548856)
		(width 0.127)
		(layer "In5.Cu")
		(net "EJTAG_RSTB")
	)
	(segment
		(start 230.227632 -22.865842)
		(end 230.227632 -21.770848)
		(width 0.127)
		(layer "In5.Cu")
		(net "EJTAG_RSTB")
	)
	(segment
		(start 199.78497 -20.0787)
		(end 199.32777 -19.6215)
		(width 0.127)
		(layer "In5.Cu")
		(net "EJTAG_RSTB")
	)
	(segment
		(start 123.981464 -20.165822)
		(end 123.981464 -34.340038)
		(width 0.127)
		(layer "In5.Cu")
		(net "EJTAG_RSTB")
	)
	(segment
		(start 232.10012 -37.500052)
		(end 232.69702 -36.903152)
		(width 0.1016)
		(layer "In5.Cu")
		(net "EJTAG_RSTB")
	)
	(segment
		(start 180.858414 -15.691358)
		(end 178.794156 -13.6271)
		(width 0.127)
		(layer "In5.Cu")
		(net "EJTAG_RSTB")
	)
	(segment
		(start 230.227632 -21.770848)
		(end 227.86594 -19.409156)
		(width 0.127)
		(layer "In5.Cu")
		(net "EJTAG_RSTB")
	)
	(segment
		(start 233.050842 -35.106356)
		(end 233.493818 -34.66338)
		(width 0.1016)
		(layer "In5.Cu")
		(net "EJTAG_RSTB")
	)
	(segment
		(start 203.317348 -18.8341)
		(end 202.072748 -20.0787)
		(width 0.127)
		(layer "In5.Cu")
		(net "EJTAG_RSTB")
	)
	(segment
		(start 142.653258 -42.65549)
		(end 143.378682 -42.65549)
		(width 0.127)
		(layer "In5.Cu")
		(net "EJTAG_RSTB")
	)
	(segment
		(start 232.69702 -36.903152)
		(end 232.69702 -35.346132)
		(width 0.1016)
		(layer "In5.Cu")
		(net "EJTAG_RSTB")
	)
	(segment
		(start 173.504606 -6.20141)
		(end 134.758176 -6.20141)
		(width 0.127)
		(layer "In5.Cu")
		(net "EJTAG_RSTB")
	)
	(segment
		(start 232.69702 -35.346132)
		(end 232.936796 -35.106356)
		(width 0.1016)
		(layer "In5.Cu")
		(net "EJTAG_RSTB")
	)
	(segment
		(start 134.758176 -6.20141)
		(end 127.5969 -13.362686)
		(width 0.127)
		(layer "In5.Cu")
		(net "EJTAG_RSTB")
	)
	(segment
		(start 233.39806 -29.871416)
		(end 233.045 -29.518356)
		(width 0.127)
		(layer "In5.Cu")
		(net "EJTAG_RSTB")
	)
	(segment
		(start 178.794156 -13.6271)
		(end 178.794156 -12.122912)
		(width 0.127)
		(layer "In5.Cu")
		(net "EJTAG_RSTB")
	)
	(segment
		(start 195.153534 -19.622008)
		(end 195.150994 -19.6215)
		(width 0.127)
		(layer "In5.Cu")
		(net "EJTAG_RSTB")
	)
	(segment
		(start 195.623942 -19.621754)
		(end 195.623688 -19.622008)
		(width 0.127)
		(layer "In5.Cu")
		(net "EJTAG_RSTB")
	)
	(segment
		(start 214.66937 -18.8341)
		(end 203.317348 -18.8341)
		(width 0.127)
		(layer "In5.Cu")
		(net "EJTAG_RSTB")
	)
	(segment
		(start 195.939664 -19.6215)
		(end 195.93941 -19.621754)
		(width 0.127)
		(layer "In5.Cu")
		(net "EJTAG_RSTB")
	)
	(segment
		(start 178.794156 -12.122912)
		(end 178.79441 -12.122658)
		(width 0.127)
		(layer "In5.Cu")
		(net "EJTAG_RSTB")
	)
	(segment
		(start 191.672718 -17.892776)
		(end 189.4713 -15.691358)
		(width 0.127)
		(layer "In5.Cu")
		(net "EJTAG_RSTB")
	)
	(segment
		(start 233.493818 -34.66338)
		(end 233.493818 -29.967174)
		(width 0.1016)
		(layer "In5.Cu")
		(net "EJTAG_RSTB")
	)
	(segment
		(start 195.623688 -19.622008)
		(end 195.153534 -19.622008)
		(width 0.127)
		(layer "In5.Cu")
		(net "EJTAG_RSTB")
	)
	(segment
		(start 194.991736 -19.6215)
		(end 193.263012 -17.892776)
		(width 0.127)
		(layer "In5.Cu")
		(net "EJTAG_RSTB")
	)
	(segment
		(start 227.86594 -19.409156)
		(end 219.988892 -19.409156)
		(width 0.127)
		(layer "In5.Cu")
		(net "EJTAG_RSTB")
	)
	(segment
		(start 178.79441 -11.491214)
		(end 173.504606 -6.20141)
		(width 0.127)
		(layer "In5.Cu")
		(net "EJTAG_RSTB")
	)
	(segment
		(start 232.7275 -25.90673)
		(end 232.7275 -25.36571)
		(width 0.127)
		(layer "In5.Cu")
		(net "EJTAG_RSTB")
	)
	(segment
		(start 139.556998 -41.52138)
		(end 141.519148 -41.52138)
		(width 0.127)
		(layer "In5.Cu")
		(net "EJTAG_RSTB")
	)
	(segment
		(start 195.93941 -19.621754)
		(end 195.623942 -19.621754)
		(width 0.127)
		(layer "In5.Cu")
		(net "EJTAG_RSTB")
	)
	(segment
		(start 193.263012 -17.892776)
		(end 191.672718 -17.892776)
		(width 0.127)
		(layer "In5.Cu")
		(net "EJTAG_RSTB")
	)
	(segment
		(start 232.7275 -25.36571)
		(end 230.227632 -22.865842)
		(width 0.127)
		(layer "In5.Cu")
		(net "EJTAG_RSTB")
	)
	(segment
		(start 138.443716 -40.963342)
		(end 138.99896 -40.963342)
		(width 0.127)
		(layer "In5.Cu")
		(net "EJTAG_RSTB")
	)
	(segment
		(start 202.072748 -20.0787)
		(end 199.78497 -20.0787)
		(width 0.127)
		(layer "In5.Cu")
		(net "EJTAG_RSTB")
	)
	(segment
		(start 178.79441 -12.122658)
		(end 178.79441 -11.491214)
		(width 0.127)
		(layer "In5.Cu")
		(net "EJTAG_RSTB")
	)
	(segment
		(start 215.384126 -19.548856)
		(end 214.66937 -18.8341)
		(width 0.127)
		(layer "In5.Cu")
		(net "EJTAG_RSTB")
	)
	(segment
		(start 195.150994 -19.6215)
		(end 194.991736 -19.6215)
		(width 0.127)
		(layer "In5.Cu")
		(net "EJTAG_RSTB")
	)
	(segment
		(start 189.4713 -15.691358)
		(end 180.858414 -15.691358)
		(width 0.127)
		(layer "In5.Cu")
		(net "EJTAG_RSTB")
	)
	(segment
		(start 127.5969 -13.362686)
		(end 127.5969 -16.550386)
		(width 0.127)
		(layer "In5.Cu")
		(net "EJTAG_RSTB")
	)
	(segment
		(start 137.713974 -40.2336)
		(end 138.443716 -40.963342)
		(width 0.127)
		(layer "In5.Cu")
		(net "EJTAG_RSTB")
	)
	(segment
		(start 219.849192 -19.548856)
		(end 215.384126 -19.548856)
		(width 0.127)
		(layer "In5.Cu")
		(net "EJTAG_RSTB")
	)
	(segment
		(start 138.99896 -40.963342)
		(end 139.556998 -41.52138)
		(width 0.127)
		(layer "In5.Cu")
		(net "EJTAG_RSTB")
	)
	(segment
		(start 127.5969 -16.550386)
		(end 123.981464 -20.165822)
		(width 0.127)
		(layer "In5.Cu")
		(net "EJTAG_RSTB")
	)
	(segment
		(start 129.875026 -40.2336)
		(end 137.713974 -40.2336)
		(width 0.127)
		(layer "In5.Cu")
		(net "EJTAG_RSTB")
	)
	(segment
		(start 233.045 -29.518356)
		(end 233.045 -26.22423)
		(width 0.127)
		(layer "In5.Cu")
		(net "EJTAG_RSTB")
	)
	(segment
		(start 144.658588 -48.860964)
		(end 144.658588 -51.224688)
		(width 0.12065)
		(layer "F.Cu")
		(net "EJTAG_PWR")
	)
	(segment
		(start 145.580354 -53.611018)
		(end 145.580354 -52.146454)
		(width 0.12065)
		(layer "F.Cu")
		(net "EJTAG_PWR")
	)
	(segment
		(start 145.580354 -52.146454)
		(end 144.8054 -51.3715)
		(width 0.12065)
		(layer "F.Cu")
		(net "EJTAG_PWR")
	)
	(segment
		(start 144.658588 -51.224688)
		(end 144.8054 -51.3715)
		(width 0.12065)
		(layer "F.Cu")
		(net "EJTAG_PWR")
	)
	(via
		(at 145.580354 -53.611018)
		(size 0.7112)
		(drill 0.3556)
		(layers "F.Cu" "B.Cu")
		(net "EJTAG_PWR")
	)
	(segment
		(start 145.726658 -44.611036)
		(end 146.2024 -44.135294)
		(width 0.12065)
		(layer "F.Cu")
		(net "EJTAG_DINT")
	)
	(segment
		(start 146.2024 -44.135294)
		(end 146.2024 -41.8211)
		(width 0.12065)
		(layer "F.Cu")
		(net "EJTAG_DINT")
	)
	(segment
		(start 144.658588 -44.611036)
		(end 145.726658 -44.611036)
		(width 0.12065)
		(layer "F.Cu")
		(net "EJTAG_DINT")
	)
	(segment
		(start 227.33 -10.414)
		(end 228.6 -10.414)
		(width 0.12065)
		(layer "F.Cu")
		(net "EEPROM_WP_8536")
	)
	(segment
		(start 229.8065 -10.414)
		(end 229.108 -10.414)
		(width 0.12065)
		(layer "F.Cu")
		(net "EEPROM_WP_8536")
	)
	(segment
		(start 229.8065 -9.398)
		(end 229.8065 -10.414)
		(width 0.12065)
		(layer "F.Cu")
		(net "EEPROM_WP_8536")
	)
	(segment
		(start 228.6 -10.414)
		(end 228.854 -10.668)
		(width 0.12065)
		(layer "F.Cu")
		(net "EEPROM_WP_8536")
	)
	(segment
		(start 229.108 -10.414)
		(end 228.854 -10.668)
		(width 0.12065)
		(layer "F.Cu")
		(net "EEPROM_WP_8536")
	)
	(via
		(at 228.854 -10.668)
		(size 0.7112)
		(drill 0.3556)
		(layers "F.Cu" "B.Cu")
		(net "EEPROM_WP_8536")
	)
	(segment
		(start 65.786 -148.717)
		(end 65.278 -148.717)
		(width 0.12065)
		(layer "F.Cu")
		(net "EEPROM_WP")
	)
	(segment
		(start 65.278 -148.717)
		(end 64.96558 -148.40458)
		(width 0.12065)
		(layer "F.Cu")
		(net "EEPROM_WP")
	)
	(segment
		(start 66.37909 -148.12391)
		(end 65.786 -148.717)
		(width 0.12065)
		(layer "F.Cu")
		(net "EEPROM_WP")
	)
	(segment
		(start 66.925952 -148.12391)
		(end 66.37909 -148.12391)
		(width 0.12065)
		(layer "F.Cu")
		(net "EEPROM_WP")
	)
	(segment
		(start 64.96558 -148.40458)
		(end 64.96558 -147.670774)
		(width 0.12065)
		(layer "F.Cu")
		(net "EEPROM_WP")
	)
	(via
		(at 65.278 -148.717)
		(size 0.7112)
		(drill 0.3556)
		(layers "F.Cu" "B.Cu")
		(net "EEPROM_WP")
	)
	(segment
		(start 66.925952 -150.66391)
		(end 68.41109 -150.66391)
		(width 0.12065)
		(layer "F.Cu")
		(net "EEPROM_SDA")
	)
	(via
		(at 68.41109 -150.66391)
		(size 0.508)
		(drill 0.254)
		(layers "F.Cu" "B.Cu")
		(net "EEPROM_SDA")
	)
	(via
		(at 69.376036 -150.68931)
		(size 0.7112)
		(drill 0.3556)
		(layers "F.Cu" "B.Cu")
		(net "EEPROM_SDA")
	)
	(segment
		(start 68.41109 -150.66391)
		(end 69.278754 -150.66391)
		(width 0.12065)
		(layer "B.Cu")
		(net "EEPROM_SDA")
	)
	(segment
		(start 69.302122 -150.68931)
		(end 69.376036 -150.68931)
		(width 0.12065)
		(layer "B.Cu")
		(net "EEPROM_SDA")
	)
	(segment
		(start 69.278754 -150.66391)
		(end 69.302122 -150.687278)
		(width 0.12065)
		(layer "B.Cu")
		(net "EEPROM_SDA")
	)
	(segment
		(start 68.36918 -150.622)
		(end 68.41109 -150.66391)
		(width 0.12065)
		(layer "B.Cu")
		(net "EEPROM_SDA")
	)
	(segment
		(start 69.302122 -150.687278)
		(end 69.302122 -150.68931)
		(width 0.12065)
		(layer "B.Cu")
		(net "EEPROM_SDA")
	)
	(segment
		(start 66.9925 -150.622)
		(end 68.36918 -150.622)
		(width 0.12065)
		(layer "B.Cu")
		(net "EEPROM_SDA")
	)
	(segment
		(start 68.11391 -149.39391)
		(end 68.326 -149.606)
		(width 0.12065)
		(layer "F.Cu")
		(net "EEPROM_SCL")
	)
	(segment
		(start 66.925952 -149.39391)
		(end 68.11391 -149.39391)
		(width 0.12065)
		(layer "F.Cu")
		(net "EEPROM_SCL")
	)
	(via
		(at 67.95516 -148.62937)
		(size 0.7112)
		(drill 0.3556)
		(layers "F.Cu" "B.Cu")
		(net "EEPROM_SCL")
	)
	(via
		(at 68.326 -149.606)
		(size 0.508)
		(drill 0.254)
		(layers "F.Cu" "B.Cu")
		(net "EEPROM_SCL")
	)
	(segment
		(start 67.95516 -148.62937)
		(end 68.326 -149.00021)
		(width 0.12065)
		(layer "B.Cu")
		(net "EEPROM_SCL")
	)
	(segment
		(start 66.9925 -149.479)
		(end 67.84213 -148.62937)
		(width 0.12065)
		(layer "B.Cu")
		(net "EEPROM_SCL")
	)
	(segment
		(start 68.326 -149.00021)
		(end 68.326 -149.606)
		(width 0.12065)
		(layer "B.Cu")
		(net "EEPROM_SCL")
	)
	(segment
		(start 67.84213 -148.62937)
		(end 67.95516 -148.62937)
		(width 0.12065)
		(layer "B.Cu")
		(net "EEPROM_SCL")
	)
	(segment
		(start 73.61809 -149.39391)
		(end 72.005952 -149.39391)
		(width 0.12065)
		(layer "F.Cu")
		(net "EEPROM_A2_R")
	)
	(segment
		(start 74.736452 -149.52091)
		(end 73.74509 -149.52091)
		(width 0.12065)
		(layer "F.Cu")
		(net "EEPROM_A2_R")
	)
	(segment
		(start 73.74509 -149.52091)
		(end 73.61809 -149.39391)
		(width 0.12065)
		(layer "F.Cu")
		(net "EEPROM_A2_R")
	)
	(via
		(at 72.543924 -149.395688)
		(size 0.7112)
		(drill 0.3556)
		(layers "F.Cu" "B.Cu")
		(net "EEPROM_A2_R")
	)
	(via
		(at 73.61809 -149.39391)
		(size 0.508)
		(drill 0.254)
		(layers "F.Cu" "B.Cu")
		(net "EEPROM_A2_R")
	)
	(segment
		(start 72.545702 -149.39391)
		(end 72.543924 -149.395688)
		(width 0.12065)
		(layer "B.Cu")
		(net "EEPROM_A2_R")
	)
	(segment
		(start 73.61809 -149.39391)
		(end 72.545702 -149.39391)
		(width 0.12065)
		(layer "B.Cu")
		(net "EEPROM_A2_R")
	)
	(segment
		(start 74.7395 -149.479)
		(end 73.70318 -149.479)
		(width 0.12065)
		(layer "B.Cu")
		(net "EEPROM_A2_R")
	)
	(segment
		(start 73.70318 -149.479)
		(end 73.61809 -149.39391)
		(width 0.12065)
		(layer "B.Cu")
		(net "EEPROM_A2_R")
	)
	(segment
		(start 219.7735 -8.128)
		(end 220.488002 -8.842502)
		(width 0.12065)
		(layer "F.Cu")
		(net "EEPROM_A2")
	)
	(segment
		(start 219.7735 -7.112)
		(end 219.7735 -8.128)
		(width 0.12065)
		(layer "F.Cu")
		(net "EEPROM_A2")
	)
	(segment
		(start 220.488002 -8.842502)
		(end 220.774768 -8.842502)
		(width 0.12065)
		(layer "F.Cu")
		(net "EEPROM_A2")
	)
	(segment
		(start 221.077282 -9.144)
		(end 220.776546 -8.843264)
		(width 0.12065)
		(layer "F.Cu")
		(net "EEPROM_A2")
	)
	(segment
		(start 220.774768 -8.842502)
		(end 220.77553 -8.843264)
		(width 0.12065)
		(layer "F.Cu")
		(net "EEPROM_A2")
	)
	(segment
		(start 220.776546 -8.843264)
		(end 220.77553 -8.843264)
		(width 0.12065)
		(layer "F.Cu")
		(net "EEPROM_A2")
	)
	(segment
		(start 222.25 -9.144)
		(end 221.077282 -9.144)
		(width 0.12065)
		(layer "F.Cu")
		(net "EEPROM_A2")
	)
	(via
		(at 220.77553 -8.843264)
		(size 0.7112)
		(drill 0.3556)
		(layers "F.Cu" "B.Cu")
		(net "EEPROM_A2")
	)
	(segment
		(start 73.61809 -148.12391)
		(end 72.005952 -148.12391)
		(width 0.12065)
		(layer "F.Cu")
		(net "EEPROM_A1_R")
	)
	(segment
		(start 74.736452 -148.12391)
		(end 73.61809 -148.12391)
		(width 0.12065)
		(layer "F.Cu")
		(net "EEPROM_A1_R")
	)
	(via
		(at 72.6186 -148.12391)
		(size 0.7112)
		(drill 0.3556)
		(layers "F.Cu" "B.Cu")
		(net "EEPROM_A1_R")
	)
	(via
		(at 73.61809 -148.12391)
		(size 0.508)
		(drill 0.254)
		(layers "F.Cu" "B.Cu")
		(net "EEPROM_A1_R")
	)
	(segment
		(start 73.61809 -148.12391)
		(end 72.6186 -148.12391)
		(width 0.12065)
		(layer "B.Cu")
		(net "EEPROM_A1_R")
	)
	(segment
		(start 74.7395 -148.082)
		(end 73.66 -148.082)
		(width 0.12065)
		(layer "B.Cu")
		(net "EEPROM_A1_R")
	)
	(segment
		(start 73.66 -148.082)
		(end 73.61809 -148.12391)
		(width 0.12065)
		(layer "B.Cu")
		(net "EEPROM_A1_R")
	)
	(segment
		(start 220.813376 -10.136886)
		(end 220.7895 -10.136886)
		(width 0.12065)
		(layer "F.Cu")
		(net "EEPROM_A1")
	)
	(segment
		(start 219.7735 -10.16)
		(end 220.766386 -10.16)
		(width 0.12065)
		(layer "F.Cu")
		(net "EEPROM_A1")
	)
	(segment
		(start 221.09049 -10.414)
		(end 220.813376 -10.136886)
		(width 0.12065)
		(layer "F.Cu")
		(net "EEPROM_A1")
	)
	(segment
		(start 222.25 -10.414)
		(end 221.09049 -10.414)
		(width 0.12065)
		(layer "F.Cu")
		(net "EEPROM_A1")
	)
	(segment
		(start 219.7735 -9.144)
		(end 219.7735 -10.16)
		(width 0.12065)
		(layer "F.Cu")
		(net "EEPROM_A1")
	)
	(segment
		(start 220.766386 -10.16)
		(end 220.7895 -10.136886)
		(width 0.12065)
		(layer "F.Cu")
		(net "EEPROM_A1")
	)
	(via
		(at 220.7895 -10.136886)
		(size 0.7112)
		(drill 0.3556)
		(layers "F.Cu" "B.Cu")
		(net "EEPROM_A1")
	)
	(segment
		(start 73.66 -146.85391)
		(end 72.005952 -146.85391)
		(width 0.12065)
		(layer "F.Cu")
		(net "EEPROM_A0_R")
	)
	(segment
		(start 74.736452 -146.85391)
		(end 73.66 -146.85391)
		(width 0.12065)
		(layer "F.Cu")
		(net "EEPROM_A0_R")
	)
	(via
		(at 73.66 -146.85391)
		(size 0.508)
		(drill 0.254)
		(layers "F.Cu" "B.Cu")
		(net "EEPROM_A0_R")
	)
	(via
		(at 72.5678 -146.85391)
		(size 0.7112)
		(drill 0.3556)
		(layers "F.Cu" "B.Cu")
		(net "EEPROM_A0_R")
	)
	(segment
		(start 73.66 -146.85391)
		(end 72.5678 -146.85391)
		(width 0.12065)
		(layer "B.Cu")
		(net "EEPROM_A0_R")
	)
	(segment
		(start 74.7395 -146.939)
		(end 73.74509 -146.939)
		(width 0.12065)
		(layer "B.Cu")
		(net "EEPROM_A0_R")
	)
	(segment
		(start 73.74509 -146.939)
		(end 73.66 -146.85391)
		(width 0.12065)
		(layer "B.Cu")
		(net "EEPROM_A0_R")
	)
	(segment
		(start 219.845382 -11.197336)
		(end 219.858082 -11.184636)
		(width 0.12065)
		(layer "F.Cu")
		(net "EEPROM_A0")
	)
	(segment
		(start 219.8878 -12.3063)
		(end 219.8878 -11.852148)
		(width 0.12065)
		(layer "F.Cu")
		(net "EEPROM_A0")
	)
	(segment
		(start 219.8878 -11.852148)
		(end 219.858082 -11.82243)
		(width 0.12065)
		(layer "F.Cu")
		(net "EEPROM_A0")
	)
	(segment
		(start 222.25 -11.684)
		(end 222.0976 -11.5316)
		(width 0.12065)
		(layer "F.Cu")
		(net "EEPROM_A0")
	)
	(segment
		(start 219.845382 -11.651488)
		(end 219.845382 -11.197336)
		(width 0.12065)
		(layer "F.Cu")
		(net "EEPROM_A0")
	)
	(segment
		(start 220.7895 -11.5316)
		(end 220.0021 -12.319)
		(width 0.12065)
		(layer "F.Cu")
		(net "EEPROM_A0")
	)
	(segment
		(start 219.858082 -11.664188)
		(end 219.845382 -11.651488)
		(width 0.12065)
		(layer "F.Cu")
		(net "EEPROM_A0")
	)
	(segment
		(start 220.0021 -12.319)
		(end 219.9005 -12.319)
		(width 0.12065)
		(layer "F.Cu")
		(net "EEPROM_A0")
	)
	(segment
		(start 222.0976 -11.5316)
		(end 220.7895 -11.5316)
		(width 0.12065)
		(layer "F.Cu")
		(net "EEPROM_A0")
	)
	(segment
		(start 219.858082 -11.82243)
		(end 219.858082 -11.664188)
		(width 0.12065)
		(layer "F.Cu")
		(net "EEPROM_A0")
	)
	(segment
		(start 219.9005 -12.319)
		(end 219.8878 -12.3063)
		(width 0.12065)
		(layer "F.Cu")
		(net "EEPROM_A0")
	)
	(via
		(at 220.7895 -11.5316)
		(size 0.7112)
		(drill 0.3556)
		(layers "F.Cu" "B.Cu")
		(net "EEPROM_A0")
	)
	(segment
		(start 240.599976 -40.999918)
		(end 241.099848 -40.500046)
		(width 0.4572)
		(layer "F.Cu")
		(net "DUT_VDDO_REF")
	)
	(segment
		(start 238.59998 -32.999934)
		(end 238.100108 -32.500062)
		(width 0.4572)
		(layer "F.Cu")
		(net "DUT_VDDO_REF")
	)
	(segment
		(start 246.599964 -40.999918)
		(end 247.099836 -40.500046)
		(width 0.4572)
		(layer "F.Cu")
		(net "DUT_VDDO_REF")
	)
	(segment
		(start 241.599974 -38.999922)
		(end 242.099846 -38.50005)
		(width 0.4572)
		(layer "F.Cu")
		(net "DUT_VDDO_REF")
	)
	(segment
		(start 238.59998 -35.999928)
		(end 238.100108 -35.500056)
		(width 0.4572)
		(layer "F.Cu")
		(net "DUT_VDDO_REF")
	)
	(via
		(at 247.099836 -40.500046)
		(size 0.4572)
		(drill 0.2032)
		(layers "F.Cu" "B.Cu")
		(net "DUT_VDDO_REF")
	)
	(via
		(at 236.083856 -12.55268)
		(size 0.7112)
		(drill 0.4064)
		(layers "F.Cu" "B.Cu")
		(net "DUT_VDDO_REF")
	)
	(via
		(at 238.100108 -35.500056)
		(size 0.4572)
		(drill 0.2032)
		(layers "F.Cu" "B.Cu")
		(net "DUT_VDDO_REF")
	)
	(via
		(at 234.0102 -18.9738)
		(size 0.7112)
		(drill 0.4064)
		(layers "F.Cu" "B.Cu")
		(net "DUT_VDDO_REF")
	)
	(via
		(at 242.099846 -38.50005)
		(size 0.4572)
		(drill 0.2032)
		(layers "F.Cu" "B.Cu")
		(net "DUT_VDDO_REF")
	)
	(via
		(at 238.100108 -32.500062)
		(size 0.4572)
		(drill 0.2032)
		(layers "F.Cu" "B.Cu")
		(net "DUT_VDDO_REF")
	)
	(via
		(at 234.955588 -10.898886)
		(size 0.7112)
		(drill 0.4064)
		(layers "F.Cu" "B.Cu")
		(net "DUT_VDDO_REF")
	)
	(via
		(at 235.0262 -11.9634)
		(size 0.7112)
		(drill 0.3556)
		(layers "F.Cu" "B.Cu")
		(net "DUT_VDDO_REF")
	)
	(via
		(at 236.147102 -11.391646)
		(size 0.7112)
		(drill 0.4064)
		(layers "F.Cu" "B.Cu")
		(net "DUT_VDDO_REF")
	)
	(via
		(at 241.099848 -40.500046)
		(size 0.4572)
		(drill 0.2032)
		(layers "F.Cu" "B.Cu")
		(net "DUT_VDDO_REF")
	)
	(via
		(at 233.1974 -18.2626)
		(size 0.7112)
		(drill 0.4064)
		(layers "F.Cu" "B.Cu")
		(net "DUT_VDDO_REF")
	)
	(segment
		(start 241.036602 -40.4368)
		(end 241.099848 -40.500046)
		(width 0.3048)
		(layer "B.Cu")
		(net "DUT_VDDO_REF")
	)
	(segment
		(start 237.8202 -32.77997)
		(end 238.100108 -32.500062)
		(width 0.3048)
		(layer "B.Cu")
		(net "DUT_VDDO_REF")
	)
	(segment
		(start 238.3028 -35.702748)
		(end 238.100108 -35.500056)
		(width 0.3048)
		(layer "B.Cu")
		(net "DUT_VDDO_REF")
	)
	(segment
		(start 237.8202 -32.9946)
		(end 237.8202 -32.77997)
		(width 0.3048)
		(layer "B.Cu")
		(net "DUT_VDDO_REF")
	)
	(segment
		(start 238.3028 -35.9918)
		(end 238.3028 -35.702748)
		(width 0.3048)
		(layer "B.Cu")
		(net "DUT_VDDO_REF")
	)
	(segment
		(start 241.598196 -37.9984)
		(end 242.099846 -38.50005)
		(width 0.3048)
		(layer "B.Cu")
		(net "DUT_VDDO_REF")
	)
	(segment
		(start 240.3856 -40.4368)
		(end 241.036602 -40.4368)
		(width 0.3048)
		(layer "B.Cu")
		(net "DUT_VDDO_REF")
	)
	(segment
		(start 241.554 -37.9984)
		(end 241.598196 -37.9984)
		(width 0.3048)
		(layer "B.Cu")
		(net "DUT_VDDO_REF")
	)
	(segment
		(start 206.190596 -14.557756)
		(end 206.190596 -16.919448)
		(width 0.508)
		(layer "F.Cu")
		(net "DUT_VDDO")
	)
	(segment
		(start 142.959582 -52.264818)
		(end 142.638018 -52.264818)
		(width 0.508)
		(layer "F.Cu")
		(net "DUT_VDDO")
	)
	(segment
		(start 235.599986 -38.999922)
		(end 235.100114 -38.50005)
		(width 0.4572)
		(layer "F.Cu")
		(net "DUT_VDDO")
	)
	(segment
		(start 145.1356 -40.9575)
		(end 146.177 -40.9575)
		(width 0.508)
		(layer "F.Cu")
		(net "DUT_VDDO")
	)
	(segment
		(start 216.1794 -2.3114)
		(end 217.0176 -3.1496)
		(width 0.508)
		(layer "F.Cu")
		(net "DUT_VDDO")
	)
	(segment
		(start 248.59996 -32.999934)
		(end 249.099832 -32.500062)
		(width 0.4572)
		(layer "F.Cu")
		(net "DUT_VDDO")
	)
	(segment
		(start 147.0152 -83.4898)
		(end 147.0152 -83.192366)
		(width 0.3048)
		(layer "F.Cu")
		(net "DUT_VDDO")
	)
	(segment
		(start 236.599984 -32.999934)
		(end 236.100112 -32.500062)
		(width 0.4572)
		(layer "F.Cu")
		(net "DUT_VDDO")
	)
	(segment
		(start 210.27644 -26.81732)
		(end 210.26374 -26.83002)
		(width 0.508)
		(layer "F.Cu")
		(net "DUT_VDDO")
	)
	(segment
		(start 142.9639 -52.2605)
		(end 142.959582 -52.264818)
		(width 0.508)
		(layer "F.Cu")
		(net "DUT_VDDO")
	)
	(segment
		(start 244.599968 -40.999918)
		(end 245.09984 -40.500046)
		(width 0.4572)
		(layer "F.Cu")
		(net "DUT_VDDO")
	)
	(segment
		(start 325.9582 -75.7936)
		(end 325.9582 -76.9366)
		(width 0.508)
		(layer "F.Cu")
		(net "DUT_VDDO")
	)
	(segment
		(start 147.53971 -41.29151)
		(end 147.1803 -40.9321)
		(width 0.508)
		(layer "F.Cu")
		(net "DUT_VDDO")
	)
	(segment
		(start 153.162 -48.44034)
		(end 153.162 -52.7431)
		(width 0.508)
		(layer "F.Cu")
		(net "DUT_VDDO")
	)
	(segment
		(start 210.26374 -23.14067)
		(end 210.26374 -26.15692)
		(width 0.508)
		(layer "F.Cu")
		(net "DUT_VDDO")
	)
	(segment
		(start 151.216868 -54.688232)
		(end 150.676102 -54.688232)
		(width 0.508)
		(layer "F.Cu")
		(net "DUT_VDDO")
	)
	(segment
		(start 147.271994 -45.593)
		(end 147.271994 -43.628818)
		(width 0.508)
		(layer "F.Cu")
		(net "DUT_VDDO")
	)
	(segment
		(start 234.599988 -32.999934)
		(end 234.100116 -32.500062)
		(width 0.4572)
		(layer "F.Cu")
		(net "DUT_VDDO")
	)
	(segment
		(start 132.816346 -59.305698)
		(end 131.470146 -59.305698)
		(width 0.508)
		(layer "F.Cu")
		(net "DUT_VDDO")
	)
	(segment
		(start 250.41352 -15.862046)
		(end 249.304556 -16.97101)
		(width 0.508)
		(layer "F.Cu")
		(net "DUT_VDDO")
	)
	(segment
		(start 232.599992 -35.999928)
		(end 232.10012 -35.500056)
		(width 0.4572)
		(layer "F.Cu")
		(net "DUT_VDDO")
	)
	(segment
		(start 216.77122 -13.24864)
		(end 217.043 -12.97686)
		(width 0.508)
		(layer "F.Cu")
		(net "DUT_VDDO")
	)
	(segment
		(start 131.470146 -59.305698)
		(end 131.470146 -58.333132)
		(width 0.508)
		(layer "F.Cu")
		(net "DUT_VDDO")
	)
	(segment
		(start 216.37498 -13.24864)
		(end 216.77122 -13.24864)
		(width 0.508)
		(layer "F.Cu")
		(net "DUT_VDDO")
	)
	(segment
		(start 208.39811 -19.217386)
		(end 208.39811 -21.27504)
		(width 0.508)
		(layer "F.Cu")
		(net "DUT_VDDO")
	)
	(segment
		(start 138.8872 -41.5163)
		(end 139.3698 -41.0337)
		(width 0.508)
		(layer "F.Cu")
		(net "DUT_VDDO")
	)
	(segment
		(start 246.599964 -32.999934)
		(end 247.099836 -32.500062)
		(width 0.4572)
		(layer "F.Cu")
		(net "DUT_VDDO")
	)
	(segment
		(start 242.599972 -35.999928)
		(end 243.099844 -35.500056)
		(width 0.4572)
		(layer "F.Cu")
		(net "DUT_VDDO")
	)
	(segment
		(start 139.3698 -41.0337)
		(end 139.8016 -41.0337)
		(width 0.508)
		(layer "F.Cu")
		(net "DUT_VDDO")
	)
	(segment
		(start 210.27644 -26.16962)
		(end 210.27644 -26.81732)
		(width 0.508)
		(layer "F.Cu")
		(net "DUT_VDDO")
	)
	(segment
		(start 215.8365 -12.5095)
		(end 215.623648 -12.722352)
		(width 0.2032)
		(layer "F.Cu")
		(net "DUT_VDDO")
	)
	(segment
		(start 153.162 -52.7431)
		(end 151.216868 -54.688232)
		(width 0.508)
		(layer "F.Cu")
		(net "DUT_VDDO")
	)
	(segment
		(start 232.599992 -32.999934)
		(end 232.10012 -32.500062)
		(width 0.4572)
		(layer "F.Cu")
		(net "DUT_VDDO")
	)
	(segment
		(start 133.140958 -73.96226)
		(end 133.140958 -73.52792)
		(width 0.508)
		(layer "F.Cu")
		(net "DUT_VDDO")
	)
	(segment
		(start 217.0176 -3.1496)
		(end 217.0176 -3.6195)
		(width 0.508)
		(layer "F.Cu")
		(net "DUT_VDDO")
	)
	(segment
		(start 207.137 -3.683)
		(end 206.7306 -3.2766)
		(width 0.508)
		(layer "F.Cu")
		(net "DUT_VDDO")
	)
	(segment
		(start 245.69166 -16.97101)
		(end 245.66372 -16.94307)
		(width 0.508)
		(layer "F.Cu")
		(net "DUT_VDDO")
	)
	(segment
		(start 249.304556 -16.97101)
		(end 245.69166 -16.97101)
		(width 0.508)
		(layer "F.Cu")
		(net "DUT_VDDO")
	)
	(segment
		(start 134.6327 -42.11701)
		(end 135.03529 -42.5196)
		(width 0.508)
		(layer "F.Cu")
		(net "DUT_VDDO")
	)
	(segment
		(start 326.8218 -74.93)
		(end 325.9582 -75.7936)
		(width 0.508)
		(layer "F.Cu")
		(net "DUT_VDDO")
	)
	(segment
		(start 327.4695 -74.93)
		(end 326.8218 -74.93)
		(width 0.508)
		(layer "F.Cu")
		(net "DUT_VDDO")
	)
	(segment
		(start 207.137 -4.3307)
		(end 207.137 -3.683)
		(width 0.508)
		(layer "F.Cu")
		(net "DUT_VDDO")
	)
	(segment
		(start 217.043 -12.5095)
		(end 215.8365 -12.5095)
		(width 0.2032)
		(layer "F.Cu")
		(net "DUT_VDDO")
	)
	(segment
		(start 147.1803 -40.9321)
		(end 146.2024 -40.9321)
		(width 0.508)
		(layer "F.Cu")
		(net "DUT_VDDO")
	)
	(segment
		(start 144.0688 -40.9575)
		(end 145.1356 -40.9575)
		(width 0.508)
		(layer "F.Cu")
		(net "DUT_VDDO")
	)
	(segment
		(start 217.043 -12.97686)
		(end 217.043 -12.5095)
		(width 0.508)
		(layer "F.Cu")
		(net "DUT_VDDO")
	)
	(segment
		(start 204.762608 -13.129768)
		(end 206.190596 -14.557756)
		(width 0.508)
		(layer "F.Cu")
		(net "DUT_VDDO")
	)
	(segment
		(start 244.599968 -32.999934)
		(end 245.09984 -32.500062)
		(width 0.4572)
		(layer "F.Cu")
		(net "DUT_VDDO")
	)
	(segment
		(start 137.586974 -74.809604)
		(end 137.586974 -75.685904)
		(width 0.508)
		(layer "F.Cu")
		(net "DUT_VDDO")
	)
	(segment
		(start 238.59998 -40.999918)
		(end 238.100108 -40.500046)
		(width 0.4572)
		(layer "F.Cu")
		(net "DUT_VDDO")
	)
	(segment
		(start 250.41352 -12.848844)
		(end 250.41352 -15.862046)
		(width 0.508)
		(layer "F.Cu")
		(net "DUT_VDDO")
	)
	(segment
		(start 206.190596 -16.919448)
		(end 206.355696 -17.174972)
		(width 0.508)
		(layer "F.Cu")
		(net "DUT_VDDO")
	)
	(segment
		(start 144.8054 -52.2605)
		(end 142.9639 -52.2605)
		(width 0.508)
		(layer "F.Cu")
		(net "DUT_VDDO")
	)
	(segment
		(start 147.271994 -43.628818)
		(end 147.53971 -43.361102)
		(width 0.508)
		(layer "F.Cu")
		(net "DUT_VDDO")
	)
	(segment
		(start 135.85825 -41.519602)
		(end 135.85825 -42.29735)
		(width 0.508)
		(layer "F.Cu")
		(net "DUT_VDDO")
	)
	(segment
		(start 146.2532 -83.4898)
		(end 146.2532 -83.192366)
		(width 0.3048)
		(layer "F.Cu")
		(net "DUT_VDDO")
	)
	(segment
		(start 230.599996 -32.999934)
		(end 230.100124 -32.500062)
		(width 0.4572)
		(layer "F.Cu")
		(net "DUT_VDDO")
	)
	(segment
		(start 242.599972 -40.999918)
		(end 243.099844 -40.500046)
		(width 0.4572)
		(layer "F.Cu")
		(net "DUT_VDDO")
	)
	(segment
		(start 147.53971 -43.361102)
		(end 147.53971 -41.29151)
		(width 0.508)
		(layer "F.Cu")
		(net "DUT_VDDO")
	)
	(segment
		(start 146.177 -40.9575)
		(end 146.2024 -40.9321)
		(width 0.508)
		(layer "F.Cu")
		(net "DUT_VDDO")
	)
	(segment
		(start 133.140958 -73.52792)
		(end 133.573774 -73.095104)
		(width 0.508)
		(layer "F.Cu")
		(net "DUT_VDDO")
	)
	(segment
		(start 245.599966 -38.999922)
		(end 246.099838 -38.50005)
		(width 0.4572)
		(layer "F.Cu")
		(net "DUT_VDDO")
	)
	(segment
		(start 206.355696 -17.174972)
		(end 208.39811 -19.217386)
		(width 0.508)
		(layer "F.Cu")
		(net "DUT_VDDO")
	)
	(segment
		(start 242.599972 -32.999934)
		(end 243.099844 -32.500062)
		(width 0.4572)
		(layer "F.Cu")
		(net "DUT_VDDO")
	)
	(segment
		(start 134.932928 -59.302396)
		(end 134.932928 -58.401458)
		(width 0.508)
		(layer "F.Cu")
		(net "DUT_VDDO")
	)
	(segment
		(start 135.03529 -42.5196)
		(end 135.636 -42.5196)
		(width 0.508)
		(layer "F.Cu")
		(net "DUT_VDDO")
	)
	(segment
		(start 210.26374 -26.15692)
		(end 210.27644 -26.16962)
		(width 0.508)
		(layer "F.Cu")
		(net "DUT_VDDO")
	)
	(segment
		(start 208.39811 -21.27504)
		(end 210.26374 -23.14067)
		(width 0.508)
		(layer "F.Cu")
		(net "DUT_VDDO")
	)
	(segment
		(start 135.85825 -42.29735)
		(end 135.636 -42.5196)
		(width 0.508)
		(layer "F.Cu")
		(net "DUT_VDDO")
	)
	(segment
		(start 248.59996 -35.999928)
		(end 249.099832 -35.500056)
		(width 0.4572)
		(layer "F.Cu")
		(net "DUT_VDDO")
	)
	(segment
		(start 215.623648 -12.722352)
		(end 215.623648 -13.1064)
		(width 0.2032)
		(layer "F.Cu")
		(net "DUT_VDDO")
	)
	(via
		(at 137.586974 -75.685904)
		(size 0.508)
		(drill 0.254)
		(layers "F.Cu" "B.Cu")
		(net "DUT_VDDO")
	)
	(via
		(at 238.100108 -40.500046)
		(size 0.4572)
		(drill 0.2032)
		(layers "F.Cu" "B.Cu")
		(net "DUT_VDDO")
	)
	(via
		(at 250.41352 -10.588244)
		(size 0.7112)
		(drill 0.4064)
		(layers "F.Cu" "B.Cu")
		(net "DUT_VDDO")
	)
	(via
		(at 234.100116 -32.500062)
		(size 0.4572)
		(drill 0.2032)
		(layers "F.Cu" "B.Cu")
		(net "DUT_VDDO")
	)
	(via
		(at 136.349486 -75.892406)
		(size 0.7112)
		(drill 0.4064)
		(layers "F.Cu" "B.Cu")
		(net "DUT_VDDO")
	)
	(via
		(at 135.636 -42.5196)
		(size 0.508)
		(drill 0.254)
		(layers "F.Cu" "B.Cu")
		(net "DUT_VDDO")
	)
	(via
		(at 153.162 -48.44034)
		(size 0.508)
		(drill 0.254)
		(layers "F.Cu" "B.Cu")
		(net "DUT_VDDO")
	)
	(via
		(at 216.37498 -13.24864)
		(size 0.508)
		(drill 0.254)
		(layers "F.Cu" "B.Cu")
		(net "DUT_VDDO")
	)
	(via
		(at 249.099832 -35.500056)
		(size 0.4572)
		(drill 0.2032)
		(layers "F.Cu" "B.Cu")
		(net "DUT_VDDO")
	)
	(via
		(at 245.66372 -16.94307)
		(size 0.508)
		(drill 0.254)
		(layers "F.Cu" "B.Cu")
		(net "DUT_VDDO")
	)
	(via
		(at 142.638018 -52.264818)
		(size 0.508)
		(drill 0.254)
		(layers "F.Cu" "B.Cu")
		(net "DUT_VDDO")
	)
	(via
		(at 204.762608 -13.129768)
		(size 0.508)
		(drill 0.254)
		(layers "F.Cu" "B.Cu")
		(net "DUT_VDDO")
	)
	(via
		(at 243.099844 -35.500056)
		(size 0.4572)
		(drill 0.2032)
		(layers "F.Cu" "B.Cu")
		(net "DUT_VDDO")
	)
	(via
		(at 147.271994 -45.593)
		(size 0.508)
		(drill 0.254)
		(layers "F.Cu" "B.Cu")
		(net "DUT_VDDO")
	)
	(via
		(at 325.9582 -76.9366)
		(size 0.508)
		(drill 0.254)
		(layers "F.Cu" "B.Cu")
		(net "DUT_VDDO")
	)
	(via
		(at 248.92 -11.176)
		(size 0.7112)
		(drill 0.3556)
		(layers "F.Cu" "B.Cu")
		(net "DUT_VDDO")
	)
	(via
		(at 243.099844 -32.500062)
		(size 0.4572)
		(drill 0.2032)
		(layers "F.Cu" "B.Cu")
		(net "DUT_VDDO")
	)
	(via
		(at 235.100114 -38.50005)
		(size 0.4572)
		(drill 0.2032)
		(layers "F.Cu" "B.Cu")
		(net "DUT_VDDO")
	)
	(via
		(at 249.099832 -32.500062)
		(size 0.4572)
		(drill 0.2032)
		(layers "F.Cu" "B.Cu")
		(net "DUT_VDDO")
	)
	(via
		(at 245.09984 -40.500046)
		(size 0.4572)
		(drill 0.2032)
		(layers "F.Cu" "B.Cu")
		(net "DUT_VDDO")
	)
	(via
		(at 131.470146 -58.333132)
		(size 0.508)
		(drill 0.254)
		(layers "F.Cu" "B.Cu")
		(net "DUT_VDDO")
	)
	(via
		(at 216.1794 -2.3114)
		(size 0.508)
		(drill 0.254)
		(layers "F.Cu" "B.Cu")
		(net "DUT_VDDO")
	)
	(via
		(at 132.903468 -49.83353)
		(size 0.7112)
		(drill 0.3556)
		(layers "F.Cu" "B.Cu")
		(net "DUT_VDDO")
	)
	(via
		(at 145.1864 -82.3976)
		(size 0.7112)
		(drill 0.3556)
		(layers "F.Cu" "B.Cu")
		(net "DUT_VDDO")
	)
	(via
		(at 136.164574 -77.311504)
		(size 0.7112)
		(drill 0.4064)
		(layers "F.Cu" "B.Cu")
		(net "DUT_VDDO")
	)
	(via
		(at 243.099844 -40.500046)
		(size 0.4572)
		(drill 0.2032)
		(layers "F.Cu" "B.Cu")
		(net "DUT_VDDO")
	)
	(via
		(at 133.573774 -73.095104)
		(size 0.508)
		(drill 0.254)
		(layers "F.Cu" "B.Cu")
		(net "DUT_VDDO")
	)
	(via
		(at 236.100112 -32.500062)
		(size 0.4572)
		(drill 0.2032)
		(layers "F.Cu" "B.Cu")
		(net "DUT_VDDO")
	)
	(via
		(at 246.099838 -38.50005)
		(size 0.4572)
		(drill 0.2032)
		(layers "F.Cu" "B.Cu")
		(net "DUT_VDDO")
	)
	(via
		(at 245.09984 -32.500062)
		(size 0.4572)
		(drill 0.2032)
		(layers "F.Cu" "B.Cu")
		(net "DUT_VDDO")
	)
	(via
		(at 138.783314 -53.014372)
		(size 0.7112)
		(drill 0.3556)
		(layers "F.Cu" "B.Cu")
		(net "DUT_VDDO")
	)
	(via
		(at 138.8872 -41.5163)
		(size 0.508)
		(drill 0.254)
		(layers "F.Cu" "B.Cu")
		(net "DUT_VDDO")
	)
	(via
		(at 134.932928 -58.401458)
		(size 0.508)
		(drill 0.254)
		(layers "F.Cu" "B.Cu")
		(net "DUT_VDDO")
	)
	(via
		(at 206.7306 -3.2766)
		(size 0.508)
		(drill 0.254)
		(layers "F.Cu" "B.Cu")
		(net "DUT_VDDO")
	)
	(via
		(at 141.707616 -83.08721)
		(size 0.7112)
		(drill 0.4064)
		(layers "F.Cu" "B.Cu")
		(net "DUT_VDDO")
	)
	(via
		(at 247.099836 -32.500062)
		(size 0.4572)
		(drill 0.2032)
		(layers "F.Cu" "B.Cu")
		(net "DUT_VDDO")
	)
	(via
		(at 232.10012 -35.500056)
		(size 0.4572)
		(drill 0.2032)
		(layers "F.Cu" "B.Cu")
		(net "DUT_VDDO")
	)
	(via
		(at 250.41352 -11.705844)
		(size 0.7112)
		(drill 0.4064)
		(layers "F.Cu" "B.Cu")
		(net "DUT_VDDO")
	)
	(via
		(at 230.100124 -32.500062)
		(size 0.4572)
		(drill 0.2032)
		(layers "F.Cu" "B.Cu")
		(net "DUT_VDDO")
	)
	(via
		(at 250.41352 -12.848844)
		(size 0.7112)
		(drill 0.4064)
		(layers "F.Cu" "B.Cu")
		(net "DUT_VDDO")
	)
	(via
		(at 232.10012 -32.500062)
		(size 0.4572)
		(drill 0.2032)
		(layers "F.Cu" "B.Cu")
		(net "DUT_VDDO")
	)
	(segment
		(start 215.032082 -17.250918)
		(end 214.42299 -17.86001)
		(width 0.508)
		(layer "B.Cu")
		(net "DUT_VDDO")
	)
	(segment
		(start 324.5358 -78.359)
		(end 325.9582 -76.9366)
		(width 0.508)
		(layer "B.Cu")
		(net "DUT_VDDO")
	)
	(segment
		(start 225.679 -20.0025)
		(end 226.822 -20.0025)
		(width 0.508)
		(layer "B.Cu")
		(net "DUT_VDDO")
	)
	(segment
		(start 246.555768 -16.94307)
		(end 249.590052 -19.977354)
		(width 0.508)
		(layer "B.Cu")
		(net "DUT_VDDO")
	)
	(segment
		(start 214.42299 -19.26209)
		(end 216.5096 -21.3487)
		(width 0.508)
		(layer "B.Cu")
		(net "DUT_VDDO")
	)
	(segment
		(start 238.3409 -40.259254)
		(end 238.100108 -40.500046)
		(width 0.3048)
		(layer "B.Cu")
		(net "DUT_VDDO")
	)
	(segment
		(start 239.395 -20.0025)
		(end 240.538 -20.0025)
		(width 0.508)
		(layer "B.Cu")
		(net "DUT_VDDO")
	)
	(segment
		(start 221.234 -19.812)
		(end 218.672918 -17.250918)
		(width 0.508)
		(layer "B.Cu")
		(net "DUT_VDDO")
	)
	(segment
		(start 230.6066 -32.258)
		(end 230.342186 -32.258)
		(width 0.3048)
		(layer "B.Cu")
		(net "DUT_VDDO")
	)
	(segment
		(start 231.6226 -35.0012)
		(end 231.6226 -35.022536)
		(width 0.3048)
		(layer "B.Cu")
		(net "DUT_VDDO")
	)
	(segment
		(start 249.316494 -32.2834)
		(end 249.099832 -32.500062)
		(width 0.3048)
		(layer "B.Cu")
		(net "DUT_VDDO")
	)
	(segment
		(start 234.823 -20.0025)
		(end 235.966 -20.0025)
		(width 0.508)
		(layer "B.Cu")
		(net "DUT_VDDO")
	)
	(segment
		(start 214.42299 -17.86001)
		(end 214.42299 -19.26209)
		(width 0.508)
		(layer "B.Cu")
		(net "DUT_VDDO")
	)
	(segment
		(start 231.394 -20.0025)
		(end 232.537 -20.0025)
		(width 0.508)
		(layer "B.Cu")
		(net "DUT_VDDO")
	)
	(segment
		(start 233.68 -20.0025)
		(end 232.537 -20.0025)
		(width 0.508)
		(layer "B.Cu")
		(net "DUT_VDDO")
	)
	(segment
		(start 214.63 -0.762)
		(end 216.1794 -2.3114)
		(width 0.508)
		(layer "B.Cu")
		(net "DUT_VDDO")
	)
	(segment
		(start 267.373354 -19.977354)
		(end 270.3322 -22.9362)
		(width 0.508)
		(layer "B.Cu")
		(net "DUT_VDDO")
	)
	(segment
		(start 234.342178 -32.258)
		(end 234.100116 -32.500062)
		(width 0.3048)
		(layer "B.Cu")
		(net "DUT_VDDO")
	)
	(segment
		(start 232.342182 -32.258)
		(end 232.10012 -32.500062)
		(width 0.3048)
		(layer "B.Cu")
		(net "DUT_VDDO")
	)
	(segment
		(start 207.4164 -0.762)
		(end 214.63 -0.762)
		(width 0.508)
		(layer "B.Cu")
		(net "DUT_VDDO")
	)
	(segment
		(start 211.5312 -10.8204)
		(end 206.856076 -6.145276)
		(width 0.508)
		(layer "B.Cu")
		(net "DUT_VDDO")
	)
	(segment
		(start 229.108 -20.0025)
		(end 230.251 -20.0025)
		(width 0.508)
		(layer "B.Cu")
		(net "DUT_VDDO")
	)
	(segment
		(start 240.538 -20.0025)
		(end 241.681 -20.0025)
		(width 0.508)
		(layer "B.Cu")
		(net "DUT_VDDO")
	)
	(segment
		(start 206.8576 -3.1496)
		(end 206.8576 -1.3208)
		(width 0.508)
		(layer "B.Cu")
		(net "DUT_VDDO")
	)
	(segment
		(start 238.252 -20.0025)
		(end 239.395 -20.0025)
		(width 0.508)
		(layer "B.Cu")
		(net "DUT_VDDO")
	)
	(segment
		(start 243.1796 -32.004)
		(end 243.1796 -32.420306)
		(width 0.3048)
		(layer "B.Cu")
		(net "DUT_VDDO")
	)
	(segment
		(start 221.234 -20.0025)
		(end 221.234 -19.812)
		(width 0.508)
		(layer "B.Cu")
		(net "DUT_VDDO")
	)
	(segment
		(start 245.316502 -32.2834)
		(end 245.09984 -32.500062)
		(width 0.3048)
		(layer "B.Cu")
		(net "DUT_VDDO")
	)
	(segment
		(start 236.342174 -32.258)
		(end 236.100112 -32.500062)
		(width 0.3048)
		(layer "B.Cu")
		(net "DUT_VDDO")
	)
	(segment
		(start 249.555 -35.0012)
		(end 249.555 -35.044888)
		(width 0.3048)
		(layer "B.Cu")
		(net "DUT_VDDO")
	)
	(segment
		(start 211.7598 -10.8204)
		(end 211.5312 -10.8204)
		(width 0.508)
		(layer "B.Cu")
		(net "DUT_VDDO")
	)
	(segment
		(start 224.536 -20.0025)
		(end 225.679 -20.0025)
		(width 0.508)
		(layer "B.Cu")
		(net "DUT_VDDO")
	)
	(segment
		(start 270.3322 -71.74484)
		(end 276.94636 -78.359)
		(width 0.508)
		(layer "B.Cu")
		(net "DUT_VDDO")
	)
	(segment
		(start 235.1659 -38.00348)
		(end 235.1659 -38.434264)
		(width 0.3048)
		(layer "B.Cu")
		(net "DUT_VDDO")
	)
	(segment
		(start 242.6208 -35.0012)
		(end 242.6208 -35.021012)
		(width 0.3048)
		(layer "B.Cu")
		(net "DUT_VDDO")
	)
	(segment
		(start 206.7306 -3.2766)
		(end 206.8576 -3.1496)
		(width 0.508)
		(layer "B.Cu")
		(net "DUT_VDDO")
	)
	(segment
		(start 249.612912 -32.2834)
		(end 249.316494 -32.2834)
		(width 0.3048)
		(layer "B.Cu")
		(net "DUT_VDDO")
	)
	(segment
		(start 227.965 -20.0025)
		(end 229.108 -20.0025)
		(width 0.508)
		(layer "B.Cu")
		(net "DUT_VDDO")
	)
	(segment
		(start 276.94636 -78.359)
		(end 324.5358 -78.359)
		(width 0.508)
		(layer "B.Cu")
		(net "DUT_VDDO")
	)
	(segment
		(start 238.3409 -40.005)
		(end 238.3409 -40.259254)
		(width 0.3048)
		(layer "B.Cu")
		(net "DUT_VDDO")
	)
	(segment
		(start 214.2236 -13.2842)
		(end 211.7598 -10.8204)
		(width 0.508)
		(layer "B.Cu")
		(net "DUT_VDDO")
	)
	(segment
		(start 245.4021 -19.095974)
		(end 245.4021 -17.20469)
		(width 0.508)
		(layer "B.Cu")
		(net "DUT_VDDO")
	)
	(segment
		(start 234.5944 -32.258)
		(end 234.342178 -32.258)
		(width 0.3048)
		(layer "B.Cu")
		(net "DUT_VDDO")
	)
	(segment
		(start 247.591072 -32.2834)
		(end 247.316498 -32.2834)
		(width 0.3048)
		(layer "B.Cu")
		(net "DUT_VDDO")
	)
	(segment
		(start 226.822 -20.0025)
		(end 227.965 -20.0025)
		(width 0.508)
		(layer "B.Cu")
		(net "DUT_VDDO")
	)
	(segment
		(start 232.611422 -32.258)
		(end 232.342182 -32.258)
		(width 0.3048)
		(layer "B.Cu")
		(net "DUT_VDDO")
	)
	(segment
		(start 235.1659 -38.434264)
		(end 235.100114 -38.50005)
		(width 0.3048)
		(layer "B.Cu")
		(net "DUT_VDDO")
	)
	(segment
		(start 206.8576 -1.3208)
		(end 207.4164 -0.762)
		(width 0.508)
		(layer "B.Cu")
		(net "DUT_VDDO")
	)
	(segment
		(start 231.394 -20.0025)
		(end 230.251 -20.0025)
		(width 0.508)
		(layer "B.Cu")
		(net "DUT_VDDO")
	)
	(segment
		(start 244.8687 -40.9956)
		(end 244.8687 -40.731186)
		(width 0.3048)
		(layer "B.Cu")
		(net "DUT_VDDO")
	)
	(segment
		(start 249.555 -35.044888)
		(end 249.099832 -35.500056)
		(width 0.3048)
		(layer "B.Cu")
		(net "DUT_VDDO")
	)
	(segment
		(start 230.342186 -32.258)
		(end 230.100124 -32.500062)
		(width 0.3048)
		(layer "B.Cu")
		(net "DUT_VDDO")
	)
	(segment
		(start 249.590052 -19.977354)
		(end 267.373354 -19.977354)
		(width 0.508)
		(layer "B.Cu")
		(net "DUT_VDDO")
	)
	(segment
		(start 206.856076 -6.145276)
		(end 206.856076 -3.402076)
		(width 0.508)
		(layer "B.Cu")
		(net "DUT_VDDO")
	)
	(segment
		(start 243.1796 -32.420306)
		(end 243.099844 -32.500062)
		(width 0.3048)
		(layer "B.Cu")
		(net "DUT_VDDO")
	)
	(segment
		(start 242.999514 -20.178014)
		(end 244.32006 -20.178014)
		(width 0.508)
		(layer "B.Cu")
		(net "DUT_VDDO")
	)
	(segment
		(start 247.316498 -32.2834)
		(end 247.099836 -32.500062)
		(width 0.3048)
		(layer "B.Cu")
		(net "DUT_VDDO")
	)
	(segment
		(start 223.393 -20.0025)
		(end 222.25 -20.0025)
		(width 0.508)
		(layer "B.Cu")
		(net "DUT_VDDO")
	)
	(segment
		(start 236.609128 -32.258)
		(end 236.342174 -32.258)
		(width 0.3048)
		(layer "B.Cu")
		(net "DUT_VDDO")
	)
	(segment
		(start 270.3322 -22.9362)
		(end 270.3322 -71.74484)
		(width 0.508)
		(layer "B.Cu")
		(net "DUT_VDDO")
	)
	(segment
		(start 244.8687 -40.731186)
		(end 245.09984 -40.500046)
		(width 0.3048)
		(layer "B.Cu")
		(net "DUT_VDDO")
	)
	(segment
		(start 238.252 -20.0025)
		(end 237.109 -20.0025)
		(width 0.508)
		(layer "B.Cu")
		(net "DUT_VDDO")
	)
	(segment
		(start 244.32006 -20.178014)
		(end 245.4021 -19.095974)
		(width 0.508)
		(layer "B.Cu")
		(net "DUT_VDDO")
	)
	(segment
		(start 242.824 -20.0025)
		(end 242.999514 -20.178014)
		(width 0.508)
		(layer "B.Cu")
		(net "DUT_VDDO")
	)
	(segment
		(start 241.681 -20.0025)
		(end 242.824 -20.0025)
		(width 0.508)
		(layer "B.Cu")
		(net "DUT_VDDO")
	)
	(segment
		(start 242.6208 -35.021012)
		(end 243.099844 -35.500056)
		(width 0.3048)
		(layer "B.Cu")
		(net "DUT_VDDO")
	)
	(segment
		(start 242.409472 -39.996872)
		(end 242.815872 -39.996872)
		(width 0.3048)
		(layer "B.Cu")
		(net "DUT_VDDO")
	)
	(segment
		(start 222.25 -20.0025)
		(end 221.234 -20.0025)
		(width 0.508)
		(layer "B.Cu")
		(net "DUT_VDDO")
	)
	(segment
		(start 233.68 -20.0025)
		(end 234.823 -20.0025)
		(width 0.508)
		(layer "B.Cu")
		(net "DUT_VDDO")
	)
	(segment
		(start 242.815872 -39.996872)
		(end 243.099844 -40.280844)
		(width 0.3048)
		(layer "B.Cu")
		(net "DUT_VDDO")
	)
	(segment
		(start 246.601488 -37.9984)
		(end 246.099838 -38.50005)
		(width 0.3048)
		(layer "B.Cu")
		(net "DUT_VDDO")
	)
	(segment
		(start 246.6086 -37.9984)
		(end 246.601488 -37.9984)
		(width 0.3048)
		(layer "B.Cu")
		(net "DUT_VDDO")
	)
	(segment
		(start 243.099844 -40.280844)
		(end 243.099844 -40.500046)
		(width 0.3048)
		(layer "B.Cu")
		(net "DUT_VDDO")
	)
	(segment
		(start 224.536 -20.0025)
		(end 223.393 -20.0025)
		(width 0.508)
		(layer "B.Cu")
		(net "DUT_VDDO")
	)
	(segment
		(start 231.6226 -35.022536)
		(end 232.10012 -35.500056)
		(width 0.3048)
		(layer "B.Cu")
		(net "DUT_VDDO")
	)
	(segment
		(start 245.66372 -16.94307)
		(end 246.555768 -16.94307)
		(width 0.508)
		(layer "B.Cu")
		(net "DUT_VDDO")
	)
	(segment
		(start 245.4021 -17.20469)
		(end 245.66372 -16.94307)
		(width 0.508)
		(layer "B.Cu")
		(net "DUT_VDDO")
	)
	(segment
		(start 235.966 -20.0025)
		(end 237.109 -20.0025)
		(width 0.508)
		(layer "B.Cu")
		(net "DUT_VDDO")
	)
	(segment
		(start 245.5926 -32.2834)
		(end 245.316502 -32.2834)
		(width 0.3048)
		(layer "B.Cu")
		(net "DUT_VDDO")
	)
	(segment
		(start 206.856076 -3.402076)
		(end 206.7306 -3.2766)
		(width 0.508)
		(layer "B.Cu")
		(net "DUT_VDDO")
	)
	(segment
		(start 218.672918 -17.250918)
		(end 215.032082 -17.250918)
		(width 0.508)
		(layer "B.Cu")
		(net "DUT_VDDO")
	)
	(segment
		(start 147.271994 -45.593)
		(end 145.894298 -45.593)
		(width 0.508)
		(layer "In2.Cu")
		(net "DUT_VDDO")
	)
	(segment
		(start 137.8839 -42.5196)
		(end 138.8872 -41.5163)
		(width 0.508)
		(layer "In2.Cu")
		(net "DUT_VDDO")
	)
	(segment
		(start 145.894298 -45.593)
		(end 143.709898 -43.4086)
		(width 0.508)
		(layer "In2.Cu")
		(net "DUT_VDDO")
	)
	(segment
		(start 141.450568 -43.4086)
		(end 139.558268 -41.5163)
		(width 0.508)
		(layer "In2.Cu")
		(net "DUT_VDDO")
	)
	(segment
		(start 139.558268 -41.5163)
		(end 138.8872 -41.5163)
		(width 0.508)
		(layer "In2.Cu")
		(net "DUT_VDDO")
	)
	(segment
		(start 143.709898 -43.4086)
		(end 141.450568 -43.4086)
		(width 0.508)
		(layer "In2.Cu")
		(net "DUT_VDDO")
	)
	(segment
		(start 135.636 -42.5196)
		(end 137.8839 -42.5196)
		(width 0.508)
		(layer "In2.Cu")
		(net "DUT_VDDO")
	)
	(segment
		(start 248.604532 -33.294828)
		(end 249.099832 -32.799528)
		(width 0.3048)
		(layer "In5.Cu")
		(net "DUT_VDDO")
	)
	(segment
		(start 249.099832 -32.799528)
		(end 249.099832 -32.500062)
		(width 0.3048)
		(layer "In5.Cu")
		(net "DUT_VDDO")
	)
	(segment
		(start 249.099832 -35.500056)
		(end 248.604532 -35.004756)
		(width 0.3048)
		(layer "In5.Cu")
		(net "DUT_VDDO")
	)
	(segment
		(start 248.604532 -35.004756)
		(end 248.604532 -33.294828)
		(width 0.3048)
		(layer "In5.Cu")
		(net "DUT_VDDO")
	)
	(segment
		(start 236.599984 -48.999902)
		(end 236.100112 -49.499774)
		(width 0.4572)
		(layer "F.Cu")
		(net "DUT_VDD")
	)
	(segment
		(start 244.599968 -50.999898)
		(end 245.09984 -51.49977)
		(width 0.4572)
		(layer "F.Cu")
		(net "DUT_VDD")
	)
	(segment
		(start 235.599986 -41.999916)
		(end 235.100114 -41.500044)
		(width 0.4572)
		(layer "F.Cu")
		(net "DUT_VDD")
	)
	(segment
		(start 309.7022 -63.2206)
		(end 309.397908 -63.2206)
		(width 0.3048)
		(layer "F.Cu")
		(net "DUT_VDD")
	)
	(segment
		(start 245.599966 -49.9999)
		(end 246.099838 -50.499772)
		(width 0.4572)
		(layer "F.Cu")
		(net "DUT_VDD")
	)
	(segment
		(start 246.599964 -44.99991)
		(end 247.099836 -44.500038)
		(width 0.4572)
		(layer "F.Cu")
		(net "DUT_VDD")
	)
	(segment
		(start 239.599978 -51.999896)
		(end 239.100106 -52.499768)
		(width 0.4572)
		(layer "F.Cu")
		(net "DUT_VDD")
	)
	(segment
		(start 237.599982 -51.999896)
		(end 237.10011 -52.499768)
		(width 0.4572)
		(layer "F.Cu")
		(net "DUT_VDD")
	)
	(segment
		(start 241.599974 -49.9999)
		(end 242.099846 -50.499772)
		(width 0.4572)
		(layer "F.Cu")
		(net "DUT_VDD")
	)
	(segment
		(start 246.599964 -52.999894)
		(end 247.099836 -53.499766)
		(width 0.4572)
		(layer "F.Cu")
		(net "DUT_VDD")
	)
	(segment
		(start 239.599978 -47.999904)
		(end 239.100106 -48.499776)
		(width 0.4572)
		(layer "F.Cu")
		(net "DUT_VDD")
	)
	(segment
		(start 240.599976 -52.999894)
		(end 241.099848 -53.499766)
		(width 0.4572)
		(layer "F.Cu")
		(net "DUT_VDD")
	)
	(segment
		(start 234.599988 -42.999914)
		(end 234.100116 -42.500042)
		(width 0.4572)
		(layer "F.Cu")
		(net "DUT_VDD")
	)
	(segment
		(start 243.59997 -49.9999)
		(end 244.099842 -50.499772)
		(width 0.4572)
		(layer "F.Cu")
		(net "DUT_VDD")
	)
	(segment
		(start 309.7022 -67.0306)
		(end 309.397908 -67.0306)
		(width 0.3048)
		(layer "F.Cu")
		(net "DUT_VDD")
	)
	(segment
		(start 245.599966 -43.999912)
		(end 246.099838 -43.50004)
		(width 0.4572)
		(layer "F.Cu")
		(net "DUT_VDD")
	)
	(segment
		(start 247.599962 -51.999896)
		(end 248.099834 -52.499768)
		(width 0.4572)
		(layer "F.Cu")
		(net "DUT_VDD")
	)
	(segment
		(start 260.477 -47.498)
		(end 261.239 -48.26)
		(width 0.254)
		(layer "F.Cu")
		(net "DUT_VDD")
	)
	(segment
		(start 309.7022 -66.2686)
		(end 309.397908 -66.2686)
		(width 0.3048)
		(layer "F.Cu")
		(net "DUT_VDD")
	)
	(segment
		(start 234.599988 -44.99991)
		(end 234.100116 -44.500038)
		(width 0.4572)
		(layer "F.Cu")
		(net "DUT_VDD")
	)
	(segment
		(start 233.59999 -41.999916)
		(end 233.100118 -41.500044)
		(width 0.4572)
		(layer "F.Cu")
		(net "DUT_VDD")
	)
	(segment
		(start 241.599974 -51.999896)
		(end 242.099846 -52.499768)
		(width 0.4572)
		(layer "F.Cu")
		(net "DUT_VDD")
	)
	(segment
		(start 238.59998 -52.999894)
		(end 238.100108 -53.499766)
		(width 0.4572)
		(layer "F.Cu")
		(net "DUT_VDD")
	)
	(segment
		(start 237.599982 -45.999908)
		(end 237.10011 -45.500036)
		(width 0.4572)
		(layer "F.Cu")
		(net "DUT_VDD")
	)
	(segment
		(start 309.7022 -60.1726)
		(end 309.397908 -60.1726)
		(width 0.3048)
		(layer "F.Cu")
		(net "DUT_VDD")
	)
	(segment
		(start 247.599962 -49.9999)
		(end 248.099834 -50.499772)
		(width 0.4572)
		(layer "F.Cu")
		(net "DUT_VDD")
	)
	(segment
		(start 233.59999 -51.999896)
		(end 233.100118 -52.499768)
		(width 0.4572)
		(layer "F.Cu")
		(net "DUT_VDD")
	)
	(segment
		(start 234.599988 -48.999902)
		(end 234.100116 -49.499774)
		(width 0.4572)
		(layer "F.Cu")
		(net "DUT_VDD")
	)
	(segment
		(start 238.59998 -42.999914)
		(end 238.100108 -42.500042)
		(width 0.4572)
		(layer "F.Cu")
		(net "DUT_VDD")
	)
	(segment
		(start 248.099834 -48.499776)
		(end 247.599962 -47.999904)
		(width 0.4572)
		(layer "F.Cu")
		(net "DUT_VDD")
	)
	(segment
		(start 235.599986 -45.999908)
		(end 235.100114 -45.500036)
		(width 0.4572)
		(layer "F.Cu")
		(net "DUT_VDD")
	)
	(segment
		(start 239.599978 -49.9999)
		(end 239.100106 -50.499772)
		(width 0.4572)
		(layer "F.Cu")
		(net "DUT_VDD")
	)
	(segment
		(start 235.599986 -53.999892)
		(end 235.100114 -54.499764)
		(width 0.4572)
		(layer "F.Cu")
		(net "DUT_VDD")
	)
	(segment
		(start 261.239 -48.26)
		(end 261.239 -65.405)
		(width 0.254)
		(layer "F.Cu")
		(net "DUT_VDD")
	)
	(segment
		(start 236.599984 -50.999898)
		(end 236.100112 -51.49977)
		(width 0.4572)
		(layer "F.Cu")
		(net "DUT_VDD")
	)
	(segment
		(start 235.599986 -49.9999)
		(end 235.100114 -50.499772)
		(width 0.4572)
		(layer "F.Cu")
		(net "DUT_VDD")
	)
	(segment
		(start 242.599972 -46.999906)
		(end 243.099844 -46.500034)
		(width 0.4572)
		(layer "F.Cu")
		(net "DUT_VDD")
	)
	(segment
		(start 246.599964 -42.999914)
		(end 247.099836 -42.500042)
		(width 0.4572)
		(layer "F.Cu")
		(net "DUT_VDD")
	)
	(segment
		(start 239.599978 -53.999892)
		(end 239.100106 -54.499764)
		(width 0.4572)
		(layer "F.Cu")
		(net "DUT_VDD")
	)
	(segment
		(start 240.599976 -44.99991)
		(end 241.099848 -44.500038)
		(width 0.4572)
		(layer "F.Cu")
		(net "DUT_VDD")
	)
	(segment
		(start 243.59997 -47.999904)
		(end 244.099842 -48.499776)
		(width 0.4572)
		(layer "F.Cu")
		(net "DUT_VDD")
	)
	(segment
		(start 243.59997 -41.999916)
		(end 244.099842 -41.500044)
		(width 0.4572)
		(layer "F.Cu")
		(net "DUT_VDD")
	)
	(segment
		(start 242.599972 -42.999914)
		(end 243.099844 -42.500042)
		(width 0.4572)
		(layer "F.Cu")
		(net "DUT_VDD")
	)
	(segment
		(start 244.599968 -52.999894)
		(end 245.09984 -53.499766)
		(width 0.4572)
		(layer "F.Cu")
		(net "DUT_VDD")
	)
	(segment
		(start 245.599966 -41.999916)
		(end 246.099838 -41.500044)
		(width 0.4572)
		(layer "F.Cu")
		(net "DUT_VDD")
	)
	(segment
		(start 233.59999 -43.999912)
		(end 233.100118 -43.50004)
		(width 0.4572)
		(layer "F.Cu")
		(net "DUT_VDD")
	)
	(segment
		(start 233.59999 -49.9999)
		(end 233.100118 -50.499772)
		(width 0.4572)
		(layer "F.Cu")
		(net "DUT_VDD")
	)
	(segment
		(start 309.7022 -67.7926)
		(end 309.397908 -67.7926)
		(width 0.3048)
		(layer "F.Cu")
		(net "DUT_VDD")
	)
	(segment
		(start 243.59997 -43.999912)
		(end 244.099842 -43.50004)
		(width 0.4572)
		(layer "F.Cu")
		(net "DUT_VDD")
	)
	(segment
		(start 243.59997 -53.999892)
		(end 244.099842 -54.499764)
		(width 0.4572)
		(layer "F.Cu")
		(net "DUT_VDD")
	)
	(segment
		(start 234.599988 -46.999906)
		(end 234.100116 -46.500034)
		(width 0.4572)
		(layer "F.Cu")
		(net "DUT_VDD")
	)
	(segment
		(start 235.599986 -43.999912)
		(end 235.100114 -43.50004)
		(width 0.4572)
		(layer "F.Cu")
		(net "DUT_VDD")
	)
	(segment
		(start 243.59997 -45.999908)
		(end 244.099842 -45.500036)
		(width 0.4572)
		(layer "F.Cu")
		(net "DUT_VDD")
	)
	(segment
		(start 309.7022 -68.5546)
		(end 309.397908 -68.5546)
		(width 0.3048)
		(layer "F.Cu")
		(net "DUT_VDD")
	)
	(segment
		(start 241.599974 -43.999912)
		(end 242.099846 -43.50004)
		(width 0.4572)
		(layer "F.Cu")
		(net "DUT_VDD")
	)
	(segment
		(start 234.599988 -40.999918)
		(end 234.100116 -40.500046)
		(width 0.4572)
		(layer "F.Cu")
		(net "DUT_VDD")
	)
	(segment
		(start 240.599976 -48.999902)
		(end 241.099848 -49.499774)
		(width 0.4572)
		(layer "F.Cu")
		(net "DUT_VDD")
	)
	(segment
		(start 246.599964 -50.999898)
		(end 247.099836 -51.49977)
		(width 0.4572)
		(layer "F.Cu")
		(net "DUT_VDD")
	)
	(segment
		(start 237.599982 -41.999916)
		(end 237.10011 -41.500044)
		(width 0.4572)
		(layer "F.Cu")
		(net "DUT_VDD")
	)
	(segment
		(start 234.599988 -52.999894)
		(end 234.100116 -53.499766)
		(width 0.4572)
		(layer "F.Cu")
		(net "DUT_VDD")
	)
	(segment
		(start 245.599966 -51.999896)
		(end 246.099838 -52.499768)
		(width 0.4572)
		(layer "F.Cu")
		(net "DUT_VDD")
	)
	(segment
		(start 242.599972 -48.999902)
		(end 243.099844 -49.499774)
		(width 0.4572)
		(layer "F.Cu")
		(net "DUT_VDD")
	)
	(segment
		(start 247.599962 -47.999904)
		(end 247.599962 -47.802038)
		(width 0.254)
		(layer "F.Cu")
		(net "DUT_VDD")
	)
	(segment
		(start 309.7022 -65.5066)
		(end 309.397908 -65.5066)
		(width 0.3048)
		(layer "F.Cu")
		(net "DUT_VDD")
	)
	(segment
		(start 237.599982 -47.999904)
		(end 237.10011 -48.499776)
		(width 0.4572)
		(layer "F.Cu")
		(net "DUT_VDD")
	)
	(segment
		(start 247.904 -47.498)
		(end 260.477 -47.498)
		(width 0.254)
		(layer "F.Cu")
		(net "DUT_VDD")
	)
	(segment
		(start 240.599976 -50.999898)
		(end 241.099848 -51.49977)
		(width 0.4572)
		(layer "F.Cu")
		(net "DUT_VDD")
	)
	(segment
		(start 242.599972 -52.999894)
		(end 243.099844 -53.499766)
		(width 0.4572)
		(layer "F.Cu")
		(net "DUT_VDD")
	)
	(segment
		(start 241.599974 -45.999908)
		(end 242.099846 -45.500036)
		(width 0.4572)
		(layer "F.Cu")
		(net "DUT_VDD")
	)
	(segment
		(start 245.599966 -45.999908)
		(end 246.099838 -45.500036)
		(width 0.4572)
		(layer "F.Cu")
		(net "DUT_VDD")
	)
	(segment
		(start 309.7022 -57.1246)
		(end 309.397908 -57.1246)
		(width 0.3048)
		(layer "F.Cu")
		(net "DUT_VDD")
	)
	(segment
		(start 238.59998 -50.999898)
		(end 238.100108 -51.49977)
		(width 0.4572)
		(layer "F.Cu")
		(net "DUT_VDD")
	)
	(segment
		(start 244.599968 -42.999914)
		(end 245.09984 -42.500042)
		(width 0.4572)
		(layer "F.Cu")
		(net "DUT_VDD")
	)
	(segment
		(start 235.599986 -51.999896)
		(end 235.100114 -52.499768)
		(width 0.4572)
		(layer "F.Cu")
		(net "DUT_VDD")
	)
	(segment
		(start 237.599982 -43.999912)
		(end 237.10011 -43.50004)
		(width 0.4572)
		(layer "F.Cu")
		(net "DUT_VDD")
	)
	(segment
		(start 241.599974 -47.999904)
		(end 242.099846 -48.499776)
		(width 0.4572)
		(layer "F.Cu")
		(net "DUT_VDD")
	)
	(segment
		(start 239.599978 -45.999908)
		(end 239.100106 -45.500036)
		(width 0.4572)
		(layer "F.Cu")
		(net "DUT_VDD")
	)
	(segment
		(start 243.59997 -51.999896)
		(end 244.099842 -52.499768)
		(width 0.4572)
		(layer "F.Cu")
		(net "DUT_VDD")
	)
	(segment
		(start 247.599962 -43.999912)
		(end 248.099834 -43.50004)
		(width 0.4572)
		(layer "F.Cu")
		(net "DUT_VDD")
	)
	(segment
		(start 245.599966 -53.999892)
		(end 246.099838 -54.499764)
		(width 0.4572)
		(layer "F.Cu")
		(net "DUT_VDD")
	)
	(segment
		(start 334.5942 -76.6191)
		(end 334.5942 -77.364336)
		(width 0.254)
		(layer "F.Cu")
		(net "DUT_VDD")
	)
	(segment
		(start 237.599982 -53.999892)
		(end 237.10011 -54.499764)
		(width 0.4572)
		(layer "F.Cu")
		(net "DUT_VDD")
	)
	(segment
		(start 309.7022 -59.4106)
		(end 309.397908 -59.4106)
		(width 0.3048)
		(layer "F.Cu")
		(net "DUT_VDD")
	)
	(segment
		(start 238.59998 -48.999902)
		(end 238.100108 -49.499774)
		(width 0.4572)
		(layer "F.Cu")
		(net "DUT_VDD")
	)
	(segment
		(start 237.599982 -49.9999)
		(end 237.10011 -50.499772)
		(width 0.4572)
		(layer "F.Cu")
		(net "DUT_VDD")
	)
	(segment
		(start 246.599964 -48.999902)
		(end 247.099836 -49.499774)
		(width 0.4572)
		(layer "F.Cu")
		(net "DUT_VDD")
	)
	(segment
		(start 244.599968 -48.999902)
		(end 245.09984 -49.499774)
		(width 0.4572)
		(layer "F.Cu")
		(net "DUT_VDD")
	)
	(segment
		(start 240.599976 -42.999914)
		(end 241.099848 -42.500042)
		(width 0.4572)
		(layer "F.Cu")
		(net "DUT_VDD")
	)
	(segment
		(start 334.5942 -77.364336)
		(end 334.524604 -77.433932)
		(width 0.254)
		(layer "F.Cu")
		(net "DUT_VDD")
	)
	(segment
		(start 246.599964 -46.999906)
		(end 247.099836 -46.500034)
		(width 0.4572)
		(layer "F.Cu")
		(net "DUT_VDD")
	)
	(segment
		(start 236.599984 -46.999906)
		(end 236.100112 -46.500034)
		(width 0.4572)
		(layer "F.Cu")
		(net "DUT_VDD")
	)
	(segment
		(start 238.59998 -46.999906)
		(end 238.100108 -46.500034)
		(width 0.4572)
		(layer "F.Cu")
		(net "DUT_VDD")
	)
	(segment
		(start 236.599984 -52.999894)
		(end 236.100112 -53.499766)
		(width 0.4572)
		(layer "F.Cu")
		(net "DUT_VDD")
	)
	(segment
		(start 309.7022 -63.9826)
		(end 309.397908 -63.9826)
		(width 0.3048)
		(layer "F.Cu")
		(net "DUT_VDD")
	)
	(segment
		(start 239.599978 -41.999916)
		(end 239.100106 -41.500044)
		(width 0.4572)
		(layer "F.Cu")
		(net "DUT_VDD")
	)
	(segment
		(start 240.599976 -46.999906)
		(end 241.099848 -46.500034)
		(width 0.4572)
		(layer "F.Cu")
		(net "DUT_VDD")
	)
	(segment
		(start 236.599984 -44.99991)
		(end 236.100112 -44.500038)
		(width 0.4572)
		(layer "F.Cu")
		(net "DUT_VDD")
	)
	(segment
		(start 309.7022 -60.9346)
		(end 309.397908 -60.9346)
		(width 0.3048)
		(layer "F.Cu")
		(net "DUT_VDD")
	)
	(segment
		(start 235.599986 -47.999904)
		(end 235.100114 -48.499776)
		(width 0.4572)
		(layer "F.Cu")
		(net "DUT_VDD")
	)
	(segment
		(start 242.599972 -44.99991)
		(end 243.099844 -44.500038)
		(width 0.4572)
		(layer "F.Cu")
		(net "DUT_VDD")
	)
	(segment
		(start 244.599968 -46.999906)
		(end 245.09984 -46.500034)
		(width 0.4572)
		(layer "F.Cu")
		(net "DUT_VDD")
	)
	(segment
		(start 309.7022 -57.8866)
		(end 309.397908 -57.8866)
		(width 0.3048)
		(layer "F.Cu")
		(net "DUT_VDD")
	)
	(segment
		(start 239.599978 -43.999912)
		(end 239.100106 -43.50004)
		(width 0.4572)
		(layer "F.Cu")
		(net "DUT_VDD")
	)
	(segment
		(start 309.7022 -58.6486)
		(end 309.397908 -58.6486)
		(width 0.3048)
		(layer "F.Cu")
		(net "DUT_VDD")
	)
	(segment
		(start 241.599974 -53.999892)
		(end 242.099846 -54.499764)
		(width 0.4572)
		(layer "F.Cu")
		(net "DUT_VDD")
	)
	(segment
		(start 309.7022 -64.7446)
		(end 309.397908 -64.7446)
		(width 0.3048)
		(layer "F.Cu")
		(net "DUT_VDD")
	)
	(segment
		(start 238.59998 -44.99991)
		(end 238.100108 -44.500038)
		(width 0.4572)
		(layer "F.Cu")
		(net "DUT_VDD")
	)
	(segment
		(start 234.599988 -50.999898)
		(end 234.100116 -51.49977)
		(width 0.4572)
		(layer "F.Cu")
		(net "DUT_VDD")
	)
	(segment
		(start 309.7022 -62.4586)
		(end 309.397908 -62.4586)
		(width 0.3048)
		(layer "F.Cu")
		(net "DUT_VDD")
	)
	(segment
		(start 309.7022 -61.6966)
		(end 309.397908 -61.6966)
		(width 0.3048)
		(layer "F.Cu")
		(net "DUT_VDD")
	)
	(segment
		(start 236.599984 -42.999914)
		(end 236.100112 -42.500042)
		(width 0.4572)
		(layer "F.Cu")
		(net "DUT_VDD")
	)
	(segment
		(start 242.599972 -50.999898)
		(end 243.099844 -51.49977)
		(width 0.4572)
		(layer "F.Cu")
		(net "DUT_VDD")
	)
	(segment
		(start 247.599962 -47.802038)
		(end 247.904 -47.498)
		(width 0.254)
		(layer "F.Cu")
		(net "DUT_VDD")
	)
	(segment
		(start 245.599966 -47.999904)
		(end 246.099838 -48.499776)
		(width 0.4572)
		(layer "F.Cu")
		(net "DUT_VDD")
	)
	(segment
		(start 247.599962 -41.999916)
		(end 248.099834 -41.500044)
		(width 0.4572)
		(layer "F.Cu")
		(net "DUT_VDD")
	)
	(segment
		(start 244.599968 -44.99991)
		(end 245.09984 -44.500038)
		(width 0.4572)
		(layer "F.Cu")
		(net "DUT_VDD")
	)
	(segment
		(start 233.59999 -47.999904)
		(end 233.100118 -48.499776)
		(width 0.4572)
		(layer "F.Cu")
		(net "DUT_VDD")
	)
	(via
		(at 239.100106 -43.50004)
		(size 0.4572)
		(drill 0.2032)
		(layers "F.Cu" "B.Cu")
		(net "DUT_VDD")
	)
	(via
		(at 245.09984 -42.500042)
		(size 0.4572)
		(drill 0.2032)
		(layers "F.Cu" "B.Cu")
		(net "DUT_VDD")
	)
	(via
		(at 248.099834 -52.499768)
		(size 0.4572)
		(drill 0.2032)
		(layers "F.Cu" "B.Cu")
		(net "DUT_VDD")
	)
	(via
		(at 297.3324 -59.5122)
		(size 0.7112)
		(drill 0.4064)
		(layers "F.Cu" "B.Cu")
		(net "DUT_VDD")
	)
	(via
		(at 247.099836 -49.499774)
		(size 0.4572)
		(drill 0.2032)
		(layers "F.Cu" "B.Cu")
		(net "DUT_VDD")
	)
	(via
		(at 234.100116 -44.500038)
		(size 0.4572)
		(drill 0.2032)
		(layers "F.Cu" "B.Cu")
		(net "DUT_VDD")
	)
	(via
		(at 244.099842 -41.500044)
		(size 0.4572)
		(drill 0.2032)
		(layers "F.Cu" "B.Cu")
		(net "DUT_VDD")
	)
	(via
		(at 304.3936 -64.5414)
		(size 0.7112)
		(drill 0.4064)
		(layers "F.Cu" "B.Cu")
		(net "DUT_VDD")
	)
	(via
		(at 248.099834 -48.499776)
		(size 0.4572)
		(drill 0.2032)
		(layers "F.Cu" "B.Cu")
		(net "DUT_VDD")
	)
	(via
		(at 301.9806 -59.5122)
		(size 0.7112)
		(drill 0.4064)
		(layers "F.Cu" "B.Cu")
		(net "DUT_VDD")
	)
	(via
		(at 298.7802 -66.421)
		(size 0.7112)
		(drill 0.4064)
		(layers "F.Cu" "B.Cu")
		(net "DUT_VDD")
	)
	(via
		(at 245.09984 -46.500034)
		(size 0.4572)
		(drill 0.2032)
		(layers "F.Cu" "B.Cu")
		(net "DUT_VDD")
	)
	(via
		(at 305.7652 -66.421)
		(size 0.7112)
		(drill 0.4064)
		(layers "F.Cu" "B.Cu")
		(net "DUT_VDD")
	)
	(via
		(at 234.100116 -53.499766)
		(size 0.4572)
		(drill 0.2032)
		(layers "F.Cu" "B.Cu")
		(net "DUT_VDD")
	)
	(via
		(at 244.099842 -54.499764)
		(size 0.4572)
		(drill 0.2032)
		(layers "F.Cu" "B.Cu")
		(net "DUT_VDD")
	)
	(via
		(at 247.099836 -53.499766)
		(size 0.4572)
		(drill 0.2032)
		(layers "F.Cu" "B.Cu")
		(net "DUT_VDD")
	)
	(via
		(at 236.100112 -42.500042)
		(size 0.4572)
		(drill 0.2032)
		(layers "F.Cu" "B.Cu")
		(net "DUT_VDD")
	)
	(via
		(at 298.0436 -61.2648)
		(size 0.7112)
		(drill 0.4064)
		(layers "F.Cu" "B.Cu")
		(net "DUT_VDD")
	)
	(via
		(at 236.100112 -44.500038)
		(size 0.4572)
		(drill 0.2032)
		(layers "F.Cu" "B.Cu")
		(net "DUT_VDD")
	)
	(via
		(at 304.5206 -61.2394)
		(size 0.7112)
		(drill 0.4064)
		(layers "F.Cu" "B.Cu")
		(net "DUT_VDD")
	)
	(via
		(at 233.100118 -50.499772)
		(size 0.4572)
		(drill 0.2032)
		(layers "F.Cu" "B.Cu")
		(net "DUT_VDD")
	)
	(via
		(at 306.6796 -59.5122)
		(size 0.7112)
		(drill 0.4064)
		(layers "F.Cu" "B.Cu")
		(net "DUT_VDD")
	)
	(via
		(at 305.4604 -64.5414)
		(size 0.7112)
		(drill 0.4064)
		(layers "F.Cu" "B.Cu")
		(net "DUT_VDD")
	)
	(via
		(at 238.100108 -53.499766)
		(size 0.4572)
		(drill 0.2032)
		(layers "F.Cu" "B.Cu")
		(net "DUT_VDD")
	)
	(via
		(at 243.099844 -49.499774)
		(size 0.4572)
		(drill 0.2032)
		(layers "F.Cu" "B.Cu")
		(net "DUT_VDD")
	)
	(via
		(at 296.2656 -59.5122)
		(size 0.7112)
		(drill 0.4064)
		(layers "F.Cu" "B.Cu")
		(net "DUT_VDD")
	)
	(via
		(at 241.099848 -49.499774)
		(size 0.4572)
		(drill 0.2032)
		(layers "F.Cu" "B.Cu")
		(net "DUT_VDD")
	)
	(via
		(at 234.100116 -49.499774)
		(size 0.4572)
		(drill 0.2032)
		(layers "F.Cu" "B.Cu")
		(net "DUT_VDD")
	)
	(via
		(at 308.0766 -59.5122)
		(size 0.7112)
		(drill 0.4064)
		(layers "F.Cu" "B.Cu")
		(net "DUT_VDD")
	)
	(via
		(at 303.3522 -66.421)
		(size 0.7112)
		(drill 0.4064)
		(layers "F.Cu" "B.Cu")
		(net "DUT_VDD")
	)
	(via
		(at 237.10011 -52.499768)
		(size 0.4572)
		(drill 0.2032)
		(layers "F.Cu" "B.Cu")
		(net "DUT_VDD")
	)
	(via
		(at 248.099834 -50.499772)
		(size 0.4572)
		(drill 0.2032)
		(layers "F.Cu" "B.Cu")
		(net "DUT_VDD")
	)
	(via
		(at 235.100114 -48.499776)
		(size 0.4572)
		(drill 0.2032)
		(layers "F.Cu" "B.Cu")
		(net "DUT_VDD")
	)
	(via
		(at 242.099846 -54.499764)
		(size 0.4572)
		(drill 0.2032)
		(layers "F.Cu" "B.Cu")
		(net "DUT_VDD")
	)
	(via
		(at 305.5874 -61.2394)
		(size 0.7112)
		(drill 0.4064)
		(layers "F.Cu" "B.Cu")
		(net "DUT_VDD")
	)
	(via
		(at 306.6542 -62.865)
		(size 0.7112)
		(drill 0.4064)
		(layers "F.Cu" "B.Cu")
		(net "DUT_VDD")
	)
	(via
		(at 238.100108 -51.49977)
		(size 0.4572)
		(drill 0.2032)
		(layers "F.Cu" "B.Cu")
		(net "DUT_VDD")
	)
	(via
		(at 296.418 -66.421)
		(size 0.7112)
		(drill 0.4064)
		(layers "F.Cu" "B.Cu")
		(net "DUT_VDD")
	)
	(via
		(at 244.099842 -48.499776)
		(size 0.4572)
		(drill 0.2032)
		(layers "F.Cu" "B.Cu")
		(net "DUT_VDD")
	)
	(via
		(at 239.100106 -52.499768)
		(size 0.4572)
		(drill 0.2032)
		(layers "F.Cu" "B.Cu")
		(net "DUT_VDD")
	)
	(via
		(at 245.09984 -44.500038)
		(size 0.4572)
		(drill 0.2032)
		(layers "F.Cu" "B.Cu")
		(net "DUT_VDD")
	)
	(via
		(at 236.100112 -49.499774)
		(size 0.4572)
		(drill 0.2032)
		(layers "F.Cu" "B.Cu")
		(net "DUT_VDD")
	)
	(via
		(at 244.099842 -50.499772)
		(size 0.4572)
		(drill 0.2032)
		(layers "F.Cu" "B.Cu")
		(net "DUT_VDD")
	)
	(via
		(at 242.099846 -45.500036)
		(size 0.4572)
		(drill 0.2032)
		(layers "F.Cu" "B.Cu")
		(net "DUT_VDD")
	)
	(via
		(at 239.100106 -50.499772)
		(size 0.4572)
		(drill 0.2032)
		(layers "F.Cu" "B.Cu")
		(net "DUT_VDD")
	)
	(via
		(at 247.099836 -44.500038)
		(size 0.4572)
		(drill 0.2032)
		(layers "F.Cu" "B.Cu")
		(net "DUT_VDD")
	)
	(via
		(at 234.100116 -40.500046)
		(size 0.4572)
		(drill 0.2032)
		(layers "F.Cu" "B.Cu")
		(net "DUT_VDD")
	)
	(via
		(at 243.099844 -53.499766)
		(size 0.4572)
		(drill 0.2032)
		(layers "F.Cu" "B.Cu")
		(net "DUT_VDD")
	)
	(via
		(at 305.6128 -59.5122)
		(size 0.7112)
		(drill 0.4064)
		(layers "F.Cu" "B.Cu")
		(net "DUT_VDD")
	)
	(via
		(at 242.099846 -52.499768)
		(size 0.4572)
		(drill 0.2032)
		(layers "F.Cu" "B.Cu")
		(net "DUT_VDD")
	)
	(via
		(at 299.0088 -63.0428)
		(size 0.7112)
		(drill 0.4064)
		(layers "F.Cu" "B.Cu")
		(net "DUT_VDD")
	)
	(via
		(at 299.847 -66.421)
		(size 0.7112)
		(drill 0.4064)
		(layers "F.Cu" "B.Cu")
		(net "DUT_VDD")
	)
	(via
		(at 244.099842 -45.500036)
		(size 0.4572)
		(drill 0.2032)
		(layers "F.Cu" "B.Cu")
		(net "DUT_VDD")
	)
	(via
		(at 238.100108 -42.500042)
		(size 0.4572)
		(drill 0.2032)
		(layers "F.Cu" "B.Cu")
		(net "DUT_VDD")
	)
	(via
		(at 304.2666 -59.5122)
		(size 0.7112)
		(drill 0.4064)
		(layers "F.Cu" "B.Cu")
		(net "DUT_VDD")
	)
	(via
		(at 236.100112 -46.500034)
		(size 0.4572)
		(drill 0.2032)
		(layers "F.Cu" "B.Cu")
		(net "DUT_VDD")
	)
	(via
		(at 237.10011 -45.500036)
		(size 0.4572)
		(drill 0.2032)
		(layers "F.Cu" "B.Cu")
		(net "DUT_VDD")
	)
	(via
		(at 243.099844 -44.500038)
		(size 0.4572)
		(drill 0.2032)
		(layers "F.Cu" "B.Cu")
		(net "DUT_VDD")
	)
	(via
		(at 248.099834 -41.500044)
		(size 0.4572)
		(drill 0.2032)
		(layers "F.Cu" "B.Cu")
		(net "DUT_VDD")
	)
	(via
		(at 245.09984 -51.49977)
		(size 0.4572)
		(drill 0.2032)
		(layers "F.Cu" "B.Cu")
		(net "DUT_VDD")
	)
	(via
		(at 306.6796 -64.5414)
		(size 0.7112)
		(drill 0.4064)
		(layers "F.Cu" "B.Cu")
		(net "DUT_VDD")
	)
	(via
		(at 239.100106 -45.500036)
		(size 0.4572)
		(drill 0.2032)
		(layers "F.Cu" "B.Cu")
		(net "DUT_VDD")
	)
	(via
		(at 297.9674 -64.6176)
		(size 0.7112)
		(drill 0.4064)
		(layers "F.Cu" "B.Cu")
		(net "DUT_VDD")
	)
	(via
		(at 246.099838 -43.50004)
		(size 0.4572)
		(drill 0.2032)
		(layers "F.Cu" "B.Cu")
		(net "DUT_VDD")
	)
	(via
		(at 300.2534 -64.6176)
		(size 0.7112)
		(drill 0.4064)
		(layers "F.Cu" "B.Cu")
		(net "DUT_VDD")
	)
	(via
		(at 304.3682 -62.865)
		(size 0.7112)
		(drill 0.4064)
		(layers "F.Cu" "B.Cu")
		(net "DUT_VDD")
	)
	(via
		(at 237.10011 -48.499776)
		(size 0.4572)
		(drill 0.2032)
		(layers "F.Cu" "B.Cu")
		(net "DUT_VDD")
	)
	(via
		(at 261.239 -65.405)
		(size 0.508)
		(drill 0.254)
		(layers "F.Cu" "B.Cu")
		(net "DUT_VDD")
	)
	(via
		(at 299.1104 -61.2648)
		(size 0.7112)
		(drill 0.4064)
		(layers "F.Cu" "B.Cu")
		(net "DUT_VDD")
	)
	(via
		(at 234.100116 -42.500042)
		(size 0.4572)
		(drill 0.2032)
		(layers "F.Cu" "B.Cu")
		(net "DUT_VDD")
	)
	(via
		(at 239.100106 -54.499764)
		(size 0.4572)
		(drill 0.2032)
		(layers "F.Cu" "B.Cu")
		(net "DUT_VDD")
	)
	(via
		(at 298.6278 -59.5122)
		(size 0.7112)
		(drill 0.4064)
		(layers "F.Cu" "B.Cu")
		(net "DUT_VDD")
	)
	(via
		(at 235.100114 -43.50004)
		(size 0.4572)
		(drill 0.2032)
		(layers "F.Cu" "B.Cu")
		(net "DUT_VDD")
	)
	(via
		(at 242.099846 -48.499776)
		(size 0.4572)
		(drill 0.2032)
		(layers "F.Cu" "B.Cu")
		(net "DUT_VDD")
	)
	(via
		(at 246.099838 -54.499764)
		(size 0.4572)
		(drill 0.2032)
		(layers "F.Cu" "B.Cu")
		(net "DUT_VDD")
	)
	(via
		(at 302.133 -66.421)
		(size 0.7112)
		(drill 0.4064)
		(layers "F.Cu" "B.Cu")
		(net "DUT_VDD")
	)
	(via
		(at 233.100118 -52.499768)
		(size 0.4572)
		(drill 0.2032)
		(layers "F.Cu" "B.Cu")
		(net "DUT_VDD")
	)
	(via
		(at 242.099846 -50.499772)
		(size 0.4572)
		(drill 0.2032)
		(layers "F.Cu" "B.Cu")
		(net "DUT_VDD")
	)
	(via
		(at 246.099838 -50.499772)
		(size 0.4572)
		(drill 0.2032)
		(layers "F.Cu" "B.Cu")
		(net "DUT_VDD")
	)
	(via
		(at 246.099838 -45.500036)
		(size 0.4572)
		(drill 0.2032)
		(layers "F.Cu" "B.Cu")
		(net "DUT_VDD")
	)
	(via
		(at 305.435 -62.865)
		(size 0.7112)
		(drill 0.4064)
		(layers "F.Cu" "B.Cu")
		(net "DUT_VDD")
	)
	(via
		(at 234.100116 -51.49977)
		(size 0.4572)
		(drill 0.2032)
		(layers "F.Cu" "B.Cu")
		(net "DUT_VDD")
	)
	(via
		(at 299.0342 -64.6176)
		(size 0.7112)
		(drill 0.4064)
		(layers "F.Cu" "B.Cu")
		(net "DUT_VDD")
	)
	(via
		(at 246.099838 -52.499768)
		(size 0.4572)
		(drill 0.2032)
		(layers "F.Cu" "B.Cu")
		(net "DUT_VDD")
	)
	(via
		(at 236.100112 -51.49977)
		(size 0.4572)
		(drill 0.2032)
		(layers "F.Cu" "B.Cu")
		(net "DUT_VDD")
	)
	(via
		(at 237.10011 -41.500044)
		(size 0.4572)
		(drill 0.2032)
		(layers "F.Cu" "B.Cu")
		(net "DUT_VDD")
	)
	(via
		(at 233.100118 -41.500044)
		(size 0.4572)
		(drill 0.2032)
		(layers "F.Cu" "B.Cu")
		(net "DUT_VDD")
	)
	(via
		(at 297.942 -63.0428)
		(size 0.7112)
		(drill 0.4064)
		(layers "F.Cu" "B.Cu")
		(net "DUT_VDD")
	)
	(via
		(at 296.418 -64.516)
		(size 0.7112)
		(drill 0.3556)
		(layers "F.Cu" "B.Cu")
		(net "DUT_VDD")
	)
	(via
		(at 247.099836 -51.49977)
		(size 0.4572)
		(drill 0.2032)
		(layers "F.Cu" "B.Cu")
		(net "DUT_VDD")
	)
	(via
		(at 241.099848 -42.500042)
		(size 0.4572)
		(drill 0.2032)
		(layers "F.Cu" "B.Cu")
		(net "DUT_VDD")
	)
	(via
		(at 245.09984 -49.499774)
		(size 0.4572)
		(drill 0.2032)
		(layers "F.Cu" "B.Cu")
		(net "DUT_VDD")
	)
	(via
		(at 245.09984 -53.499766)
		(size 0.4572)
		(drill 0.2032)
		(layers "F.Cu" "B.Cu")
		(net "DUT_VDD")
	)
	(via
		(at 235.100114 -50.499772)
		(size 0.4572)
		(drill 0.2032)
		(layers "F.Cu" "B.Cu")
		(net "DUT_VDD")
	)
	(via
		(at 301.0662 -66.421)
		(size 0.7112)
		(drill 0.4064)
		(layers "F.Cu" "B.Cu")
		(net "DUT_VDD")
	)
	(via
		(at 306.832 -66.421)
		(size 0.7112)
		(drill 0.4064)
		(layers "F.Cu" "B.Cu")
		(net "DUT_VDD")
	)
	(via
		(at 237.10011 -50.499772)
		(size 0.4572)
		(drill 0.2032)
		(layers "F.Cu" "B.Cu")
		(net "DUT_VDD")
	)
	(via
		(at 243.099844 -46.500034)
		(size 0.4572)
		(drill 0.2032)
		(layers "F.Cu" "B.Cu")
		(net "DUT_VDD")
	)
	(via
		(at 302.1584 -62.1284)
		(size 0.7112)
		(drill 0.3556)
		(layers "F.Cu" "B.Cu")
		(net "DUT_VDD")
	)
	(via
		(at 242.099846 -43.50004)
		(size 0.4572)
		(drill 0.2032)
		(layers "F.Cu" "B.Cu")
		(net "DUT_VDD")
	)
	(via
		(at 300.9138 -59.5122)
		(size 0.7112)
		(drill 0.4064)
		(layers "F.Cu" "B.Cu")
		(net "DUT_VDD")
	)
	(via
		(at 236.100112 -53.499766)
		(size 0.4572)
		(drill 0.2032)
		(layers "F.Cu" "B.Cu")
		(net "DUT_VDD")
	)
	(via
		(at 308.356 -66.421)
		(size 0.7112)
		(drill 0.4064)
		(layers "F.Cu" "B.Cu")
		(net "DUT_VDD")
	)
	(via
		(at 241.099848 -51.49977)
		(size 0.4572)
		(drill 0.2032)
		(layers "F.Cu" "B.Cu")
		(net "DUT_VDD")
	)
	(via
		(at 297.4848 -66.421)
		(size 0.7112)
		(drill 0.4064)
		(layers "F.Cu" "B.Cu")
		(net "DUT_VDD")
	)
	(via
		(at 235.100114 -41.500044)
		(size 0.4572)
		(drill 0.2032)
		(layers "F.Cu" "B.Cu")
		(net "DUT_VDD")
	)
	(via
		(at 241.099848 -44.500038)
		(size 0.4572)
		(drill 0.2032)
		(layers "F.Cu" "B.Cu")
		(net "DUT_VDD")
	)
	(via
		(at 304.419 -66.421)
		(size 0.7112)
		(drill 0.4064)
		(layers "F.Cu" "B.Cu")
		(net "DUT_VDD")
	)
	(via
		(at 334.524604 -77.433932)
		(size 0.508)
		(drill 0.254)
		(layers "F.Cu" "B.Cu")
		(net "DUT_VDD")
	)
	(via
		(at 247.099836 -46.500034)
		(size 0.4572)
		(drill 0.2032)
		(layers "F.Cu" "B.Cu")
		(net "DUT_VDD")
	)
	(via
		(at 241.099848 -46.500034)
		(size 0.4572)
		(drill 0.2032)
		(layers "F.Cu" "B.Cu")
		(net "DUT_VDD")
	)
	(via
		(at 244.099842 -43.50004)
		(size 0.4572)
		(drill 0.2032)
		(layers "F.Cu" "B.Cu")
		(net "DUT_VDD")
	)
	(via
		(at 244.099842 -52.499768)
		(size 0.4572)
		(drill 0.2032)
		(layers "F.Cu" "B.Cu")
		(net "DUT_VDD")
	)
	(via
		(at 300.228 -63.0428)
		(size 0.7112)
		(drill 0.4064)
		(layers "F.Cu" "B.Cu")
		(net "DUT_VDD")
	)
	(via
		(at 300.3296 -61.2648)
		(size 0.7112)
		(drill 0.4064)
		(layers "F.Cu" "B.Cu")
		(net "DUT_VDD")
	)
	(via
		(at 235.100114 -54.499764)
		(size 0.4572)
		(drill 0.2032)
		(layers "F.Cu" "B.Cu")
		(net "DUT_VDD")
	)
	(via
		(at 303.1998 -59.5122)
		(size 0.7112)
		(drill 0.4064)
		(layers "F.Cu" "B.Cu")
		(net "DUT_VDD")
	)
	(via
		(at 243.099844 -51.49977)
		(size 0.4572)
		(drill 0.2032)
		(layers "F.Cu" "B.Cu")
		(net "DUT_VDD")
	)
	(via
		(at 248.099834 -43.50004)
		(size 0.4572)
		(drill 0.2032)
		(layers "F.Cu" "B.Cu")
		(net "DUT_VDD")
	)
	(via
		(at 299.6946 -59.5122)
		(size 0.7112)
		(drill 0.4064)
		(layers "F.Cu" "B.Cu")
		(net "DUT_VDD")
	)
	(via
		(at 235.100114 -45.500036)
		(size 0.4572)
		(drill 0.2032)
		(layers "F.Cu" "B.Cu")
		(net "DUT_VDD")
	)
	(via
		(at 239.100106 -41.500044)
		(size 0.4572)
		(drill 0.2032)
		(layers "F.Cu" "B.Cu")
		(net "DUT_VDD")
	)
	(via
		(at 243.099844 -42.500042)
		(size 0.4572)
		(drill 0.2032)
		(layers "F.Cu" "B.Cu")
		(net "DUT_VDD")
	)
	(via
		(at 306.8066 -61.2394)
		(size 0.7112)
		(drill 0.4064)
		(layers "F.Cu" "B.Cu")
		(net "DUT_VDD")
	)
	(via
		(at 238.100108 -44.500038)
		(size 0.4572)
		(drill 0.2032)
		(layers "F.Cu" "B.Cu")
		(net "DUT_VDD")
	)
	(via
		(at 238.100108 -46.500034)
		(size 0.4572)
		(drill 0.2032)
		(layers "F.Cu" "B.Cu")
		(net "DUT_VDD")
	)
	(via
		(at 233.100118 -43.50004)
		(size 0.4572)
		(drill 0.2032)
		(layers "F.Cu" "B.Cu")
		(net "DUT_VDD")
	)
	(via
		(at 239.100106 -48.499776)
		(size 0.4572)
		(drill 0.2032)
		(layers "F.Cu" "B.Cu")
		(net "DUT_VDD")
	)
	(via
		(at 247.099836 -42.500042)
		(size 0.4572)
		(drill 0.2032)
		(layers "F.Cu" "B.Cu")
		(net "DUT_VDD")
	)
	(via
		(at 234.100116 -46.500034)
		(size 0.4572)
		(drill 0.2032)
		(layers "F.Cu" "B.Cu")
		(net "DUT_VDD")
	)
	(via
		(at 246.099838 -41.500044)
		(size 0.4572)
		(drill 0.2032)
		(layers "F.Cu" "B.Cu")
		(net "DUT_VDD")
	)
	(via
		(at 238.100108 -49.499774)
		(size 0.4572)
		(drill 0.2032)
		(layers "F.Cu" "B.Cu")
		(net "DUT_VDD")
	)
	(via
		(at 246.099838 -48.499776)
		(size 0.4572)
		(drill 0.2032)
		(layers "F.Cu" "B.Cu")
		(net "DUT_VDD")
	)
	(via
		(at 233.100118 -48.499776)
		(size 0.4572)
		(drill 0.2032)
		(layers "F.Cu" "B.Cu")
		(net "DUT_VDD")
	)
	(via
		(at 235.100114 -52.499768)
		(size 0.4572)
		(drill 0.2032)
		(layers "F.Cu" "B.Cu")
		(net "DUT_VDD")
	)
	(via
		(at 237.10011 -43.50004)
		(size 0.4572)
		(drill 0.2032)
		(layers "F.Cu" "B.Cu")
		(net "DUT_VDD")
	)
	(via
		(at 241.099848 -53.499766)
		(size 0.4572)
		(drill 0.2032)
		(layers "F.Cu" "B.Cu")
		(net "DUT_VDD")
	)
	(via
		(at 237.10011 -54.499764)
		(size 0.4572)
		(drill 0.2032)
		(layers "F.Cu" "B.Cu")
		(net "DUT_VDD")
	)
	(segment
		(start 309.7022 -56.261)
		(end 309.319168 -56.261)
		(width 0.3048)
		(layer "B.Cu")
		(net "DUT_VDD")
	)
	(segment
		(start 309.7022 -61.595)
		(end 309.319168 -61.595)
		(width 0.3048)
		(layer "B.Cu")
		(net "DUT_VDD")
	)
	(segment
		(start 328.46645 -78.43901)
		(end 327.27646 -79.629)
		(width 0.254)
		(layer "B.Cu")
		(net "DUT_VDD")
	)
	(segment
		(start 309.7022 -62.357)
		(end 309.319168 -62.357)
		(width 0.3048)
		(layer "B.Cu")
		(net "DUT_VDD")
	)
	(segment
		(start 309.7022 -63.881)
		(end 309.319168 -63.881)
		(width 0.3048)
		(layer "B.Cu")
		(net "DUT_VDD")
	)
	(segment
		(start 309.7022 -65.405)
		(end 309.319168 -65.405)
		(width 0.3048)
		(layer "B.Cu")
		(net "DUT_VDD")
	)
	(segment
		(start 309.7022 -67.691)
		(end 309.319168 -67.691)
		(width 0.3048)
		(layer "B.Cu")
		(net "DUT_VDD")
	)
	(segment
		(start 333.519526 -78.43901)
		(end 328.46645 -78.43901)
		(width 0.254)
		(layer "B.Cu")
		(net "DUT_VDD")
	)
	(segment
		(start 309.7022 -60.833)
		(end 309.319168 -60.833)
		(width 0.3048)
		(layer "B.Cu")
		(net "DUT_VDD")
	)
	(segment
		(start 327.27646 -79.629)
		(end 275.463 -79.629)
		(width 0.254)
		(layer "B.Cu")
		(net "DUT_VDD")
	)
	(segment
		(start 275.463 -79.629)
		(end 261.239 -65.405)
		(width 0.254)
		(layer "B.Cu")
		(net "DUT_VDD")
	)
	(segment
		(start 309.7022 -63.119)
		(end 309.319168 -63.119)
		(width 0.3048)
		(layer "B.Cu")
		(net "DUT_VDD")
	)
	(segment
		(start 309.7022 -59.309)
		(end 309.319168 -59.309)
		(width 0.3048)
		(layer "B.Cu")
		(net "DUT_VDD")
	)
	(segment
		(start 309.7022 -60.071)
		(end 309.319168 -60.071)
		(width 0.3048)
		(layer "B.Cu")
		(net "DUT_VDD")
	)
	(segment
		(start 309.7022 -64.643)
		(end 309.319168 -64.643)
		(width 0.3048)
		(layer "B.Cu")
		(net "DUT_VDD")
	)
	(segment
		(start 309.7022 -66.167)
		(end 309.319168 -66.167)
		(width 0.3048)
		(layer "B.Cu")
		(net "DUT_VDD")
	)
	(segment
		(start 334.524604 -77.433932)
		(end 333.519526 -78.43901)
		(width 0.254)
		(layer "B.Cu")
		(net "DUT_VDD")
	)
	(segment
		(start 309.7022 -57.785)
		(end 309.319168 -57.785)
		(width 0.3048)
		(layer "B.Cu")
		(net "DUT_VDD")
	)
	(segment
		(start 309.7022 -58.547)
		(end 309.319168 -58.547)
		(width 0.3048)
		(layer "B.Cu")
		(net "DUT_VDD")
	)
	(segment
		(start 309.7022 -66.929)
		(end 309.319168 -66.929)
		(width 0.3048)
		(layer "B.Cu")
		(net "DUT_VDD")
	)
	(segment
		(start 235.3818 -41.995852)
		(end 235.3818 -41.78173)
		(width 0.3048)
		(layer "B.Cu")
		(net "DUT_VDD")
	)
	(segment
		(start 309.7022 -57.023)
		(end 309.319168 -57.023)
		(width 0.3048)
		(layer "B.Cu")
		(net "DUT_VDD")
	)
	(segment
		(start 235.3818 -41.78173)
		(end 235.100114 -41.500044)
		(width 0.3048)
		(layer "B.Cu")
		(net "DUT_VDD")
	)
	(segment
		(start 232.599992 -33.999932)
		(end 232.10012 -33.50006)
		(width 0.12065)
		(layer "F.Cu")
		(net "DUT_TDO_R")
	)
	(segment
		(start 135.27024 -39.30904)
		(end 135.27024 -38.619684)
		(width 0.12065)
		(layer "F.Cu")
		(net "DUT_TDO_R")
	)
	(segment
		(start 135.411972 -39.926514)
		(end 135.411972 -39.450772)
		(width 0.12065)
		(layer "F.Cu")
		(net "DUT_TDO_R")
	)
	(segment
		(start 135.880348 -40.39489)
		(end 135.411972 -39.926514)
		(width 0.12065)
		(layer "F.Cu")
		(net "DUT_TDO_R")
	)
	(segment
		(start 135.411972 -39.450772)
		(end 135.27024 -39.30904)
		(width 0.12065)
		(layer "F.Cu")
		(net "DUT_TDO_R")
	)
	(via
		(at 136.692132 -39.68877)
		(size 0.7112)
		(drill 0.3556)
		(layers "F.Cu" "B.Cu")
		(net "DUT_TDO_R")
	)
	(via
		(at 232.10012 -33.50006)
		(size 0.4572)
		(drill 0.2032)
		(layers "F.Cu" "B.Cu")
		(net "DUT_TDO_R")
	)
	(via
		(at 135.27024 -38.619684)
		(size 0.508)
		(drill 0.254)
		(layers "F.Cu" "B.Cu")
		(net "DUT_TDO_R")
	)
	(segment
		(start 135.27024 -38.619684)
		(end 136.339326 -39.68877)
		(width 0.12065)
		(layer "B.Cu")
		(net "DUT_TDO_R")
	)
	(segment
		(start 136.339326 -39.68877)
		(end 136.692132 -39.68877)
		(width 0.12065)
		(layer "B.Cu")
		(net "DUT_TDO_R")
	)
	(segment
		(start 214.366348 -19.609054)
		(end 208.82864 -19.609054)
		(width 0.127)
		(layer "In5.Cu")
		(net "DUT_TDO_R")
	)
	(segment
		(start 191.212724 -18.6944)
		(end 188.971682 -16.453358)
		(width 0.127)
		(layer "In5.Cu")
		(net "DUT_TDO_R")
	)
	(segment
		(start 180.542438 -16.453358)
		(end 178.032156 -13.943076)
		(width 0.127)
		(layer "In5.Cu")
		(net "DUT_TDO_R")
	)
	(segment
		(start 135.074152 -6.96341)
		(end 128.3589 -13.678662)
		(width 0.127)
		(layer "In5.Cu")
		(net "DUT_TDO_R")
	)
	(segment
		(start 195.077842 -20.384008)
		(end 195.075302 -20.3835)
		(width 0.127)
		(layer "In5.Cu")
		(net "DUT_TDO_R")
	)
	(segment
		(start 199.468994 -20.8407)
		(end 199.011794 -20.3835)
		(width 0.127)
		(layer "In5.Cu")
		(net "DUT_TDO_R")
	)
	(segment
		(start 204.5335 -20.1803)
		(end 203.8731 -20.8407)
		(width 0.127)
		(layer "In5.Cu")
		(net "DUT_TDO_R")
	)
	(segment
		(start 134.748524 -39.1414)
		(end 135.27024 -38.619684)
		(width 0.127)
		(layer "In5.Cu")
		(net "DUT_TDO_R")
	)
	(segment
		(start 129.860802 -39.1414)
		(end 134.748524 -39.1414)
		(width 0.127)
		(layer "In5.Cu")
		(net "DUT_TDO_R")
	)
	(segment
		(start 203.8731 -20.8407)
		(end 199.468994 -20.8407)
		(width 0.127)
		(layer "In5.Cu")
		(net "DUT_TDO_R")
	)
	(segment
		(start 196.25564 -20.3835)
		(end 196.255386 -20.383754)
		(width 0.127)
		(layer "In5.Cu")
		(net "DUT_TDO_R")
	)
	(segment
		(start 173.18863 -6.96341)
		(end 135.074152 -6.96341)
		(width 0.127)
		(layer "In5.Cu")
		(net "DUT_TDO_R")
	)
	(segment
		(start 196.255386 -20.383754)
		(end 195.939918 -20.383754)
		(width 0.127)
		(layer "In5.Cu")
		(net "DUT_TDO_R")
	)
	(segment
		(start 178.032156 -11.806936)
		(end 173.18863 -6.96341)
		(width 0.127)
		(layer "In5.Cu")
		(net "DUT_TDO_R")
	)
	(segment
		(start 195.939664 -20.384008)
		(end 195.077842 -20.384008)
		(width 0.127)
		(layer "In5.Cu")
		(net "DUT_TDO_R")
	)
	(segment
		(start 195.939918 -20.383754)
		(end 195.939664 -20.384008)
		(width 0.127)
		(layer "In5.Cu")
		(net "DUT_TDO_R")
	)
	(segment
		(start 125.271022 -34.55162)
		(end 129.860802 -39.1414)
		(width 0.127)
		(layer "In5.Cu")
		(net "DUT_TDO_R")
	)
	(segment
		(start 228.4603 -22.411944)
		(end 228.4603 -21.522182)
		(width 0.127)
		(layer "In5.Cu")
		(net "DUT_TDO_R")
	)
	(segment
		(start 232.3846 -28.829)
		(end 232.3846 -26.336244)
		(width 0.127)
		(layer "In5.Cu")
		(net "DUT_TDO_R")
	)
	(segment
		(start 232.49382 -33.10636)
		(end 232.49382 -28.93822)
		(width 0.1016)
		(layer "In5.Cu")
		(net "DUT_TDO_R")
	)
	(segment
		(start 195.075302 -20.3835)
		(end 194.67576 -20.3835)
		(width 0.127)
		(layer "In5.Cu")
		(net "DUT_TDO_R")
	)
	(segment
		(start 220.165168 -20.310856)
		(end 215.06815 -20.310856)
		(width 0.127)
		(layer "In5.Cu")
		(net "DUT_TDO_R")
	)
	(segment
		(start 232.10012 -33.50006)
		(end 232.49382 -33.10636)
		(width 0.1016)
		(layer "In5.Cu")
		(net "DUT_TDO_R")
	)
	(segment
		(start 128.3589 -29.315664)
		(end 125.271022 -32.403542)
		(width 0.127)
		(layer "In5.Cu")
		(net "DUT_TDO_R")
	)
	(segment
		(start 208.82864 -19.609054)
		(end 208.257394 -20.1803)
		(width 0.127)
		(layer "In5.Cu")
		(net "DUT_TDO_R")
	)
	(segment
		(start 232.49382 -28.93822)
		(end 232.3846 -28.829)
		(width 0.1016)
		(layer "In5.Cu")
		(net "DUT_TDO_R")
	)
	(segment
		(start 128.3589 -13.678662)
		(end 128.3589 -29.315664)
		(width 0.127)
		(layer "In5.Cu")
		(net "DUT_TDO_R")
	)
	(segment
		(start 227.109274 -20.171156)
		(end 220.304868 -20.171156)
		(width 0.127)
		(layer "In5.Cu")
		(net "DUT_TDO_R")
	)
	(segment
		(start 194.67576 -20.3835)
		(end 192.98666 -18.6944)
		(width 0.127)
		(layer "In5.Cu")
		(net "DUT_TDO_R")
	)
	(segment
		(start 232.3846 -26.336244)
		(end 228.4603 -22.411944)
		(width 0.127)
		(layer "In5.Cu")
		(net "DUT_TDO_R")
	)
	(segment
		(start 178.032156 -13.943076)
		(end 178.032156 -11.806936)
		(width 0.127)
		(layer "In5.Cu")
		(net "DUT_TDO_R")
	)
	(segment
		(start 199.011794 -20.3835)
		(end 196.25564 -20.3835)
		(width 0.127)
		(layer "In5.Cu")
		(net "DUT_TDO_R")
	)
	(segment
		(start 220.304868 -20.171156)
		(end 220.165168 -20.310856)
		(width 0.127)
		(layer "In5.Cu")
		(net "DUT_TDO_R")
	)
	(segment
		(start 228.4603 -21.522182)
		(end 227.109274 -20.171156)
		(width 0.127)
		(layer "In5.Cu")
		(net "DUT_TDO_R")
	)
	(segment
		(start 192.98666 -18.6944)
		(end 191.212724 -18.6944)
		(width 0.127)
		(layer "In5.Cu")
		(net "DUT_TDO_R")
	)
	(segment
		(start 188.971682 -16.453358)
		(end 180.542438 -16.453358)
		(width 0.127)
		(layer "In5.Cu")
		(net "DUT_TDO_R")
	)
	(segment
		(start 215.06815 -20.310856)
		(end 214.366348 -19.609054)
		(width 0.127)
		(layer "In5.Cu")
		(net "DUT_TDO_R")
	)
	(segment
		(start 208.257394 -20.1803)
		(end 204.5335 -20.1803)
		(width 0.127)
		(layer "In5.Cu")
		(net "DUT_TDO_R")
	)
	(segment
		(start 125.271022 -32.403542)
		(end 125.271022 -34.55162)
		(width 0.127)
		(layer "In5.Cu")
		(net "DUT_TDO_R")
	)
	(segment
		(start 136.74725 -41.519602)
		(end 136.74725 -40.416988)
		(width 0.12065)
		(layer "F.Cu")
		(net "DUT_TDO")
	)
	(segment
		(start 136.74725 -40.416988)
		(end 136.769348 -40.39489)
		(width 0.12065)
		(layer "F.Cu")
		(net "DUT_TDO")
	)
	(segment
		(start 137.002012 -41.519602)
		(end 137.79246 -40.729154)
		(width 0.12065)
		(layer "F.Cu")
		(net "DUT_TDO")
	)
	(segment
		(start 136.74725 -41.519602)
		(end 137.002012 -41.519602)
		(width 0.12065)
		(layer "F.Cu")
		(net "DUT_TDO")
	)
	(segment
		(start 134.6327 -38.757098)
		(end 134.410704 -38.535102)
		(width 0.12065)
		(layer "F.Cu")
		(net "DUT_TDI_R")
	)
	(segment
		(start 134.6327 -40.05961)
		(end 134.6327 -38.757098)
		(width 0.12065)
		(layer "F.Cu")
		(net "DUT_TDI_R")
	)
	(segment
		(start 232.599992 -40.999918)
		(end 232.10012 -40.500046)
		(width 0.12065)
		(layer "F.Cu")
		(net "DUT_TDI_R")
	)
	(via
		(at 134.410704 -38.535102)
		(size 0.508)
		(drill 0.254)
		(layers "F.Cu" "B.Cu")
		(net "DUT_TDI_R")
	)
	(via
		(at 232.10012 -40.500046)
		(size 0.4572)
		(drill 0.2032)
		(layers "F.Cu" "B.Cu")
		(net "DUT_TDI_R")
	)
	(via
		(at 135.1026 -39.5732)
		(size 0.7112)
		(drill 0.3556)
		(layers "F.Cu" "B.Cu")
		(net "DUT_TDI_R")
	)
	(segment
		(start 134.410704 -38.535102)
		(end 134.8486 -38.972998)
		(width 0.12065)
		(layer "B.Cu")
		(net "DUT_TDI_R")
	)
	(segment
		(start 134.8486 -39.3192)
		(end 135.1026 -39.5732)
		(width 0.12065)
		(layer "B.Cu")
		(net "DUT_TDI_R")
	)
	(segment
		(start 134.8486 -38.972998)
		(end 134.8486 -39.3192)
		(width 0.12065)
		(layer "B.Cu")
		(net "DUT_TDI_R")
	)
	(segment
		(start 178.545744 -20.598638)
		(end 180.983636 -18.160746)
		(width 0.127)
		(layer "In5.Cu")
		(net "DUT_TDI_R")
	)
	(segment
		(start 195.039996 -20.765008)
		(end 196.097652 -20.765008)
		(width 0.127)
		(layer "In5.Cu")
		(net "DUT_TDI_R")
	)
	(segment
		(start 127.761746 -30.7594)
		(end 169.762424 -30.7594)
		(width 0.127)
		(layer "In5.Cu")
		(net "DUT_TDI_R")
	)
	(segment
		(start 192.580006 -19.0754)
		(end 194.269106 -20.7645)
		(width 0.127)
		(layer "In5.Cu")
		(net "DUT_TDI_R")
	)
	(segment
		(start 196.097906 -20.764754)
		(end 196.413374 -20.764754)
		(width 0.127)
		(layer "In5.Cu")
		(net "DUT_TDI_R")
	)
	(segment
		(start 226.347274 -20.552156)
		(end 227.2919 -21.496782)
		(width 0.127)
		(layer "In5.Cu")
		(net "DUT_TDI_R")
	)
	(segment
		(start 134.407402 -38.5318)
		(end 129.79019 -38.5318)
		(width 0.127)
		(layer "In5.Cu")
		(net "DUT_TDI_R")
	)
	(segment
		(start 231.709722 -28.829)
		(end 231.70642 -28.832302)
		(width 0.1016)
		(layer "In5.Cu")
		(net "DUT_TDI_R")
	)
	(segment
		(start 125.652022 -32.869124)
		(end 127.761746 -30.7594)
		(width 0.127)
		(layer "In5.Cu")
		(net "DUT_TDI_R")
	)
	(segment
		(start 231.70642 -35.661346)
		(end 231.493822 -35.873944)
		(width 0.1016)
		(layer "In5.Cu")
		(net "DUT_TDI_R")
	)
	(segment
		(start 191.054736 -19.0754)
		(end 192.580006 -19.0754)
		(width 0.127)
		(layer "In5.Cu")
		(net "DUT_TDI_R")
	)
	(segment
		(start 129.79019 -38.5318)
		(end 125.652022 -34.393632)
		(width 0.127)
		(layer "In5.Cu")
		(net "DUT_TDI_R")
	)
	(segment
		(start 231.493822 -39.893748)
		(end 232.10012 -40.500046)
		(width 0.1016)
		(layer "In5.Cu")
		(net "DUT_TDI_R")
	)
	(segment
		(start 214.20836 -19.990054)
		(end 214.910162 -20.691856)
		(width 0.127)
		(layer "In5.Cu")
		(net "DUT_TDI_R")
	)
	(segment
		(start 134.410704 -38.535102)
		(end 134.407402 -38.5318)
		(width 0.127)
		(layer "In5.Cu")
		(net "DUT_TDI_R")
	)
	(segment
		(start 125.652022 -34.393632)
		(end 125.652022 -32.869124)
		(width 0.127)
		(layer "In5.Cu")
		(net "DUT_TDI_R")
	)
	(segment
		(start 204.2541 -21.2217)
		(end 204.9145 -20.5613)
		(width 0.127)
		(layer "In5.Cu")
		(net "DUT_TDI_R")
	)
	(segment
		(start 204.9145 -20.5613)
		(end 208.415382 -20.5613)
		(width 0.127)
		(layer "In5.Cu")
		(net "DUT_TDI_R")
	)
	(segment
		(start 227.2919 -21.496782)
		(end 227.2919 -21.846794)
		(width 0.127)
		(layer "In5.Cu")
		(net "DUT_TDI_R")
	)
	(segment
		(start 178.545744 -21.97608)
		(end 178.545744 -20.598638)
		(width 0.127)
		(layer "In5.Cu")
		(net "DUT_TDI_R")
	)
	(segment
		(start 180.983636 -18.160746)
		(end 181.299104 -18.160746)
		(width 0.127)
		(layer "In5.Cu")
		(net "DUT_TDI_R")
	)
	(segment
		(start 208.415382 -20.5613)
		(end 208.986628 -19.990054)
		(width 0.127)
		(layer "In5.Cu")
		(net "DUT_TDI_R")
	)
	(segment
		(start 196.413374 -20.764754)
		(end 196.413628 -20.7645)
		(width 0.127)
		(layer "In5.Cu")
		(net "DUT_TDI_R")
	)
	(segment
		(start 190.140082 -18.161)
		(end 191.054736 -19.0754)
		(width 0.127)
		(layer "In5.Cu")
		(net "DUT_TDI_R")
	)
	(segment
		(start 194.269106 -20.7645)
		(end 195.037456 -20.7645)
		(width 0.127)
		(layer "In5.Cu")
		(net "DUT_TDI_R")
	)
	(segment
		(start 196.097652 -20.765008)
		(end 196.097906 -20.764754)
		(width 0.127)
		(layer "In5.Cu")
		(net "DUT_TDI_R")
	)
	(segment
		(start 220.462856 -20.552156)
		(end 226.347274 -20.552156)
		(width 0.127)
		(layer "In5.Cu")
		(net "DUT_TDI_R")
	)
	(segment
		(start 231.493822 -35.873944)
		(end 231.493822 -39.893748)
		(width 0.1016)
		(layer "In5.Cu")
		(net "DUT_TDI_R")
	)
	(segment
		(start 169.762424 -30.7594)
		(end 178.545744 -21.97608)
		(width 0.127)
		(layer "In5.Cu")
		(net "DUT_TDI_R")
	)
	(segment
		(start 195.037456 -20.7645)
		(end 195.039996 -20.765008)
		(width 0.127)
		(layer "In5.Cu")
		(net "DUT_TDI_R")
	)
	(segment
		(start 227.2919 -21.846794)
		(end 231.709722 -26.264616)
		(width 0.127)
		(layer "In5.Cu")
		(net "DUT_TDI_R")
	)
	(segment
		(start 181.299358 -18.161)
		(end 190.140082 -18.161)
		(width 0.127)
		(layer "In5.Cu")
		(net "DUT_TDI_R")
	)
	(segment
		(start 220.323156 -20.691856)
		(end 220.462856 -20.552156)
		(width 0.127)
		(layer "In5.Cu")
		(net "DUT_TDI_R")
	)
	(segment
		(start 181.299104 -18.160746)
		(end 181.299358 -18.161)
		(width 0.127)
		(layer "In5.Cu")
		(net "DUT_TDI_R")
	)
	(segment
		(start 231.70642 -28.832302)
		(end 231.70642 -35.661346)
		(width 0.1016)
		(layer "In5.Cu")
		(net "DUT_TDI_R")
	)
	(segment
		(start 199.311006 -21.2217)
		(end 204.2541 -21.2217)
		(width 0.127)
		(layer "In5.Cu")
		(net "DUT_TDI_R")
	)
	(segment
		(start 231.709722 -26.264616)
		(end 231.709722 -28.829)
		(width 0.127)
		(layer "In5.Cu")
		(net "DUT_TDI_R")
	)
	(segment
		(start 214.910162 -20.691856)
		(end 220.323156 -20.691856)
		(width 0.127)
		(layer "In5.Cu")
		(net "DUT_TDI_R")
	)
	(segment
		(start 196.413628 -20.7645)
		(end 198.853806 -20.7645)
		(width 0.127)
		(layer "In5.Cu")
		(net "DUT_TDI_R")
	)
	(segment
		(start 198.853806 -20.7645)
		(end 199.311006 -21.2217)
		(width 0.127)
		(layer "In5.Cu")
		(net "DUT_TDI_R")
	)
	(segment
		(start 208.986628 -19.990054)
		(end 214.20836 -19.990054)
		(width 0.127)
		(layer "In5.Cu")
		(net "DUT_TDI_R")
	)
	(segment
		(start 133.7437 -40.21201)
		(end 134.6327 -41.10101)
		(width 0.12065)
		(layer "F.Cu")
		(net "DUT_TDI")
	)
	(segment
		(start 133.7437 -40.05961)
		(end 133.7437 -40.21201)
		(width 0.12065)
		(layer "F.Cu")
		(net "DUT_TDI")
	)
	(segment
		(start 232.599992 -36.999926)
		(end 232.10012 -36.500054)
		(width 0.12065)
		(layer "F.Cu")
		(net "DUT_TAP_SEL_R")
	)
	(segment
		(start 219.09278 -28.08478)
		(end 220.472 -29.464)
		(width 0.12065)
		(layer "F.Cu")
		(net "DUT_TAP_SEL_R")
	)
	(segment
		(start 215.31834 -28.08478)
		(end 219.09278 -28.08478)
		(width 0.12065)
		(layer "F.Cu")
		(net "DUT_TAP_SEL_R")
	)
	(segment
		(start 213.0679 -26.8224)
		(end 214.33028 -28.08478)
		(width 0.12065)
		(layer "F.Cu")
		(net "DUT_TAP_SEL_R")
	)
	(segment
		(start 220.472 -29.464)
		(end 220.5228 -29.464)
		(width 0.12065)
		(layer "F.Cu")
		(net "DUT_TAP_SEL_R")
	)
	(segment
		(start 214.33028 -28.08478)
		(end 215.31834 -28.08478)
		(width 0.12065)
		(layer "F.Cu")
		(net "DUT_TAP_SEL_R")
	)
	(via
		(at 220.5228 -29.464)
		(size 0.508)
		(drill 0.254)
		(layers "F.Cu" "B.Cu")
		(net "DUT_TAP_SEL_R")
	)
	(via
		(at 232.10012 -36.500054)
		(size 0.4572)
		(drill 0.2032)
		(layers "F.Cu" "B.Cu")
		(net "DUT_TAP_SEL_R")
	)
	(via
		(at 215.31834 -28.08478)
		(size 0.7112)
		(drill 0.3556)
		(layers "F.Cu" "B.Cu")
		(net "DUT_TAP_SEL_R")
	)
	(segment
		(start 220.5228 -29.464)
		(end 220.726 -29.464)
		(width 0.127)
		(layer "In2.Cu")
		(net "DUT_TAP_SEL_R")
	)
	(segment
		(start 229.931722 -31.906464)
		(end 230.081328 -31.906464)
		(width 0.127)
		(layer "In2.Cu")
		(net "DUT_TAP_SEL_R")
	)
	(segment
		(start 229.039928 -28.865068)
		(end 229.5652 -29.39034)
		(width 0.127)
		(layer "In2.Cu")
		(net "DUT_TAP_SEL_R")
	)
	(segment
		(start 231.6226 -33.447736)
		(end 231.6226 -36.022534)
		(width 0.127)
		(layer "In2.Cu")
		(net "DUT_TAP_SEL_R")
	)
	(segment
		(start 220.726 -29.464)
		(end 221.324932 -28.865068)
		(width 0.127)
		(layer "In2.Cu")
		(net "DUT_TAP_SEL_R")
	)
	(segment
		(start 231.6226 -36.022534)
		(end 232.10012 -36.500054)
		(width 0.127)
		(layer "In2.Cu")
		(net "DUT_TAP_SEL_R")
	)
	(segment
		(start 230.93172 -32.906462)
		(end 231.081326 -32.906462)
		(width 0.127)
		(layer "In2.Cu")
		(net "DUT_TAP_SEL_R")
	)
	(segment
		(start 231.081326 -32.906462)
		(end 231.6226 -33.447736)
		(width 0.127)
		(layer "In2.Cu")
		(net "DUT_TAP_SEL_R")
	)
	(segment
		(start 221.324932 -28.865068)
		(end 229.039928 -28.865068)
		(width 0.127)
		(layer "In2.Cu")
		(net "DUT_TAP_SEL_R")
	)
	(segment
		(start 230.506524 -32.481266)
		(end 230.93172 -32.906462)
		(width 0.127)
		(layer "In2.Cu")
		(net "DUT_TAP_SEL_R")
	)
	(segment
		(start 229.5652 -31.539942)
		(end 229.931722 -31.906464)
		(width 0.127)
		(layer "In2.Cu")
		(net "DUT_TAP_SEL_R")
	)
	(segment
		(start 229.5652 -29.39034)
		(end 229.5652 -31.539942)
		(width 0.127)
		(layer "In2.Cu")
		(net "DUT_TAP_SEL_R")
	)
	(segment
		(start 230.506524 -32.33166)
		(end 230.506524 -32.481266)
		(width 0.127)
		(layer "In2.Cu")
		(net "DUT_TAP_SEL_R")
	)
	(segment
		(start 230.081328 -31.906464)
		(end 230.506524 -32.33166)
		(width 0.127)
		(layer "In2.Cu")
		(net "DUT_TAP_SEL_R")
	)
	(segment
		(start 212.1789 -26.8224)
		(end 211.614512 -26.8224)
		(width 0.12065)
		(layer "F.Cu")
		(net "DUT_TAP_SEL")
	)
	(segment
		(start 211.614512 -26.8224)
		(end 211.606892 -26.83002)
		(width 0.12065)
		(layer "F.Cu")
		(net "DUT_TAP_SEL")
	)
	(segment
		(start 212.217 -26.7843)
		(end 212.217 -25.527)
		(width 0.12065)
		(layer "F.Cu")
		(net "DUT_TAP_SEL")
	)
	(segment
		(start 211.606892 -26.83002)
		(end 211.15274 -26.83002)
		(width 0.12065)
		(layer "F.Cu")
		(net "DUT_TAP_SEL")
	)
	(segment
		(start 212.1789 -26.8224)
		(end 212.217 -26.7843)
		(width 0.12065)
		(layer "F.Cu")
		(net "DUT_TAP_SEL")
	)
	(segment
		(start 243.59997 -56.999886)
		(end 244.099842 -57.499758)
		(width 0.4572)
		(layer "F.Cu")
		(net "DUT_AVD_TX")
	)
	(segment
		(start 240.599976 -55.999888)
		(end 241.099848 -56.49976)
		(width 0.4572)
		(layer "F.Cu")
		(net "DUT_AVD_TX")
	)
	(segment
		(start 240.599976 -59.99988)
		(end 241.099848 -60.499752)
		(width 0.4572)
		(layer "F.Cu")
		(net "DUT_AVD_TX")
	)
	(segment
		(start 239.599978 -56.999886)
		(end 239.100106 -57.499758)
		(width 0.4572)
		(layer "F.Cu")
		(net "DUT_AVD_TX")
	)
	(segment
		(start 243.59997 -58.999882)
		(end 244.099842 -59.499754)
		(width 0.4572)
		(layer "F.Cu")
		(net "DUT_AVD_TX")
	)
	(segment
		(start 177.485802 -71.376032)
		(end 177.485802 -71.694802)
		(width 0.3048)
		(layer "F.Cu")
		(net "DUT_AVD_TX")
	)
	(segment
		(start 160.251902 -54.231032)
		(end 160.798002 -54.231032)
		(width 0.254)
		(layer "F.Cu")
		(net "DUT_AVD_TX")
	)
	(segment
		(start 245.599966 -58.999882)
		(end 246.099838 -59.499754)
		(width 0.4572)
		(layer "F.Cu")
		(net "DUT_AVD_TX")
	)
	(segment
		(start 238.59998 -55.999888)
		(end 238.100108 -56.49976)
		(width 0.4572)
		(layer "F.Cu")
		(net "DUT_AVD_TX")
	)
	(segment
		(start 176.723802 -71.376032)
		(end 176.723802 -71.694802)
		(width 0.3048)
		(layer "F.Cu")
		(net "DUT_AVD_TX")
	)
	(segment
		(start 241.599974 -58.999882)
		(end 242.099846 -59.499754)
		(width 0.4572)
		(layer "F.Cu")
		(net "DUT_AVD_TX")
	)
	(segment
		(start 240.599976 -57.999884)
		(end 241.099848 -58.499756)
		(width 0.4572)
		(layer "F.Cu")
		(net "DUT_AVD_TX")
	)
	(segment
		(start 237.599982 -56.999886)
		(end 237.10011 -57.499758)
		(width 0.4572)
		(layer "F.Cu")
		(net "DUT_AVD_TX")
	)
	(segment
		(start 241.599974 -56.999886)
		(end 242.099846 -57.499758)
		(width 0.4572)
		(layer "F.Cu")
		(net "DUT_AVD_TX")
	)
	(segment
		(start 238.59998 -59.99988)
		(end 238.100108 -60.499752)
		(width 0.4572)
		(layer "F.Cu")
		(net "DUT_AVD_TX")
	)
	(segment
		(start 236.599984 -57.999884)
		(end 236.100112 -58.499756)
		(width 0.4572)
		(layer "F.Cu")
		(net "DUT_AVD_TX")
	)
	(segment
		(start 236.599984 -59.99988)
		(end 236.100112 -60.499752)
		(width 0.4572)
		(layer "F.Cu")
		(net "DUT_AVD_TX")
	)
	(segment
		(start 244.599968 -57.999884)
		(end 245.09984 -58.499756)
		(width 0.4572)
		(layer "F.Cu")
		(net "DUT_AVD_TX")
	)
	(segment
		(start 244.599968 -59.99988)
		(end 245.09984 -60.499752)
		(width 0.4572)
		(layer "F.Cu")
		(net "DUT_AVD_TX")
	)
	(segment
		(start 237.599982 -58.999882)
		(end 237.10011 -59.499754)
		(width 0.4572)
		(layer "F.Cu")
		(net "DUT_AVD_TX")
	)
	(segment
		(start 238.59998 -57.999884)
		(end 238.100108 -58.499756)
		(width 0.4572)
		(layer "F.Cu")
		(net "DUT_AVD_TX")
	)
	(segment
		(start 239.599978 -58.999882)
		(end 239.100106 -59.499754)
		(width 0.4572)
		(layer "F.Cu")
		(net "DUT_AVD_TX")
	)
	(segment
		(start 235.599986 -56.999886)
		(end 235.100114 -57.499758)
		(width 0.4572)
		(layer "F.Cu")
		(net "DUT_AVD_TX")
	)
	(segment
		(start 245.599966 -56.999886)
		(end 246.099838 -57.499758)
		(width 0.4572)
		(layer "F.Cu")
		(net "DUT_AVD_TX")
	)
	(segment
		(start 175.961802 -71.376032)
		(end 175.961802 -71.694802)
		(width 0.3048)
		(layer "F.Cu")
		(net "DUT_AVD_TX")
	)
	(segment
		(start 236.599984 -55.999888)
		(end 236.100112 -56.49976)
		(width 0.4572)
		(layer "F.Cu")
		(net "DUT_AVD_TX")
	)
	(segment
		(start 242.599972 -59.99988)
		(end 243.099844 -60.499752)
		(width 0.4572)
		(layer "F.Cu")
		(net "DUT_AVD_TX")
	)
	(segment
		(start 242.599972 -55.999888)
		(end 243.099844 -56.49976)
		(width 0.4572)
		(layer "F.Cu")
		(net "DUT_AVD_TX")
	)
	(segment
		(start 160.798002 -54.231032)
		(end 161.509202 -54.942232)
		(width 0.254)
		(layer "F.Cu")
		(net "DUT_AVD_TX")
	)
	(segment
		(start 235.599986 -58.999882)
		(end 235.100114 -59.499754)
		(width 0.4572)
		(layer "F.Cu")
		(net "DUT_AVD_TX")
	)
	(segment
		(start 244.599968 -55.999888)
		(end 245.09984 -56.49976)
		(width 0.4572)
		(layer "F.Cu")
		(net "DUT_AVD_TX")
	)
	(segment
		(start 242.599972 -57.999884)
		(end 243.099844 -58.499756)
		(width 0.4572)
		(layer "F.Cu")
		(net "DUT_AVD_TX")
	)
	(via
		(at 237.10011 -57.499758)
		(size 0.4572)
		(drill 0.2032)
		(layers "F.Cu" "B.Cu")
		(net "DUT_AVD_TX")
	)
	(via
		(at 237.10011 -59.499754)
		(size 0.4572)
		(drill 0.2032)
		(layers "F.Cu" "B.Cu")
		(net "DUT_AVD_TX")
	)
	(via
		(at 175.6156 -78.74)
		(size 0.7112)
		(drill 0.3556)
		(layers "F.Cu" "B.Cu")
		(net "DUT_AVD_TX")
	)
	(via
		(at 245.09984 -56.49976)
		(size 0.4572)
		(drill 0.2032)
		(layers "F.Cu" "B.Cu")
		(net "DUT_AVD_TX")
	)
	(via
		(at 238.100108 -58.499756)
		(size 0.4572)
		(drill 0.2032)
		(layers "F.Cu" "B.Cu")
		(net "DUT_AVD_TX")
	)
	(via
		(at 239.100106 -57.499758)
		(size 0.4572)
		(drill 0.2032)
		(layers "F.Cu" "B.Cu")
		(net "DUT_AVD_TX")
	)
	(via
		(at 176.774602 -75.643232)
		(size 0.7112)
		(drill 0.4064)
		(layers "F.Cu" "B.Cu")
		(net "DUT_AVD_TX")
	)
	(via
		(at 175.428402 -74.195432)
		(size 0.7112)
		(drill 0.4064)
		(layers "F.Cu" "B.Cu")
		(net "DUT_AVD_TX")
	)
	(via
		(at 241.099848 -60.499752)
		(size 0.4572)
		(drill 0.2032)
		(layers "F.Cu" "B.Cu")
		(net "DUT_AVD_TX")
	)
	(via
		(at 244.099842 -59.499754)
		(size 0.4572)
		(drill 0.2032)
		(layers "F.Cu" "B.Cu")
		(net "DUT_AVD_TX")
	)
	(via
		(at 161.509202 -54.942232)
		(size 0.508)
		(drill 0.254)
		(layers "F.Cu" "B.Cu")
		(net "DUT_AVD_TX")
	)
	(via
		(at 243.099844 -56.49976)
		(size 0.4572)
		(drill 0.2032)
		(layers "F.Cu" "B.Cu")
		(net "DUT_AVD_TX")
	)
	(via
		(at 243.099844 -58.499756)
		(size 0.4572)
		(drill 0.2032)
		(layers "F.Cu" "B.Cu")
		(net "DUT_AVD_TX")
	)
	(via
		(at 245.09984 -60.499752)
		(size 0.4572)
		(drill 0.2032)
		(layers "F.Cu" "B.Cu")
		(net "DUT_AVD_TX")
	)
	(via
		(at 175.428402 -73.052432)
		(size 0.7112)
		(drill 0.4064)
		(layers "F.Cu" "B.Cu")
		(net "DUT_AVD_TX")
	)
	(via
		(at 244.099842 -57.499758)
		(size 0.4572)
		(drill 0.2032)
		(layers "F.Cu" "B.Cu")
		(net "DUT_AVD_TX")
	)
	(via
		(at 236.100112 -60.499752)
		(size 0.4572)
		(drill 0.2032)
		(layers "F.Cu" "B.Cu")
		(net "DUT_AVD_TX")
	)
	(via
		(at 238.100108 -60.499752)
		(size 0.4572)
		(drill 0.2032)
		(layers "F.Cu" "B.Cu")
		(net "DUT_AVD_TX")
	)
	(via
		(at 238.100108 -56.49976)
		(size 0.4572)
		(drill 0.2032)
		(layers "F.Cu" "B.Cu")
		(net "DUT_AVD_TX")
	)
	(via
		(at 243.099844 -60.499752)
		(size 0.4572)
		(drill 0.2032)
		(layers "F.Cu" "B.Cu")
		(net "DUT_AVD_TX")
	)
	(via
		(at 176.774602 -74.500232)
		(size 0.7112)
		(drill 0.4064)
		(layers "F.Cu" "B.Cu")
		(net "DUT_AVD_TX")
	)
	(via
		(at 246.099838 -59.499754)
		(size 0.4572)
		(drill 0.2032)
		(layers "F.Cu" "B.Cu")
		(net "DUT_AVD_TX")
	)
	(via
		(at 236.100112 -56.49976)
		(size 0.4572)
		(drill 0.2032)
		(layers "F.Cu" "B.Cu")
		(net "DUT_AVD_TX")
	)
	(via
		(at 176.774602 -76.786232)
		(size 0.7112)
		(drill 0.4064)
		(layers "F.Cu" "B.Cu")
		(net "DUT_AVD_TX")
	)
	(via
		(at 239.8522 -68.834)
		(size 0.7112)
		(drill 0.3556)
		(layers "F.Cu" "B.Cu")
		(net "DUT_AVD_TX")
	)
	(via
		(at 181.102 -78.74)
		(size 0.508)
		(drill 0.254)
		(layers "F.Cu" "B.Cu")
		(net "DUT_AVD_TX")
	)
	(via
		(at 235.100114 -59.499754)
		(size 0.4572)
		(drill 0.2032)
		(layers "F.Cu" "B.Cu")
		(net "DUT_AVD_TX")
	)
	(via
		(at 241.099848 -58.499756)
		(size 0.4572)
		(drill 0.2032)
		(layers "F.Cu" "B.Cu")
		(net "DUT_AVD_TX")
	)
	(via
		(at 242.099846 -57.499758)
		(size 0.4572)
		(drill 0.2032)
		(layers "F.Cu" "B.Cu")
		(net "DUT_AVD_TX")
	)
	(via
		(at 242.099846 -59.499754)
		(size 0.4572)
		(drill 0.2032)
		(layers "F.Cu" "B.Cu")
		(net "DUT_AVD_TX")
	)
	(via
		(at 164.9476 -59.563)
		(size 0.508)
		(drill 0.254)
		(layers "F.Cu" "B.Cu")
		(net "DUT_AVD_TX")
	)
	(via
		(at 245.09984 -58.499756)
		(size 0.4572)
		(drill 0.2032)
		(layers "F.Cu" "B.Cu")
		(net "DUT_AVD_TX")
	)
	(via
		(at 241.099848 -56.49976)
		(size 0.4572)
		(drill 0.2032)
		(layers "F.Cu" "B.Cu")
		(net "DUT_AVD_TX")
	)
	(via
		(at 239.100106 -59.499754)
		(size 0.4572)
		(drill 0.2032)
		(layers "F.Cu" "B.Cu")
		(net "DUT_AVD_TX")
	)
	(via
		(at 235.100114 -57.499758)
		(size 0.4572)
		(drill 0.2032)
		(layers "F.Cu" "B.Cu")
		(net "DUT_AVD_TX")
	)
	(via
		(at 246.099838 -57.499758)
		(size 0.4572)
		(drill 0.2032)
		(layers "F.Cu" "B.Cu")
		(net "DUT_AVD_TX")
	)
	(via
		(at 236.100112 -58.499756)
		(size 0.4572)
		(drill 0.2032)
		(layers "F.Cu" "B.Cu")
		(net "DUT_AVD_TX")
	)
	(segment
		(start 245.872 -57.27192)
		(end 246.099838 -57.499758)
		(width 0.3048)
		(layer "B.Cu")
		(net "DUT_AVD_TX")
	)
	(segment
		(start 235.8644 -56.00192)
		(end 235.8644 -56.264048)
		(width 0.3048)
		(layer "B.Cu")
		(net "DUT_AVD_TX")
	)
	(segment
		(start 230.378 -78.74)
		(end 181.102 -78.74)
		(width 0.254)
		(layer "B.Cu")
		(net "DUT_AVD_TX")
	)
	(segment
		(start 175.961802 -71.376032)
		(end 175.961802 -71.764398)
		(width 0.3048)
		(layer "B.Cu")
		(net "DUT_AVD_TX")
	)
	(segment
		(start 245.872 -59.271916)
		(end 246.099838 -59.499754)
		(width 0.3048)
		(layer "B.Cu")
		(net "DUT_AVD_TX")
	)
	(segment
		(start 176.723802 -71.376032)
		(end 176.723802 -71.764398)
		(width 0.3048)
		(layer "B.Cu")
		(net "DUT_AVD_TX")
	)
	(segment
		(start 177.485802 -71.376032)
		(end 177.485802 -71.764398)
		(width 0.3048)
		(layer "B.Cu")
		(net "DUT_AVD_TX")
	)
	(segment
		(start 245.872 -59.0042)
		(end 245.872 -59.271916)
		(width 0.3048)
		(layer "B.Cu")
		(net "DUT_AVD_TX")
	)
	(segment
		(start 245.872 -56.9976)
		(end 245.872 -57.27192)
		(width 0.3048)
		(layer "B.Cu")
		(net "DUT_AVD_TX")
	)
	(segment
		(start 235.712 -73.406)
		(end 230.378 -78.74)
		(width 0.254)
		(layer "B.Cu")
		(net "DUT_AVD_TX")
	)
	(segment
		(start 235.8644 -56.264048)
		(end 236.100112 -56.49976)
		(width 0.3048)
		(layer "B.Cu")
		(net "DUT_AVD_TX")
	)
	(segment
		(start 164.9476 -59.563)
		(end 164.9476 -58.572654)
		(width 0.254)
		(layer "In2.Cu")
		(net "DUT_AVD_TX")
	)
	(segment
		(start 164.9476 -58.572654)
		(end 161.509202 -55.134256)
		(width 0.254)
		(layer "In2.Cu")
		(net "DUT_AVD_TX")
	)
	(segment
		(start 161.509202 -55.134256)
		(end 161.509202 -54.942232)
		(width 0.254)
		(layer "In2.Cu")
		(net "DUT_AVD_TX")
	)
	(segment
		(start 164.9476 -59.563)
		(end 177.342546 -59.563)
		(width 0.254)
		(layer "In5.Cu")
		(net "DUT_AVD_TX")
	)
	(segment
		(start 177.342546 -59.563)
		(end 178.7906 -61.011054)
		(width 0.254)
		(layer "In5.Cu")
		(net "DUT_AVD_TX")
	)
	(segment
		(start 178.7906 -76.4286)
		(end 181.102 -78.74)
		(width 0.254)
		(layer "In5.Cu")
		(net "DUT_AVD_TX")
	)
	(segment
		(start 178.7906 -61.011054)
		(end 178.7906 -76.4286)
		(width 0.254)
		(layer "In5.Cu")
		(net "DUT_AVD_TX")
	)
	(segment
		(start 241.599974 -41.999916)
		(end 242.099846 -41.500044)
		(width 0.4572)
		(layer "F.Cu")
		(net "DUT_AVD_PCIE_Q")
	)
	(segment
		(start 248.59996 -46.999906)
		(end 249.099832 -46.500034)
		(width 0.4572)
		(layer "F.Cu")
		(net "DUT_AVD_PCIE_Q")
	)
	(segment
		(start 232.599992 -46.999906)
		(end 232.10012 -46.500034)
		(width 0.4572)
		(layer "F.Cu")
		(net "DUT_AVD_PCIE_Q")
	)
	(segment
		(start 232.599992 -53.999892)
		(end 232.10012 -54.499764)
		(width 0.4572)
		(layer "F.Cu")
		(net "DUT_AVD_PCIE_Q")
	)
	(segment
		(start 248.59996 -53.999892)
		(end 249.099832 -54.499764)
		(width 0.4572)
		(layer "F.Cu")
		(net "DUT_AVD_PCIE_Q")
	)
	(via
		(at 232.10012 -54.499764)
		(size 0.4572)
		(drill 0.2032)
		(layers "F.Cu" "B.Cu")
		(net "DUT_AVD_PCIE_Q")
	)
	(via
		(at 249.099832 -54.499764)
		(size 0.4572)
		(drill 0.2032)
		(layers "F.Cu" "B.Cu")
		(net "DUT_AVD_PCIE_Q")
	)
	(via
		(at 189.493398 -54.353968)
		(size 0.508)
		(drill 0.254)
		(layers "F.Cu" "B.Cu")
		(net "DUT_AVD_PCIE_Q")
	)
	(via
		(at 242.099846 -41.500044)
		(size 0.4572)
		(drill 0.2032)
		(layers "F.Cu" "B.Cu")
		(net "DUT_AVD_PCIE_Q")
	)
	(via
		(at 249.099832 -46.500034)
		(size 0.4572)
		(drill 0.2032)
		(layers "F.Cu" "B.Cu")
		(net "DUT_AVD_PCIE_Q")
	)
	(via
		(at 190.331598 -53.896768)
		(size 0.508)
		(drill 0.254)
		(layers "F.Cu" "B.Cu")
		(net "DUT_AVD_PCIE_Q")
	)
	(via
		(at 189.544198 -53.439568)
		(size 0.508)
		(drill 0.254)
		(layers "F.Cu" "B.Cu")
		(net "DUT_AVD_PCIE_Q")
	)
	(via
		(at 232.10012 -46.500034)
		(size 0.4572)
		(drill 0.2032)
		(layers "F.Cu" "B.Cu")
		(net "DUT_AVD_PCIE_Q")
	)
	(via
		(at 186.9694 -50.0888)
		(size 0.7112)
		(drill 0.3556)
		(layers "F.Cu" "B.Cu")
		(net "DUT_AVD_PCIE_Q")
	)
	(segment
		(start 242.409472 -41.012872)
		(end 242.409472 -41.190418)
		(width 0.3048)
		(layer "B.Cu")
		(net "DUT_AVD_PCIE_Q")
	)
	(segment
		(start 249.2629 -46.663102)
		(end 249.099832 -46.500034)
		(width 0.3048)
		(layer "B.Cu")
		(net "DUT_AVD_PCIE_Q")
	)
	(segment
		(start 249.2756 -54.99227)
		(end 249.2756 -54.675532)
		(width 0.3048)
		(layer "B.Cu")
		(net "DUT_AVD_PCIE_Q")
	)
	(segment
		(start 231.8766 -54.991)
		(end 231.8766 -54.723284)
		(width 0.3048)
		(layer "B.Cu")
		(net "DUT_AVD_PCIE_Q")
	)
	(segment
		(start 249.2629 -47.0027)
		(end 249.2629 -46.663102)
		(width 0.3048)
		(layer "B.Cu")
		(net "DUT_AVD_PCIE_Q")
	)
	(segment
		(start 231.8766 -46.276514)
		(end 232.10012 -46.500034)
		(width 0.3048)
		(layer "B.Cu")
		(net "DUT_AVD_PCIE_Q")
	)
	(segment
		(start 242.409472 -41.190418)
		(end 242.099846 -41.500044)
		(width 0.3048)
		(layer "B.Cu")
		(net "DUT_AVD_PCIE_Q")
	)
	(segment
		(start 249.2756 -54.675532)
		(end 249.099832 -54.499764)
		(width 0.3048)
		(layer "B.Cu")
		(net "DUT_AVD_PCIE_Q")
	)
	(segment
		(start 231.8766 -45.9994)
		(end 231.8766 -46.276514)
		(width 0.3048)
		(layer "B.Cu")
		(net "DUT_AVD_PCIE_Q")
	)
	(segment
		(start 231.8766 -54.723284)
		(end 232.10012 -54.499764)
		(width 0.3048)
		(layer "B.Cu")
		(net "DUT_AVD_PCIE_Q")
	)
	(segment
		(start 249.599958 -59.99988)
		(end 250.09983 -60.499752)
		(width 0.4572)
		(layer "F.Cu")
		(net "DUT_AVD_PCIE")
	)
	(segment
		(start 228.6 -50.999898)
		(end 228.100128 -51.49977)
		(width 0.4572)
		(layer "F.Cu")
		(net "DUT_AVD_PCIE")
	)
	(segment
		(start 252.599952 -54.99989)
		(end 253.099824 -55.499762)
		(width 0.4572)
		(layer "F.Cu")
		(net "DUT_AVD_PCIE")
	)
	(segment
		(start 252.599952 -50.999898)
		(end 253.099824 -51.49977)
		(width 0.4572)
		(layer "F.Cu")
		(net "DUT_AVD_PCIE")
	)
	(segment
		(start 228.6 -44.99991)
		(end 228.100128 -44.500038)
		(width 0.4572)
		(layer "F.Cu")
		(net "DUT_AVD_PCIE")
	)
	(segment
		(start 228.6 -58.999882)
		(end 228.100128 -59.499754)
		(width 0.4572)
		(layer "F.Cu")
		(net "DUT_AVD_PCIE")
	)
	(segment
		(start 178.4096 -66.167)
		(end 178.732434 -66.167)
		(width 0.3048)
		(layer "F.Cu")
		(net "DUT_AVD_PCIE")
	)
	(segment
		(start 228.6 -48.999902)
		(end 228.100128 -49.499774)
		(width 0.4572)
		(layer "F.Cu")
		(net "DUT_AVD_PCIE")
	)
	(segment
		(start 252.599952 -35.999928)
		(end 253.099824 -35.500056)
		(width 0.4572)
		(layer "F.Cu")
		(net "DUT_AVD_PCIE")
	)
	(segment
		(start 230.599996 -46.999906)
		(end 230.100124 -46.500034)
		(width 0.4572)
		(layer "F.Cu")
		(net "DUT_AVD_PCIE")
	)
	(segment
		(start 252.599952 -33.999932)
		(end 253.099824 -33.50006)
		(width 0.4572)
		(layer "F.Cu")
		(net "DUT_AVD_PCIE")
	)
	(segment
		(start 178.4096 -67.691)
		(end 178.732434 -67.691)
		(width 0.3048)
		(layer "F.Cu")
		(net "DUT_AVD_PCIE")
	)
	(segment
		(start 252.599952 -36.999926)
		(end 253.099824 -36.500054)
		(width 0.4572)
		(layer "F.Cu")
		(net "DUT_AVD_PCIE")
	)
	(segment
		(start 229.599998 -59.99988)
		(end 229.100126 -60.499752)
		(width 0.4572)
		(layer "F.Cu")
		(net "DUT_AVD_PCIE")
	)
	(segment
		(start 236.599984 -40.999918)
		(end 236.100112 -40.500046)
		(width 0.4572)
		(layer "F.Cu")
		(net "DUT_AVD_PCIE")
	)
	(segment
		(start 250.599956 -59.99988)
		(end 251.099828 -60.499752)
		(width 0.4572)
		(layer "F.Cu")
		(net "DUT_AVD_PCIE")
	)
	(segment
		(start 247.599962 -53.999892)
		(end 248.099834 -54.499764)
		(width 0.4572)
		(layer "F.Cu")
		(net "DUT_AVD_PCIE")
	)
	(segment
		(start 252.599952 -44.99991)
		(end 253.099824 -44.500038)
		(width 0.4572)
		(layer "F.Cu")
		(net "DUT_AVD_PCIE")
	)
	(segment
		(start 228.6 -52.999894)
		(end 228.100128 -53.499766)
		(width 0.4572)
		(layer "F.Cu")
		(net "DUT_AVD_PCIE")
	)
	(segment
		(start 228.6 -54.99989)
		(end 228.100128 -55.499762)
		(width 0.4572)
		(layer "F.Cu")
		(net "DUT_AVD_PCIE")
	)
	(segment
		(start 250.599956 -41.999916)
		(end 251.099828 -41.500044)
		(width 0.4572)
		(layer "F.Cu")
		(net "DUT_AVD_PCIE")
	)
	(segment
		(start 252.599952 -34.99993)
		(end 253.099824 -34.500058)
		(width 0.4572)
		(layer "F.Cu")
		(net "DUT_AVD_PCIE")
	)
	(segment
		(start 178.4096 -69.215)
		(end 178.732434 -69.215)
		(width 0.3048)
		(layer "F.Cu")
		(net "DUT_AVD_PCIE")
	)
	(segment
		(start 252.599952 -45.999908)
		(end 253.099824 -45.500036)
		(width 0.4572)
		(layer "F.Cu")
		(net "DUT_AVD_PCIE")
	)
	(segment
		(start 252.599952 -47.999904)
		(end 253.099824 -48.499776)
		(width 0.4572)
		(layer "F.Cu")
		(net "DUT_AVD_PCIE")
	)
	(segment
		(start 228.6 -56.999886)
		(end 228.100128 -57.499758)
		(width 0.4572)
		(layer "F.Cu")
		(net "DUT_AVD_PCIE")
	)
	(segment
		(start 248.59996 -44.99991)
		(end 249.099832 -44.500038)
		(width 0.4572)
		(layer "F.Cu")
		(net "DUT_AVD_PCIE")
	)
	(segment
		(start 253.59995 -41.999916)
		(end 254.099822 -41.500044)
		(width 0.4572)
		(layer "F.Cu")
		(net "DUT_AVD_PCIE")
	)
	(segment
		(start 248.59996 -59.99988)
		(end 249.099832 -60.499752)
		(width 0.4572)
		(layer "F.Cu")
		(net "DUT_AVD_PCIE")
	)
	(segment
		(start 233.59999 -45.999908)
		(end 233.100118 -45.500036)
		(width 0.4572)
		(layer "F.Cu")
		(net "DUT_AVD_PCIE")
	)
	(segment
		(start 228.6 -40.999918)
		(end 228.100128 -40.500046)
		(width 0.4572)
		(layer "F.Cu")
		(net "DUT_AVD_PCIE")
	)
	(segment
		(start 252.599952 -58.999882)
		(end 253.099824 -59.499754)
		(width 0.4572)
		(layer "F.Cu")
		(net "DUT_AVD_PCIE")
	)
	(segment
		(start 229.599998 -46.999906)
		(end 229.100126 -46.500034)
		(width 0.4572)
		(layer "F.Cu")
		(net "DUT_AVD_PCIE")
	)
	(segment
		(start 252.599952 -59.99988)
		(end 253.099824 -60.499752)
		(width 0.4572)
		(layer "F.Cu")
		(net "DUT_AVD_PCIE")
	)
	(segment
		(start 252.599952 -53.999892)
		(end 253.099824 -54.499764)
		(width 0.4572)
		(layer "F.Cu")
		(net "DUT_AVD_PCIE")
	)
	(segment
		(start 246.599964 -59.99988)
		(end 247.099836 -60.499752)
		(width 0.4572)
		(layer "F.Cu")
		(net "DUT_AVD_PCIE")
	)
	(segment
		(start 228.6 -39.99992)
		(end 228.100128 -39.500048)
		(width 0.4572)
		(layer "F.Cu")
		(net "DUT_AVD_PCIE")
	)
	(segment
		(start 228.6 -43.999912)
		(end 228.100128 -43.50004)
		(width 0.4572)
		(layer "F.Cu")
		(net "DUT_AVD_PCIE")
	)
	(segment
		(start 230.599996 -59.99988)
		(end 230.100124 -60.499752)
		(width 0.4572)
		(layer "F.Cu")
		(net "DUT_AVD_PCIE")
	)
	(segment
		(start 252.599952 -37.999924)
		(end 253.099824 -37.500052)
		(width 0.4572)
		(layer "F.Cu")
		(net "DUT_AVD_PCIE")
	)
	(segment
		(start 178.4096 -65.405)
		(end 178.732434 -65.405)
		(width 0.3048)
		(layer "F.Cu")
		(net "DUT_AVD_PCIE")
	)
	(segment
		(start 252.599952 -42.999914)
		(end 253.099824 -42.500042)
		(width 0.4572)
		(layer "F.Cu")
		(net "DUT_AVD_PCIE")
	)
	(segment
		(start 252.599952 -46.999906)
		(end 253.099824 -46.500034)
		(width 0.4572)
		(layer "F.Cu")
		(net "DUT_AVD_PCIE")
	)
	(segment
		(start 231.599994 -59.99988)
		(end 231.100122 -60.499752)
		(width 0.4572)
		(layer "F.Cu")
		(net "DUT_AVD_PCIE")
	)
	(segment
		(start 160.620202 -53.189632)
		(end 160.251902 -53.189632)
		(width 0.254)
		(layer "F.Cu")
		(net "DUT_AVD_PCIE")
	)
	(segment
		(start 252.599952 -52.999894)
		(end 253.099824 -53.499766)
		(width 0.4572)
		(layer "F.Cu")
		(net "DUT_AVD_PCIE")
	)
	(segment
		(start 253.59995 -50.999898)
		(end 254.099822 -51.49977)
		(width 0.4572)
		(layer "F.Cu")
		(net "DUT_AVD_PCIE")
	)
	(segment
		(start 233.59999 -53.999892)
		(end 233.100118 -54.499764)
		(width 0.4572)
		(layer "F.Cu")
		(net "DUT_AVD_PCIE")
	)
	(segment
		(start 227.600002 -59.99988)
		(end 227.10013 -60.499752)
		(width 0.4572)
		(layer "F.Cu")
		(net "DUT_AVD_PCIE")
	)
	(segment
		(start 250.599956 -46.999906)
		(end 251.099828 -46.500034)
		(width 0.4572)
		(layer "F.Cu")
		(net "DUT_AVD_PCIE")
	)
	(segment
		(start 251.599954 -59.99988)
		(end 252.099826 -60.499752)
		(width 0.4572)
		(layer "F.Cu")
		(net "DUT_AVD_PCIE")
	)
	(segment
		(start 228.6 -38.999922)
		(end 228.100128 -38.50005)
		(width 0.4572)
		(layer "F.Cu")
		(net "DUT_AVD_PCIE")
	)
	(segment
		(start 228.6 -41.999916)
		(end 228.100128 -41.500044)
		(width 0.4572)
		(layer "F.Cu")
		(net "DUT_AVD_PCIE")
	)
	(segment
		(start 228.6 -37.999924)
		(end 228.100128 -37.500052)
		(width 0.4572)
		(layer "F.Cu")
		(net "DUT_AVD_PCIE")
	)
	(segment
		(start 230.599996 -41.999916)
		(end 230.100124 -41.500044)
		(width 0.4572)
		(layer "F.Cu")
		(net "DUT_AVD_PCIE")
	)
	(segment
		(start 253.59995 -59.99988)
		(end 254.099822 -60.499752)
		(width 0.4572)
		(layer "F.Cu")
		(net "DUT_AVD_PCIE")
	)
	(segment
		(start 252.599952 -41.999916)
		(end 253.099824 -41.500044)
		(width 0.4572)
		(layer "F.Cu")
		(net "DUT_AVD_PCIE")
	)
	(segment
		(start 228.6 -47.999904)
		(end 228.100128 -48.499776)
		(width 0.4572)
		(layer "F.Cu")
		(net "DUT_AVD_PCIE")
	)
	(segment
		(start 252.599952 -55.999888)
		(end 253.099824 -56.49976)
		(width 0.4572)
		(layer "F.Cu")
		(net "DUT_AVD_PCIE")
	)
	(segment
		(start 228.6 -46.999906)
		(end 228.100128 -46.500034)
		(width 0.4572)
		(layer "F.Cu")
		(net "DUT_AVD_PCIE")
	)
	(segment
		(start 251.599954 -46.999906)
		(end 252.099826 -46.500034)
		(width 0.4572)
		(layer "F.Cu")
		(net "DUT_AVD_PCIE")
	)
	(segment
		(start 233.59999 -59.99988)
		(end 233.100118 -60.499752)
		(width 0.4572)
		(layer "F.Cu")
		(net "DUT_AVD_PCIE")
	)
	(segment
		(start 252.599952 -49.9999)
		(end 253.099824 -50.499772)
		(width 0.4572)
		(layer "F.Cu")
		(net "DUT_AVD_PCIE")
	)
	(segment
		(start 228.6 -55.999888)
		(end 228.100128 -56.49976)
		(width 0.4572)
		(layer "F.Cu")
		(net "DUT_AVD_PCIE")
	)
	(segment
		(start 252.599952 -39.99992)
		(end 253.099824 -39.500048)
		(width 0.4572)
		(layer "F.Cu")
		(net "DUT_AVD_PCIE")
	)
	(segment
		(start 228.6 -35.999928)
		(end 228.100128 -35.500056)
		(width 0.4572)
		(layer "F.Cu")
		(net "DUT_AVD_PCIE")
	)
	(segment
		(start 178.4096 -68.453)
		(end 178.732434 -68.453)
		(width 0.3048)
		(layer "F.Cu")
		(net "DUT_AVD_PCIE")
	)
	(segment
		(start 228.6 -42.999914)
		(end 228.100128 -42.500042)
		(width 0.4572)
		(layer "F.Cu")
		(net "DUT_AVD_PCIE")
	)
	(segment
		(start 162.6616 -55.23103)
		(end 160.620202 -53.189632)
		(width 0.254)
		(layer "F.Cu")
		(net "DUT_AVD_PCIE")
	)
	(segment
		(start 253.59995 -33.999932)
		(end 254.099822 -33.50006)
		(width 0.4572)
		(layer "F.Cu")
		(net "DUT_AVD_PCIE")
	)
	(segment
		(start 228.6 -59.99988)
		(end 228.100128 -60.499752)
		(width 0.4572)
		(layer "F.Cu")
		(net "DUT_AVD_PCIE")
	)
	(segment
		(start 229.599998 -41.999916)
		(end 229.100126 -41.500044)
		(width 0.4572)
		(layer "F.Cu")
		(net "DUT_AVD_PCIE")
	)
	(segment
		(start 178.4096 -66.929)
		(end 178.732434 -66.929)
		(width 0.3048)
		(layer "F.Cu")
		(net "DUT_AVD_PCIE")
	)
	(segment
		(start 162.6616 -55.4228)
		(end 162.6616 -55.23103)
		(width 0.254)
		(layer "F.Cu")
		(net "DUT_AVD_PCIE")
	)
	(segment
		(start 252.599952 -40.999918)
		(end 253.099824 -40.500046)
		(width 0.4572)
		(layer "F.Cu")
		(net "DUT_AVD_PCIE")
	)
	(segment
		(start 252.599952 -43.999912)
		(end 253.099824 -43.50004)
		(width 0.4572)
		(layer "F.Cu")
		(net "DUT_AVD_PCIE")
	)
	(segment
		(start 227.600002 -33.999932)
		(end 227.10013 -33.50006)
		(width 0.4572)
		(layer "F.Cu")
		(net "DUT_AVD_PCIE")
	)
	(segment
		(start 252.599952 -48.999902)
		(end 253.099824 -49.499774)
		(width 0.4572)
		(layer "F.Cu")
		(net "DUT_AVD_PCIE")
	)
	(segment
		(start 228.6 -49.9999)
		(end 228.100128 -50.499772)
		(width 0.4572)
		(layer "F.Cu")
		(net "DUT_AVD_PCIE")
	)
	(segment
		(start 251.599954 -41.999916)
		(end 252.099826 -41.500044)
		(width 0.4572)
		(layer "F.Cu")
		(net "DUT_AVD_PCIE")
	)
	(segment
		(start 228.6 -34.99993)
		(end 228.100128 -34.500058)
		(width 0.4572)
		(layer "F.Cu")
		(net "DUT_AVD_PCIE")
	)
	(segment
		(start 252.599952 -38.999922)
		(end 253.099824 -38.50005)
		(width 0.4572)
		(layer "F.Cu")
		(net "DUT_AVD_PCIE")
	)
	(segment
		(start 247.599962 -45.999908)
		(end 248.099834 -45.500036)
		(width 0.4572)
		(layer "F.Cu")
		(net "DUT_AVD_PCIE")
	)
	(segment
		(start 228.6 -53.999892)
		(end 228.100128 -54.499764)
		(width 0.4572)
		(layer "F.Cu")
		(net "DUT_AVD_PCIE")
	)
	(segment
		(start 252.599952 -57.999884)
		(end 253.099824 -58.499756)
		(width 0.4572)
		(layer "F.Cu")
		(net "DUT_AVD_PCIE")
	)
	(segment
		(start 228.6 -36.999926)
		(end 228.100128 -36.500054)
		(width 0.4572)
		(layer "F.Cu")
		(net "DUT_AVD_PCIE")
	)
	(segment
		(start 227.600002 -50.999898)
		(end 227.10013 -51.49977)
		(width 0.4572)
		(layer "F.Cu")
		(net "DUT_AVD_PCIE")
	)
	(segment
		(start 232.599992 -59.99988)
		(end 232.10012 -60.499752)
		(width 0.4572)
		(layer "F.Cu")
		(net "DUT_AVD_PCIE")
	)
	(segment
		(start 228.6 -33.999932)
		(end 228.100128 -33.50006)
		(width 0.4572)
		(layer "F.Cu")
		(net "DUT_AVD_PCIE")
	)
	(segment
		(start 234.599988 -59.99988)
		(end 234.100116 -60.499752)
		(width 0.4572)
		(layer "F.Cu")
		(net "DUT_AVD_PCIE")
	)
	(segment
		(start 252.599952 -56.999886)
		(end 253.099824 -57.499758)
		(width 0.4572)
		(layer "F.Cu")
		(net "DUT_AVD_PCIE")
	)
	(segment
		(start 228.6 -57.999884)
		(end 228.100128 -58.499756)
		(width 0.4572)
		(layer "F.Cu")
		(net "DUT_AVD_PCIE")
	)
	(segment
		(start 228.6 -45.999908)
		(end 228.100128 -45.500036)
		(width 0.4572)
		(layer "F.Cu")
		(net "DUT_AVD_PCIE")
	)
	(segment
		(start 227.600002 -41.999916)
		(end 227.10013 -41.500044)
		(width 0.4572)
		(layer "F.Cu")
		(net "DUT_AVD_PCIE")
	)
	(segment
		(start 247.599962 -59.99988)
		(end 248.099834 -60.499752)
		(width 0.4572)
		(layer "F.Cu")
		(net "DUT_AVD_PCIE")
	)
	(segment
		(start 178.4096 -63.881)
		(end 178.732434 -63.881)
		(width 0.3048)
		(layer "F.Cu")
		(net "DUT_AVD_PCIE")
	)
	(segment
		(start 178.4096 -64.643)
		(end 178.732434 -64.643)
		(width 0.3048)
		(layer "F.Cu")
		(net "DUT_AVD_PCIE")
	)
	(via
		(at 253.099824 -42.500042)
		(size 0.4572)
		(drill 0.2032)
		(layers "F.Cu" "B.Cu")
		(net "DUT_AVD_PCIE")
	)
	(via
		(at 248.099834 -45.500036)
		(size 0.4572)
		(drill 0.2032)
		(layers "F.Cu" "B.Cu")
		(net "DUT_AVD_PCIE")
	)
	(via
		(at 228.100128 -57.499758)
		(size 0.4572)
		(drill 0.2032)
		(layers "F.Cu" "B.Cu")
		(net "DUT_AVD_PCIE")
	)
	(via
		(at 233.100118 -60.499752)
		(size 0.4572)
		(drill 0.2032)
		(layers "F.Cu" "B.Cu")
		(net "DUT_AVD_PCIE")
	)
	(via
		(at 253.099824 -59.499754)
		(size 0.4572)
		(drill 0.2032)
		(layers "F.Cu" "B.Cu")
		(net "DUT_AVD_PCIE")
	)
	(via
		(at 228.100128 -34.500058)
		(size 0.4572)
		(drill 0.2032)
		(layers "F.Cu" "B.Cu")
		(net "DUT_AVD_PCIE")
	)
	(via
		(at 227.10013 -33.50006)
		(size 0.4572)
		(drill 0.2032)
		(layers "F.Cu" "B.Cu")
		(net "DUT_AVD_PCIE")
	)
	(via
		(at 228.100128 -39.500048)
		(size 0.4572)
		(drill 0.2032)
		(layers "F.Cu" "B.Cu")
		(net "DUT_AVD_PCIE")
	)
	(via
		(at 253.099824 -46.500034)
		(size 0.4572)
		(drill 0.2032)
		(layers "F.Cu" "B.Cu")
		(net "DUT_AVD_PCIE")
	)
	(via
		(at 233.100118 -45.500036)
		(size 0.4572)
		(drill 0.2032)
		(layers "F.Cu" "B.Cu")
		(net "DUT_AVD_PCIE")
	)
	(via
		(at 228.100128 -58.499756)
		(size 0.4572)
		(drill 0.2032)
		(layers "F.Cu" "B.Cu")
		(net "DUT_AVD_PCIE")
	)
	(via
		(at 253.099824 -35.500056)
		(size 0.4572)
		(drill 0.2032)
		(layers "F.Cu" "B.Cu")
		(net "DUT_AVD_PCIE")
	)
	(via
		(at 253.099824 -57.499758)
		(size 0.4572)
		(drill 0.2032)
		(layers "F.Cu" "B.Cu")
		(net "DUT_AVD_PCIE")
	)
	(via
		(at 253.099824 -37.500052)
		(size 0.4572)
		(drill 0.2032)
		(layers "F.Cu" "B.Cu")
		(net "DUT_AVD_PCIE")
	)
	(via
		(at 252.099826 -41.500044)
		(size 0.4572)
		(drill 0.2032)
		(layers "F.Cu" "B.Cu")
		(net "DUT_AVD_PCIE")
	)
	(via
		(at 180.882798 -55.725568)
		(size 0.7112)
		(drill 0.4064)
		(layers "F.Cu" "B.Cu")
		(net "DUT_AVD_PCIE")
	)
	(via
		(at 253.099824 -54.499764)
		(size 0.4572)
		(drill 0.2032)
		(layers "F.Cu" "B.Cu")
		(net "DUT_AVD_PCIE")
	)
	(via
		(at 253.099824 -48.499776)
		(size 0.4572)
		(drill 0.2032)
		(layers "F.Cu" "B.Cu")
		(net "DUT_AVD_PCIE")
	)
	(via
		(at 228.100128 -37.500052)
		(size 0.4572)
		(drill 0.2032)
		(layers "F.Cu" "B.Cu")
		(net "DUT_AVD_PCIE")
	)
	(via
		(at 228.100128 -33.50006)
		(size 0.4572)
		(drill 0.2032)
		(layers "F.Cu" "B.Cu")
		(net "DUT_AVD_PCIE")
	)
	(via
		(at 186.0042 -63.881)
		(size 0.7112)
		(drill 0.4064)
		(layers "F.Cu" "B.Cu")
		(net "DUT_AVD_PCIE")
	)
	(via
		(at 253.099824 -41.500044)
		(size 0.4572)
		(drill 0.2032)
		(layers "F.Cu" "B.Cu")
		(net "DUT_AVD_PCIE")
	)
	(via
		(at 228.100128 -49.499774)
		(size 0.4572)
		(drill 0.2032)
		(layers "F.Cu" "B.Cu")
		(net "DUT_AVD_PCIE")
	)
	(via
		(at 233.100118 -54.499764)
		(size 0.4572)
		(drill 0.2032)
		(layers "F.Cu" "B.Cu")
		(net "DUT_AVD_PCIE")
	)
	(via
		(at 228.100128 -38.50005)
		(size 0.4572)
		(drill 0.2032)
		(layers "F.Cu" "B.Cu")
		(net "DUT_AVD_PCIE")
	)
	(via
		(at 253.099824 -40.500046)
		(size 0.4572)
		(drill 0.2032)
		(layers "F.Cu" "B.Cu")
		(net "DUT_AVD_PCIE")
	)
	(via
		(at 252.099826 -60.499752)
		(size 0.4572)
		(drill 0.2032)
		(layers "F.Cu" "B.Cu")
		(net "DUT_AVD_PCIE")
	)
	(via
		(at 253.099824 -49.499774)
		(size 0.4572)
		(drill 0.2032)
		(layers "F.Cu" "B.Cu")
		(net "DUT_AVD_PCIE")
	)
	(via
		(at 187.6552 -67.437)
		(size 0.7112)
		(drill 0.4064)
		(layers "F.Cu" "B.Cu")
		(net "DUT_AVD_PCIE")
	)
	(via
		(at 253.099824 -39.500048)
		(size 0.4572)
		(drill 0.2032)
		(layers "F.Cu" "B.Cu")
		(net "DUT_AVD_PCIE")
	)
	(via
		(at 186.0042 -65.532)
		(size 0.7112)
		(drill 0.4064)
		(layers "F.Cu" "B.Cu")
		(net "DUT_AVD_PCIE")
	)
	(via
		(at 228.100128 -36.500054)
		(size 0.4572)
		(drill 0.2032)
		(layers "F.Cu" "B.Cu")
		(net "DUT_AVD_PCIE")
	)
	(via
		(at 186.0042 -67.437)
		(size 0.7112)
		(drill 0.4064)
		(layers "F.Cu" "B.Cu")
		(net "DUT_AVD_PCIE")
	)
	(via
		(at 234.100116 -60.499752)
		(size 0.4572)
		(drill 0.2032)
		(layers "F.Cu" "B.Cu")
		(net "DUT_AVD_PCIE")
	)
	(via
		(at 251.099828 -41.500044)
		(size 0.4572)
		(drill 0.2032)
		(layers "F.Cu" "B.Cu")
		(net "DUT_AVD_PCIE")
	)
	(via
		(at 228.100128 -44.500038)
		(size 0.4572)
		(drill 0.2032)
		(layers "F.Cu" "B.Cu")
		(net "DUT_AVD_PCIE")
	)
	(via
		(at 229.100126 -46.500034)
		(size 0.4572)
		(drill 0.2032)
		(layers "F.Cu" "B.Cu")
		(net "DUT_AVD_PCIE")
	)
	(via
		(at 253.099824 -51.49977)
		(size 0.4572)
		(drill 0.2032)
		(layers "F.Cu" "B.Cu")
		(net "DUT_AVD_PCIE")
	)
	(via
		(at 187.6552 -65.532)
		(size 0.7112)
		(drill 0.4064)
		(layers "F.Cu" "B.Cu")
		(net "DUT_AVD_PCIE")
	)
	(via
		(at 228.100128 -45.500036)
		(size 0.4572)
		(drill 0.2032)
		(layers "F.Cu" "B.Cu")
		(net "DUT_AVD_PCIE")
	)
	(via
		(at 254.099822 -60.499752)
		(size 0.4572)
		(drill 0.2032)
		(layers "F.Cu" "B.Cu")
		(net "DUT_AVD_PCIE")
	)
	(via
		(at 253.099824 -43.50004)
		(size 0.4572)
		(drill 0.2032)
		(layers "F.Cu" "B.Cu")
		(net "DUT_AVD_PCIE")
	)
	(via
		(at 228.100128 -46.500034)
		(size 0.4572)
		(drill 0.2032)
		(layers "F.Cu" "B.Cu")
		(net "DUT_AVD_PCIE")
	)
	(via
		(at 228.100128 -60.499752)
		(size 0.4572)
		(drill 0.2032)
		(layers "F.Cu" "B.Cu")
		(net "DUT_AVD_PCIE")
	)
	(via
		(at 183.9722 -63.881)
		(size 0.7112)
		(drill 0.4064)
		(layers "F.Cu" "B.Cu")
		(net "DUT_AVD_PCIE")
	)
	(via
		(at 253.099824 -56.49976)
		(size 0.4572)
		(drill 0.2032)
		(layers "F.Cu" "B.Cu")
		(net "DUT_AVD_PCIE")
	)
	(via
		(at 230.100124 -60.499752)
		(size 0.4572)
		(drill 0.2032)
		(layers "F.Cu" "B.Cu")
		(net "DUT_AVD_PCIE")
	)
	(via
		(at 181.6862 -63.881)
		(size 0.7112)
		(drill 0.4064)
		(layers "F.Cu" "B.Cu")
		(net "DUT_AVD_PCIE")
	)
	(via
		(at 254.099822 -51.49977)
		(size 0.4572)
		(drill 0.2032)
		(layers "F.Cu" "B.Cu")
		(net "DUT_AVD_PCIE")
	)
	(via
		(at 228.100128 -55.499762)
		(size 0.4572)
		(drill 0.2032)
		(layers "F.Cu" "B.Cu")
		(net "DUT_AVD_PCIE")
	)
	(via
		(at 179.5272 -65.532)
		(size 0.7112)
		(drill 0.4064)
		(layers "F.Cu" "B.Cu")
		(net "DUT_AVD_PCIE")
	)
	(via
		(at 180.933598 -52.779168)
		(size 0.7112)
		(drill 0.4064)
		(layers "F.Cu" "B.Cu")
		(net "DUT_AVD_PCIE")
	)
	(via
		(at 251.099828 -46.500034)
		(size 0.4572)
		(drill 0.2032)
		(layers "F.Cu" "B.Cu")
		(net "DUT_AVD_PCIE")
	)
	(via
		(at 253.099824 -60.499752)
		(size 0.4572)
		(drill 0.2032)
		(layers "F.Cu" "B.Cu")
		(net "DUT_AVD_PCIE")
	)
	(via
		(at 231.100122 -60.499752)
		(size 0.4572)
		(drill 0.2032)
		(layers "F.Cu" "B.Cu")
		(net "DUT_AVD_PCIE")
	)
	(via
		(at 179.5272 -64.008)
		(size 0.7112)
		(drill 0.4064)
		(layers "F.Cu" "B.Cu")
		(net "DUT_AVD_PCIE")
	)
	(via
		(at 253.099824 -55.499762)
		(size 0.4572)
		(drill 0.2032)
		(layers "F.Cu" "B.Cu")
		(net "DUT_AVD_PCIE")
	)
	(via
		(at 228.100128 -40.500046)
		(size 0.4572)
		(drill 0.2032)
		(layers "F.Cu" "B.Cu")
		(net "DUT_AVD_PCIE")
	)
	(via
		(at 227.388928 -47.360586)
		(size 0.7112)
		(drill 0.3556)
		(layers "F.Cu" "B.Cu")
		(net "DUT_AVD_PCIE")
	)
	(via
		(at 228.100128 -53.499766)
		(size 0.4572)
		(drill 0.2032)
		(layers "F.Cu" "B.Cu")
		(net "DUT_AVD_PCIE")
	)
	(via
		(at 228.100128 -41.500044)
		(size 0.4572)
		(drill 0.2032)
		(layers "F.Cu" "B.Cu")
		(net "DUT_AVD_PCIE")
	)
	(via
		(at 248.099834 -60.499752)
		(size 0.4572)
		(drill 0.2032)
		(layers "F.Cu" "B.Cu")
		(net "DUT_AVD_PCIE")
	)
	(via
		(at 228.100128 -42.500042)
		(size 0.4572)
		(drill 0.2032)
		(layers "F.Cu" "B.Cu")
		(net "DUT_AVD_PCIE")
	)
	(via
		(at 228.100128 -50.499772)
		(size 0.4572)
		(drill 0.2032)
		(layers "F.Cu" "B.Cu")
		(net "DUT_AVD_PCIE")
	)
	(via
		(at 179.5272 -67.437)
		(size 0.7112)
		(drill 0.4064)
		(layers "F.Cu" "B.Cu")
		(net "DUT_AVD_PCIE")
	)
	(via
		(at 232.10012 -60.499752)
		(size 0.4572)
		(drill 0.2032)
		(layers "F.Cu" "B.Cu")
		(net "DUT_AVD_PCIE")
	)
	(via
		(at 181.6862 -65.532)
		(size 0.7112)
		(drill 0.4064)
		(layers "F.Cu" "B.Cu")
		(net "DUT_AVD_PCIE")
	)
	(via
		(at 253.099824 -34.500058)
		(size 0.4572)
		(drill 0.2032)
		(layers "F.Cu" "B.Cu")
		(net "DUT_AVD_PCIE")
	)
	(via
		(at 254.099822 -41.500044)
		(size 0.4572)
		(drill 0.2032)
		(layers "F.Cu" "B.Cu")
		(net "DUT_AVD_PCIE")
	)
	(via
		(at 228.100128 -43.50004)
		(size 0.4572)
		(drill 0.2032)
		(layers "F.Cu" "B.Cu")
		(net "DUT_AVD_PCIE")
	)
	(via
		(at 247.099836 -60.499752)
		(size 0.4572)
		(drill 0.2032)
		(layers "F.Cu" "B.Cu")
		(net "DUT_AVD_PCIE")
	)
	(via
		(at 183.9722 -67.437)
		(size 0.7112)
		(drill 0.4064)
		(layers "F.Cu" "B.Cu")
		(net "DUT_AVD_PCIE")
	)
	(via
		(at 249.099832 -60.499752)
		(size 0.4572)
		(drill 0.2032)
		(layers "F.Cu" "B.Cu")
		(net "DUT_AVD_PCIE")
	)
	(via
		(at 183.9722 -65.532)
		(size 0.7112)
		(drill 0.4064)
		(layers "F.Cu" "B.Cu")
		(net "DUT_AVD_PCIE")
	)
	(via
		(at 228.100128 -56.49976)
		(size 0.4572)
		(drill 0.2032)
		(layers "F.Cu" "B.Cu")
		(net "DUT_AVD_PCIE")
	)
	(via
		(at 228.100128 -35.500056)
		(size 0.4572)
		(drill 0.2032)
		(layers "F.Cu" "B.Cu")
		(net "DUT_AVD_PCIE")
	)
	(via
		(at 252.099826 -46.500034)
		(size 0.4572)
		(drill 0.2032)
		(layers "F.Cu" "B.Cu")
		(net "DUT_AVD_PCIE")
	)
	(via
		(at 228.100128 -59.499754)
		(size 0.4572)
		(drill 0.2032)
		(layers "F.Cu" "B.Cu")
		(net "DUT_AVD_PCIE")
	)
	(via
		(at 250.09983 -60.499752)
		(size 0.4572)
		(drill 0.2032)
		(layers "F.Cu" "B.Cu")
		(net "DUT_AVD_PCIE")
	)
	(via
		(at 178.952398 -56.258968)
		(size 0.7112)
		(drill 0.4064)
		(layers "F.Cu" "B.Cu")
		(net "DUT_AVD_PCIE")
	)
	(via
		(at 249.099832 -44.500038)
		(size 0.4572)
		(drill 0.2032)
		(layers "F.Cu" "B.Cu")
		(net "DUT_AVD_PCIE")
	)
	(via
		(at 227.10013 -51.49977)
		(size 0.4572)
		(drill 0.2032)
		(layers "F.Cu" "B.Cu")
		(net "DUT_AVD_PCIE")
	)
	(via
		(at 228.100128 -51.49977)
		(size 0.4572)
		(drill 0.2032)
		(layers "F.Cu" "B.Cu")
		(net "DUT_AVD_PCIE")
	)
	(via
		(at 253.099824 -53.499766)
		(size 0.4572)
		(drill 0.2032)
		(layers "F.Cu" "B.Cu")
		(net "DUT_AVD_PCIE")
	)
	(via
		(at 248.099834 -54.499764)
		(size 0.4572)
		(drill 0.2032)
		(layers "F.Cu" "B.Cu")
		(net "DUT_AVD_PCIE")
	)
	(via
		(at 181.6862 -67.437)
		(size 0.7112)
		(drill 0.4064)
		(layers "F.Cu" "B.Cu")
		(net "DUT_AVD_PCIE")
	)
	(via
		(at 180.882798 -54.176168)
		(size 0.7112)
		(drill 0.4064)
		(layers "F.Cu" "B.Cu")
		(net "DUT_AVD_PCIE")
	)
	(via
		(at 179.561998 -51.585368)
		(size 0.7112)
		(drill 0.3556)
		(layers "F.Cu" "B.Cu")
		(net "DUT_AVD_PCIE")
	)
	(via
		(at 229.100126 -60.499752)
		(size 0.4572)
		(drill 0.2032)
		(layers "F.Cu" "B.Cu")
		(net "DUT_AVD_PCIE")
	)
	(via
		(at 227.10013 -41.500044)
		(size 0.4572)
		(drill 0.2032)
		(layers "F.Cu" "B.Cu")
		(net "DUT_AVD_PCIE")
	)
	(via
		(at 162.6616 -55.4228)
		(size 0.508)
		(drill 0.254)
		(layers "F.Cu" "B.Cu")
		(net "DUT_AVD_PCIE")
	)
	(via
		(at 229.100126 -41.500044)
		(size 0.4572)
		(drill 0.2032)
		(layers "F.Cu" "B.Cu")
		(net "DUT_AVD_PCIE")
	)
	(via
		(at 253.099824 -38.50005)
		(size 0.4572)
		(drill 0.2032)
		(layers "F.Cu" "B.Cu")
		(net "DUT_AVD_PCIE")
	)
	(via
		(at 230.100124 -46.500034)
		(size 0.4572)
		(drill 0.2032)
		(layers "F.Cu" "B.Cu")
		(net "DUT_AVD_PCIE")
	)
	(via
		(at 228.100128 -54.499764)
		(size 0.4572)
		(drill 0.2032)
		(layers "F.Cu" "B.Cu")
		(net "DUT_AVD_PCIE")
	)
	(via
		(at 227.10013 -60.499752)
		(size 0.4572)
		(drill 0.2032)
		(layers "F.Cu" "B.Cu")
		(net "DUT_AVD_PCIE")
	)
	(via
		(at 253.099824 -45.500036)
		(size 0.4572)
		(drill 0.2032)
		(layers "F.Cu" "B.Cu")
		(net "DUT_AVD_PCIE")
	)
	(via
		(at 253.099824 -58.499756)
		(size 0.4572)
		(drill 0.2032)
		(layers "F.Cu" "B.Cu")
		(net "DUT_AVD_PCIE")
	)
	(via
		(at 254.099822 -33.50006)
		(size 0.4572)
		(drill 0.2032)
		(layers "F.Cu" "B.Cu")
		(net "DUT_AVD_PCIE")
	)
	(via
		(at 183.9722 -69.088)
		(size 0.7112)
		(drill 0.4064)
		(layers "F.Cu" "B.Cu")
		(net "DUT_AVD_PCIE")
	)
	(via
		(at 253.099824 -50.499772)
		(size 0.4572)
		(drill 0.2032)
		(layers "F.Cu" "B.Cu")
		(net "DUT_AVD_PCIE")
	)
	(via
		(at 179.5272 -69.215)
		(size 0.7112)
		(drill 0.4064)
		(layers "F.Cu" "B.Cu")
		(net "DUT_AVD_PCIE")
	)
	(via
		(at 253.099824 -33.50006)
		(size 0.4572)
		(drill 0.2032)
		(layers "F.Cu" "B.Cu")
		(net "DUT_AVD_PCIE")
	)
	(via
		(at 187.6552 -63.881)
		(size 0.7112)
		(drill 0.4064)
		(layers "F.Cu" "B.Cu")
		(net "DUT_AVD_PCIE")
	)
	(via
		(at 254 -47.498)
		(size 0.7112)
		(drill 0.3556)
		(layers "F.Cu" "B.Cu")
		(net "DUT_AVD_PCIE")
	)
	(via
		(at 181.6862 -69.088)
		(size 0.7112)
		(drill 0.4064)
		(layers "F.Cu" "B.Cu")
		(net "DUT_AVD_PCIE")
	)
	(via
		(at 228.100128 -48.499776)
		(size 0.4572)
		(drill 0.2032)
		(layers "F.Cu" "B.Cu")
		(net "DUT_AVD_PCIE")
	)
	(via
		(at 230.100124 -41.500044)
		(size 0.4572)
		(drill 0.2032)
		(layers "F.Cu" "B.Cu")
		(net "DUT_AVD_PCIE")
	)
	(via
		(at 253.099824 -36.500054)
		(size 0.4572)
		(drill 0.2032)
		(layers "F.Cu" "B.Cu")
		(net "DUT_AVD_PCIE")
	)
	(via
		(at 186.0042 -69.088)
		(size 0.7112)
		(drill 0.4064)
		(layers "F.Cu" "B.Cu")
		(net "DUT_AVD_PCIE")
	)
	(via
		(at 187.6552 -69.088)
		(size 0.7112)
		(drill 0.4064)
		(layers "F.Cu" "B.Cu")
		(net "DUT_AVD_PCIE")
	)
	(via
		(at 236.100112 -40.500046)
		(size 0.4572)
		(drill 0.2032)
		(layers "F.Cu" "B.Cu")
		(net "DUT_AVD_PCIE")
	)
	(via
		(at 251.099828 -60.499752)
		(size 0.4572)
		(drill 0.2032)
		(layers "F.Cu" "B.Cu")
		(net "DUT_AVD_PCIE")
	)
	(via
		(at 253.099824 -44.500038)
		(size 0.4572)
		(drill 0.2032)
		(layers "F.Cu" "B.Cu")
		(net "DUT_AVD_PCIE")
	)
	(segment
		(start 178.3842 -69.215)
		(end 178.823366 -69.215)
		(width 0.3048)
		(layer "B.Cu")
		(net "DUT_AVD_PCIE")
	)
	(segment
		(start 233.2482 -55.0037)
		(end 233.2482 -54.647846)
		(width 0.3048)
		(layer "B.Cu")
		(net "DUT_AVD_PCIE")
	)
	(segment
		(start 210.693 -47.625)
		(end 205.3082 -53.0098)
		(width 0.254)
		(layer "B.Cu")
		(net "DUT_AVD_PCIE")
	)
	(segment
		(start 166.607998 -55.4228)
		(end 162.6616 -55.4228)
		(width 0.254)
		(layer "B.Cu")
		(net "DUT_AVD_PCIE")
	)
	(segment
		(start 247.9294 -44.9961)
		(end 247.9294 -45.329602)
		(width 0.3048)
		(layer "B.Cu")
		(net "DUT_AVD_PCIE")
	)
	(segment
		(start 247.9294 -45.329602)
		(end 248.099834 -45.500036)
		(width 0.3048)
		(layer "B.Cu")
		(net "DUT_AVD_PCIE")
	)
	(segment
		(start 178.3842 -66.929)
		(end 178.823366 -66.929)
		(width 0.3048)
		(layer "B.Cu")
		(net "DUT_AVD_PCIE")
	)
	(segment
		(start 249.301 -44.701206)
		(end 249.099832 -44.500038)
		(width 0.3048)
		(layer "B.Cu")
		(net "DUT_AVD_PCIE")
	)
	(segment
		(start 182.050436 -54.9656)
		(end 181.976268 -55.039768)
		(width 0.254)
		(layer "B.Cu")
		(net "DUT_AVD_PCIE")
	)
	(segment
		(start 232.862882 -45.737272)
		(end 233.100118 -45.500036)
		(width 0.3048)
		(layer "B.Cu")
		(net "DUT_AVD_PCIE")
	)
	(segment
		(start 178.3842 -64.643)
		(end 178.823366 -64.643)
		(width 0.3048)
		(layer "B.Cu")
		(net "DUT_AVD_PCIE")
	)
	(segment
		(start 233.2482 -54.647846)
		(end 233.100118 -54.499764)
		(width 0.3048)
		(layer "B.Cu")
		(net "DUT_AVD_PCIE")
	)
	(segment
		(start 178.3842 -63.881)
		(end 178.823366 -63.881)
		(width 0.3048)
		(layer "B.Cu")
		(net "DUT_AVD_PCIE")
	)
	(segment
		(start 236.2835 -40.005)
		(end 236.2835 -40.316658)
		(width 0.3048)
		(layer "B.Cu")
		(net "DUT_AVD_PCIE")
	)
	(segment
		(start 178.3842 -67.691)
		(end 178.823366 -67.691)
		(width 0.3048)
		(layer "B.Cu")
		(net "DUT_AVD_PCIE")
	)
	(segment
		(start 249.301 -44.9961)
		(end 249.301 -44.701206)
		(width 0.3048)
		(layer "B.Cu")
		(net "DUT_AVD_PCIE")
	)
	(segment
		(start 178.3842 -66.167)
		(end 178.823366 -66.167)
		(width 0.3048)
		(layer "B.Cu")
		(net "DUT_AVD_PCIE")
	)
	(segment
		(start 247.9167 -54.99354)
		(end 247.9167 -54.682898)
		(width 0.3048)
		(layer "B.Cu")
		(net "DUT_AVD_PCIE")
	)
	(segment
		(start 178.3842 -65.405)
		(end 178.823366 -65.405)
		(width 0.3048)
		(layer "B.Cu")
		(net "DUT_AVD_PCIE")
	)
	(segment
		(start 193.9036 -54.9656)
		(end 182.050436 -54.9656)
		(width 0.254)
		(layer "B.Cu")
		(net "DUT_AVD_PCIE")
	)
	(segment
		(start 247.9167 -54.682898)
		(end 248.099834 -54.499764)
		(width 0.3048)
		(layer "B.Cu")
		(net "DUT_AVD_PCIE")
	)
	(segment
		(start 226.658424 -47.625)
		(end 210.693 -47.625)
		(width 0.254)
		(layer "B.Cu")
		(net "DUT_AVD_PCIE")
	)
	(segment
		(start 166.99103 -55.039768)
		(end 166.607998 -55.4228)
		(width 0.254)
		(layer "B.Cu")
		(net "DUT_AVD_PCIE")
	)
	(segment
		(start 181.976268 -55.039768)
		(end 166.99103 -55.039768)
		(width 0.254)
		(layer "B.Cu")
		(net "DUT_AVD_PCIE")
	)
	(segment
		(start 232.605072 -45.737272)
		(end 232.862882 -45.737272)
		(width 0.3048)
		(layer "B.Cu")
		(net "DUT_AVD_PCIE")
	)
	(segment
		(start 236.2835 -40.316658)
		(end 236.100112 -40.500046)
		(width 0.3048)
		(layer "B.Cu")
		(net "DUT_AVD_PCIE")
	)
	(segment
		(start 195.8594 -53.0098)
		(end 193.9036 -54.9656)
		(width 0.254)
		(layer "B.Cu")
		(net "DUT_AVD_PCIE")
	)
	(segment
		(start 178.3842 -68.453)
		(end 178.823366 -68.453)
		(width 0.3048)
		(layer "B.Cu")
		(net "DUT_AVD_PCIE")
	)
	(segment
		(start 205.3082 -53.0098)
		(end 195.8594 -53.0098)
		(width 0.254)
		(layer "B.Cu")
		(net "DUT_AVD_PCIE")
	)
	(segment
		(start 233.172 -45.974)
		(end 233.100118 -45.902118)
		(width 0.3048)
		(layer "In2.Cu")
		(net "DUT_AVD_PCIE")
	)
	(segment
		(start 233.100118 -45.902118)
		(end 233.100118 -45.500036)
		(width 0.3048)
		(layer "In2.Cu")
		(net "DUT_AVD_PCIE")
	)
	(segment
		(start 228.100128 -45.965872)
		(end 228.100128 -45.500036)
		(width 0.3048)
		(layer "In2.Cu")
		(net "DUT_AVD_PCIE")
	)
	(segment
		(start 236.601 -41.000934)
		(end 236.100112 -40.500046)
		(width 0.3048)
		(layer "In2.Cu")
		(net "DUT_AVD_PCIE")
	)
	(segment
		(start 236.601 -42.037)
		(end 236.601 -41.000934)
		(width 0.3048)
		(layer "In2.Cu")
		(net "DUT_AVD_PCIE")
	)
	(segment
		(start 228.092 -45.974)
		(end 228.100128 -45.965872)
		(width 0.3048)
		(layer "In2.Cu")
		(net "DUT_AVD_PCIE")
	)
	(segment
		(start 31.304738 -126.884938)
		(end 30.904942 -126.485142)
		(width 0.12065)
		(layer "F.Cu")
		(net "DPB_HW_REVISION")
	)
	(via
		(at 30.904942 -126.485142)
		(size 0.4572)
		(drill 0.2032)
		(layers "F.Cu" "B.Cu")
		(net "DPB_HW_REVISION")
	)
	(via
		(at 11.6332 -174.0154)
		(size 0.508)
		(drill 0.254)
		(layers "F.Cu" "B.Cu")
		(net "DPB_HW_REVISION")
	)
	(via
		(at 54.520846 -203.797154)
		(size 0.7112)
		(drill 0.3556)
		(layers "F.Cu" "B.Cu")
		(net "DPB_HW_REVISION")
	)
	(segment
		(start 20.5613 -121.5644)
		(end 20.5486 -121.5771)
		(width 0.12065)
		(layer "B.Cu")
		(net "DPB_HW_REVISION")
	)
	(segment
		(start 20.5486 -121.5771)
		(end 20.5486 -122.174)
		(width 0.12065)
		(layer "B.Cu")
		(net "DPB_HW_REVISION")
	)
	(segment
		(start 40.500046 -225.92538)
		(end 40.500046 -224.065846)
		(width 0.12065)
		(layer "B.Cu")
		(net "DPB_HW_REVISION")
	)
	(segment
		(start 39.878 -212.657944)
		(end 47.557944 -204.978)
		(width 0.12065)
		(layer "B.Cu")
		(net "DPB_HW_REVISION")
	)
	(segment
		(start 30.74162 -126.32182)
		(end 30.904942 -126.485142)
		(width 0.12065)
		(layer "B.Cu")
		(net "DPB_HW_REVISION")
	)
	(segment
		(start 28.465272 -126.32182)
		(end 30.74162 -126.32182)
		(width 0.12065)
		(layer "B.Cu")
		(net "DPB_HW_REVISION")
	)
	(segment
		(start 20.5486 -122.174)
		(end 22.32025 -123.94565)
		(width 0.12065)
		(layer "B.Cu")
		(net "DPB_HW_REVISION")
	)
	(segment
		(start 40.500046 -224.065846)
		(end 39.878 -223.4438)
		(width 0.12065)
		(layer "B.Cu")
		(net "DPB_HW_REVISION")
	)
	(segment
		(start 49.274476 -175.777652)
		(end 42.292524 -175.777652)
		(width 0.12065)
		(layer "B.Cu")
		(net "DPB_HW_REVISION")
	)
	(segment
		(start 39.878 -223.4438)
		(end 39.878 -212.657944)
		(width 0.12065)
		(layer "B.Cu")
		(net "DPB_HW_REVISION")
	)
	(segment
		(start 26.089102 -123.94565)
		(end 28.465272 -126.32182)
		(width 0.12065)
		(layer "B.Cu")
		(net "DPB_HW_REVISION")
	)
	(segment
		(start 54.520846 -203.797154)
		(end 56.66105 -201.65695)
		(width 0.12065)
		(layer "B.Cu")
		(net "DPB_HW_REVISION")
	)
	(segment
		(start 56.66105 -201.65695)
		(end 56.66105 -176.426114)
		(width 0.12065)
		(layer "B.Cu")
		(net "DPB_HW_REVISION")
	)
	(segment
		(start 47.557944 -204.978)
		(end 53.34 -204.978)
		(width 0.12065)
		(layer "B.Cu")
		(net "DPB_HW_REVISION")
	)
	(segment
		(start 26.416 -173.8122)
		(end 25.7302 -174.498)
		(width 0.12065)
		(layer "B.Cu")
		(net "DPB_HW_REVISION")
	)
	(segment
		(start 56.66105 -176.426114)
		(end 55.095394 -174.860458)
		(width 0.12065)
		(layer "B.Cu")
		(net "DPB_HW_REVISION")
	)
	(segment
		(start 22.32025 -123.94565)
		(end 26.089102 -123.94565)
		(width 0.12065)
		(layer "B.Cu")
		(net "DPB_HW_REVISION")
	)
	(segment
		(start 53.34 -204.978)
		(end 54.520846 -203.797154)
		(width 0.12065)
		(layer "B.Cu")
		(net "DPB_HW_REVISION")
	)
	(segment
		(start 40.327072 -173.8122)
		(end 26.416 -173.8122)
		(width 0.12065)
		(layer "B.Cu")
		(net "DPB_HW_REVISION")
	)
	(segment
		(start 42.292524 -175.777652)
		(end 40.327072 -173.8122)
		(width 0.12065)
		(layer "B.Cu")
		(net "DPB_HW_REVISION")
	)
	(segment
		(start 50.19167 -174.860458)
		(end 49.274476 -175.777652)
		(width 0.12065)
		(layer "B.Cu")
		(net "DPB_HW_REVISION")
	)
	(segment
		(start 25.7302 -174.498)
		(end 12.1158 -174.498)
		(width 0.12065)
		(layer "B.Cu")
		(net "DPB_HW_REVISION")
	)
	(segment
		(start 55.095394 -174.860458)
		(end 50.19167 -174.860458)
		(width 0.12065)
		(layer "B.Cu")
		(net "DPB_HW_REVISION")
	)
	(segment
		(start 12.1158 -174.498)
		(end 11.6332 -174.0154)
		(width 0.12065)
		(layer "B.Cu")
		(net "DPB_HW_REVISION")
	)
	(segment
		(start 16.581882 -134.172706)
		(end 15.402306 -134.172706)
		(width 0.127)
		(layer "In5.Cu")
		(net "DPB_HW_REVISION")
	)
	(segment
		(start 12.7 -172.9486)
		(end 11.6332 -174.0154)
		(width 0.127)
		(layer "In5.Cu")
		(net "DPB_HW_REVISION")
	)
	(segment
		(start 22.449282 -132.207)
		(end 19.4564 -132.207)
		(width 0.127)
		(layer "In5.Cu")
		(net "DPB_HW_REVISION")
	)
	(segment
		(start 22.461982 -132.2197)
		(end 22.449282 -132.207)
		(width 0.127)
		(layer "In5.Cu")
		(net "DPB_HW_REVISION")
	)
	(segment
		(start 24.625554 -132.207)
		(end 22.864318 -132.207)
		(width 0.127)
		(layer "In5.Cu")
		(net "DPB_HW_REVISION")
	)
	(segment
		(start 19.123406 -132.539994)
		(end 18.214594 -132.539994)
		(width 0.127)
		(layer "In5.Cu")
		(net "DPB_HW_REVISION")
	)
	(segment
		(start 22.864318 -132.207)
		(end 22.851618 -132.2197)
		(width 0.127)
		(layer "In5.Cu")
		(net "DPB_HW_REVISION")
	)
	(segment
		(start 30.347412 -126.485142)
		(end 24.625554 -132.207)
		(width 0.127)
		(layer "In5.Cu")
		(net "DPB_HW_REVISION")
	)
	(segment
		(start 15.402306 -134.172706)
		(end 12.7 -136.875012)
		(width 0.127)
		(layer "In5.Cu")
		(net "DPB_HW_REVISION")
	)
	(segment
		(start 19.4564 -132.207)
		(end 19.123406 -132.539994)
		(width 0.127)
		(layer "In5.Cu")
		(net "DPB_HW_REVISION")
	)
	(segment
		(start 18.214594 -132.539994)
		(end 16.581882 -134.172706)
		(width 0.127)
		(layer "In5.Cu")
		(net "DPB_HW_REVISION")
	)
	(segment
		(start 30.904942 -126.485142)
		(end 30.347412 -126.485142)
		(width 0.127)
		(layer "In5.Cu")
		(net "DPB_HW_REVISION")
	)
	(segment
		(start 12.7 -136.875012)
		(end 12.7 -172.9486)
		(width 0.127)
		(layer "In5.Cu")
		(net "DPB_HW_REVISION")
	)
	(segment
		(start 22.851618 -132.2197)
		(end 22.461982 -132.2197)
		(width 0.127)
		(layer "In5.Cu")
		(net "DPB_HW_REVISION")
	)
	(segment
		(start 28.928822 -138.084814)
		(end 26.847038 -140.166598)
		(width 0.12065)
		(layer "F.Cu")
		(net "DP_RST_N_R")
	)
	(segment
		(start 24.411432 -140.240004)
		(end 24.078184 -140.573252)
		(width 0.12065)
		(layer "F.Cu")
		(net "DP_RST_N_R")
	)
	(segment
		(start 23.376382 -140.461492)
		(end 22.420834 -140.461492)
		(width 0.12065)
		(layer "F.Cu")
		(net "DP_RST_N_R")
	)
	(segment
		(start 23.488142 -140.573252)
		(end 23.376382 -140.461492)
		(width 0.12065)
		(layer "F.Cu")
		(net "DP_RST_N_R")
	)
	(segment
		(start 25.703022 -140.240004)
		(end 24.411432 -140.240004)
		(width 0.12065)
		(layer "F.Cu")
		(net "DP_RST_N_R")
	)
	(segment
		(start 21.6789 -140.693394)
		(end 21.549106 -140.693394)
		(width 0.12065)
		(layer "F.Cu")
		(net "DP_RST_N_R")
	)
	(segment
		(start 24.078184 -140.573252)
		(end 23.488142 -140.573252)
		(width 0.12065)
		(layer "F.Cu")
		(net "DP_RST_N_R")
	)
	(segment
		(start 22.420834 -140.461492)
		(end 21.910802 -140.461492)
		(width 0.12065)
		(layer "F.Cu")
		(net "DP_RST_N_R")
	)
	(segment
		(start 29.704792 -138.084814)
		(end 28.928822 -138.084814)
		(width 0.12065)
		(layer "F.Cu")
		(net "DP_RST_N_R")
	)
	(segment
		(start 25.776428 -140.166598)
		(end 25.703022 -140.240004)
		(width 0.12065)
		(layer "F.Cu")
		(net "DP_RST_N_R")
	)
	(segment
		(start 21.549106 -140.693394)
		(end 21.3995 -140.843)
		(width 0.12065)
		(layer "F.Cu")
		(net "DP_RST_N_R")
	)
	(segment
		(start 21.910802 -140.461492)
		(end 21.6789 -140.693394)
		(width 0.12065)
		(layer "F.Cu")
		(net "DP_RST_N_R")
	)
	(segment
		(start 26.847038 -140.166598)
		(end 25.776428 -140.166598)
		(width 0.12065)
		(layer "F.Cu")
		(net "DP_RST_N_R")
	)
	(via
		(at 22.420834 -140.461492)
		(size 0.7112)
		(drill 0.3556)
		(layers "F.Cu" "B.Cu")
		(net "DP_RST_N_R")
	)
	(segment
		(start 235.59135 -5.07746)
		(end 235.129324 -5.07746)
		(width 0.12065)
		(layer "F.Cu")
		(net "DP_RST_N")
	)
	(segment
		(start 236.4105 -7.342378)
		(end 236.4105 -6.92658)
		(width 0.12065)
		(layer "F.Cu")
		(net "DP_RST_N")
	)
	(segment
		(start 246.8626 -3.466084)
		(end 246.8626 -4.572254)
		(width 0.12065)
		(layer "F.Cu")
		(net "DP_RST_N")
	)
	(segment
		(start 236.4105 -6.92658)
		(end 236.4105 -5.98678)
		(width 0.12065)
		(layer "F.Cu")
		(net "DP_RST_N")
	)
	(segment
		(start 19.884898 -141.303248)
		(end 19.878294 -141.309852)
		(width 0.12065)
		(layer "F.Cu")
		(net "DP_RST_N")
	)
	(segment
		(start 241.436398 -8.25119)
		(end 237.319312 -8.25119)
		(width 0.12065)
		(layer "F.Cu")
		(net "DP_RST_N")
	)
	(segment
		(start 246.863108 -4.572762)
		(end 246.863108 -4.95935)
		(width 0.12065)
		(layer "F.Cu")
		(net "DP_RST_N")
	)
	(segment
		(start 248.158 -2.170684)
		(end 246.8626 -3.466084)
		(width 0.12065)
		(layer "F.Cu")
		(net "DP_RST_N")
	)
	(segment
		(start 246.362728 -6.011672)
		(end 243.675916 -6.011672)
		(width 0.12065)
		(layer "F.Cu")
		(net "DP_RST_N")
	)
	(segment
		(start 259.207 -0.719836)
		(end 259.207 -1.4224)
		(width 0.12065)
		(layer "F.Cu")
		(net "DP_RST_N")
	)
	(segment
		(start 237.319312 -8.25119)
		(end 236.4105 -7.342378)
		(width 0.12065)
		(layer "F.Cu")
		(net "DP_RST_N")
	)
	(segment
		(start 234.37215 -4.320286)
		(end 234.370118 -4.320286)
		(width 0.12065)
		(layer "F.Cu")
		(net "DP_RST_N")
	)
	(segment
		(start 235.129324 -5.07746)
		(end 234.37215 -4.320286)
		(width 0.12065)
		(layer "F.Cu")
		(net "DP_RST_N")
	)
	(segment
		(start 234.370118 -4.320286)
		(end 233.549444 -3.499612)
		(width 0.12065)
		(layer "F.Cu")
		(net "DP_RST_N")
	)
	(segment
		(start 18.964148 -141.309852)
		(end 18.796 -141.478)
		(width 0.12065)
		(layer "F.Cu")
		(net "DP_RST_N")
	)
	(segment
		(start 259.41274 -0.514096)
		(end 259.207 -0.719836)
		(width 0.12065)
		(layer "F.Cu")
		(net "DP_RST_N")
	)
	(segment
		(start 20.050252 -141.303248)
		(end 19.884898 -141.303248)
		(width 0.12065)
		(layer "F.Cu")
		(net "DP_RST_N")
	)
	(segment
		(start 236.4105 -5.98678)
		(end 236.40288 -5.97916)
		(width 0.12065)
		(layer "F.Cu")
		(net "DP_RST_N")
	)
	(segment
		(start 259.207 -1.4224)
		(end 258.458716 -2.170684)
		(width 0.12065)
		(layer "F.Cu")
		(net "DP_RST_N")
	)
	(segment
		(start 246.8626 -4.572254)
		(end 246.863108 -4.572762)
		(width 0.12065)
		(layer "F.Cu")
		(net "DP_RST_N")
	)
	(segment
		(start 246.8626 -5.5118)
		(end 246.362728 -6.011672)
		(width 0.12065)
		(layer "F.Cu")
		(net "DP_RST_N")
	)
	(segment
		(start 246.863108 -4.95935)
		(end 246.8626 -4.959858)
		(width 0.12065)
		(layer "F.Cu")
		(net "DP_RST_N")
	)
	(segment
		(start 243.675916 -6.011672)
		(end 241.436398 -8.25119)
		(width 0.12065)
		(layer "F.Cu")
		(net "DP_RST_N")
	)
	(segment
		(start 19.878294 -141.309852)
		(end 18.964148 -141.309852)
		(width 0.12065)
		(layer "F.Cu")
		(net "DP_RST_N")
	)
	(segment
		(start 236.40288 -5.88899)
		(end 235.59135 -5.07746)
		(width 0.12065)
		(layer "F.Cu")
		(net "DP_RST_N")
	)
	(segment
		(start 246.8626 -4.959858)
		(end 246.8626 -5.5118)
		(width 0.12065)
		(layer "F.Cu")
		(net "DP_RST_N")
	)
	(segment
		(start 20.5105 -140.843)
		(end 20.050252 -141.303248)
		(width 0.12065)
		(layer "F.Cu")
		(net "DP_RST_N")
	)
	(segment
		(start 236.40288 -5.97916)
		(end 236.40288 -5.88899)
		(width 0.12065)
		(layer "F.Cu")
		(net "DP_RST_N")
	)
	(segment
		(start 258.458716 -2.170684)
		(end 248.158 -2.170684)
		(width 0.12065)
		(layer "F.Cu")
		(net "DP_RST_N")
	)
	(via
		(at 18.796 -141.478)
		(size 0.508)
		(drill 0.254)
		(layers "F.Cu" "B.Cu")
		(net "DP_RST_N")
	)
	(segment
		(start 226.9871 -4.325112)
		(end 224.439988 -1.778)
		(width 0.127)
		(layer "In2.Cu")
		(net "DP_RST_N")
	)
	(segment
		(start 205.95463 1.154938)
		(end 205.953868 1.154176)
		(width 0.127)
		(layer "In2.Cu")
		(net "DP_RST_N")
	)
	(segment
		(start 27.655012 -89.0524)
		(end 26.513536 -89.0524)
		(width 0.127)
		(layer "In2.Cu")
		(net "DP_RST_N")
	)
	(segment
		(start 196.48551 -1.932178)
		(end 196.210428 -2.20726)
		(width 0.127)
		(layer "In2.Cu")
		(net "DP_RST_N")
	)
	(segment
		(start 224.439988 -1.778)
		(end 223.441514 -1.778)
		(width 0.127)
		(layer "In2.Cu")
		(net "DP_RST_N")
	)
	(segment
		(start 18.078196 -94.87408)
		(end 16.310356 -96.64192)
		(width 0.127)
		(layer "In2.Cu")
		(net "DP_RST_N")
	)
	(segment
		(start 220.508576 1.154938)
		(end 205.95463 1.154938)
		(width 0.127)
		(layer "In2.Cu")
		(net "DP_RST_N")
	)
	(segment
		(start 16.310356 -97.57537)
		(end 10.215118 -103.670608)
		(width 0.127)
		(layer "In2.Cu")
		(net "DP_RST_N")
	)
	(segment
		(start 58.67654 -86.48446)
		(end 58.15711 -87.00389)
		(width 0.127)
		(layer "In2.Cu")
		(net "DP_RST_N")
	)
	(segment
		(start 58.15711 -87.00389)
		(end 53.506878 -87.00389)
		(width 0.127)
		(layer "In2.Cu")
		(net "DP_RST_N")
	)
	(segment
		(start 29.915866 -87.738966)
		(end 28.968446 -87.738966)
		(width 0.127)
		(layer "In2.Cu")
		(net "DP_RST_N")
	)
	(segment
		(start 12.780518 -139.192254)
		(end 15.066264 -141.478)
		(width 0.127)
		(layer "In2.Cu")
		(net "DP_RST_N")
	)
	(segment
		(start 5.331206 -131.98094)
		(end 12.54252 -139.192254)
		(width 0.127)
		(layer "In2.Cu")
		(net "DP_RST_N")
	)
	(segment
		(start 53.078888 -86.5759)
		(end 44.6024 -86.5759)
		(width 0.127)
		(layer "In2.Cu")
		(net "DP_RST_N")
	)
	(segment
		(start 24.087582 -91.478354)
		(end 23.430992 -91.478354)
		(width 0.127)
		(layer "In2.Cu")
		(net "DP_RST_N")
	)
	(segment
		(start 194.962018 -1.348486)
		(end 188.558932 -1.348486)
		(width 0.127)
		(layer "In2.Cu")
		(net "DP_RST_N")
	)
	(segment
		(start 188.558932 -1.348486)
		(end 187.921646 -0.7112)
		(width 0.127)
		(layer "In2.Cu")
		(net "DP_RST_N")
	)
	(segment
		(start 177.09007 -2.010156)
		(end 132.150358 -2.010156)
		(width 0.127)
		(layer "In2.Cu")
		(net "DP_RST_N")
	)
	(segment
		(start 98.780346 -75.01001)
		(end 96.72955 -77.060806)
		(width 0.127)
		(layer "In2.Cu")
		(net "DP_RST_N")
	)
	(segment
		(start 98.7806 -50.901092)
		(end 98.7806 -71.62546)
		(width 0.127)
		(layer "In2.Cu")
		(net "DP_RST_N")
	)
	(segment
		(start 184.09539 -0.982726)
		(end 178.1175 -0.982726)
		(width 0.127)
		(layer "In2.Cu")
		(net "DP_RST_N")
	)
	(segment
		(start 20.035266 -94.87408)
		(end 18.078196 -94.87408)
		(width 0.127)
		(layer "In2.Cu")
		(net "DP_RST_N")
	)
	(segment
		(start 96.405446 -77.385672)
		(end 96.1644 -77.627734)
		(width 0.127)
		(layer "In2.Cu")
		(net "DP_RST_N")
	)
	(segment
		(start 202.46213 -2.3368)
		(end 197.4977 -2.3368)
		(width 0.127)
		(layer "In2.Cu")
		(net "DP_RST_N")
	)
	(segment
		(start 10.215118 -104.200452)
		(end 8.506206 -105.909364)
		(width 0.127)
		(layer "In2.Cu")
		(net "DP_RST_N")
	)
	(segment
		(start 197.093078 -1.932178)
		(end 196.48551 -1.932178)
		(width 0.127)
		(layer "In2.Cu")
		(net "DP_RST_N")
	)
	(segment
		(start 10.214864 -104.123236)
		(end 10.215118 -104.12349)
		(width 0.127)
		(layer "In2.Cu")
		(net "DP_RST_N")
	)
	(segment
		(start 10.215118 -103.807514)
		(end 10.214864 -103.807768)
		(width 0.127)
		(layer "In2.Cu")
		(net "DP_RST_N")
	)
	(segment
		(start 8.506206 -105.909364)
		(end 8.506206 -108.644182)
		(width 0.127)
		(layer "In2.Cu")
		(net "DP_RST_N")
	)
	(segment
		(start 98.7806 -71.62546)
		(end 98.780346 -74.543666)
		(width 0.127)
		(layer "In2.Cu")
		(net "DP_RST_N")
	)
	(segment
		(start 15.066264 -141.478)
		(end 18.796 -141.478)
		(width 0.127)
		(layer "In2.Cu")
		(net "DP_RST_N")
	)
	(segment
		(start 205.953868 1.154176)
		(end 202.46213 -2.3368)
		(width 0.127)
		(layer "In2.Cu")
		(net "DP_RST_N")
	)
	(segment
		(start 186.22645 -1.37795)
		(end 184.490614 -1.37795)
		(width 0.127)
		(layer "In2.Cu")
		(net "DP_RST_N")
	)
	(segment
		(start 53.506878 -87.00389)
		(end 53.078888 -86.5759)
		(width 0.127)
		(layer "In2.Cu")
		(net "DP_RST_N")
	)
	(segment
		(start 23.430992 -91.478354)
		(end 20.035266 -94.87408)
		(width 0.127)
		(layer "In2.Cu")
		(net "DP_RST_N")
	)
	(segment
		(start 8.506206 -108.644182)
		(end 5.331206 -111.819182)
		(width 0.127)
		(layer "In2.Cu")
		(net "DP_RST_N")
	)
	(segment
		(start 132.150358 -2.010156)
		(end 124.847604 -9.308846)
		(width 0.127)
		(layer "In2.Cu")
		(net "DP_RST_N")
	)
	(segment
		(start 96.1644 -80.100424)
		(end 93.486478 -82.778346)
		(width 0.127)
		(layer "In2.Cu")
		(net "DP_RST_N")
	)
	(segment
		(start 187.921646 -0.7112)
		(end 186.8932 -0.7112)
		(width 0.127)
		(layer "In2.Cu")
		(net "DP_RST_N")
	)
	(segment
		(start 195.820792 -2.20726)
		(end 194.962018 -1.348486)
		(width 0.127)
		(layer "In2.Cu")
		(net "DP_RST_N")
	)
	(segment
		(start 178.1175 -0.982726)
		(end 177.09007 -2.010156)
		(width 0.127)
		(layer "In2.Cu")
		(net "DP_RST_N")
	)
	(segment
		(start 93.486478 -82.778346)
		(end 92.902024 -82.778346)
		(width 0.127)
		(layer "In2.Cu")
		(net "DP_RST_N")
	)
	(segment
		(start 16.310356 -96.64192)
		(end 16.310356 -97.57537)
		(width 0.127)
		(layer "In2.Cu")
		(net "DP_RST_N")
	)
	(segment
		(start 96.13519 -34.53638)
		(end 96.13519 -48.255682)
		(width 0.127)
		(layer "In2.Cu")
		(net "DP_RST_N")
	)
	(segment
		(start 26.513536 -89.0524)
		(end 24.087582 -91.478354)
		(width 0.127)
		(layer "In2.Cu")
		(net "DP_RST_N")
	)
	(segment
		(start 121.362724 -9.308846)
		(end 96.13519 -34.53638)
		(width 0.127)
		(layer "In2.Cu")
		(net "DP_RST_N")
	)
	(segment
		(start 98.780346 -74.543666)
		(end 98.780346 -75.01001)
		(width 0.127)
		(layer "In2.Cu")
		(net "DP_RST_N")
	)
	(segment
		(start 96.13519 -48.255682)
		(end 98.7806 -50.901092)
		(width 0.127)
		(layer "In2.Cu")
		(net "DP_RST_N")
	)
	(segment
		(start 233.549444 -3.499612)
		(end 232.723944 -4.325112)
		(width 0.127)
		(layer "In2.Cu")
		(net "DP_RST_N")
	)
	(segment
		(start 10.215118 -104.12349)
		(end 10.215118 -104.200452)
		(width 0.127)
		(layer "In2.Cu")
		(net "DP_RST_N")
	)
	(segment
		(start 10.215118 -103.670608)
		(end 10.215118 -103.807514)
		(width 0.127)
		(layer "In2.Cu")
		(net "DP_RST_N")
	)
	(segment
		(start 96.72955 -77.060806)
		(end 96.623124 -77.167486)
		(width 0.127)
		(layer "In2.Cu")
		(net "DP_RST_N")
	)
	(segment
		(start 96.1644 -77.627734)
		(end 96.1644 -80.100424)
		(width 0.127)
		(layer "In2.Cu")
		(net "DP_RST_N")
	)
	(segment
		(start 28.968446 -87.738966)
		(end 27.655012 -89.0524)
		(width 0.127)
		(layer "In2.Cu")
		(net "DP_RST_N")
	)
	(segment
		(start 232.723944 -4.325112)
		(end 226.9871 -4.325112)
		(width 0.127)
		(layer "In2.Cu")
		(net "DP_RST_N")
	)
	(segment
		(start 29.91612 -87.73922)
		(end 29.915866 -87.738966)
		(width 0.127)
		(layer "In2.Cu")
		(net "DP_RST_N")
	)
	(segment
		(start 44.6024 -86.5759)
		(end 43.43908 -87.73922)
		(width 0.127)
		(layer "In2.Cu")
		(net "DP_RST_N")
	)
	(segment
		(start 196.210428 -2.20726)
		(end 195.820792 -2.20726)
		(width 0.127)
		(layer "In2.Cu")
		(net "DP_RST_N")
	)
	(segment
		(start 92.902024 -82.778346)
		(end 89.19591 -86.48446)
		(width 0.127)
		(layer "In2.Cu")
		(net "DP_RST_N")
	)
	(segment
		(start 12.54252 -139.192254)
		(end 12.780518 -139.192254)
		(width 0.127)
		(layer "In2.Cu")
		(net "DP_RST_N")
	)
	(segment
		(start 10.214864 -103.807768)
		(end 10.214864 -104.123236)
		(width 0.127)
		(layer "In2.Cu")
		(net "DP_RST_N")
	)
	(segment
		(start 96.623124 -77.167486)
		(end 96.405446 -77.385164)
		(width 0.127)
		(layer "In2.Cu")
		(net "DP_RST_N")
	)
	(segment
		(start 5.331206 -111.819182)
		(end 5.331206 -131.98094)
		(width 0.127)
		(layer "In2.Cu")
		(net "DP_RST_N")
	)
	(segment
		(start 223.441514 -1.778)
		(end 220.508576 1.154938)
		(width 0.127)
		(layer "In2.Cu")
		(net "DP_RST_N")
	)
	(segment
		(start 96.405446 -77.385164)
		(end 96.405446 -77.385672)
		(width 0.127)
		(layer "In2.Cu")
		(net "DP_RST_N")
	)
	(segment
		(start 124.847604 -9.308846)
		(end 121.362724 -9.308846)
		(width 0.127)
		(layer "In2.Cu")
		(net "DP_RST_N")
	)
	(segment
		(start 197.4977 -2.3368)
		(end 197.093078 -1.932178)
		(width 0.127)
		(layer "In2.Cu")
		(net "DP_RST_N")
	)
	(segment
		(start 89.19591 -86.48446)
		(end 58.67654 -86.48446)
		(width 0.127)
		(layer "In2.Cu")
		(net "DP_RST_N")
	)
	(segment
		(start 43.43908 -87.73922)
		(end 29.91612 -87.73922)
		(width 0.127)
		(layer "In2.Cu")
		(net "DP_RST_N")
	)
	(segment
		(start 186.8932 -0.7112)
		(end 186.22645 -1.37795)
		(width 0.127)
		(layer "In2.Cu")
		(net "DP_RST_N")
	)
	(segment
		(start 184.490614 -1.37795)
		(end 184.09539 -0.982726)
		(width 0.127)
		(layer "In2.Cu")
		(net "DP_RST_N")
	)
	(segment
		(start 48.954182 -117.241828)
		(end 48.07585 -118.12016)
		(width 0.12065)
		(layer "F.Cu")
		(net "DP_BMC_CPU_RST_N_R")
	)
	(segment
		(start 44.104814 -122.084846)
		(end 45.38726 -120.8024)
		(width 0.12065)
		(layer "F.Cu")
		(net "DP_BMC_CPU_RST_N_R")
	)
	(segment
		(start 47.1424 -120.8024)
		(end 48.07585 -119.86895)
		(width 0.12065)
		(layer "F.Cu")
		(net "DP_BMC_CPU_RST_N_R")
	)
	(segment
		(start 45.38726 -120.8024)
		(end 47.1424 -120.8024)
		(width 0.12065)
		(layer "F.Cu")
		(net "DP_BMC_CPU_RST_N_R")
	)
	(segment
		(start 48.07585 -119.86895)
		(end 48.07585 -119.604028)
		(width 0.12065)
		(layer "F.Cu")
		(net "DP_BMC_CPU_RST_N_R")
	)
	(segment
		(start 48.07585 -118.12016)
		(end 48.07585 -119.604028)
		(width 0.12065)
		(layer "F.Cu")
		(net "DP_BMC_CPU_RST_N_R")
	)
	(via
		(at 48.07585 -119.604028)
		(size 0.7112)
		(drill 0.3556)
		(layers "F.Cu" "B.Cu")
		(net "DP_BMC_CPU_RST_N_R")
	)
	(segment
		(start 235.551726 -3.499612)
		(end 236.374178 -2.67716)
		(width 0.12065)
		(layer "F.Cu")
		(net "DEBUG_CARD_TX")
	)
	(segment
		(start 223.393 0.047244)
		(end 223.393 -0.9398)
		(width 0.12065)
		(layer "F.Cu")
		(net "DEBUG_CARD_TX")
	)
	(segment
		(start 223.20377 0.815848)
		(end 223.20377 0.236474)
		(width 0.12065)
		(layer "F.Cu")
		(net "DEBUG_CARD_TX")
	)
	(segment
		(start 235.549694 -3.499612)
		(end 235.551726 -3.499612)
		(width 0.12065)
		(layer "F.Cu")
		(net "DEBUG_CARD_TX")
	)
	(segment
		(start 223.497902 1.10998)
		(end 223.20377 0.815848)
		(width 0.12065)
		(layer "F.Cu")
		(net "DEBUG_CARD_TX")
	)
	(segment
		(start 236.374178 0.35814)
		(end 235.622338 1.10998)
		(width 0.12065)
		(layer "F.Cu")
		(net "DEBUG_CARD_TX")
	)
	(segment
		(start 223.393 -0.9398)
		(end 223.59366 -1.14046)
		(width 0.12065)
		(layer "F.Cu")
		(net "DEBUG_CARD_TX")
	)
	(segment
		(start 224.946718 -1.63449)
		(end 225.8441 -1.63449)
		(width 0.12065)
		(layer "F.Cu")
		(net "DEBUG_CARD_TX")
	)
	(segment
		(start 224.452688 -1.14046)
		(end 224.946718 -1.63449)
		(width 0.12065)
		(layer "F.Cu")
		(net "DEBUG_CARD_TX")
	)
	(segment
		(start 235.622338 1.10998)
		(end 223.497902 1.10998)
		(width 0.12065)
		(layer "F.Cu")
		(net "DEBUG_CARD_TX")
	)
	(segment
		(start 236.374178 -2.67716)
		(end 236.374178 0.35814)
		(width 0.12065)
		(layer "F.Cu")
		(net "DEBUG_CARD_TX")
	)
	(segment
		(start 223.20377 0.236474)
		(end 223.393 0.047244)
		(width 0.12065)
		(layer "F.Cu")
		(net "DEBUG_CARD_TX")
	)
	(segment
		(start 223.59366 -1.14046)
		(end 224.452688 -1.14046)
		(width 0.12065)
		(layer "F.Cu")
		(net "DEBUG_CARD_TX")
	)
	(segment
		(start 225.8441 0.36449)
		(end 233.684572 0.36449)
		(width 0.12065)
		(layer "F.Cu")
		(net "DEBUG_CARD_RX")
	)
	(segment
		(start 233.684572 0.36449)
		(end 235.549694 -1.500632)
		(width 0.12065)
		(layer "F.Cu")
		(net "DEBUG_CARD_RX")
	)
	(segment
		(start 34.874454 -165.706044)
		(end 34.874454 -164.702744)
		(width 0.381)
		(layer "F.Cu")
		(net "DDR_VREF")
	)
	(segment
		(start 32.141668 -147.838668)
		(end 31.5214 -147.2184)
		(width 0.381)
		(layer "F.Cu")
		(net "DDR_VREF")
	)
	(segment
		(start 36.398454 -163.559744)
		(end 36.398454 -162.671252)
		(width 0.381)
		(layer "F.Cu")
		(net "DDR_VREF")
	)
	(segment
		(start 31.5214 -145.732246)
		(end 30.670754 -144.8816)
		(width 0.381)
		(layer "F.Cu")
		(net "DDR_VREF")
	)
	(segment
		(start 28.9052 -144.8816)
		(end 28.067 -145.7198)
		(width 0.381)
		(layer "F.Cu")
		(net "DDR_VREF")
	)
	(segment
		(start 36.168076 -161.46653)
		(end 36.168076 -157.179772)
		(width 0.3556)
		(layer "F.Cu")
		(net "DDR_VREF")
	)
	(segment
		(start 32.577532 -147.838668)
		(end 33.48482 -146.93138)
		(width 0.381)
		(layer "F.Cu")
		(net "DDR_VREF")
	)
	(segment
		(start 32.577532 -147.838668)
		(end 32.141668 -147.838668)
		(width 0.381)
		(layer "F.Cu")
		(net "DDR_VREF")
	)
	(segment
		(start 36.403026 -162.66668)
		(end 36.403026 -161.70148)
		(width 0.381)
		(layer "F.Cu")
		(net "DDR_VREF")
	)
	(segment
		(start 28.067 -145.7198)
		(end 28.067 -149.8854)
		(width 0.381)
		(layer "F.Cu")
		(net "DDR_VREF")
	)
	(segment
		(start 36.398454 -162.671252)
		(end 36.403026 -162.66668)
		(width 0.381)
		(layer "F.Cu")
		(net "DDR_VREF")
	)
	(segment
		(start 34.709354 -165.871144)
		(end 34.874454 -165.706044)
		(width 0.381)
		(layer "F.Cu")
		(net "DDR_VREF")
	)
	(segment
		(start 34.874454 -164.702744)
		(end 34.874454 -163.559744)
		(width 0.381)
		(layer "F.Cu")
		(net "DDR_VREF")
	)
	(segment
		(start 27.3304 -154.860498)
		(end 26.886154 -155.304744)
		(width 0.381)
		(layer "F.Cu")
		(net "DDR_VREF")
	)
	(segment
		(start 32.577532 -147.838668)
		(end 32.577532 -148.211794)
		(width 0.381)
		(layer "F.Cu")
		(net "DDR_VREF")
	)
	(segment
		(start 27.3304 -150.622)
		(end 27.3304 -154.860498)
		(width 0.381)
		(layer "F.Cu")
		(net "DDR_VREF")
	)
	(segment
		(start 33.48482 -146.93138)
		(end 33.857946 -146.93138)
		(width 0.381)
		(layer "F.Cu")
		(net "DDR_VREF")
	)
	(segment
		(start 28.067 -149.8854)
		(end 27.3304 -150.622)
		(width 0.381)
		(layer "F.Cu")
		(net "DDR_VREF")
	)
	(segment
		(start 34.874454 -163.559744)
		(end 35.255454 -163.559744)
		(width 0.381)
		(layer "F.Cu")
		(net "DDR_VREF")
	)
	(segment
		(start 32.577532 -151.189436)
		(end 32.96793 -151.579834)
		(width 0.12065)
		(layer "F.Cu")
		(net "DDR_VREF")
	)
	(segment
		(start 36.403026 -161.70148)
		(end 36.168076 -161.46653)
		(width 0.3556)
		(layer "F.Cu")
		(net "DDR_VREF")
	)
	(segment
		(start 32.577532 -148.211794)
		(end 32.577532 -151.189436)
		(width 0.12065)
		(layer "F.Cu")
		(net "DDR_VREF")
	)
	(segment
		(start 36.398454 -164.702744)
		(end 36.398454 -163.559744)
		(width 0.381)
		(layer "F.Cu")
		(net "DDR_VREF")
	)
	(segment
		(start 35.255454 -163.559744)
		(end 36.398454 -164.702744)
		(width 0.381)
		(layer "F.Cu")
		(net "DDR_VREF")
	)
	(segment
		(start 36.90493 -135.684768)
		(end 36.505134 -135.284972)
		(width 0.12065)
		(layer "F.Cu")
		(net "DDR_VREF")
	)
	(segment
		(start 31.5214 -147.2184)
		(end 31.5214 -145.732246)
		(width 0.381)
		(layer "F.Cu")
		(net "DDR_VREF")
	)
	(segment
		(start 30.670754 -144.8816)
		(end 28.9052 -144.8816)
		(width 0.381)
		(layer "F.Cu")
		(net "DDR_VREF")
	)
	(via
		(at 26.886154 -155.304744)
		(size 0.508)
		(drill 0.254)
		(layers "F.Cu" "B.Cu")
		(net "DDR_VREF")
	)
	(via
		(at 36.505134 -135.284972)
		(size 0.4572)
		(drill 0.2032)
		(layers "F.Cu" "B.Cu")
		(net "DDR_VREF")
	)
	(via
		(at 26.886154 -161.798)
		(size 0.7112)
		(drill 0.3556)
		(layers "F.Cu" "B.Cu")
		(net "DDR_VREF")
	)
	(via
		(at 34.709354 -165.871144)
		(size 0.508)
		(drill 0.254)
		(layers "F.Cu" "B.Cu")
		(net "DDR_VREF")
	)
	(via
		(at 29.0576 -139.7)
		(size 0.508)
		(drill 0.254)
		(layers "F.Cu" "B.Cu")
		(net "DDR_VREF")
	)
	(segment
		(start 33.821878 -164.983668)
		(end 27.623008 -164.983668)
		(width 0.381)
		(layer "B.Cu")
		(net "DDR_VREF")
	)
	(segment
		(start 26.886154 -161.798)
		(end 26.886154 -155.304744)
		(width 0.381)
		(layer "B.Cu")
		(net "DDR_VREF")
	)
	(segment
		(start 26.886154 -164.246814)
		(end 26.886154 -161.798)
		(width 0.381)
		(layer "B.Cu")
		(net "DDR_VREF")
	)
	(segment
		(start 34.709354 -165.871144)
		(end 33.821878 -164.983668)
		(width 0.381)
		(layer "B.Cu")
		(net "DDR_VREF")
	)
	(segment
		(start 27.623008 -164.983668)
		(end 26.886154 -164.246814)
		(width 0.381)
		(layer "B.Cu")
		(net "DDR_VREF")
	)
	(segment
		(start 29.0576 -139.7)
		(end 29.702506 -139.055094)
		(width 0.381)
		(layer "In2.Cu")
		(net "DDR_VREF")
	)
	(segment
		(start 34.271204 -139.055094)
		(end 35.425634 -137.900664)
		(width 0.381)
		(layer "In2.Cu")
		(net "DDR_VREF")
	)
	(segment
		(start 35.425634 -137.900664)
		(end 35.425634 -137.137902)
		(width 0.381)
		(layer "In2.Cu")
		(net "DDR_VREF")
	)
	(segment
		(start 35.425634 -137.137902)
		(end 36.505134 -136.058402)
		(width 0.381)
		(layer "In2.Cu")
		(net "DDR_VREF")
	)
	(segment
		(start 29.702506 -139.055094)
		(end 34.271204 -139.055094)
		(width 0.381)
		(layer "In2.Cu")
		(net "DDR_VREF")
	)
	(segment
		(start 36.505134 -136.058402)
		(end 36.505134 -135.284972)
		(width 0.381)
		(layer "In2.Cu")
		(net "DDR_VREF")
	)
	(segment
		(start 29.0576 -148.7932)
		(end 27.2034 -150.6474)
		(width 0.508)
		(layer "In5.Cu")
		(net "DDR_VREF")
	)
	(segment
		(start 27.2034 -150.6474)
		(end 27.2034 -154.987498)
		(width 0.508)
		(layer "In5.Cu")
		(net "DDR_VREF")
	)
	(segment
		(start 29.0576 -139.7)
		(end 29.0576 -148.7932)
		(width 0.508)
		(layer "In5.Cu")
		(net "DDR_VREF")
	)
	(segment
		(start 27.2034 -154.987498)
		(end 26.886154 -155.304744)
		(width 0.508)
		(layer "In5.Cu")
		(net "DDR_VREF")
	)
	(segment
		(start 51.506628 -133.949948)
		(end 51.641756 -134.085076)
		(width 0.12065)
		(layer "F.Cu")
		(net "DACRSET")
	)
	(segment
		(start 52.17668 -134.62)
		(end 52.832 -134.62)
		(width 0.12065)
		(layer "F.Cu")
		(net "DACRSET")
	)
	(segment
		(start 51.641756 -134.085076)
		(end 52.17668 -134.62)
		(width 0.12065)
		(layer "F.Cu")
		(net "DACRSET")
	)
	(segment
		(start 47.3964 -133.949948)
		(end 51.506628 -133.949948)
		(width 0.12065)
		(layer "F.Cu")
		(net "DACRSET")
	)
	(segment
		(start 46.731428 -133.284976)
		(end 47.3964 -133.949948)
		(width 0.12065)
		(layer "F.Cu")
		(net "DACRSET")
	)
	(segment
		(start 46.50486 -133.284976)
		(end 46.731428 -133.284976)
		(width 0.12065)
		(layer "F.Cu")
		(net "DACRSET")
	)
	(via
		(at 51.641756 -134.085076)
		(size 0.7112)
		(drill 0.3556)
		(layers "F.Cu" "B.Cu")
		(net "DACRSET")
	)
	(segment
		(start 46.664118 -132.842)
		(end 46.65599 -132.850128)
		(width 0.12065)
		(layer "F.Cu")
		(net "DACR")
	)
	(segment
		(start 46.65599 -132.850128)
		(end 46.139608 -132.850128)
		(width 0.12065)
		(layer "F.Cu")
		(net "DACR")
	)
	(segment
		(start 50.292 -132.842)
		(end 46.664118 -132.842)
		(width 0.12065)
		(layer "F.Cu")
		(net "DACR")
	)
	(segment
		(start 46.139608 -132.850128)
		(end 45.70476 -133.284976)
		(width 0.12065)
		(layer "F.Cu")
		(net "DACR")
	)
	(segment
		(start 44.904914 -133.284976)
		(end 45.30471 -132.88518)
		(width 0.12065)
		(layer "F.Cu")
		(net "DACG")
	)
	(via
		(at 45.30471 -132.88518)
		(size 0.4572)
		(drill 0.2032)
		(layers "F.Cu" "B.Cu")
		(net "DACG")
	)
	(segment
		(start 45.720762 -132.88518)
		(end 45.30471 -132.88518)
		(width 0.12065)
		(layer "B.Cu")
		(net "DACG")
	)
	(segment
		(start 46.179994 -133.344412)
		(end 45.720762 -132.88518)
		(width 0.12065)
		(layer "B.Cu")
		(net "DACG")
	)
	(segment
		(start 44.104814 -133.284976)
		(end 44.50461 -132.88518)
		(width 0.12065)
		(layer "F.Cu")
		(net "DACB")
	)
	(via
		(at 44.50461 -132.88518)
		(size 0.4572)
		(drill 0.2032)
		(layers "F.Cu" "B.Cu")
		(net "DACB")
	)
	(segment
		(start 44.098972 -131.81711)
		(end 44.095162 -131.82092)
		(width 0.12065)
		(layer "B.Cu")
		(net "DACB")
	)
	(segment
		(start 44.095162 -132.475732)
		(end 44.50461 -132.88518)
		(width 0.12065)
		(layer "B.Cu")
		(net "DACB")
	)
	(segment
		(start 44.098972 -131.287774)
		(end 44.098972 -131.81711)
		(width 0.12065)
		(layer "B.Cu")
		(net "DACB")
	)
	(segment
		(start 44.095162 -131.82092)
		(end 44.095162 -132.475732)
		(width 0.12065)
		(layer "B.Cu")
		(net "DACB")
	)
	(segment
		(start 227.4062 -4.5593)
		(end 227.711 -4.2545)
		(width 0.12065)
		(layer "F.Cu")
		(net "CONSOLE_LED_0")
	)
	(segment
		(start 227.4062 -5.842)
		(end 227.4062 -4.5593)
		(width 0.12065)
		(layer "F.Cu")
		(net "CONSOLE_LED_0")
	)
	(segment
		(start 156.718 -98.2599)
		(end 156.6799 -98.298)
		(width 0.12065)
		(layer "F.Cu")
		(net "CLKGNE_SS_EN")
	)
	(segment
		(start 157.324298 -96.072198)
		(end 157.324298 -97.818702)
		(width 0.12065)
		(layer "F.Cu")
		(net "CLKGNE_SS_EN")
	)
	(segment
		(start 156.718 -95.25)
		(end 156.718 -95.4659)
		(width 0.12065)
		(layer "F.Cu")
		(net "CLKGNE_SS_EN")
	)
	(segment
		(start 158.853378 -93.114622)
		(end 156.718 -95.25)
		(width 0.12065)
		(layer "F.Cu")
		(net "CLKGNE_SS_EN")
	)
	(segment
		(start 157.324298 -97.818702)
		(end 156.8831 -98.2599)
		(width 0.12065)
		(layer "F.Cu")
		(net "CLKGNE_SS_EN")
	)
	(segment
		(start 156.718 -95.4659)
		(end 157.324298 -96.072198)
		(width 0.12065)
		(layer "F.Cu")
		(net "CLKGNE_SS_EN")
	)
	(segment
		(start 156.6799 -98.298)
		(end 155.8036 -98.298)
		(width 0.12065)
		(layer "F.Cu")
		(net "CLKGNE_SS_EN")
	)
	(segment
		(start 159.03194 -93.114622)
		(end 158.853378 -93.114622)
		(width 0.12065)
		(layer "F.Cu")
		(net "CLKGNE_SS_EN")
	)
	(segment
		(start 156.8831 -98.2599)
		(end 156.718 -98.2599)
		(width 0.12065)
		(layer "F.Cu")
		(net "CLKGNE_SS_EN")
	)
	(via
		(at 155.8036 -98.298)
		(size 0.7112)
		(drill 0.3556)
		(layers "F.Cu" "B.Cu")
		(net "CLKGNE_SS_EN")
	)
	(segment
		(start 153.6573 -87.4268)
		(end 154.45486 -86.62924)
		(width 0.12065)
		(layer "F.Cu")
		(net "CLKGNE_SADR_R")
	)
	(segment
		(start 153.6573 -87.4268)
		(end 153.6573 -88.4428)
		(width 0.12065)
		(layer "F.Cu")
		(net "CLKGNE_SADR_R")
	)
	(segment
		(start 154.45486 -85.86978)
		(end 154.45486 -84.86394)
		(width 0.12065)
		(layer "F.Cu")
		(net "CLKGNE_SADR_R")
	)
	(segment
		(start 154.45486 -86.62924)
		(end 154.45486 -85.86978)
		(width 0.12065)
		(layer "F.Cu")
		(net "CLKGNE_SADR_R")
	)
	(via
		(at 154.45486 -85.86978)
		(size 0.7112)
		(drill 0.3556)
		(layers "F.Cu" "B.Cu")
		(net "CLKGNE_SADR_R")
	)
	(segment
		(start 156.907992 -89.826338)
		(end 155.676854 -88.5952)
		(width 0.12065)
		(layer "F.Cu")
		(net "CLKGNE_SADR")
	)
	(segment
		(start 155.676854 -88.5952)
		(end 154.6987 -88.5952)
		(width 0.12065)
		(layer "F.Cu")
		(net "CLKGNE_SADR")
	)
	(segment
		(start 158.294578 -89.826338)
		(end 156.907992 -89.826338)
		(width 0.12065)
		(layer "F.Cu")
		(net "CLKGNE_SADR")
	)
	(segment
		(start 154.6987 -88.5952)
		(end 154.5463 -88.4428)
		(width 0.12065)
		(layer "F.Cu")
		(net "CLKGNE_SADR")
	)
	(segment
		(start 160.031938 -88.088978)
		(end 160.031938 -87.195152)
		(width 0.12065)
		(layer "F.Cu")
		(net "CLKGEN_SDA")
	)
	(segment
		(start 160.031938 -87.195152)
		(end 159.663638 -86.826852)
		(width 0.12065)
		(layer "F.Cu")
		(net "CLKGEN_SDA")
	)
	(segment
		(start 159.259778 -86.826852)
		(end 159.07004 -86.637114)
		(width 0.12065)
		(layer "F.Cu")
		(net "CLKGEN_SDA")
	)
	(segment
		(start 159.512 -85.6869)
		(end 159.07004 -86.12886)
		(width 0.12065)
		(layer "F.Cu")
		(net "CLKGEN_SDA")
	)
	(segment
		(start 159.07004 -86.12886)
		(end 159.07004 -86.637114)
		(width 0.12065)
		(layer "F.Cu")
		(net "CLKGEN_SDA")
	)
	(segment
		(start 159.663638 -86.826852)
		(end 159.259778 -86.826852)
		(width 0.12065)
		(layer "F.Cu")
		(net "CLKGEN_SDA")
	)
	(via
		(at 159.07004 -86.637114)
		(size 0.7112)
		(drill 0.3556)
		(layers "F.Cu" "B.Cu")
		(net "CLKGEN_SDA")
	)
	(segment
		(start 158.795466 -87.217504)
		(end 158.496 -86.918038)
		(width 0.12065)
		(layer "F.Cu")
		(net "CLKGEN_SCL")
	)
	(segment
		(start 159.532066 -87.421212)
		(end 159.328358 -87.217504)
		(width 0.12065)
		(layer "F.Cu")
		(net "CLKGEN_SCL")
	)
	(segment
		(start 158.1277 -85.3186)
		(end 157.5308 -85.3186)
		(width 0.12065)
		(layer "F.Cu")
		(net "CLKGEN_SCL")
	)
	(segment
		(start 158.496 -85.6869)
		(end 158.1277 -85.3186)
		(width 0.12065)
		(layer "F.Cu")
		(net "CLKGEN_SCL")
	)
	(segment
		(start 159.328358 -87.217504)
		(end 158.795466 -87.217504)
		(width 0.12065)
		(layer "F.Cu")
		(net "CLKGEN_SCL")
	)
	(segment
		(start 159.532066 -88.088978)
		(end 159.532066 -87.421212)
		(width 0.12065)
		(layer "F.Cu")
		(net "CLKGEN_SCL")
	)
	(segment
		(start 158.496 -86.918038)
		(end 158.496 -85.6869)
		(width 0.12065)
		(layer "F.Cu")
		(net "CLKGEN_SCL")
	)
	(via
		(at 157.5308 -85.3186)
		(size 0.7112)
		(drill 0.3556)
		(layers "F.Cu" "B.Cu")
		(net "CLKGEN_SCL")
	)
	(segment
		(start 158.627064 -93.853)
		(end 159.258 -93.853)
		(width 0.12065)
		(layer "F.Cu")
		(net "CLKGEN_PWGD")
	)
	(segment
		(start 157.686248 -97.385378)
		(end 157.686248 -96.021652)
		(width 0.12065)
		(layer "F.Cu")
		(net "CLKGEN_PWGD")
	)
	(segment
		(start 158.242 -98.298)
		(end 159.2326 -99.2886)
		(width 0.12065)
		(layer "F.Cu")
		(net "CLKGEN_PWGD")
	)
	(segment
		(start 158.242 -98.2599)
		(end 158.242 -97.94113)
		(width 0.12065)
		(layer "F.Cu")
		(net "CLKGEN_PWGD")
	)
	(segment
		(start 159.258 -93.853)
		(end 159.532066 -93.578934)
		(width 0.12065)
		(layer "F.Cu")
		(net "CLKGEN_PWGD")
	)
	(segment
		(start 158.242 -94.238064)
		(end 158.627064 -93.853)
		(width 0.12065)
		(layer "F.Cu")
		(net "CLKGEN_PWGD")
	)
	(segment
		(start 157.686248 -96.021652)
		(end 158.242 -95.4659)
		(width 0.12065)
		(layer "F.Cu")
		(net "CLKGEN_PWGD")
	)
	(segment
		(start 158.242 -97.94113)
		(end 157.686248 -97.385378)
		(width 0.12065)
		(layer "F.Cu")
		(net "CLKGEN_PWGD")
	)
	(segment
		(start 159.532066 -93.578934)
		(end 159.532066 -93.063822)
		(width 0.12065)
		(layer "F.Cu")
		(net "CLKGEN_PWGD")
	)
	(segment
		(start 158.242 -98.2599)
		(end 158.242 -98.298)
		(width 0.12065)
		(layer "F.Cu")
		(net "CLKGEN_PWGD")
	)
	(segment
		(start 158.242 -95.4659)
		(end 158.242 -94.238064)
		(width 0.12065)
		(layer "F.Cu")
		(net "CLKGEN_PWGD")
	)
	(via
		(at 159.2326 -99.2886)
		(size 0.7112)
		(drill 0.3556)
		(layers "F.Cu" "B.Cu")
		(net "CLKGEN_PWGD")
	)
	(segment
		(start 161.487612 -93.503242)
		(end 161.487358 -93.503496)
		(width 0.136652)
		(layer "F.Cu")
		(net "CLKGEN_P3_R")
	)
	(segment
		(start 161.50971 -93.996764)
		(end 161.986468 -94.473522)
		(width 0.136652)
		(layer "F.Cu")
		(net "CLKGEN_P3_R")
	)
	(segment
		(start 161.4424 -93.6117)
		(end 161.4424 -93.834204)
		(width 0.136652)
		(layer "F.Cu")
		(net "CLKGEN_P3_R")
	)
	(segment
		(start 161.532062 -93.063822)
		(end 161.532062 -93.395292)
		(width 0.136652)
		(layer "F.Cu")
		(net "CLKGEN_P3_R")
	)
	(arc
		(start 161.532062 -93.395292)
		(mid 161.520521 -93.45367)
		(end 161.487612 -93.503242)
		(width 0.136652)
		(layer "F.Cu")
		(net "CLKGEN_P3_R")
	)
	(arc
		(start 161.986468 -94.473522)
		(mid 162.379192 -94.93974)
		(end 162.687 -95.4659)
		(width 0.136652)
		(layer "F.Cu")
		(net "CLKGEN_P3_R")
	)
	(arc
		(start 161.4424 -93.834204)
		(mid 161.459898 -93.922171)
		(end 161.50971 -93.996764)
		(width 0.136652)
		(layer "F.Cu")
		(net "CLKGEN_P3_R")
	)
	(arc
		(start 161.487358 -93.503496)
		(mid 161.454133 -93.553126)
		(end 161.4424 -93.6117)
		(width 0.136652)
		(layer "F.Cu")
		(net "CLKGEN_P3_R")
	)
	(segment
		(start 162.687 -97.1804)
		(end 163.068 -97.5614)
		(width 0.136652)
		(layer "F.Cu")
		(net "CLKGEN_P3")
	)
	(segment
		(start 162.687 -96.3549)
		(end 162.687 -97.1804)
		(width 0.136652)
		(layer "F.Cu")
		(net "CLKGEN_P3")
	)
	(segment
		(start 165.263322 -92.381578)
		(end 165.6715 -91.9734)
		(width 0.136652)
		(layer "F.Cu")
		(net "CLKGEN_P2_R")
	)
	(segment
		(start 164.706046 -92.367354)
		(end 164.72027 -92.381578)
		(width 0.136652)
		(layer "F.Cu")
		(net "CLKGEN_P2_R")
	)
	(segment
		(start 164.899848 -92.456)
		(end 165.083744 -92.456)
		(width 0.136652)
		(layer "F.Cu")
		(net "CLKGEN_P2_R")
	)
	(segment
		(start 163.269422 -91.326462)
		(end 163.563046 -91.326462)
		(width 0.136652)
		(layer "F.Cu")
		(net "CLKGEN_P2_R")
	)
	(segment
		(start 164.6174 -92.137992)
		(end 164.6174 -92.15374)
		(width 0.136652)
		(layer "F.Cu")
		(net "CLKGEN_P2_R")
	)
	(segment
		(start 163.826698 -91.435682)
		(end 163.91509 -91.435682)
		(width 0.136652)
		(layer "F.Cu")
		(net "CLKGEN_P2_R")
	)
	(arc
		(start 164.412168 -91.641422)
		(mid 164.564125 -91.869309)
		(end 164.6174 -92.137992)
		(width 0.136652)
		(layer "F.Cu")
		(net "CLKGEN_P2_R")
	)
	(arc
		(start 163.694872 -91.381072)
		(mid 163.755354 -91.421485)
		(end 163.826698 -91.435682)
		(width 0.136652)
		(layer "F.Cu")
		(net "CLKGEN_P2_R")
	)
	(arc
		(start 165.083744 -92.456)
		(mid 165.180931 -92.43665)
		(end 165.263322 -92.381578)
		(width 0.136652)
		(layer "F.Cu")
		(net "CLKGEN_P2_R")
	)
	(arc
		(start 163.91509 -91.435682)
		(mid 164.184126 -91.489045)
		(end 164.412168 -91.641422)
		(width 0.136652)
		(layer "F.Cu")
		(net "CLKGEN_P2_R")
	)
	(arc
		(start 164.6174 -92.15374)
		(mid 164.640491 -92.269356)
		(end 164.706046 -92.367354)
		(width 0.136652)
		(layer "F.Cu")
		(net "CLKGEN_P2_R")
	)
	(arc
		(start 164.72027 -92.381578)
		(mid 164.802647 -92.436684)
		(end 164.899848 -92.456)
		(width 0.136652)
		(layer "F.Cu")
		(net "CLKGEN_P2_R")
	)
	(arc
		(start 163.563046 -91.326462)
		(mid 163.634392 -91.340654)
		(end 163.694872 -91.381072)
		(width 0.136652)
		(layer "F.Cu")
		(net "CLKGEN_P2_R")
	)
	(segment
		(start 167.7162 -91.9734)
		(end 167.767 -92.0242)
		(width 0.136652)
		(layer "F.Cu")
		(net "CLKGEN_P2")
	)
	(segment
		(start 166.5605 -91.9734)
		(end 167.7162 -91.9734)
		(width 0.136652)
		(layer "F.Cu")
		(net "CLKGEN_P2")
	)
	(segment
		(start 163.854892 -89.4334)
		(end 164.077904 -89.4334)
		(width 0.136652)
		(layer "F.Cu")
		(net "CLKGEN_P1_R")
	)
	(segment
		(start 165.450774 -88.76538)
		(end 165.6715 -88.5444)
		(width 0.136652)
		(layer "F.Cu")
		(net "CLKGEN_P1_R")
	)
	(segment
		(start 164.9476 -88.9)
		(end 165.1254 -88.9)
		(width 0.136652)
		(layer "F.Cu")
		(net "CLKGEN_P1_R")
	)
	(segment
		(start 163.269422 -89.326466)
		(end 163.596574 -89.326466)
		(width 0.136652)
		(layer "F.Cu")
		(net "CLKGEN_P1_R")
	)
	(segment
		(start 164.2618 -89.3572)
		(end 164.5539 -89.0651)
		(width 0.136652)
		(layer "F.Cu")
		(net "CLKGEN_P1_R")
	)
	(segment
		(start 164.5539 -89.0651)
		(end 164.557202 -89.061544)
		(width 0.136652)
		(layer "F.Cu")
		(net "CLKGEN_P1_R")
	)
	(arc
		(start 164.557202 -89.061544)
		(mid 164.736333 -88.941945)
		(end 164.9476 -88.9)
		(width 0.136652)
		(layer "F.Cu")
		(net "CLKGEN_P1_R")
	)
	(arc
		(start 163.72586 -89.38006)
		(mid 163.785075 -89.419563)
		(end 163.854892 -89.4334)
		(width 0.136652)
		(layer "F.Cu")
		(net "CLKGEN_P1_R")
	)
	(arc
		(start 163.596574 -89.326466)
		(mid 163.666545 -89.340402)
		(end 163.72586 -89.38006)
		(width 0.136652)
		(layer "F.Cu")
		(net "CLKGEN_P1_R")
	)
	(arc
		(start 164.077904 -89.4334)
		(mid 164.177438 -89.413601)
		(end 164.2618 -89.3572)
		(width 0.136652)
		(layer "F.Cu")
		(net "CLKGEN_P1_R")
	)
	(arc
		(start 165.1254 -88.9)
		(mid 165.301486 -88.865068)
		(end 165.450774 -88.76538)
		(width 0.136652)
		(layer "F.Cu")
		(net "CLKGEN_P1_R")
	)
	(segment
		(start 160.6804 -94.498668)
		(end 160.532064 -94.350332)
		(width 0.12065)
		(layer "F.Cu")
		(net "CLKGEN_OE3_R")
	)
	(segment
		(start 160.528 -94.651068)
		(end 160.6804 -94.498668)
		(width 0.12065)
		(layer "F.Cu")
		(net "CLKGEN_OE3_R")
	)
	(segment
		(start 160.528 -95.4659)
		(end 160.528 -94.651068)
		(width 0.12065)
		(layer "F.Cu")
		(net "CLKGEN_OE3_R")
	)
	(segment
		(start 160.532064 -94.350332)
		(end 160.532064 -93.063822)
		(width 0.12065)
		(layer "F.Cu")
		(net "CLKGEN_OE3_R")
	)
	(via
		(at 160.6804 -94.498668)
		(size 0.7112)
		(drill 0.3556)
		(layers "F.Cu" "B.Cu")
		(net "CLKGEN_OE3_R")
	)
	(segment
		(start 159.385 -96.3549)
		(end 160.528 -96.3549)
		(width 0.12065)
		(layer "F.Cu")
		(net "CLKGEN_OE3")
	)
	(segment
		(start 159.385 -97.4979)
		(end 159.385 -96.3549)
		(width 0.12065)
		(layer "F.Cu")
		(net "CLKGEN_OE3")
	)
	(segment
		(start 160.528 -97.5614)
		(end 160.528 -96.3549)
		(width 0.12065)
		(layer "F.Cu")
		(net "CLKGEN_OE3")
	)
	(segment
		(start 165.6715 -94.5134)
		(end 164.7444 -94.5134)
		(width 0.12065)
		(layer "F.Cu")
		(net "CLKGEN_OE2_R")
	)
	(segment
		(start 164.719 -94.488)
		(end 163.320222 -93.089222)
		(width 0.12065)
		(layer "F.Cu")
		(net "CLKGEN_OE2_R")
	)
	(segment
		(start 163.320222 -93.089222)
		(end 163.320222 -92.32646)
		(width 0.12065)
		(layer "F.Cu")
		(net "CLKGEN_OE2_R")
	)
	(segment
		(start 164.7444 -94.5134)
		(end 164.719 -94.488)
		(width 0.12065)
		(layer "F.Cu")
		(net "CLKGEN_OE2_R")
	)
	(via
		(at 164.719 -94.488)
		(size 0.7112)
		(drill 0.3556)
		(layers "F.Cu" "B.Cu")
		(net "CLKGEN_OE2_R")
	)
	(segment
		(start 166.5605 -95.6564)
		(end 167.5765 -95.6564)
		(width 0.12065)
		(layer "F.Cu")
		(net "CLKGEN_OE2")
	)
	(segment
		(start 167.5765 -95.13697)
		(end 167.767 -94.94647)
		(width 0.12065)
		(layer "F.Cu")
		(net "CLKGEN_OE2")
	)
	(segment
		(start 167.5765 -95.6564)
		(end 167.5765 -95.13697)
		(width 0.12065)
		(layer "F.Cu")
		(net "CLKGEN_OE2")
	)
	(segment
		(start 167.767 -94.94647)
		(end 167.767 -94.5134)
		(width 0.12065)
		(layer "F.Cu")
		(net "CLKGEN_OE2")
	)
	(segment
		(start 166.5605 -95.6564)
		(end 166.5605 -94.5134)
		(width 0.12065)
		(layer "F.Cu")
		(net "CLKGEN_OE2")
	)
	(segment
		(start 165.364668 -87.5284)
		(end 165.6715 -87.5284)
		(width 0.12065)
		(layer "F.Cu")
		(net "CLKGEN_OE1_R")
	)
	(segment
		(start 164.977572 -86.71179)
		(end 164.977572 -87.141304)
		(width 0.12065)
		(layer "F.Cu")
		(net "CLKGEN_OE1_R")
	)
	(segment
		(start 164.013896 -87.792306)
		(end 164.013896 -86.719918)
		(width 0.12065)
		(layer "F.Cu")
		(net "CLKGEN_OE1_R")
	)
	(segment
		(start 163.320222 -88.48598)
		(end 164.013896 -87.792306)
		(width 0.12065)
		(layer "F.Cu")
		(net "CLKGEN_OE1_R")
	)
	(segment
		(start 164.977572 -87.141304)
		(end 165.364668 -87.5284)
		(width 0.12065)
		(layer "F.Cu")
		(net "CLKGEN_OE1_R")
	)
	(segment
		(start 164.013896 -86.719918)
		(end 164.132514 -86.6013)
		(width 0.12065)
		(layer "F.Cu")
		(net "CLKGEN_OE1_R")
	)
	(segment
		(start 163.320222 -88.82634)
		(end 163.320222 -88.48598)
		(width 0.12065)
		(layer "F.Cu")
		(net "CLKGEN_OE1_R")
	)
	(segment
		(start 164.132514 -86.6013)
		(end 164.495734 -86.6013)
		(width 0.12065)
		(layer "F.Cu")
		(net "CLKGEN_OE1_R")
	)
	(segment
		(start 164.495734 -86.6013)
		(end 164.867082 -86.6013)
		(width 0.12065)
		(layer "F.Cu")
		(net "CLKGEN_OE1_R")
	)
	(segment
		(start 164.867082 -86.6013)
		(end 164.977572 -86.71179)
		(width 0.12065)
		(layer "F.Cu")
		(net "CLKGEN_OE1_R")
	)
	(via
		(at 164.495734 -86.6013)
		(size 0.7112)
		(drill 0.3556)
		(layers "F.Cu" "B.Cu")
		(net "CLKGEN_OE1_R")
	)
	(segment
		(start 166.5605 -86.3854)
		(end 166.5605 -87.5284)
		(width 0.12065)
		(layer "F.Cu")
		(net "CLKGEN_OE1")
	)
	(segment
		(start 167.6654 -87.5284)
		(end 166.5605 -87.5284)
		(width 0.12065)
		(layer "F.Cu")
		(net "CLKGEN_OE1")
	)
	(segment
		(start 167.5765 -86.3854)
		(end 166.5605 -86.3854)
		(width 0.12065)
		(layer "F.Cu")
		(net "CLKGEN_OE1")
	)
	(segment
		(start 161.6202 -95.4659)
		(end 161.86023 -95.22587)
		(width 0.136652)
		(layer "F.Cu")
		(net "CLKGEN_N3_R")
	)
	(segment
		(start 161.031936 -93.34246)
		(end 161.031936 -93.063822)
		(width 0.136652)
		(layer "F.Cu")
		(net "CLKGEN_N3_R")
	)
	(segment
		(start 161.1376 -93.8403)
		(end 161.1376 -93.597476)
		(width 0.136652)
		(layer "F.Cu")
		(net "CLKGEN_N3_R")
	)
	(segment
		(start 161.86023 -94.778576)
		(end 161.29 -94.208346)
		(width 0.136652)
		(layer "F.Cu")
		(net "CLKGEN_N3_R")
	)
	(arc
		(start 161.084768 -93.469968)
		(mid 161.045679 -93.411467)
		(end 161.031936 -93.34246)
		(width 0.136652)
		(layer "F.Cu")
		(net "CLKGEN_N3_R")
	)
	(arc
		(start 161.29 -94.208346)
		(mid 161.177171 -94.039485)
		(end 161.1376 -93.8403)
		(width 0.136652)
		(layer "F.Cu")
		(net "CLKGEN_N3_R")
	)
	(arc
		(start 161.86023 -95.22587)
		(mid 161.952815 -95.00226)
		(end 161.86023 -94.778576)
		(width 0.136652)
		(layer "F.Cu")
		(net "CLKGEN_N3_R")
	)
	(arc
		(start 161.1376 -93.597476)
		(mid 161.123872 -93.528463)
		(end 161.084768 -93.469968)
		(width 0.136652)
		(layer "F.Cu")
		(net "CLKGEN_N3_R")
	)
	(segment
		(start 161.6202 -96.3549)
		(end 161.6202 -97.3836)
		(width 0.136652)
		(layer "F.Cu")
		(net "CLKGEN_N3")
	)
	(segment
		(start 161.6202 -97.3836)
		(end 161.798 -97.5614)
		(width 0.136652)
		(layer "F.Cu")
		(net "CLKGEN_N3")
	)
	(segment
		(start 164.4904 -92.583)
		(end 164.504624 -92.597224)
		(width 0.136652)
		(layer "F.Cu")
		(net "CLKGEN_N2_R")
	)
	(segment
		(start 165.269672 -92.841572)
		(end 165.6715 -93.2434)
		(width 0.136652)
		(layer "F.Cu")
		(net "CLKGEN_N2_R")
	)
	(segment
		(start 164.899848 -92.7608)
		(end 165.0746 -92.7608)
		(width 0.136652)
		(layer "F.Cu")
		(net "CLKGEN_N2_R")
	)
	(segment
		(start 164.3126 -92.137992)
		(end 164.3126 -92.153994)
		(width 0.136652)
		(layer "F.Cu")
		(net "CLKGEN_N2_R")
	)
	(segment
		(start 163.793424 -91.740482)
		(end 163.793424 -91.739466)
		(width 0.136652)
		(layer "F.Cu")
		(net "CLKGEN_N2_R")
	)
	(segment
		(start 164.196522 -91.857068)
		(end 164.196268 -91.857068)
		(width 0.136652)
		(layer "F.Cu")
		(net "CLKGEN_N2_R")
	)
	(segment
		(start 163.269422 -91.826334)
		(end 163.58616 -91.826334)
		(width 0.136652)
		(layer "F.Cu")
		(net "CLKGEN_N2_R")
	)
	(segment
		(start 163.826698 -91.740482)
		(end 163.915344 -91.740482)
		(width 0.136652)
		(layer "F.Cu")
		(net "CLKGEN_N2_R")
	)
	(arc
		(start 164.196268 -91.857068)
		(mid 164.282389 -91.985957)
		(end 164.3126 -92.137992)
		(width 0.136652)
		(layer "F.Cu")
		(net "CLKGEN_N2_R")
	)
	(arc
		(start 165.0746 -92.7608)
		(mid 165.180161 -92.781797)
		(end 165.269672 -92.841572)
		(width 0.136652)
		(layer "F.Cu")
		(net "CLKGEN_N2_R")
	)
	(arc
		(start 163.58616 -91.826334)
		(mid 163.642245 -91.815178)
		(end 163.689792 -91.783408)
		(width 0.136652)
		(layer "F.Cu")
		(net "CLKGEN_N2_R")
	)
	(arc
		(start 164.3126 -92.153994)
		(mid 164.358858 -92.386169)
		(end 164.4904 -92.583)
		(width 0.136652)
		(layer "F.Cu")
		(net "CLKGEN_N2_R")
	)
	(arc
		(start 163.793424 -91.739466)
		(mid 163.810052 -91.74026)
		(end 163.826698 -91.740482)
		(width 0.136652)
		(layer "F.Cu")
		(net "CLKGEN_N2_R")
	)
	(arc
		(start 164.504624 -92.597224)
		(mid 164.685969 -92.718302)
		(end 164.899848 -92.7608)
		(width 0.136652)
		(layer "F.Cu")
		(net "CLKGEN_N2_R")
	)
	(arc
		(start 163.915344 -91.740482)
		(mid 164.067547 -91.770775)
		(end 164.196522 -91.857068)
		(width 0.136652)
		(layer "F.Cu")
		(net "CLKGEN_N2_R")
	)
	(arc
		(start 163.689792 -91.783408)
		(mid 163.737339 -91.751638)
		(end 163.793424 -91.740482)
		(width 0.136652)
		(layer "F.Cu")
		(net "CLKGEN_N2_R")
	)
	(segment
		(start 166.59098 -93.27388)
		(end 167.73652 -93.27388)
		(width 0.136652)
		(layer "F.Cu")
		(net "CLKGEN_N2")
	)
	(segment
		(start 167.73652 -93.27388)
		(end 167.767 -93.2434)
		(width 0.136652)
		(layer "F.Cu")
		(net "CLKGEN_N2")
	)
	(segment
		(start 166.5605 -93.2434)
		(end 166.59098 -93.27388)
		(width 0.136652)
		(layer "F.Cu")
		(net "CLKGEN_N2")
	)
	(segment
		(start 164.9476 -89.2048)
		(end 165.163246 -89.2048)
		(width 0.136652)
		(layer "F.Cu")
		(net "CLKGEN_N1_R")
	)
	(segment
		(start 163.81603 -89.7382)
		(end 164.078158 -89.7382)
		(width 0.136652)
		(layer "F.Cu")
		(net "CLKGEN_N1_R")
	)
	(segment
		(start 163.269422 -89.826338)
		(end 163.603432 -89.826338)
		(width 0.136652)
		(layer "F.Cu")
		(net "CLKGEN_N1_R")
	)
	(segment
		(start 164.744146 -89.306146)
		(end 164.773102 -89.276936)
		(width 0.136652)
		(layer "F.Cu")
		(net "CLKGEN_N1_R")
	)
	(segment
		(start 165.42385 -89.31275)
		(end 165.6715 -89.5604)
		(width 0.136652)
		(layer "F.Cu")
		(net "CLKGEN_N1_R")
	)
	(segment
		(start 164.477446 -89.572846)
		(end 164.744146 -89.306146)
		(width 0.136652)
		(layer "F.Cu")
		(net "CLKGEN_N1_R")
	)
	(arc
		(start 164.078158 -89.7382)
		(mid 164.294251 -89.695234)
		(end 164.477446 -89.572846)
		(width 0.136652)
		(layer "F.Cu")
		(net "CLKGEN_N1_R")
	)
	(arc
		(start 163.709604 -89.782396)
		(mid 163.758404 -89.749662)
		(end 163.81603 -89.7382)
		(width 0.136652)
		(layer "F.Cu")
		(net "CLKGEN_N1_R")
	)
	(arc
		(start 163.603432 -89.826338)
		(mid 163.660878 -89.814911)
		(end 163.709604 -89.782396)
		(width 0.136652)
		(layer "F.Cu")
		(net "CLKGEN_N1_R")
	)
	(arc
		(start 165.163246 -89.2048)
		(mid 165.304286 -89.232855)
		(end 165.42385 -89.31275)
		(width 0.136652)
		(layer "F.Cu")
		(net "CLKGEN_N1_R")
	)
	(arc
		(start 164.773102 -89.276936)
		(mid 164.853177 -89.223524)
		(end 164.9476 -89.2048)
		(width 0.136652)
		(layer "F.Cu")
		(net "CLKGEN_N1_R")
	)
	(segment
		(start 316.448948 -28.782264)
		(end 316.448948 -17.93875)
		(width 0.136652)
		(layer "F.Cu")
		(net "CLK_P_8")
	)
	(segment
		(start 317.779146 -32.4358)
		(end 317.779146 -30.365446)
		(width 0.136652)
		(layer "F.Cu")
		(net "CLK_P_8")
	)
	(segment
		(start 319.369948 -13.377672)
		(end 319.320164 -13.377672)
		(width 0.136652)
		(layer "F.Cu")
		(net "CLK_P_8")
	)
	(segment
		(start 319.94348 -14.357604)
		(end 319.94348 -14.082522)
		(width 0.136652)
		(layer "F.Cu")
		(net "CLK_P_8")
	)
	(segment
		(start 316.448694 -29.034994)
		(end 316.448694 -28.782518)
		(width 0.136652)
		(layer "F.Cu")
		(net "CLK_P_8")
	)
	(segment
		(start 319.77457 -13.674852)
		(end 319.553336 -13.453618)
		(width 0.136652)
		(layer "F.Cu")
		(net "CLK_P_8")
	)
	(segment
		(start 319.134236 -13.581126)
		(end 319.13449 -13.58138)
		(width 0.136652)
		(layer "F.Cu")
		(net "CLK_P_8")
	)
	(segment
		(start 319.94348 -14.082522)
		(end 319.943226 -14.082776)
		(width 0.136652)
		(layer "F.Cu")
		(net "CLK_P_8")
	)
	(segment
		(start 319.13449 -13.58138)
		(end 319.13449 -13.930122)
		(width 0.136652)
		(layer "F.Cu")
		(net "CLK_P_8")
	)
	(segment
		(start 316.448948 -17.93875)
		(end 319.882012 -14.505686)
		(width 0.136652)
		(layer "F.Cu")
		(net "CLK_P_8")
	)
	(segment
		(start 317.779146 -30.365446)
		(end 316.448694 -29.034994)
		(width 0.136652)
		(layer "F.Cu")
		(net "CLK_P_8")
	)
	(segment
		(start 316.448694 -28.782518)
		(end 316.448948 -28.782264)
		(width 0.136652)
		(layer "F.Cu")
		(net "CLK_P_8")
	)
	(segment
		(start 317.418466 -32.98063)
		(end 317.648844 -32.749998)
		(width 0.136652)
		(layer "F.Cu")
		(net "CLK_P_8")
	)
	(arc
		(start 319.197482 -13.428472)
		(mid 319.150684 -13.49851)
		(end 319.134236 -13.581126)
		(width 0.136652)
		(layer "F.Cu")
		(net "CLK_P_8")
	)
	(arc
		(start 317.648844 -32.749998)
		(mid 317.745248 -32.605858)
		(end 317.779146 -32.4358)
		(width 0.136652)
		(layer "F.Cu")
		(net "CLK_P_8")
	)
	(arc
		(start 319.943226 -14.082776)
		(mid 319.899449 -13.862046)
		(end 319.77457 -13.674852)
		(width 0.136652)
		(layer "F.Cu")
		(net "CLK_P_8")
	)
	(arc
		(start 319.882012 -14.505686)
		(mid 319.927491 -14.43776)
		(end 319.94348 -14.357604)
		(width 0.136652)
		(layer "F.Cu")
		(net "CLK_P_8")
	)
	(arc
		(start 319.320164 -13.377672)
		(mid 319.253775 -13.390878)
		(end 319.197482 -13.428472)
		(width 0.136652)
		(layer "F.Cu")
		(net "CLK_P_8")
	)
	(arc
		(start 319.55105 -13.451332)
		(mid 319.467709 -13.396765)
		(end 319.369948 -13.377672)
		(width 0.136652)
		(layer "F.Cu")
		(net "CLK_P_8")
	)
	(arc
		(start 319.553336 -13.453618)
		(mid 319.552197 -13.452471)
		(end 319.55105 -13.451332)
		(width 0.136652)
		(layer "F.Cu")
		(net "CLK_P_8")
	)
	(segment
		(start 293.320978 -4.983734)
		(end 293.320978 -4.984242)
		(width 0.136652)
		(layer "F.Cu")
		(net "CLK_P_6")
	)
	(segment
		(start 297.13428 -13.825474)
		(end 297.13428 -13.930122)
		(width 0.136652)
		(layer "F.Cu")
		(net "CLK_P_6")
	)
	(segment
		(start 293.320978 -4.984242)
		(end 295.5798 -7.243064)
		(width 0.136652)
		(layer "F.Cu")
		(net "CLK_P_6")
	)
	(segment
		(start 295.5798 -11.7602)
		(end 296.773092 -12.953492)
		(width 0.136652)
		(layer "F.Cu")
		(net "CLK_P_6")
	)
	(segment
		(start 277.192486 -4.417822)
		(end 292.755066 -4.417822)
		(width 0.136652)
		(layer "F.Cu")
		(net "CLK_P_6")
	)
	(segment
		(start 276.904958 -4.70535)
		(end 277.192486 -4.417822)
		(width 0.136652)
		(layer "F.Cu")
		(net "CLK_P_6")
	)
	(segment
		(start 292.755066 -4.417822)
		(end 293.320978 -4.983734)
		(width 0.136652)
		(layer "F.Cu")
		(net "CLK_P_6")
	)
	(segment
		(start 295.5798 -7.243064)
		(end 295.5798 -11.7602)
		(width 0.136652)
		(layer "F.Cu")
		(net "CLK_P_6")
	)
	(arc
		(start 296.773092 -12.953492)
		(mid 297.040409 -13.353561)
		(end 297.13428 -13.825474)
		(width 0.136652)
		(layer "F.Cu")
		(net "CLK_P_6")
	)
	(segment
		(start 167.1828 -14.097)
		(end 166.9415 -13.8557)
		(width 0.136652)
		(layer "F.Cu")
		(net "CLK_P_4")
	)
	(segment
		(start 168.963594 -15.2908)
		(end 167.952928 -15.2908)
		(width 0.136652)
		(layer "F.Cu")
		(net "CLK_P_4")
	)
	(segment
		(start 166.9415 -13.855954)
		(end 166.916862 -13.831316)
		(width 0.136652)
		(layer "F.Cu")
		(net "CLK_P_4")
	)
	(segment
		(start 177.17389 -14.01699)
		(end 176.852326 -14.338554)
		(width 0.136652)
		(layer "F.Cu")
		(net "CLK_P_4")
	)
	(segment
		(start 175.632364 -14.84376)
		(end 171.582588 -14.84376)
		(width 0.136652)
		(layer "F.Cu")
		(net "CLK_P_4")
	)
	(segment
		(start 167.386 -14.586966)
		(end 167.385746 -14.58722)
		(width 0.136652)
		(layer "F.Cu")
		(net "CLK_P_4")
	)
	(segment
		(start 166.182294 -13.882116)
		(end 166.134542 -13.930122)
		(width 0.136652)
		(layer "F.Cu")
		(net "CLK_P_4")
	)
	(segment
		(start 167.386 -14.723872)
		(end 167.386 -14.586966)
		(width 0.136652)
		(layer "F.Cu")
		(net "CLK_P_4")
	)
	(segment
		(start 181.19344 -14.18844)
		(end 180.86578 -13.86078)
		(width 0.136652)
		(layer "F.Cu")
		(net "CLK_P_4")
	)
	(segment
		(start 166.7002 -13.7414)
		(end 166.5224 -13.7414)
		(width 0.136652)
		(layer "F.Cu")
		(net "CLK_P_4")
	)
	(segment
		(start 180.86578 -13.86078)
		(end 177.55108 -13.86078)
		(width 0.136652)
		(layer "F.Cu")
		(net "CLK_P_4")
	)
	(segment
		(start 166.9415 -13.8557)
		(end 166.9415 -13.855954)
		(width 0.136652)
		(layer "F.Cu")
		(net "CLK_P_4")
	)
	(segment
		(start 171.582588 -14.84376)
		(end 169.126916 -15.276576)
		(width 0.136652)
		(layer "F.Cu")
		(net "CLK_P_4")
	)
	(arc
		(start 166.916862 -13.831316)
		(mid 166.817472 -13.764813)
		(end 166.7002 -13.7414)
		(width 0.136652)
		(layer "F.Cu")
		(net "CLK_P_4")
	)
	(arc
		(start 166.5224 -13.7414)
		(mid 166.338344 -13.777917)
		(end 166.182294 -13.882116)
		(width 0.136652)
		(layer "F.Cu")
		(net "CLK_P_4")
	)
	(arc
		(start 167.385746 -14.58722)
		(mid 167.332982 -14.321957)
		(end 167.1828 -14.097)
		(width 0.136652)
		(layer "F.Cu")
		(net "CLK_P_4")
	)
	(arc
		(start 167.952928 -15.2908)
		(mid 167.552049 -15.124751)
		(end 167.386 -14.723872)
		(width 0.136652)
		(layer "F.Cu")
		(net "CLK_P_4")
	)
	(arc
		(start 176.852326 -14.338554)
		(mid 176.292588 -14.712466)
		(end 175.632364 -14.84376)
		(width 0.136652)
		(layer "F.Cu")
		(net "CLK_P_4")
	)
	(arc
		(start 169.126916 -15.276576)
		(mid 169.045565 -15.287249)
		(end 168.963594 -15.2908)
		(width 0.136652)
		(layer "F.Cu")
		(net "CLK_P_4")
	)
	(arc
		(start 177.55108 -13.86078)
		(mid 177.346942 -13.901368)
		(end 177.17389 -14.01699)
		(width 0.136652)
		(layer "F.Cu")
		(net "CLK_P_4")
	)
	(segment
		(start 142.997174 -13.633704)
		(end 143.133826 -13.497052)
		(width 0.136652)
		(layer "F.Cu")
		(net "CLK_P_2")
	)
	(segment
		(start 143.773144 -13.21435)
		(end 144.244314 -13.21435)
		(width 0.136652)
		(layer "F.Cu")
		(net "CLK_P_2")
	)
	(segment
		(start 141.468094 -29.915866)
		(end 142.733268 -28.650692)
		(width 0.136652)
		(layer "F.Cu")
		(net "CLK_P_2")
	)
	(segment
		(start 141.427708 -33.530286)
		(end 141.427708 -30.012894)
		(width 0.136652)
		(layer "F.Cu")
		(net "CLK_P_2")
	)
	(segment
		(start 142.9004 -28.24734)
		(end 142.9004 -13.867384)
		(width 0.136652)
		(layer "F.Cu")
		(net "CLK_P_2")
	)
	(segment
		(start 144.244314 -13.930122)
		(end 144.134332 -13.930122)
		(width 0.136652)
		(layer "F.Cu")
		(net "CLK_P_2")
	)
	(arc
		(start 141.798802 -33.90138)
		(mid 141.536399 -33.792689)
		(end 141.427708 -33.530286)
		(width 0.136652)
		(layer "F.Cu")
		(net "CLK_P_2")
	)
	(arc
		(start 142.733268 -28.650692)
		(mid 142.856921 -28.465633)
		(end 142.9004 -28.24734)
		(width 0.136652)
		(layer "F.Cu")
		(net "CLK_P_2")
	)
	(arc
		(start 141.427708 -30.012894)
		(mid 141.438183 -29.960322)
		(end 141.468094 -29.915866)
		(width 0.136652)
		(layer "F.Cu")
		(net "CLK_P_2")
	)
	(arc
		(start 142.9004 -13.867384)
		(mid 142.925554 -13.740925)
		(end 142.997174 -13.633704)
		(width 0.136652)
		(layer "F.Cu")
		(net "CLK_P_2")
	)
	(arc
		(start 143.671798 -13.222478)
		(mid 143.722308 -13.216379)
		(end 143.773144 -13.21435)
		(width 0.136652)
		(layer "F.Cu")
		(net "CLK_P_2")
	)
	(arc
		(start 144.244314 -13.21435)
		(mid 144.6022 -13.572236)
		(end 144.244314 -13.930122)
		(width 0.136652)
		(layer "F.Cu")
		(net "CLK_P_2")
	)
	(arc
		(start 143.133826 -13.497052)
		(mid 143.381228 -13.31746)
		(end 143.671798 -13.222478)
		(width 0.136652)
		(layer "F.Cu")
		(net "CLK_P_2")
	)
	(segment
		(start 320.24828 -14.357604)
		(end 320.24828 -14.082776)
		(width 0.136652)
		(layer "F.Cu")
		(net "CLK_N_8")
	)
	(segment
		(start 318.444626 -32.98063)
		(end 318.214248 -32.749998)
		(width 0.136652)
		(layer "F.Cu")
		(net "CLK_N_8")
	)
	(segment
		(start 316.753748 -28.908756)
		(end 316.753748 -18.065242)
		(width 0.136652)
		(layer "F.Cu")
		(net "CLK_N_8")
	)
	(segment
		(start 318.083946 -32.4358)
		(end 318.083946 -30.238954)
		(width 0.136652)
		(layer "F.Cu")
		(net "CLK_N_8")
	)
	(segment
		(start 319.884298 -13.264896)
		(end 319.884298 -12.530074)
		(width 0.136652)
		(layer "F.Cu")
		(net "CLK_N_8")
	)
	(segment
		(start 319.990216 -13.459206)
		(end 319.946782 -13.415772)
		(width 0.136652)
		(layer "F.Cu")
		(net "CLK_N_8")
	)
	(segment
		(start 316.753748 -18.065242)
		(end 320.097658 -14.721332)
		(width 0.136652)
		(layer "F.Cu")
		(net "CLK_N_8")
	)
	(segment
		(start 318.083946 -30.238954)
		(end 316.753748 -28.908756)
		(width 0.136652)
		(layer "F.Cu")
		(net "CLK_N_8")
	)
	(arc
		(start 319.921636 -13.3858)
		(mid 319.90625 -13.359576)
		(end 319.894712 -13.331444)
		(width 0.136652)
		(layer "F.Cu")
		(net "CLK_N_8")
	)
	(arc
		(start 318.214248 -32.749998)
		(mid 318.117844 -32.605858)
		(end 318.083946 -32.4358)
		(width 0.136652)
		(layer "F.Cu")
		(net "CLK_N_8")
	)
	(arc
		(start 320.097658 -14.721332)
		(mid 320.20911 -14.554438)
		(end 320.24828 -14.357604)
		(width 0.136652)
		(layer "F.Cu")
		(net "CLK_N_8")
	)
	(arc
		(start 319.894712 -13.331444)
		(mid 319.886872 -13.298583)
		(end 319.884298 -13.264896)
		(width 0.136652)
		(layer "F.Cu")
		(net "CLK_N_8")
	)
	(arc
		(start 319.946782 -13.415772)
		(mid 319.933524 -13.401361)
		(end 319.921636 -13.3858)
		(width 0.136652)
		(layer "F.Cu")
		(net "CLK_N_8")
	)
	(arc
		(start 320.24828 -14.082776)
		(mid 320.181268 -13.745321)
		(end 319.990216 -13.459206)
		(width 0.136652)
		(layer "F.Cu")
		(net "CLK_N_8")
	)
	(segment
		(start 293.625778 -4.857242)
		(end 293.625778 -4.85775)
		(width 0.136652)
		(layer "F.Cu")
		(net "CLK_N_6")
	)
	(segment
		(start 292.881558 -4.113022)
		(end 293.625778 -4.857242)
		(width 0.136652)
		(layer "F.Cu")
		(net "CLK_N_6")
	)
	(segment
		(start 277.365714 -4.113022)
		(end 292.881558 -4.113022)
		(width 0.136652)
		(layer "F.Cu")
		(net "CLK_N_6")
	)
	(segment
		(start 296.989246 -12.530074)
		(end 297.884342 -12.530074)
		(width 0.136652)
		(layer "F.Cu")
		(net "CLK_N_6")
	)
	(segment
		(start 293.625778 -4.85775)
		(end 295.8846 -7.116572)
		(width 0.136652)
		(layer "F.Cu")
		(net "CLK_N_6")
	)
	(segment
		(start 295.8846 -11.633708)
		(end 296.633646 -12.382754)
		(width 0.136652)
		(layer "F.Cu")
		(net "CLK_N_6")
	)
	(segment
		(start 276.85365 -3.600958)
		(end 277.365714 -4.113022)
		(width 0.136652)
		(layer "F.Cu")
		(net "CLK_N_6")
	)
	(segment
		(start 295.8846 -7.116572)
		(end 295.8846 -11.633708)
		(width 0.136652)
		(layer "F.Cu")
		(net "CLK_N_6")
	)
	(arc
		(start 296.633646 -12.382754)
		(mid 296.796797 -12.491768)
		(end 296.989246 -12.530074)
		(width 0.136652)
		(layer "F.Cu")
		(net "CLK_N_6")
	)
	(segment
		(start 167.6908 -14.723872)
		(end 167.6908 -14.58722)
		(width 0.136652)
		(layer "F.Cu")
		(net "CLK_N_4")
	)
	(segment
		(start 168.964102 -14.986)
		(end 167.952928 -14.986)
		(width 0.136652)
		(layer "F.Cu")
		(net "CLK_N_4")
	)
	(segment
		(start 176.958244 -13.801344)
		(end 176.63668 -14.122908)
		(width 0.136652)
		(layer "F.Cu")
		(net "CLK_N_4")
	)
	(segment
		(start 177.774092 -13.55598)
		(end 177.551334 -13.555726)
		(width 0.136652)
		(layer "F.Cu")
		(net "CLK_N_4")
	)
	(segment
		(start 171.555918 -14.53896)
		(end 169.074084 -14.976348)
		(width 0.136652)
		(layer "F.Cu")
		(net "CLK_N_4")
	)
	(segment
		(start 181.19344 -13.156184)
		(end 180.793644 -13.55598)
		(width 0.136652)
		(layer "F.Cu")
		(net "CLK_N_4")
	)
	(segment
		(start 166.88435 -12.981432)
		(end 166.88435 -12.530074)
		(width 0.136652)
		(layer "F.Cu")
		(net "CLK_N_4")
	)
	(segment
		(start 180.793644 -13.55598)
		(end 177.774092 -13.55598)
		(width 0.136652)
		(layer "F.Cu")
		(net "CLK_N_4")
	)
	(segment
		(start 167.398446 -13.881354)
		(end 167.157146 -13.640054)
		(width 0.136652)
		(layer "F.Cu")
		(net "CLK_N_4")
	)
	(segment
		(start 175.632364 -14.53896)
		(end 171.555918 -14.53896)
		(width 0.136652)
		(layer "F.Cu")
		(net "CLK_N_4")
	)
	(arc
		(start 167.157146 -13.640054)
		(mid 166.955237 -13.337876)
		(end 166.88435 -12.981432)
		(width 0.136652)
		(layer "F.Cu")
		(net "CLK_N_4")
	)
	(arc
		(start 169.074084 -14.976348)
		(mid 169.019303 -14.983564)
		(end 168.964102 -14.986)
		(width 0.136652)
		(layer "F.Cu")
		(net "CLK_N_4")
	)
	(arc
		(start 167.952928 -14.986)
		(mid 167.767576 -14.909224)
		(end 167.6908 -14.723872)
		(width 0.136652)
		(layer "F.Cu")
		(net "CLK_N_4")
	)
	(arc
		(start 176.63668 -14.122908)
		(mid 176.17591 -14.430848)
		(end 175.632364 -14.53896)
		(width 0.136652)
		(layer "F.Cu")
		(net "CLK_N_4")
	)
	(arc
		(start 167.6908 -14.58722)
		(mid 167.614815 -14.205218)
		(end 167.398446 -13.881354)
		(width 0.136652)
		(layer "F.Cu")
		(net "CLK_N_4")
	)
	(arc
		(start 177.551334 -13.555726)
		(mid 177.230389 -13.619584)
		(end 176.958244 -13.801344)
		(width 0.136652)
		(layer "F.Cu")
		(net "CLK_N_4")
	)
	(segment
		(start 144.0688 -12.90955)
		(end 143.772382 -12.90955)
		(width 0.136652)
		(layer "F.Cu")
		(net "CLK_N_2")
	)
	(segment
		(start 142.517622 -28.435046)
		(end 141.252448 -29.70022)
		(width 0.136652)
		(layer "F.Cu")
		(net "CLK_N_2")
	)
	(segment
		(start 142.918434 -13.281152)
		(end 142.781528 -13.418058)
		(width 0.136652)
		(layer "F.Cu")
		(net "CLK_N_2")
	)
	(segment
		(start 141.122908 -30.01264)
		(end 141.122908 -33.477454)
		(width 0.136652)
		(layer "F.Cu")
		(net "CLK_N_2")
	)
	(segment
		(start 144.884394 -12.530074)
		(end 144.813274 -12.601194)
		(width 0.136652)
		(layer "F.Cu")
		(net "CLK_N_2")
	)
	(segment
		(start 142.5956 -13.867384)
		(end 142.5956 -28.247086)
		(width 0.136652)
		(layer "F.Cu")
		(net "CLK_N_2")
	)
	(arc
		(start 144.38122 -12.862052)
		(mid 144.226802 -12.897591)
		(end 144.0688 -12.90955)
		(width 0.136652)
		(layer "F.Cu")
		(net "CLK_N_2")
	)
	(arc
		(start 141.122908 -33.477454)
		(mid 141.025395 -33.759777)
		(end 140.77442 -33.9217)
		(width 0.136652)
		(layer "F.Cu")
		(net "CLK_N_2")
	)
	(arc
		(start 141.252448 -29.70022)
		(mid 141.156589 -29.843544)
		(end 141.122908 -30.01264)
		(width 0.136652)
		(layer "F.Cu")
		(net "CLK_N_2")
	)
	(arc
		(start 144.813274 -12.601194)
		(mid 144.613111 -12.757902)
		(end 144.38122 -12.862052)
		(width 0.136652)
		(layer "F.Cu")
		(net "CLK_N_2")
	)
	(arc
		(start 142.5956 -28.247086)
		(mid 142.575327 -28.348828)
		(end 142.517622 -28.435046)
		(width 0.136652)
		(layer "F.Cu")
		(net "CLK_N_2")
	)
	(arc
		(start 142.781528 -13.418058)
		(mid 142.643918 -13.62424)
		(end 142.5956 -13.867384)
		(width 0.136652)
		(layer "F.Cu")
		(net "CLK_N_2")
	)
	(arc
		(start 143.772382 -12.90955)
		(mid 143.697595 -12.91254)
		(end 143.623284 -12.921488)
		(width 0.136652)
		(layer "F.Cu")
		(net "CLK_N_2")
	)
	(arc
		(start 143.623284 -12.921488)
		(mid 143.242602 -13.045936)
		(end 142.918434 -13.281152)
		(width 0.136652)
		(layer "F.Cu")
		(net "CLK_N_2")
	)
	(segment
		(start 11.395964 -92.533978)
		(end 11.395964 -91.729814)
		(width 0.12065)
		(layer "F.Cu")
		(net "CLK_50M_RMII_PHY")
	)
	(segment
		(start 13.569188 -90.897456)
		(end 13.008102 -90.33637)
		(width 0.12065)
		(layer "F.Cu")
		(net "CLK_50M_RMII_PHY")
	)
	(segment
		(start 13.229844 -91.2368)
		(end 13.569188 -90.897456)
		(width 0.12065)
		(layer "F.Cu")
		(net "CLK_50M_RMII_PHY")
	)
	(segment
		(start 13.008102 -89.32291)
		(end 13.340334 -88.990678)
		(width 0.12065)
		(layer "F.Cu")
		(net "CLK_50M_RMII_PHY")
	)
	(segment
		(start 11.395964 -91.729814)
		(end 11.888978 -91.2368)
		(width 0.12065)
		(layer "F.Cu")
		(net "CLK_50M_RMII_PHY")
	)
	(segment
		(start 25.9334 -71.521828)
		(end 26.034746 -71.420482)
		(width 0.12065)
		(layer "F.Cu")
		(net "CLK_50M_RMII_PHY")
	)
	(segment
		(start 25.160478 -71.521828)
		(end 25.9334 -71.521828)
		(width 0.12065)
		(layer "F.Cu")
		(net "CLK_50M_RMII_PHY")
	)
	(segment
		(start 13.008102 -90.33637)
		(end 13.008102 -89.32291)
		(width 0.12065)
		(layer "F.Cu")
		(net "CLK_50M_RMII_PHY")
	)
	(segment
		(start 11.888978 -91.2368)
		(end 13.229844 -91.2368)
		(width 0.12065)
		(layer "F.Cu")
		(net "CLK_50M_RMII_PHY")
	)
	(via
		(at 8.9662 -76.9874)
		(size 0.508)
		(drill 0.254)
		(layers "F.Cu" "B.Cu")
		(net "CLK_50M_RMII_PHY")
	)
	(via
		(at 13.340334 -88.990678)
		(size 0.508)
		(drill 0.254)
		(layers "F.Cu" "B.Cu")
		(net "CLK_50M_RMII_PHY")
	)
	(via
		(at 25.041352 -71.5391)
		(size 0.7112)
		(drill 0.3556)
		(layers "F.Cu" "B.Cu")
		(net "CLK_50M_RMII_PHY")
	)
	(via
		(at 26.034746 -71.420482)
		(size 0.508)
		(drill 0.254)
		(layers "F.Cu" "B.Cu")
		(net "CLK_50M_RMII_PHY")
	)
	(segment
		(start 25.15997 -71.420482)
		(end 25.041352 -71.5391)
		(width 0.12065)
		(layer "B.Cu")
		(net "CLK_50M_RMII_PHY")
	)
	(segment
		(start 26.034746 -71.420482)
		(end 25.15997 -71.420482)
		(width 0.12065)
		(layer "B.Cu")
		(net "CLK_50M_RMII_PHY")
	)
	(segment
		(start 8.9662 -75.1332)
		(end 12.2301 -71.8693)
		(width 0.127)
		(layer "In2.Cu")
		(net "CLK_50M_RMII_PHY")
	)
	(segment
		(start 25.585928 -71.8693)
		(end 26.034746 -71.420482)
		(width 0.127)
		(layer "In2.Cu")
		(net "CLK_50M_RMII_PHY")
	)
	(segment
		(start 12.2301 -71.8693)
		(end 25.585928 -71.8693)
		(width 0.127)
		(layer "In2.Cu")
		(net "CLK_50M_RMII_PHY")
	)
	(segment
		(start 8.9662 -76.9874)
		(end 8.9662 -75.1332)
		(width 0.127)
		(layer "In2.Cu")
		(net "CLK_50M_RMII_PHY")
	)
	(segment
		(start 8.9662 -77.216)
		(end 10.4902 -78.74)
		(width 0.127)
		(layer "In5.Cu")
		(net "CLK_50M_RMII_PHY")
	)
	(segment
		(start 10.5283 -80.865218)
		(end 10.4902 -80.903318)
		(width 0.127)
		(layer "In5.Cu")
		(net "CLK_50M_RMII_PHY")
	)
	(segment
		(start 12.31519 -86.712044)
		(end 13.095986 -87.49284)
		(width 0.127)
		(layer "In5.Cu")
		(net "CLK_50M_RMII_PHY")
	)
	(segment
		(start 13.095986 -87.49284)
		(end 13.095986 -88.74633)
		(width 0.127)
		(layer "In5.Cu")
		(net "CLK_50M_RMII_PHY")
	)
	(segment
		(start 10.4902 -82.1182)
		(end 12.31519 -83.94319)
		(width 0.127)
		(layer "In5.Cu")
		(net "CLK_50M_RMII_PHY")
	)
	(segment
		(start 12.31519 -83.94319)
		(end 12.31519 -86.712044)
		(width 0.127)
		(layer "In5.Cu")
		(net "CLK_50M_RMII_PHY")
	)
	(segment
		(start 10.5283 -80.475582)
		(end 10.5283 -80.865218)
		(width 0.127)
		(layer "In5.Cu")
		(net "CLK_50M_RMII_PHY")
	)
	(segment
		(start 8.9662 -76.9874)
		(end 8.9662 -77.216)
		(width 0.127)
		(layer "In5.Cu")
		(net "CLK_50M_RMII_PHY")
	)
	(segment
		(start 10.4902 -80.903318)
		(end 10.4902 -82.1182)
		(width 0.127)
		(layer "In5.Cu")
		(net "CLK_50M_RMII_PHY")
	)
	(segment
		(start 13.095986 -88.74633)
		(end 13.340334 -88.990678)
		(width 0.127)
		(layer "In5.Cu")
		(net "CLK_50M_RMII_PHY")
	)
	(segment
		(start 10.4902 -78.74)
		(end 10.4902 -80.437482)
		(width 0.127)
		(layer "In5.Cu")
		(net "CLK_50M_RMII_PHY")
	)
	(segment
		(start 10.4902 -80.437482)
		(end 10.5283 -80.475582)
		(width 0.127)
		(layer "In5.Cu")
		(net "CLK_50M_RMII_PHY")
	)
	(segment
		(start 12.665964 -98.818192)
		(end 12.665964 -97.613978)
		(width 0.12065)
		(layer "F.Cu")
		(net "CLK_50M_BMC0")
	)
	(segment
		(start 15.60449 -100.02393)
		(end 13.871702 -100.02393)
		(width 0.12065)
		(layer "F.Cu")
		(net "CLK_50M_BMC0")
	)
	(segment
		(start 15.960852 -99.667568)
		(end 15.60449 -100.02393)
		(width 0.12065)
		(layer "F.Cu")
		(net "CLK_50M_BMC0")
	)
	(segment
		(start 13.871702 -100.02393)
		(end 12.665964 -98.818192)
		(width 0.12065)
		(layer "F.Cu")
		(net "CLK_50M_BMC0")
	)
	(via
		(at 32.034988 -109.810042)
		(size 0.508)
		(drill 0.254)
		(layers "F.Cu" "B.Cu")
		(net "CLK_50M_BMC0")
	)
	(via
		(at 15.960852 -99.667568)
		(size 0.508)
		(drill 0.254)
		(layers "F.Cu" "B.Cu")
		(net "CLK_50M_BMC0")
	)
	(via
		(at 33.579816 -110.395258)
		(size 0.7112)
		(drill 0.3556)
		(layers "F.Cu" "B.Cu")
		(net "CLK_50M_BMC0")
	)
	(segment
		(start 33.579816 -110.395258)
		(end 34.209482 -110.395258)
		(width 0.12065)
		(layer "B.Cu")
		(net "CLK_50M_BMC0")
	)
	(segment
		(start 35.330384 -109.319314)
		(end 34.336736 -109.319314)
		(width 0.12065)
		(layer "B.Cu")
		(net "CLK_50M_BMC0")
	)
	(segment
		(start 34.209482 -110.395258)
		(end 34.330132 -110.274608)
		(width 0.12065)
		(layer "B.Cu")
		(net "CLK_50M_BMC0")
	)
	(segment
		(start 32.620204 -110.395258)
		(end 33.579816 -110.395258)
		(width 0.12065)
		(layer "B.Cu")
		(net "CLK_50M_BMC0")
	)
	(segment
		(start 32.034988 -109.810042)
		(end 32.620204 -110.395258)
		(width 0.12065)
		(layer "B.Cu")
		(net "CLK_50M_BMC0")
	)
	(segment
		(start 34.336736 -109.319314)
		(end 34.330132 -109.31271)
		(width 0.12065)
		(layer "B.Cu")
		(net "CLK_50M_BMC0")
	)
	(segment
		(start 34.330132 -110.274608)
		(end 34.330132 -109.31271)
		(width 0.12065)
		(layer "B.Cu")
		(net "CLK_50M_BMC0")
	)
	(segment
		(start 22.504146 -99.949)
		(end 16.242284 -99.949)
		(width 0.127)
		(layer "In5.Cu")
		(net "CLK_50M_BMC0")
	)
	(segment
		(start 30.625034 -108.400088)
		(end 30.625034 -105.800906)
		(width 0.127)
		(layer "In5.Cu")
		(net "CLK_50M_BMC0")
	)
	(segment
		(start 27.850084 -103.025956)
		(end 25.581102 -103.025956)
		(width 0.127)
		(layer "In5.Cu")
		(net "CLK_50M_BMC0")
	)
	(segment
		(start 25.581102 -103.025956)
		(end 22.504146 -99.949)
		(width 0.127)
		(layer "In5.Cu")
		(net "CLK_50M_BMC0")
	)
	(segment
		(start 32.034988 -109.810042)
		(end 30.625034 -108.400088)
		(width 0.127)
		(layer "In5.Cu")
		(net "CLK_50M_BMC0")
	)
	(segment
		(start 30.625034 -105.800906)
		(end 27.850084 -103.025956)
		(width 0.127)
		(layer "In5.Cu")
		(net "CLK_50M_BMC0")
	)
	(segment
		(start 16.242284 -99.949)
		(end 15.960852 -99.667568)
		(width 0.127)
		(layer "In5.Cu")
		(net "CLK_50M_BMC0")
	)
	(segment
		(start 40.104822 -123.684792)
		(end 39.705026 -123.284996)
		(width 0.12065)
		(layer "F.Cu")
		(net "CLK_50M_BMC_NCSI_R")
	)
	(via
		(at 39.705026 -123.284996)
		(size 0.4572)
		(drill 0.2032)
		(layers "F.Cu" "B.Cu")
		(net "CLK_50M_BMC_NCSI_R")
	)
	(via
		(at 40.496236 -120.73763)
		(size 0.7112)
		(drill 0.3556)
		(layers "F.Cu" "B.Cu")
		(net "CLK_50M_BMC_NCSI_R")
	)
	(segment
		(start 40.496236 -120.73763)
		(end 39.705026 -121.52884)
		(width 0.12065)
		(layer "B.Cu")
		(net "CLK_50M_BMC_NCSI_R")
	)
	(segment
		(start 40.496236 -120.118124)
		(end 40.496236 -120.73763)
		(width 0.12065)
		(layer "B.Cu")
		(net "CLK_50M_BMC_NCSI_R")
	)
	(segment
		(start 41.271952 -119.342408)
		(end 40.496236 -120.118124)
		(width 0.12065)
		(layer "B.Cu")
		(net "CLK_50M_BMC_NCSI_R")
	)
	(segment
		(start 39.705026 -121.52884)
		(end 39.705026 -123.284996)
		(width 0.12065)
		(layer "B.Cu")
		(net "CLK_50M_BMC_NCSI_R")
	)
	(segment
		(start 41.656 -117.1575)
		(end 41.271952 -117.541548)
		(width 0.12065)
		(layer "B.Cu")
		(net "CLK_50M_BMC_NCSI_R")
	)
	(segment
		(start 41.271952 -117.541548)
		(end 41.271952 -119.342408)
		(width 0.12065)
		(layer "B.Cu")
		(net "CLK_50M_BMC_NCSI_R")
	)
	(segment
		(start 10.125964 -92.533978)
		(end 10.125964 -94.326964)
		(width 0.12065)
		(layer "F.Cu")
		(net "CLK_50M_BMC_NCSI")
	)
	(via
		(at 10.125964 -94.326964)
		(size 0.508)
		(drill 0.254)
		(layers "F.Cu" "B.Cu")
		(net "CLK_50M_BMC_NCSI")
	)
	(via
		(at 42.592498 -83.676236)
		(size 0.508)
		(drill 0.254)
		(layers "F.Cu" "B.Cu")
		(net "CLK_50M_BMC_NCSI")
	)
	(via
		(at 42.525442 -86.709504)
		(size 0.7112)
		(drill 0.3556)
		(layers "F.Cu" "B.Cu")
		(net "CLK_50M_BMC_NCSI")
	)
	(segment
		(start 42.3418 -99.441)
		(end 43.216576 -98.566224)
		(width 0.12065)
		(layer "B.Cu")
		(net "CLK_50M_BMC_NCSI")
	)
	(segment
		(start 43.0022 -84.085938)
		(end 43.0022 -86.232746)
		(width 0.12065)
		(layer "B.Cu")
		(net "CLK_50M_BMC_NCSI")
	)
	(segment
		(start 43.0022 -86.232746)
		(end 42.525442 -86.709504)
		(width 0.12065)
		(layer "B.Cu")
		(net "CLK_50M_BMC_NCSI")
	)
	(segment
		(start 43.235118 -101.883718)
		(end 42.3418 -100.9904)
		(width 0.12065)
		(layer "B.Cu")
		(net "CLK_50M_BMC_NCSI")
	)
	(segment
		(start 42.3418 -100.9904)
		(end 42.3418 -99.441)
		(width 0.12065)
		(layer "B.Cu")
		(net "CLK_50M_BMC_NCSI")
	)
	(segment
		(start 42.18559 -116.2685)
		(end 43.235118 -115.218972)
		(width 0.12065)
		(layer "B.Cu")
		(net "CLK_50M_BMC_NCSI")
	)
	(segment
		(start 43.235118 -115.218972)
		(end 43.235118 -101.883718)
		(width 0.12065)
		(layer "B.Cu")
		(net "CLK_50M_BMC_NCSI")
	)
	(segment
		(start 43.216576 -98.566224)
		(end 43.216576 -87.400638)
		(width 0.12065)
		(layer "B.Cu")
		(net "CLK_50M_BMC_NCSI")
	)
	(segment
		(start 43.216576 -87.400638)
		(end 42.525442 -86.709504)
		(width 0.12065)
		(layer "B.Cu")
		(net "CLK_50M_BMC_NCSI")
	)
	(segment
		(start 41.656 -116.2685)
		(end 42.18559 -116.2685)
		(width 0.12065)
		(layer "B.Cu")
		(net "CLK_50M_BMC_NCSI")
	)
	(segment
		(start 42.592498 -83.676236)
		(end 43.0022 -84.085938)
		(width 0.12065)
		(layer "B.Cu")
		(net "CLK_50M_BMC_NCSI")
	)
	(segment
		(start 10.791952 -93.660976)
		(end 13.68933 -93.660976)
		(width 0.127)
		(layer "In2.Cu")
		(net "CLK_50M_BMC_NCSI")
	)
	(segment
		(start 13.68933 -93.660976)
		(end 18.320766 -89.02954)
		(width 0.127)
		(layer "In2.Cu")
		(net "CLK_50M_BMC_NCSI")
	)
	(segment
		(start 25.844246 -84.1121)
		(end 29.902658 -84.1121)
		(width 0.127)
		(layer "In2.Cu")
		(net "CLK_50M_BMC_NCSI")
	)
	(segment
		(start 41.966134 -84.3026)
		(end 42.592498 -83.676236)
		(width 0.127)
		(layer "In2.Cu")
		(net "CLK_50M_BMC_NCSI")
	)
	(segment
		(start 24.9047 -85.051646)
		(end 25.844246 -84.1121)
		(width 0.127)
		(layer "In2.Cu")
		(net "CLK_50M_BMC_NCSI")
	)
	(segment
		(start 18.320766 -89.02954)
		(end 21.212048 -89.02954)
		(width 0.127)
		(layer "In2.Cu")
		(net "CLK_50M_BMC_NCSI")
	)
	(segment
		(start 10.125964 -94.326964)
		(end 10.791952 -93.660976)
		(width 0.127)
		(layer "In2.Cu")
		(net "CLK_50M_BMC_NCSI")
	)
	(segment
		(start 29.902658 -84.1121)
		(end 30.093158 -84.3026)
		(width 0.127)
		(layer "In2.Cu")
		(net "CLK_50M_BMC_NCSI")
	)
	(segment
		(start 21.900134 -88.341454)
		(end 22.262846 -88.341454)
		(width 0.127)
		(layer "In2.Cu")
		(net "CLK_50M_BMC_NCSI")
	)
	(segment
		(start 24.9047 -85.6996)
		(end 24.9047 -85.051646)
		(width 0.127)
		(layer "In2.Cu")
		(net "CLK_50M_BMC_NCSI")
	)
	(segment
		(start 30.093158 -84.3026)
		(end 41.966134 -84.3026)
		(width 0.127)
		(layer "In2.Cu")
		(net "CLK_50M_BMC_NCSI")
	)
	(segment
		(start 21.212048 -89.02954)
		(end 21.900134 -88.341454)
		(width 0.127)
		(layer "In2.Cu")
		(net "CLK_50M_BMC_NCSI")
	)
	(segment
		(start 22.262846 -88.341454)
		(end 24.9047 -85.6996)
		(width 0.127)
		(layer "In2.Cu")
		(net "CLK_50M_BMC_NCSI")
	)
	(segment
		(start 43.304714 -134.884922)
		(end 43.70451 -134.485126)
		(width 0.12065)
		(layer "F.Cu")
		(net "CBL_PRSNT_N_8")
	)
	(via
		(at 272.4912 0.2032)
		(size 0.508)
		(drill 0.254)
		(layers "F.Cu" "B.Cu")
		(net "CBL_PRSNT_N_8")
	)
	(via
		(at 43.70451 -134.485126)
		(size 0.4572)
		(drill 0.2032)
		(layers "F.Cu" "B.Cu")
		(net "CBL_PRSNT_N_8")
	)
	(via
		(at 83.569556 -119.893588)
		(size 0.508)
		(drill 0.254)
		(layers "F.Cu" "B.Cu")
		(net "CBL_PRSNT_N_8")
	)
	(via
		(at 101.7016 -48.0314)
		(size 0.508)
		(drill 0.254)
		(layers "F.Cu" "B.Cu")
		(net "CBL_PRSNT_N_8")
	)
	(via
		(at 47.349664 -145.600674)
		(size 0.7112)
		(drill 0.3556)
		(layers "F.Cu" "B.Cu")
		(net "CBL_PRSNT_N_8")
	)
	(segment
		(start 272.8087 -0.889)
		(end 272.8087 -0.1143)
		(width 0.12065)
		(layer "B.Cu")
		(net "CBL_PRSNT_N_8")
	)
	(segment
		(start 46.228 -144.47901)
		(end 47.349664 -145.600674)
		(width 0.12065)
		(layer "B.Cu")
		(net "CBL_PRSNT_N_8")
	)
	(segment
		(start 101.7016 -48.0314)
		(end 102.671118 -49.000918)
		(width 0.12065)
		(layer "B.Cu")
		(net "CBL_PRSNT_N_8")
	)
	(segment
		(start 102.671118 -49.000918)
		(end 102.671118 -60.052458)
		(width 0.12065)
		(layer "B.Cu")
		(net "CBL_PRSNT_N_8")
	)
	(segment
		(start 46.228 -137.16)
		(end 46.228 -144.47901)
		(width 0.12065)
		(layer "B.Cu")
		(net "CBL_PRSNT_N_8")
	)
	(segment
		(start 100.4316 -90.214704)
		(end 84.685124 -105.96118)
		(width 0.12065)
		(layer "B.Cu")
		(net "CBL_PRSNT_N_8")
	)
	(segment
		(start 44.095162 -134.875778)
		(end 44.095162 -136.227566)
		(width 0.12065)
		(layer "B.Cu")
		(net "CBL_PRSNT_N_8")
	)
	(segment
		(start 44.362116 -136.49452)
		(end 44.666408 -136.49452)
		(width 0.12065)
		(layer "B.Cu")
		(net "CBL_PRSNT_N_8")
	)
	(segment
		(start 45.847 -136.779)
		(end 46.228 -137.16)
		(width 0.12065)
		(layer "B.Cu")
		(net "CBL_PRSNT_N_8")
	)
	(segment
		(start 84.685124 -105.96118)
		(end 84.685124 -118.77802)
		(width 0.12065)
		(layer "B.Cu")
		(net "CBL_PRSNT_N_8")
	)
	(segment
		(start 102.671118 -60.052458)
		(end 100.4316 -62.291976)
		(width 0.12065)
		(layer "B.Cu")
		(net "CBL_PRSNT_N_8")
	)
	(segment
		(start 272.8087 -0.889)
		(end 272.8087 -1.9304)
		(width 0.12065)
		(layer "B.Cu")
		(net "CBL_PRSNT_N_8")
	)
	(segment
		(start 48.641 -146.89201)
		(end 48.641 -147.6375)
		(width 0.12065)
		(layer "B.Cu")
		(net "CBL_PRSNT_N_8")
	)
	(segment
		(start 47.349664 -145.600674)
		(end 48.641 -146.89201)
		(width 0.12065)
		(layer "B.Cu")
		(net "CBL_PRSNT_N_8")
	)
	(segment
		(start 100.4316 -62.291976)
		(end 100.4316 -90.214704)
		(width 0.12065)
		(layer "B.Cu")
		(net "CBL_PRSNT_N_8")
	)
	(segment
		(start 44.095162 -136.227566)
		(end 44.362116 -136.49452)
		(width 0.12065)
		(layer "B.Cu")
		(net "CBL_PRSNT_N_8")
	)
	(segment
		(start 44.666408 -136.49452)
		(end 44.950888 -136.779)
		(width 0.12065)
		(layer "B.Cu")
		(net "CBL_PRSNT_N_8")
	)
	(segment
		(start 272.8087 -0.1143)
		(end 272.4912 0.2032)
		(width 0.12065)
		(layer "B.Cu")
		(net "CBL_PRSNT_N_8")
	)
	(segment
		(start 44.950888 -136.779)
		(end 45.847 -136.779)
		(width 0.12065)
		(layer "B.Cu")
		(net "CBL_PRSNT_N_8")
	)
	(segment
		(start 43.70451 -134.485126)
		(end 44.095162 -134.875778)
		(width 0.12065)
		(layer "B.Cu")
		(net "CBL_PRSNT_N_8")
	)
	(segment
		(start 84.685124 -118.77802)
		(end 83.569556 -119.893588)
		(width 0.12065)
		(layer "B.Cu")
		(net "CBL_PRSNT_N_8")
	)
	(segment
		(start 44.137072 -134.891272)
		(end 46.48073 -134.891272)
		(width 0.127)
		(layer "In2.Cu")
		(net "CBL_PRSNT_N_8")
	)
	(segment
		(start 56.105806 -134.7724)
		(end 67.651376 -134.7724)
		(width 0.127)
		(layer "In2.Cu")
		(net "CBL_PRSNT_N_8")
	)
	(segment
		(start 83.569556 -122.555762)
		(end 83.569556 -119.893588)
		(width 0.127)
		(layer "In2.Cu")
		(net "CBL_PRSNT_N_8")
	)
	(segment
		(start 76.204318 -131.6736)
		(end 77.7875 -130.090418)
		(width 0.127)
		(layer "In2.Cu")
		(net "CBL_PRSNT_N_8")
	)
	(segment
		(start 43.730926 -134.485126)
		(end 44.137072 -134.891272)
		(width 0.127)
		(layer "In2.Cu")
		(net "CBL_PRSNT_N_8")
	)
	(segment
		(start 46.48073 -134.891272)
		(end 46.869858 -135.2804)
		(width 0.127)
		(layer "In2.Cu")
		(net "CBL_PRSNT_N_8")
	)
	(segment
		(start 55.597806 -135.2804)
		(end 56.105806 -134.7724)
		(width 0.127)
		(layer "In2.Cu")
		(net "CBL_PRSNT_N_8")
	)
	(segment
		(start 77.7875 -130.090418)
		(end 77.7875 -128.337818)
		(width 0.127)
		(layer "In2.Cu")
		(net "CBL_PRSNT_N_8")
	)
	(segment
		(start 70.750176 -131.6736)
		(end 76.204318 -131.6736)
		(width 0.127)
		(layer "In2.Cu")
		(net "CBL_PRSNT_N_8")
	)
	(segment
		(start 67.651376 -134.7724)
		(end 70.750176 -131.6736)
		(width 0.127)
		(layer "In2.Cu")
		(net "CBL_PRSNT_N_8")
	)
	(segment
		(start 77.7875 -128.337818)
		(end 83.569556 -122.555762)
		(width 0.127)
		(layer "In2.Cu")
		(net "CBL_PRSNT_N_8")
	)
	(segment
		(start 43.70451 -134.485126)
		(end 43.730926 -134.485126)
		(width 0.127)
		(layer "In2.Cu")
		(net "CBL_PRSNT_N_8")
	)
	(segment
		(start 46.869858 -135.2804)
		(end 55.597806 -135.2804)
		(width 0.127)
		(layer "In2.Cu")
		(net "CBL_PRSNT_N_8")
	)
	(segment
		(start 260.0198 4.17449)
		(end 258.335272 2.489962)
		(width 0.127)
		(layer "In5.Cu")
		(net "CBL_PRSNT_N_8")
	)
	(segment
		(start 245.682008 4.17449)
		(end 128.044448 4.17449)
		(width 0.127)
		(layer "In5.Cu")
		(net "CBL_PRSNT_N_8")
	)
	(segment
		(start 247.366536 2.489962)
		(end 245.682008 4.17449)
		(width 0.127)
		(layer "In5.Cu")
		(net "CBL_PRSNT_N_8")
	)
	(segment
		(start 266.735814 1.046988)
		(end 265.8745 1.046988)
		(width 0.127)
		(layer "In5.Cu")
		(net "CBL_PRSNT_N_8")
	)
	(segment
		(start 265.8745 1.046988)
		(end 262.746998 4.17449)
		(width 0.127)
		(layer "In5.Cu")
		(net "CBL_PRSNT_N_8")
	)
	(segment
		(start 104.919272 -38.259004)
		(end 102.84841 -40.329866)
		(width 0.127)
		(layer "In5.Cu")
		(net "CBL_PRSNT_N_8")
	)
	(segment
		(start 128.044448 4.17449)
		(end 104.919272 -18.950686)
		(width 0.127)
		(layer "In5.Cu")
		(net "CBL_PRSNT_N_8")
	)
	(segment
		(start 104.919272 -18.950686)
		(end 104.919272 -38.259004)
		(width 0.127)
		(layer "In5.Cu")
		(net "CBL_PRSNT_N_8")
	)
	(segment
		(start 262.746998 4.17449)
		(end 260.0198 4.17449)
		(width 0.127)
		(layer "In5.Cu")
		(net "CBL_PRSNT_N_8")
	)
	(segment
		(start 272.161 2.1082)
		(end 269.879572 2.1082)
		(width 0.127)
		(layer "In5.Cu")
		(net "CBL_PRSNT_N_8")
	)
	(segment
		(start 272.4658 1.8034)
		(end 272.161 2.1082)
		(width 0.127)
		(layer "In5.Cu")
		(net "CBL_PRSNT_N_8")
	)
	(segment
		(start 269.879572 2.1082)
		(end 268.797786 1.026414)
		(width 0.127)
		(layer "In5.Cu")
		(net "CBL_PRSNT_N_8")
	)
	(segment
		(start 272.4658 0.2286)
		(end 272.4658 1.8034)
		(width 0.127)
		(layer "In5.Cu")
		(net "CBL_PRSNT_N_8")
	)
	(segment
		(start 266.756388 1.026414)
		(end 266.735814 1.046988)
		(width 0.127)
		(layer "In5.Cu")
		(net "CBL_PRSNT_N_8")
	)
	(segment
		(start 102.84841 -46.88459)
		(end 101.7016 -48.0314)
		(width 0.127)
		(layer "In5.Cu")
		(net "CBL_PRSNT_N_8")
	)
	(segment
		(start 102.84841 -40.329866)
		(end 102.84841 -46.88459)
		(width 0.127)
		(layer "In5.Cu")
		(net "CBL_PRSNT_N_8")
	)
	(segment
		(start 258.335272 2.489962)
		(end 247.366536 2.489962)
		(width 0.127)
		(layer "In5.Cu")
		(net "CBL_PRSNT_N_8")
	)
	(segment
		(start 268.797786 1.026414)
		(end 266.756388 1.026414)
		(width 0.127)
		(layer "In5.Cu")
		(net "CBL_PRSNT_N_8")
	)
	(segment
		(start 272.4912 0.2032)
		(end 272.4658 0.2286)
		(width 0.127)
		(layer "In5.Cu")
		(net "CBL_PRSNT_N_8")
	)
	(segment
		(start 51.444906 -138.852148)
		(end 51.857148 -138.852148)
		(width 0.12065)
		(layer "F.Cu")
		(net "CBL_PRSNT_N_7")
	)
	(segment
		(start 275.336 -0.127)
		(end 274.144486 -0.127)
		(width 0.12065)
		(layer "F.Cu")
		(net "CBL_PRSNT_N_7")
	)
	(segment
		(start 52.7685 -139.319)
		(end 53.2765 -139.827)
		(width 0.12065)
		(layer "F.Cu")
		(net "CBL_PRSNT_N_7")
	)
	(segment
		(start 46.50486 -136.484868)
		(end 47.136812 -136.484868)
		(width 0.12065)
		(layer "F.Cu")
		(net "CBL_PRSNT_N_7")
	)
	(segment
		(start 51.857148 -138.852148)
		(end 52.324 -139.319)
		(width 0.12065)
		(layer "F.Cu")
		(net "CBL_PRSNT_N_7")
	)
	(segment
		(start 51.165252 -139.131802)
		(end 51.444906 -138.852148)
		(width 0.12065)
		(layer "F.Cu")
		(net "CBL_PRSNT_N_7")
	)
	(segment
		(start 52.5018 -139.319)
		(end 52.7685 -139.319)
		(width 0.12065)
		(layer "F.Cu")
		(net "CBL_PRSNT_N_7")
	)
	(segment
		(start 49.783746 -139.131802)
		(end 51.165252 -139.131802)
		(width 0.12065)
		(layer "F.Cu")
		(net "CBL_PRSNT_N_7")
	)
	(segment
		(start 47.136812 -136.484868)
		(end 49.783746 -139.131802)
		(width 0.12065)
		(layer "F.Cu")
		(net "CBL_PRSNT_N_7")
	)
	(segment
		(start 52.324 -139.319)
		(end 52.5018 -139.319)
		(width 0.12065)
		(layer "F.Cu")
		(net "CBL_PRSNT_N_7")
	)
	(segment
		(start 276.1615 -0.127)
		(end 275.336 -0.127)
		(width 0.12065)
		(layer "F.Cu")
		(net "CBL_PRSNT_N_7")
	)
	(via
		(at 83.82 -127.4826)
		(size 0.508)
		(drill 0.254)
		(layers "F.Cu" "B.Cu")
		(net "CBL_PRSNT_N_7")
	)
	(via
		(at 275.336 -0.127)
		(size 0.508)
		(drill 0.254)
		(layers "F.Cu" "B.Cu")
		(net "CBL_PRSNT_N_7")
	)
	(via
		(at 52.5018 -139.319)
		(size 0.508)
		(drill 0.254)
		(layers "F.Cu" "B.Cu")
		(net "CBL_PRSNT_N_7")
	)
	(via
		(at 83.82 -126.038102)
		(size 0.7112)
		(drill 0.3556)
		(layers "F.Cu" "B.Cu")
		(net "CBL_PRSNT_N_7")
	)
	(via
		(at 104.4956 -46.7106)
		(size 0.508)
		(drill 0.254)
		(layers "F.Cu" "B.Cu")
		(net "CBL_PRSNT_N_7")
	)
	(segment
		(start 83.82 -121.3358)
		(end 85.047074 -120.108726)
		(width 0.12065)
		(layer "B.Cu")
		(net "CBL_PRSNT_N_7")
	)
	(segment
		(start 100.79355 -90.364818)
		(end 100.79355 -62.44209)
		(width 0.12065)
		(layer "B.Cu")
		(net "CBL_PRSNT_N_7")
	)
	(segment
		(start 104.4956 -47.33036)
		(end 104.4956 -46.7106)
		(width 0.12065)
		(layer "B.Cu")
		(net "CBL_PRSNT_N_7")
	)
	(segment
		(start 83.82 -126.038102)
		(end 83.82 -127.4826)
		(width 0.12065)
		(layer "B.Cu")
		(net "CBL_PRSNT_N_7")
	)
	(segment
		(start 103.033068 -60.202572)
		(end 103.033068 -48.792892)
		(width 0.12065)
		(layer "B.Cu")
		(net "CBL_PRSNT_N_7")
	)
	(segment
		(start 85.047074 -120.108726)
		(end 85.047074 -106.111294)
		(width 0.12065)
		(layer "B.Cu")
		(net "CBL_PRSNT_N_7")
	)
	(segment
		(start 100.79355 -62.44209)
		(end 103.033068 -60.202572)
		(width 0.12065)
		(layer "B.Cu")
		(net "CBL_PRSNT_N_7")
	)
	(segment
		(start 85.047074 -106.111294)
		(end 100.79355 -90.364818)
		(width 0.12065)
		(layer "B.Cu")
		(net "CBL_PRSNT_N_7")
	)
	(segment
		(start 103.033068 -48.792892)
		(end 104.4956 -47.33036)
		(width 0.12065)
		(layer "B.Cu")
		(net "CBL_PRSNT_N_7")
	)
	(segment
		(start 83.82 -126.038102)
		(end 83.82 -121.3358)
		(width 0.12065)
		(layer "B.Cu")
		(net "CBL_PRSNT_N_7")
	)
	(segment
		(start 66.124582 -139.2047)
		(end 66.010282 -139.319)
		(width 0.127)
		(layer "In2.Cu")
		(net "CBL_PRSNT_N_7")
	)
	(segment
		(start 80.811624 -131.1529)
		(end 79.783686 -131.1529)
		(width 0.127)
		(layer "In2.Cu")
		(net "CBL_PRSNT_N_7")
	)
	(segment
		(start 66.010282 -139.319)
		(end 52.5018 -139.319)
		(width 0.127)
		(layer "In2.Cu")
		(net "CBL_PRSNT_N_7")
	)
	(segment
		(start 71.731886 -139.2047)
		(end 66.124582 -139.2047)
		(width 0.127)
		(layer "In2.Cu")
		(net "CBL_PRSNT_N_7")
	)
	(segment
		(start 79.783686 -131.1529)
		(end 71.731886 -139.2047)
		(width 0.127)
		(layer "In2.Cu")
		(net "CBL_PRSNT_N_7")
	)
	(segment
		(start 83.82 -127.4826)
		(end 83.82 -128.144524)
		(width 0.127)
		(layer "In2.Cu")
		(net "CBL_PRSNT_N_7")
	)
	(segment
		(start 83.82 -128.144524)
		(end 80.811624 -131.1529)
		(width 0.127)
		(layer "In2.Cu")
		(net "CBL_PRSNT_N_7")
	)
	(segment
		(start 104.4956 -46.7106)
		(end 104.688386 -46.517814)
		(width 0.127)
		(layer "In5.Cu")
		(net "CBL_PRSNT_N_7")
	)
	(segment
		(start 266.209272 -0.223012)
		(end 266.25296 -0.2667)
		(width 0.127)
		(layer "In5.Cu")
		(net "CBL_PRSNT_N_7")
	)
	(segment
		(start 257.439414 1.219708)
		(end 258.925822 -0.2667)
		(width 0.127)
		(layer "In5.Cu")
		(net "CBL_PRSNT_N_7")
	)
	(segment
		(start 106.493818 -38.551612)
		(end 106.493818 -19.172682)
		(width 0.127)
		(layer "In5.Cu")
		(net "CBL_PRSNT_N_7")
	)
	(segment
		(start 104.688386 -40.357044)
		(end 106.493818 -38.551612)
		(width 0.127)
		(layer "In5.Cu")
		(net "CBL_PRSNT_N_7")
	)
	(segment
		(start 246.779542 1.219708)
		(end 257.439414 1.219708)
		(width 0.127)
		(layer "In5.Cu")
		(net "CBL_PRSNT_N_7")
	)
	(segment
		(start 266.25296 -0.2667)
		(end 274.7264 -0.2667)
		(width 0.127)
		(layer "In5.Cu")
		(net "CBL_PRSNT_N_7")
	)
	(segment
		(start 258.925822 -0.2667)
		(end 265.03884 -0.2667)
		(width 0.127)
		(layer "In5.Cu")
		(net "CBL_PRSNT_N_7")
	)
	(segment
		(start 265.03884 -0.2667)
		(end 265.082528 -0.223012)
		(width 0.127)
		(layer "In5.Cu")
		(net "CBL_PRSNT_N_7")
	)
	(segment
		(start 104.688386 -46.517814)
		(end 104.688386 -40.357044)
		(width 0.127)
		(layer "In5.Cu")
		(net "CBL_PRSNT_N_7")
	)
	(segment
		(start 128.57099 2.90449)
		(end 245.09476 2.90449)
		(width 0.127)
		(layer "In5.Cu")
		(net "CBL_PRSNT_N_7")
	)
	(segment
		(start 245.09476 2.90449)
		(end 246.779542 1.219708)
		(width 0.127)
		(layer "In5.Cu")
		(net "CBL_PRSNT_N_7")
	)
	(segment
		(start 106.493818 -19.172682)
		(end 128.57099 2.90449)
		(width 0.127)
		(layer "In5.Cu")
		(net "CBL_PRSNT_N_7")
	)
	(segment
		(start 274.8661 -0.127)
		(end 275.336 -0.127)
		(width 0.127)
		(layer "In5.Cu")
		(net "CBL_PRSNT_N_7")
	)
	(segment
		(start 265.082528 -0.223012)
		(end 266.209272 -0.223012)
		(width 0.127)
		(layer "In5.Cu")
		(net "CBL_PRSNT_N_7")
	)
	(segment
		(start 274.7264 -0.2667)
		(end 274.8661 -0.127)
		(width 0.127)
		(layer "In5.Cu")
		(net "CBL_PRSNT_N_7")
	)
	(segment
		(start 275.85924 -5.82676)
		(end 275.209 -6.477)
		(width 0.12065)
		(layer "F.Cu")
		(net "CBL_PRSNT_N_6")
	)
	(segment
		(start 46.8503 -135.255)
		(end 48.73625 -137.14095)
		(width 0.12065)
		(layer "F.Cu")
		(net "CBL_PRSNT_N_6")
	)
	(segment
		(start 52.034948 -137.245852)
		(end 52.5018 -136.779)
		(width 0.12065)
		(layer "F.Cu")
		(net "CBL_PRSNT_N_6")
	)
	(segment
		(start 51.28895 -137.14095)
		(end 51.393852 -137.245852)
		(width 0.12065)
		(layer "F.Cu")
		(net "CBL_PRSNT_N_6")
	)
	(segment
		(start 52.5018 -136.779)
		(end 53.2765 -136.779)
		(width 0.12065)
		(layer "F.Cu")
		(net "CBL_PRSNT_N_6")
	)
	(segment
		(start 274.4343 -5.7023)
		(end 275.209 -6.477)
		(width 0.12065)
		(layer "F.Cu")
		(net "CBL_PRSNT_N_6")
	)
	(segment
		(start 45.70476 -135.684768)
		(end 46.134528 -135.255)
		(width 0.12065)
		(layer "F.Cu")
		(net "CBL_PRSNT_N_6")
	)
	(segment
		(start 48.73625 -137.14095)
		(end 51.28895 -137.14095)
		(width 0.12065)
		(layer "F.Cu")
		(net "CBL_PRSNT_N_6")
	)
	(segment
		(start 51.393852 -137.245852)
		(end 52.034948 -137.245852)
		(width 0.12065)
		(layer "F.Cu")
		(net "CBL_PRSNT_N_6")
	)
	(segment
		(start 46.134528 -135.255)
		(end 46.8503 -135.255)
		(width 0.12065)
		(layer "F.Cu")
		(net "CBL_PRSNT_N_6")
	)
	(segment
		(start 274.147026 -5.7023)
		(end 274.4343 -5.7023)
		(width 0.12065)
		(layer "F.Cu")
		(net "CBL_PRSNT_N_6")
	)
	(segment
		(start 276.06498 -5.82676)
		(end 275.85924 -5.82676)
		(width 0.12065)
		(layer "F.Cu")
		(net "CBL_PRSNT_N_6")
	)
	(via
		(at 274.324318 -6.863588)
		(size 0.7112)
		(drill 0.3556)
		(layers "F.Cu" "B.Cu")
		(net "CBL_PRSNT_N_6")
	)
	(via
		(at 84.607908 -123.419108)
		(size 0.508)
		(drill 0.254)
		(layers "F.Cu" "B.Cu")
		(net "CBL_PRSNT_N_6")
	)
	(via
		(at 52.5018 -136.779)
		(size 0.508)
		(drill 0.254)
		(layers "F.Cu" "B.Cu")
		(net "CBL_PRSNT_N_6")
	)
	(via
		(at 107.126278 -45.211746)
		(size 0.508)
		(drill 0.254)
		(layers "F.Cu" "B.Cu")
		(net "CBL_PRSNT_N_6")
	)
	(via
		(at 275.209 -6.477)
		(size 0.508)
		(drill 0.254)
		(layers "F.Cu" "B.Cu")
		(net "CBL_PRSNT_N_6")
	)
	(segment
		(start 84.607908 -121.059956)
		(end 84.607908 -123.419108)
		(width 0.12065)
		(layer "B.Cu")
		(net "CBL_PRSNT_N_6")
	)
	(segment
		(start 274.944078 -6.741922)
		(end 274.445984 -6.741922)
		(width 0.12065)
		(layer "B.Cu")
		(net "CBL_PRSNT_N_6")
	)
	(segment
		(start 275.209 -6.477)
		(end 274.944078 -6.741922)
		(width 0.12065)
		(layer "B.Cu")
		(net "CBL_PRSNT_N_6")
	)
	(segment
		(start 85.409024 -106.261408)
		(end 85.409024 -120.25884)
		(width 0.12065)
		(layer "B.Cu")
		(net "CBL_PRSNT_N_6")
	)
	(segment
		(start 107.126278 -45.211746)
		(end 103.395018 -48.943006)
		(width 0.12065)
		(layer "B.Cu")
		(net "CBL_PRSNT_N_6")
	)
	(segment
		(start 101.185218 -62.562486)
		(end 101.185218 -81.652618)
		(width 0.12065)
		(layer "B.Cu")
		(net "CBL_PRSNT_N_6")
	)
	(segment
		(start 101.185472 -90.48496)
		(end 85.409024 -106.261408)
		(width 0.12065)
		(layer "B.Cu")
		(net "CBL_PRSNT_N_6")
	)
	(segment
		(start 103.395018 -60.352686)
		(end 101.185218 -62.562486)
		(width 0.12065)
		(layer "B.Cu")
		(net "CBL_PRSNT_N_6")
	)
	(segment
		(start 101.185472 -81.652872)
		(end 101.185472 -90.48496)
		(width 0.12065)
		(layer "B.Cu")
		(net "CBL_PRSNT_N_6")
	)
	(segment
		(start 274.445984 -6.741922)
		(end 274.324318 -6.863588)
		(width 0.12065)
		(layer "B.Cu")
		(net "CBL_PRSNT_N_6")
	)
	(segment
		(start 103.395018 -48.943006)
		(end 103.395018 -60.352686)
		(width 0.12065)
		(layer "B.Cu")
		(net "CBL_PRSNT_N_6")
	)
	(segment
		(start 101.185218 -81.652618)
		(end 101.185472 -81.652872)
		(width 0.12065)
		(layer "B.Cu")
		(net "CBL_PRSNT_N_6")
	)
	(segment
		(start 85.409024 -120.25884)
		(end 84.607908 -121.059956)
		(width 0.12065)
		(layer "B.Cu")
		(net "CBL_PRSNT_N_6")
	)
	(segment
		(start 84.607908 -123.419108)
		(end 84.607908 -123.492514)
		(width 0.127)
		(layer "In2.Cu")
		(net "CBL_PRSNT_N_6")
	)
	(segment
		(start 84.607908 -123.492514)
		(end 78.1685 -129.931922)
		(width 0.127)
		(layer "In2.Cu")
		(net "CBL_PRSNT_N_6")
	)
	(segment
		(start 78.1685 -130.248406)
		(end 72.501506 -135.9154)
		(width 0.127)
		(layer "In2.Cu")
		(net "CBL_PRSNT_N_6")
	)
	(segment
		(start 56.57977 -135.9154)
		(end 56.07177 -136.4234)
		(width 0.127)
		(layer "In2.Cu")
		(net "CBL_PRSNT_N_6")
	)
	(segment
		(start 72.501506 -135.9154)
		(end 56.57977 -135.9154)
		(width 0.127)
		(layer "In2.Cu")
		(net "CBL_PRSNT_N_6")
	)
	(segment
		(start 78.1685 -129.931922)
		(end 78.1685 -130.248406)
		(width 0.127)
		(layer "In2.Cu")
		(net "CBL_PRSNT_N_6")
	)
	(segment
		(start 56.07177 -136.4234)
		(end 52.8574 -136.4234)
		(width 0.127)
		(layer "In2.Cu")
		(net "CBL_PRSNT_N_6")
	)
	(segment
		(start 52.8574 -136.4234)
		(end 52.5018 -136.779)
		(width 0.127)
		(layer "In2.Cu")
		(net "CBL_PRSNT_N_6")
	)
	(segment
		(start 107.126278 -40.973248)
		(end 107.126278 -45.211746)
		(width 0.127)
		(layer "In5.Cu")
		(net "CBL_PRSNT_N_6")
	)
	(segment
		(start 274.876514 -6.809486)
		(end 270.528542 -6.809486)
		(width 0.127)
		(layer "In5.Cu")
		(net "CBL_PRSNT_N_6")
	)
	(segment
		(start 131.524502 -1.429766)
		(end 127.29083 -1.429766)
		(width 0.127)
		(layer "In5.Cu")
		(net "CBL_PRSNT_N_6")
	)
	(segment
		(start 269.886176 -7.451852)
		(end 269.045436 -7.451852)
		(width 0.127)
		(layer "In5.Cu")
		(net "CBL_PRSNT_N_6")
	)
	(segment
		(start 196.2531 -1.0795)
		(end 187.3504 -1.0795)
		(width 0.127)
		(layer "In5.Cu")
		(net "CBL_PRSNT_N_6")
	)
	(segment
		(start 204.17282 -2.159)
		(end 197.3326 -2.159)
		(width 0.127)
		(layer "In5.Cu")
		(net "CBL_PRSNT_N_6")
	)
	(segment
		(start 207.052164 0.720344)
		(end 204.17282 -2.159)
		(width 0.127)
		(layer "In5.Cu")
		(net "CBL_PRSNT_N_6")
	)
	(segment
		(start 197.3326 -2.159)
		(end 196.2531 -1.0795)
		(width 0.127)
		(layer "In5.Cu")
		(net "CBL_PRSNT_N_6")
	)
	(segment
		(start 187.3504 -1.0795)
		(end 186.4741 -1.9558)
		(width 0.127)
		(layer "In5.Cu")
		(net "CBL_PRSNT_N_6")
	)
	(segment
		(start 270.528542 -6.809486)
		(end 269.886176 -7.451852)
		(width 0.127)
		(layer "In5.Cu")
		(net "CBL_PRSNT_N_6")
	)
	(segment
		(start 180.53558 -0.61341)
		(end 132.340858 -0.61341)
		(width 0.127)
		(layer "In5.Cu")
		(net "CBL_PRSNT_N_6")
	)
	(segment
		(start 269.045436 -7.451852)
		(end 266.299442 -4.705858)
		(width 0.127)
		(layer "In5.Cu")
		(net "CBL_PRSNT_N_6")
	)
	(segment
		(start 108.917486 -39.18204)
		(end 107.126278 -40.973248)
		(width 0.127)
		(layer "In5.Cu")
		(net "CBL_PRSNT_N_6")
	)
	(segment
		(start 275.209 -6.477)
		(end 274.876514 -6.809486)
		(width 0.127)
		(layer "In5.Cu")
		(net "CBL_PRSNT_N_6")
	)
	(segment
		(start 127.29083 -1.429766)
		(end 108.917486 -19.80311)
		(width 0.127)
		(layer "In5.Cu")
		(net "CBL_PRSNT_N_6")
	)
	(segment
		(start 181.87797 -1.9558)
		(end 180.53558 -0.61341)
		(width 0.127)
		(layer "In5.Cu")
		(net "CBL_PRSNT_N_6")
	)
	(segment
		(start 251.177044 -3.095244)
		(end 247.8151 -3.095244)
		(width 0.127)
		(layer "In5.Cu")
		(net "CBL_PRSNT_N_6")
	)
	(segment
		(start 253.889002 -5.807202)
		(end 251.177044 -3.095244)
		(width 0.127)
		(layer "In5.Cu")
		(net "CBL_PRSNT_N_6")
	)
	(segment
		(start 247.8151 -3.095244)
		(end 243.999512 0.720344)
		(width 0.127)
		(layer "In5.Cu")
		(net "CBL_PRSNT_N_6")
	)
	(segment
		(start 108.917486 -19.80311)
		(end 108.917486 -39.18204)
		(width 0.127)
		(layer "In5.Cu")
		(net "CBL_PRSNT_N_6")
	)
	(segment
		(start 261.452868 -4.705858)
		(end 260.351524 -5.807202)
		(width 0.127)
		(layer "In5.Cu")
		(net "CBL_PRSNT_N_6")
	)
	(segment
		(start 132.340858 -0.61341)
		(end 131.524502 -1.429766)
		(width 0.127)
		(layer "In5.Cu")
		(net "CBL_PRSNT_N_6")
	)
	(segment
		(start 243.999512 0.720344)
		(end 207.052164 0.720344)
		(width 0.127)
		(layer "In5.Cu")
		(net "CBL_PRSNT_N_6")
	)
	(segment
		(start 260.351524 -5.807202)
		(end 253.889002 -5.807202)
		(width 0.127)
		(layer "In5.Cu")
		(net "CBL_PRSNT_N_6")
	)
	(segment
		(start 266.299442 -4.705858)
		(end 261.452868 -4.705858)
		(width 0.127)
		(layer "In5.Cu")
		(net "CBL_PRSNT_N_6")
	)
	(segment
		(start 186.4741 -1.9558)
		(end 181.87797 -1.9558)
		(width 0.127)
		(layer "In5.Cu")
		(net "CBL_PRSNT_N_6")
	)
	(segment
		(start 44.104814 -134.884922)
		(end 44.50461 -134.485126)
		(width 0.12065)
		(layer "F.Cu")
		(net "CBL_PRSNT_N_5")
	)
	(segment
		(start 275.17979 -10.384282)
		(end 275.178266 -10.385806)
		(width 0.12065)
		(layer "F.Cu")
		(net "CBL_PRSNT_N_5")
	)
	(segment
		(start 274.839176 -10.046716)
		(end 275.178266 -10.385806)
		(width 0.12065)
		(layer "F.Cu")
		(net "CBL_PRSNT_N_5")
	)
	(segment
		(start 274.287996 -10.046716)
		(end 274.839176 -10.046716)
		(width 0.12065)
		(layer "F.Cu")
		(net "CBL_PRSNT_N_5")
	)
	(segment
		(start 276.162516 -10.384282)
		(end 275.17979 -10.384282)
		(width 0.12065)
		(layer "F.Cu")
		(net "CBL_PRSNT_N_5")
	)
	(via
		(at 85.23478 -124.83084)
		(size 0.508)
		(drill 0.254)
		(layers "F.Cu" "B.Cu")
		(net "CBL_PRSNT_N_5")
	)
	(via
		(at 50.7746 -138.303)
		(size 0.508)
		(drill 0.254)
		(layers "F.Cu" "B.Cu")
		(net "CBL_PRSNT_N_5")
	)
	(via
		(at 275.178266 -10.385806)
		(size 0.508)
		(drill 0.254)
		(layers "F.Cu" "B.Cu")
		(net "CBL_PRSNT_N_5")
	)
	(via
		(at 109.982 -43.1038)
		(size 0.508)
		(drill 0.254)
		(layers "F.Cu" "B.Cu")
		(net "CBL_PRSNT_N_5")
	)
	(via
		(at 44.50461 -134.485126)
		(size 0.4572)
		(drill 0.2032)
		(layers "F.Cu" "B.Cu")
		(net "CBL_PRSNT_N_5")
	)
	(via
		(at 86.03615 -122.304556)
		(size 0.7112)
		(drill 0.3556)
		(layers "F.Cu" "B.Cu")
		(net "CBL_PRSNT_N_5")
	)
	(segment
		(start 44.50461 -134.485126)
		(end 44.893484 -134.874)
		(width 0.12065)
		(layer "B.Cu")
		(net "CBL_PRSNT_N_5")
	)
	(segment
		(start 101.547168 -81.51368)
		(end 101.547422 -81.513934)
		(width 0.12065)
		(layer "B.Cu")
		(net "CBL_PRSNT_N_5")
	)
	(segment
		(start 86.03615 -106.146346)
		(end 86.03615 -122.304556)
		(width 0.12065)
		(layer "B.Cu")
		(net "CBL_PRSNT_N_5")
	)
	(segment
		(start 109.982 -43.1038)
		(end 103.756968 -49.328832)
		(width 0.12065)
		(layer "B.Cu")
		(net "CBL_PRSNT_N_5")
	)
	(segment
		(start 44.893484 -134.874)
		(end 45.141134 -134.874)
		(width 0.12065)
		(layer "B.Cu")
		(net "CBL_PRSNT_N_5")
	)
	(segment
		(start 101.547422 -81.513934)
		(end 101.547422 -90.635074)
		(width 0.12065)
		(layer "B.Cu")
		(net "CBL_PRSNT_N_5")
	)
	(segment
		(start 47.347378 -134.875778)
		(end 50.7746 -138.303)
		(width 0.12065)
		(layer "B.Cu")
		(net "CBL_PRSNT_N_5")
	)
	(segment
		(start 86.03615 -124.02947)
		(end 85.23478 -124.83084)
		(width 0.12065)
		(layer "B.Cu")
		(net "CBL_PRSNT_N_5")
	)
	(segment
		(start 45.142912 -134.875778)
		(end 47.347378 -134.875778)
		(width 0.12065)
		(layer "B.Cu")
		(net "CBL_PRSNT_N_5")
	)
	(segment
		(start 103.756968 -49.328832)
		(end 103.756968 -60.5028)
		(width 0.12065)
		(layer "B.Cu")
		(net "CBL_PRSNT_N_5")
	)
	(segment
		(start 86.03615 -122.304556)
		(end 86.03615 -124.02947)
		(width 0.12065)
		(layer "B.Cu")
		(net "CBL_PRSNT_N_5")
	)
	(segment
		(start 101.547422 -90.635074)
		(end 86.03615 -106.146346)
		(width 0.12065)
		(layer "B.Cu")
		(net "CBL_PRSNT_N_5")
	)
	(segment
		(start 50.7746 -138.303)
		(end 51.2826 -138.811)
		(width 0.12065)
		(layer "B.Cu")
		(net "CBL_PRSNT_N_5")
	)
	(segment
		(start 51.2826 -138.811)
		(end 53.2765 -138.811)
		(width 0.12065)
		(layer "B.Cu")
		(net "CBL_PRSNT_N_5")
	)
	(segment
		(start 103.756968 -60.5028)
		(end 101.547168 -62.7126)
		(width 0.12065)
		(layer "B.Cu")
		(net "CBL_PRSNT_N_5")
	)
	(segment
		(start 101.547168 -62.7126)
		(end 101.547168 -81.51368)
		(width 0.12065)
		(layer "B.Cu")
		(net "CBL_PRSNT_N_5")
	)
	(segment
		(start 45.141134 -134.874)
		(end 45.142912 -134.875778)
		(width 0.12065)
		(layer "B.Cu")
		(net "CBL_PRSNT_N_5")
	)
	(segment
		(start 50.973482 -138.303)
		(end 50.7746 -138.303)
		(width 0.127)
		(layer "In2.Cu")
		(net "CBL_PRSNT_N_5")
	)
	(segment
		(start 71.714106 -137.9601)
		(end 55.831994 -137.9601)
		(width 0.127)
		(layer "In2.Cu")
		(net "CBL_PRSNT_N_5")
	)
	(segment
		(start 55.704994 -137.8331)
		(end 51.443382 -137.8331)
		(width 0.127)
		(layer "In2.Cu")
		(net "CBL_PRSNT_N_5")
	)
	(segment
		(start 79.283306 -130.3909)
		(end 71.714106 -137.9601)
		(width 0.127)
		(layer "In2.Cu")
		(net "CBL_PRSNT_N_5")
	)
	(segment
		(start 55.831994 -137.9601)
		(end 55.704994 -137.8331)
		(width 0.127)
		(layer "In2.Cu")
		(net "CBL_PRSNT_N_5")
	)
	(segment
		(start 51.443382 -137.8331)
		(end 50.973482 -138.303)
		(width 0.127)
		(layer "In2.Cu")
		(net "CBL_PRSNT_N_5")
	)
	(segment
		(start 79.67472 -130.3909)
		(end 79.283306 -130.3909)
		(width 0.127)
		(layer "In2.Cu")
		(net "CBL_PRSNT_N_5")
	)
	(segment
		(start 85.23478 -124.83084)
		(end 79.67472 -130.3909)
		(width 0.127)
		(layer "In2.Cu")
		(net "CBL_PRSNT_N_5")
	)
	(segment
		(start 111.632746 -27.341322)
		(end 124.1679 -14.806168)
		(width 0.127)
		(layer "In5.Cu")
		(net "CBL_PRSNT_N_5")
	)
	(segment
		(start 270.003016 -11.69797)
		(end 270.201898 -11.896852)
		(width 0.127)
		(layer "In5.Cu")
		(net "CBL_PRSNT_N_5")
	)
	(segment
		(start 209.483452 -4.88696)
		(end 211.081112 -3.2893)
		(width 0.127)
		(layer "In5.Cu")
		(net "CBL_PRSNT_N_5")
	)
	(segment
		(start 211.081112 -3.2893)
		(end 222.991172 -3.2893)
		(width 0.127)
		(layer "In5.Cu")
		(net "CBL_PRSNT_N_5")
	)
	(segment
		(start 197.4596 -5.9436)
		(end 207.5053 -5.9436)
		(width 0.127)
		(layer "In5.Cu")
		(net "CBL_PRSNT_N_5")
	)
	(segment
		(start 111.632746 -27.761946)
		(end 111.632746 -27.341322)
		(width 0.127)
		(layer "In5.Cu")
		(net "CBL_PRSNT_N_5")
	)
	(segment
		(start 177.18151 -2.77241)
		(end 179.0827 -4.6736)
		(width 0.127)
		(layer "In5.Cu")
		(net "CBL_PRSNT_N_5")
	)
	(segment
		(start 270.201898 -11.896852)
		(end 273.799554 -11.896852)
		(width 0.127)
		(layer "In5.Cu")
		(net "CBL_PRSNT_N_5")
	)
	(segment
		(start 188.84646 -6.705854)
		(end 196.697346 -6.705854)
		(width 0.127)
		(layer "In5.Cu")
		(net "CBL_PRSNT_N_5")
	)
	(segment
		(start 223.623124 -3.2893)
		(end 224.095818 -3.2893)
		(width 0.127)
		(layer "In5.Cu")
		(net "CBL_PRSNT_N_5")
	)
	(segment
		(start 266.057888 -7.52348)
		(end 266.057888 -8.865362)
		(width 0.127)
		(layer "In5.Cu")
		(net "CBL_PRSNT_N_5")
	)
	(segment
		(start 275.178266 -10.51814)
		(end 275.178266 -10.385806)
		(width 0.127)
		(layer "In5.Cu")
		(net "CBL_PRSNT_N_5")
	)
	(segment
		(start 243.461794 -5.214112)
		(end 246.16156 -7.913878)
		(width 0.127)
		(layer "In5.Cu")
		(net "CBL_PRSNT_N_5")
	)
	(segment
		(start 196.697346 -6.705854)
		(end 197.4596 -5.9436)
		(width 0.127)
		(layer "In5.Cu")
		(net "CBL_PRSNT_N_5")
	)
	(segment
		(start 223.62287 -3.289046)
		(end 223.623124 -3.2893)
		(width 0.127)
		(layer "In5.Cu")
		(net "CBL_PRSNT_N_5")
	)
	(segment
		(start 111.633 -27.7622)
		(end 111.632746 -27.761946)
		(width 0.127)
		(layer "In5.Cu")
		(net "CBL_PRSNT_N_5")
	)
	(segment
		(start 124.1679 -11.840464)
		(end 133.235954 -2.77241)
		(width 0.127)
		(layer "In5.Cu")
		(net "CBL_PRSNT_N_5")
	)
	(segment
		(start 111.633 -40.05961)
		(end 111.633 -27.7622)
		(width 0.127)
		(layer "In5.Cu")
		(net "CBL_PRSNT_N_5")
	)
	(segment
		(start 109.982 -41.71061)
		(end 111.633 -40.05961)
		(width 0.127)
		(layer "In5.Cu")
		(net "CBL_PRSNT_N_5")
	)
	(segment
		(start 266.057888 -8.865362)
		(end 267.445744 -10.253218)
		(width 0.127)
		(layer "In5.Cu")
		(net "CBL_PRSNT_N_5")
	)
	(segment
		(start 124.1679 -14.806168)
		(end 124.1679 -11.840464)
		(width 0.127)
		(layer "In5.Cu")
		(net "CBL_PRSNT_N_5")
	)
	(segment
		(start 133.235954 -2.77241)
		(end 177.18151 -2.77241)
		(width 0.127)
		(layer "In5.Cu")
		(net "CBL_PRSNT_N_5")
	)
	(segment
		(start 262.846312 -6.35508)
		(end 264.889488 -6.35508)
		(width 0.127)
		(layer "In5.Cu")
		(net "CBL_PRSNT_N_5")
	)
	(segment
		(start 179.0827 -4.6736)
		(end 186.814206 -4.6736)
		(width 0.127)
		(layer "In5.Cu")
		(net "CBL_PRSNT_N_5")
	)
	(segment
		(start 222.991172 -3.2893)
		(end 222.991426 -3.289046)
		(width 0.127)
		(layer "In5.Cu")
		(net "CBL_PRSNT_N_5")
	)
	(segment
		(start 260.39191 -7.913878)
		(end 261.214362 -7.091426)
		(width 0.127)
		(layer "In5.Cu")
		(net "CBL_PRSNT_N_5")
	)
	(segment
		(start 246.16156 -7.913878)
		(end 260.39191 -7.913878)
		(width 0.127)
		(layer "In5.Cu")
		(net "CBL_PRSNT_N_5")
	)
	(segment
		(start 207.5053 -5.9436)
		(end 208.56194 -4.88696)
		(width 0.127)
		(layer "In5.Cu")
		(net "CBL_PRSNT_N_5")
	)
	(segment
		(start 262.109966 -7.091426)
		(end 262.846312 -6.35508)
		(width 0.127)
		(layer "In5.Cu")
		(net "CBL_PRSNT_N_5")
	)
	(segment
		(start 273.799554 -11.896852)
		(end 275.178266 -10.51814)
		(width 0.127)
		(layer "In5.Cu")
		(net "CBL_PRSNT_N_5")
	)
	(segment
		(start 186.814206 -4.6736)
		(end 188.84646 -6.705854)
		(width 0.127)
		(layer "In5.Cu")
		(net "CBL_PRSNT_N_5")
	)
	(segment
		(start 109.982 -43.1038)
		(end 109.982 -41.71061)
		(width 0.127)
		(layer "In5.Cu")
		(net "CBL_PRSNT_N_5")
	)
	(segment
		(start 261.214362 -7.091426)
		(end 262.109966 -7.091426)
		(width 0.127)
		(layer "In5.Cu")
		(net "CBL_PRSNT_N_5")
	)
	(segment
		(start 224.095818 -3.2893)
		(end 226.02063 -5.214112)
		(width 0.127)
		(layer "In5.Cu")
		(net "CBL_PRSNT_N_5")
	)
	(segment
		(start 267.445744 -10.253218)
		(end 267.445744 -10.440416)
		(width 0.127)
		(layer "In5.Cu")
		(net "CBL_PRSNT_N_5")
	)
	(segment
		(start 268.703298 -11.69797)
		(end 270.003016 -11.69797)
		(width 0.127)
		(layer "In5.Cu")
		(net "CBL_PRSNT_N_5")
	)
	(segment
		(start 264.889488 -6.35508)
		(end 266.057888 -7.52348)
		(width 0.127)
		(layer "In5.Cu")
		(net "CBL_PRSNT_N_5")
	)
	(segment
		(start 222.991426 -3.289046)
		(end 223.62287 -3.289046)
		(width 0.127)
		(layer "In5.Cu")
		(net "CBL_PRSNT_N_5")
	)
	(segment
		(start 226.02063 -5.214112)
		(end 243.461794 -5.214112)
		(width 0.127)
		(layer "In5.Cu")
		(net "CBL_PRSNT_N_5")
	)
	(segment
		(start 208.56194 -4.88696)
		(end 209.483452 -4.88696)
		(width 0.127)
		(layer "In5.Cu")
		(net "CBL_PRSNT_N_5")
	)
	(segment
		(start 267.445744 -10.440416)
		(end 268.703298 -11.69797)
		(width 0.127)
		(layer "In5.Cu")
		(net "CBL_PRSNT_N_5")
	)
	(segment
		(start 53.0098 -137.795)
		(end 53.2765 -137.795)
		(width 0.12065)
		(layer "F.Cu")
		(net "CBL_PRSNT_N_4")
	)
	(segment
		(start 51.91506 -137.71626)
		(end 52.5018 -138.303)
		(width 0.12065)
		(layer "F.Cu")
		(net "CBL_PRSNT_N_4")
	)
	(segment
		(start 46.965616 -135.684768)
		(end 46.50486 -135.684768)
		(width 0.12065)
		(layer "F.Cu")
		(net "CBL_PRSNT_N_4")
	)
	(segment
		(start 50.008028 -137.71626)
		(end 51.91506 -137.71626)
		(width 0.12065)
		(layer "F.Cu")
		(net "CBL_PRSNT_N_4")
	)
	(segment
		(start 48.997108 -137.71626)
		(end 46.965616 -135.684768)
		(width 0.12065)
		(layer "F.Cu")
		(net "CBL_PRSNT_N_4")
	)
	(segment
		(start 50.008028 -137.71626)
		(end 48.997108 -137.71626)
		(width 0.12065)
		(layer "F.Cu")
		(net "CBL_PRSNT_N_4")
	)
	(segment
		(start 52.5018 -138.303)
		(end 53.0098 -137.795)
		(width 0.12065)
		(layer "F.Cu")
		(net "CBL_PRSNT_N_4")
	)
	(via
		(at 52.5018 -138.303)
		(size 0.508)
		(drill 0.254)
		(layers "F.Cu" "B.Cu")
		(net "CBL_PRSNT_N_4")
	)
	(via
		(at 50.008028 -137.71626)
		(size 0.7112)
		(drill 0.3556)
		(layers "F.Cu" "B.Cu")
		(net "CBL_PRSNT_N_4")
	)
	(via
		(at 83.207606 -128.0922)
		(size 0.508)
		(drill 0.254)
		(layers "F.Cu" "B.Cu")
		(net "CBL_PRSNT_N_4")
	)
	(segment
		(start 100.06965 -90.06459)
		(end 84.323174 -105.811066)
		(width 0.12065)
		(layer "B.Cu")
		(net "CBL_PRSNT_N_4")
	)
	(segment
		(start 164.973 -34.2265)
		(end 164.973 -38.705536)
		(width 0.12065)
		(layer "B.Cu")
		(net "CBL_PRSNT_N_4")
	)
	(segment
		(start 103.406702 -46.39945)
		(end 101.556566 -46.39945)
		(width 0.12065)
		(layer "B.Cu")
		(net "CBL_PRSNT_N_4")
	)
	(segment
		(start 141.399006 -41.43375)
		(end 140.976858 -41.011602)
		(width 0.12065)
		(layer "B.Cu")
		(net "CBL_PRSNT_N_4")
	)
	(segment
		(start 164.973 -38.705536)
		(end 161.896044 -41.782492)
		(width 0.12065)
		(layer "B.Cu")
		(net "CBL_PRSNT_N_4")
	)
	(segment
		(start 116.674392 -39.49065)
		(end 110.315502 -39.49065)
		(width 0.12065)
		(layer "B.Cu")
		(net "CBL_PRSNT_N_4")
	)
	(segment
		(start 154.28976 -41.782492)
		(end 153.941018 -41.43375)
		(width 0.12065)
		(layer "B.Cu")
		(net "CBL_PRSNT_N_4")
	)
	(segment
		(start 138.30173 -41.011602)
		(end 137.650728 -41.662604)
		(width 0.12065)
		(layer "B.Cu")
		(net "CBL_PRSNT_N_4")
	)
	(segment
		(start 100.06965 -62.47765)
		(end 100.06965 -90.06459)
		(width 0.12065)
		(layer "B.Cu")
		(net "CBL_PRSNT_N_4")
	)
	(segment
		(start 123.33351 -40.5257)
		(end 121.4501 -38.64229)
		(width 0.12065)
		(layer "B.Cu")
		(net "CBL_PRSNT_N_4")
	)
	(segment
		(start 96.799654 -51.156362)
		(end 96.799654 -59.207654)
		(width 0.12065)
		(layer "B.Cu")
		(net "CBL_PRSNT_N_4")
	)
	(segment
		(start 132.7785 -40.5257)
		(end 123.33351 -40.5257)
		(width 0.12065)
		(layer "B.Cu")
		(net "CBL_PRSNT_N_4")
	)
	(segment
		(start 83.102704 -119.676672)
		(end 83.102704 -127.987298)
		(width 0.12065)
		(layer "B.Cu")
		(net "CBL_PRSNT_N_4")
	)
	(segment
		(start 153.941018 -41.43375)
		(end 141.399006 -41.43375)
		(width 0.12065)
		(layer "B.Cu")
		(net "CBL_PRSNT_N_4")
	)
	(segment
		(start 161.896044 -41.782492)
		(end 154.28976 -41.782492)
		(width 0.12065)
		(layer "B.Cu")
		(net "CBL_PRSNT_N_4")
	)
	(segment
		(start 117.522752 -38.64229)
		(end 116.674392 -39.49065)
		(width 0.12065)
		(layer "B.Cu")
		(net "CBL_PRSNT_N_4")
	)
	(segment
		(start 96.799654 -59.207654)
		(end 100.06965 -62.47765)
		(width 0.12065)
		(layer "B.Cu")
		(net "CBL_PRSNT_N_4")
	)
	(segment
		(start 110.315502 -39.49065)
		(end 103.406702 -46.39945)
		(width 0.12065)
		(layer "B.Cu")
		(net "CBL_PRSNT_N_4")
	)
	(segment
		(start 165.227 -33.9725)
		(end 164.973 -34.2265)
		(width 0.12065)
		(layer "B.Cu")
		(net "CBL_PRSNT_N_4")
	)
	(segment
		(start 137.650728 -41.662604)
		(end 133.915404 -41.662604)
		(width 0.12065)
		(layer "B.Cu")
		(net "CBL_PRSNT_N_4")
	)
	(segment
		(start 84.323174 -105.811066)
		(end 84.323174 -118.456202)
		(width 0.12065)
		(layer "B.Cu")
		(net "CBL_PRSNT_N_4")
	)
	(segment
		(start 83.102704 -127.987298)
		(end 83.207606 -128.0922)
		(width 0.12065)
		(layer "B.Cu")
		(net "CBL_PRSNT_N_4")
	)
	(segment
		(start 133.915404 -41.662604)
		(end 132.7785 -40.5257)
		(width 0.12065)
		(layer "B.Cu")
		(net "CBL_PRSNT_N_4")
	)
	(segment
		(start 84.323174 -118.456202)
		(end 83.102704 -119.676672)
		(width 0.12065)
		(layer "B.Cu")
		(net "CBL_PRSNT_N_4")
	)
	(segment
		(start 140.976858 -41.011602)
		(end 138.30173 -41.011602)
		(width 0.12065)
		(layer "B.Cu")
		(net "CBL_PRSNT_N_4")
	)
	(segment
		(start 165.227 -33.9725)
		(end 166.37 -33.9725)
		(width 0.12065)
		(layer "B.Cu")
		(net "CBL_PRSNT_N_4")
	)
	(segment
		(start 121.4501 -38.64229)
		(end 117.522752 -38.64229)
		(width 0.12065)
		(layer "B.Cu")
		(net "CBL_PRSNT_N_4")
	)
	(segment
		(start 101.556566 -46.39945)
		(end 96.799654 -51.156362)
		(width 0.12065)
		(layer "B.Cu")
		(net "CBL_PRSNT_N_4")
	)
	(segment
		(start 71.9455 -138.4427)
		(end 55.775606 -138.4427)
		(width 0.127)
		(layer "In2.Cu")
		(net "CBL_PRSNT_N_4")
	)
	(segment
		(start 80.527906 -130.7719)
		(end 79.6163 -130.7719)
		(width 0.127)
		(layer "In2.Cu")
		(net "CBL_PRSNT_N_4")
	)
	(segment
		(start 83.207606 -128.0922)
		(end 80.527906 -130.7719)
		(width 0.127)
		(layer "In2.Cu")
		(net "CBL_PRSNT_N_4")
	)
	(segment
		(start 55.635906 -138.303)
		(end 52.5018 -138.303)
		(width 0.127)
		(layer "In2.Cu")
		(net "CBL_PRSNT_N_4")
	)
	(segment
		(start 55.775606 -138.4427)
		(end 55.635906 -138.303)
		(width 0.127)
		(layer "In2.Cu")
		(net "CBL_PRSNT_N_4")
	)
	(segment
		(start 79.6163 -130.7719)
		(end 71.9455 -138.4427)
		(width 0.127)
		(layer "In2.Cu")
		(net "CBL_PRSNT_N_4")
	)
	(segment
		(start 44.904914 -134.884922)
		(end 45.30471 -134.485126)
		(width 0.12065)
		(layer "F.Cu")
		(net "CBL_PRSNT_N_3")
	)
	(via
		(at 156.718 -36.703)
		(size 0.508)
		(drill 0.254)
		(layers "F.Cu" "B.Cu")
		(net "CBL_PRSNT_N_3")
	)
	(via
		(at 77.3176 -129.8956)
		(size 0.508)
		(drill 0.254)
		(layers "F.Cu" "B.Cu")
		(net "CBL_PRSNT_N_3")
	)
	(via
		(at 45.30471 -134.485126)
		(size 0.4572)
		(drill 0.2032)
		(layers "F.Cu" "B.Cu")
		(net "CBL_PRSNT_N_3")
	)
	(via
		(at 156.139134 -35.124898)
		(size 0.508)
		(drill 0.254)
		(layers "F.Cu" "B.Cu")
		(net "CBL_PRSNT_N_3")
	)
	(via
		(at 154.883358 -40.35044)
		(size 0.7112)
		(drill 0.3556)
		(layers "F.Cu" "B.Cu")
		(net "CBL_PRSNT_N_3")
	)
	(segment
		(start 156.7053 -36.703)
		(end 156.718 -36.703)
		(width 0.12065)
		(layer "B.Cu")
		(net "CBL_PRSNT_N_3")
	)
	(segment
		(start 95.32366 -87.5538)
		(end 98.8441 -84.03336)
		(width 0.12065)
		(layer "B.Cu")
		(net "CBL_PRSNT_N_3")
	)
	(segment
		(start 76.606908 -118.414292)
		(end 77.1398 -117.8814)
		(width 0.12065)
		(layer "B.Cu")
		(net "CBL_PRSNT_N_3")
	)
	(segment
		(start 78.1558 -115.5192)
		(end 78.1558 -104.29494)
		(width 0.12065)
		(layer "B.Cu")
		(net "CBL_PRSNT_N_3")
	)
	(segment
		(start 76.606908 -121.895108)
		(end 76.606908 -118.414292)
		(width 0.12065)
		(layer "B.Cu")
		(net "CBL_PRSNT_N_3")
	)
	(segment
		(start 158.508192 -34.034476)
		(end 158.32963 -34.034476)
		(width 0.12065)
		(layer "B.Cu")
		(net "CBL_PRSNT_N_3")
	)
	(segment
		(start 78.1558 -104.29494)
		(end 85.470492 -96.980248)
		(width 0.12065)
		(layer "B.Cu")
		(net "CBL_PRSNT_N_3")
	)
	(segment
		(start 51.3588 -137.414)
		(end 48.429926 -134.485126)
		(width 0.12065)
		(layer "B.Cu")
		(net "CBL_PRSNT_N_3")
	)
	(segment
		(start 155.454604 -34.388806)
		(end 156.139134 -35.073336)
		(width 0.12065)
		(layer "B.Cu")
		(net "CBL_PRSNT_N_3")
	)
	(segment
		(start 76.835762 -123.800616)
		(end 76.835762 -122.123962)
		(width 0.12065)
		(layer "B.Cu")
		(net "CBL_PRSNT_N_3")
	)
	(segment
		(start 111.461296 -36.611052)
		(end 121.370852 -36.611052)
		(width 0.12065)
		(layer "B.Cu")
		(net "CBL_PRSNT_N_3")
	)
	(segment
		(start 156.337 -38.896798)
		(end 156.337 -37.1602)
		(width 0.12065)
		(layer "B.Cu")
		(net "CBL_PRSNT_N_3")
	)
	(segment
		(start 156.6926 -36.6903)
		(end 156.7053 -36.703)
		(width 0.12065)
		(layer "B.Cu")
		(net "CBL_PRSNT_N_3")
	)
	(segment
		(start 141.90726 -40.2082)
		(end 154.741118 -40.2082)
		(width 0.12065)
		(layer "B.Cu")
		(net "CBL_PRSNT_N_3")
	)
	(segment
		(start 77.1398 -117.8814)
		(end 77.1398 -116.5352)
		(width 0.12065)
		(layer "B.Cu")
		(net "CBL_PRSNT_N_3")
	)
	(segment
		(start 156.337 -37.1602)
		(end 156.718 -36.7792)
		(width 0.12065)
		(layer "B.Cu")
		(net "CBL_PRSNT_N_3")
	)
	(segment
		(start 48.429926 -134.485126)
		(end 45.30471 -134.485126)
		(width 0.12065)
		(layer "B.Cu")
		(net "CBL_PRSNT_N_3")
	)
	(segment
		(start 53.2765 -137.795)
		(end 52.8955 -137.414)
		(width 0.12065)
		(layer "B.Cu")
		(net "CBL_PRSNT_N_3")
	)
	(segment
		(start 134.7724 -40.4368)
		(end 137.040112 -40.4368)
		(width 0.12065)
		(layer "B.Cu")
		(net "CBL_PRSNT_N_3")
	)
	(segment
		(start 137.040112 -40.4368)
		(end 137.69086 -39.786052)
		(width 0.12065)
		(layer "B.Cu")
		(net "CBL_PRSNT_N_3")
	)
	(segment
		(start 124.05995 -39.30015)
		(end 133.63575 -39.30015)
		(width 0.12065)
		(layer "B.Cu")
		(net "CBL_PRSNT_N_3")
	)
	(segment
		(start 95.411798 -59.553602)
		(end 95.411798 -50.809398)
		(width 0.12065)
		(layer "B.Cu")
		(net "CBL_PRSNT_N_3")
	)
	(segment
		(start 156.6926 -36.35756)
		(end 156.6926 -36.6903)
		(width 0.12065)
		(layer "B.Cu")
		(net "CBL_PRSNT_N_3")
	)
	(segment
		(start 77.632052 -129.581148)
		(end 77.632052 -124.596906)
		(width 0.12065)
		(layer "B.Cu")
		(net "CBL_PRSNT_N_3")
	)
	(segment
		(start 156.139134 -35.073336)
		(end 156.139134 -35.124898)
		(width 0.12065)
		(layer "B.Cu")
		(net "CBL_PRSNT_N_3")
	)
	(segment
		(start 101.047296 -45.1739)
		(end 102.898448 -45.1739)
		(width 0.12065)
		(layer "B.Cu")
		(net "CBL_PRSNT_N_3")
	)
	(segment
		(start 95.411798 -50.809398)
		(end 101.047296 -45.1739)
		(width 0.12065)
		(layer "B.Cu")
		(net "CBL_PRSNT_N_3")
	)
	(segment
		(start 141.485112 -39.786052)
		(end 141.90726 -40.2082)
		(width 0.12065)
		(layer "B.Cu")
		(net "CBL_PRSNT_N_3")
	)
	(segment
		(start 157.24886 -35.115246)
		(end 157.24886 -35.8013)
		(width 0.12065)
		(layer "B.Cu")
		(net "CBL_PRSNT_N_3")
	)
	(segment
		(start 121.370852 -36.611052)
		(end 124.05995 -39.30015)
		(width 0.12065)
		(layer "B.Cu")
		(net "CBL_PRSNT_N_3")
	)
	(segment
		(start 52.8955 -137.414)
		(end 51.3588 -137.414)
		(width 0.12065)
		(layer "B.Cu")
		(net "CBL_PRSNT_N_3")
	)
	(segment
		(start 98.8441 -84.03336)
		(end 98.8441 -62.985904)
		(width 0.12065)
		(layer "B.Cu")
		(net "CBL_PRSNT_N_3")
	)
	(segment
		(start 77.3176 -129.8956)
		(end 77.632052 -129.581148)
		(width 0.12065)
		(layer "B.Cu")
		(net "CBL_PRSNT_N_3")
	)
	(segment
		(start 154.741118 -40.2082)
		(end 154.883358 -40.35044)
		(width 0.12065)
		(layer "B.Cu")
		(net "CBL_PRSNT_N_3")
	)
	(segment
		(start 155.454604 -34.036508)
		(end 155.454604 -34.388806)
		(width 0.12065)
		(layer "B.Cu")
		(net "CBL_PRSNT_N_3")
	)
	(segment
		(start 154.883358 -40.35044)
		(end 156.337 -38.896798)
		(width 0.12065)
		(layer "B.Cu")
		(net "CBL_PRSNT_N_3")
	)
	(segment
		(start 156.718 -36.7792)
		(end 156.718 -36.703)
		(width 0.12065)
		(layer "B.Cu")
		(net "CBL_PRSNT_N_3")
	)
	(segment
		(start 137.69086 -39.786052)
		(end 141.485112 -39.786052)
		(width 0.12065)
		(layer "B.Cu")
		(net "CBL_PRSNT_N_3")
	)
	(segment
		(start 157.24886 -35.8013)
		(end 156.6926 -36.35756)
		(width 0.12065)
		(layer "B.Cu")
		(net "CBL_PRSNT_N_3")
	)
	(segment
		(start 85.470492 -96.980248)
		(end 85.470492 -92.976446)
		(width 0.12065)
		(layer "B.Cu")
		(net "CBL_PRSNT_N_3")
	)
	(segment
		(start 133.63575 -39.30015)
		(end 134.7724 -40.4368)
		(width 0.12065)
		(layer "B.Cu")
		(net "CBL_PRSNT_N_3")
	)
	(segment
		(start 77.1398 -116.5352)
		(end 78.1558 -115.5192)
		(width 0.12065)
		(layer "B.Cu")
		(net "CBL_PRSNT_N_3")
	)
	(segment
		(start 77.632052 -124.596906)
		(end 76.835762 -123.800616)
		(width 0.12065)
		(layer "B.Cu")
		(net "CBL_PRSNT_N_3")
	)
	(segment
		(start 76.835762 -122.123962)
		(end 76.606908 -121.895108)
		(width 0.12065)
		(layer "B.Cu")
		(net "CBL_PRSNT_N_3")
	)
	(segment
		(start 158.32963 -34.034476)
		(end 157.24886 -35.115246)
		(width 0.12065)
		(layer "B.Cu")
		(net "CBL_PRSNT_N_3")
	)
	(segment
		(start 85.470492 -92.976446)
		(end 90.893138 -87.5538)
		(width 0.12065)
		(layer "B.Cu")
		(net "CBL_PRSNT_N_3")
	)
	(segment
		(start 90.893138 -87.5538)
		(end 95.32366 -87.5538)
		(width 0.12065)
		(layer "B.Cu")
		(net "CBL_PRSNT_N_3")
	)
	(segment
		(start 102.898448 -45.1739)
		(end 111.461296 -36.611052)
		(width 0.12065)
		(layer "B.Cu")
		(net "CBL_PRSNT_N_3")
	)
	(segment
		(start 98.8441 -62.985904)
		(end 95.411798 -59.553602)
		(width 0.12065)
		(layer "B.Cu")
		(net "CBL_PRSNT_N_3")
	)
	(segment
		(start 46.8122 -134.8994)
		(end 55.439818 -134.8994)
		(width 0.127)
		(layer "In2.Cu")
		(net "CBL_PRSNT_N_3")
	)
	(segment
		(start 45.30471 -134.485126)
		(end 46.397926 -134.485126)
		(width 0.127)
		(layer "In2.Cu")
		(net "CBL_PRSNT_N_3")
	)
	(segment
		(start 75.9206 -131.2926)
		(end 77.3176 -129.8956)
		(width 0.127)
		(layer "In2.Cu")
		(net "CBL_PRSNT_N_3")
	)
	(segment
		(start 46.397926 -134.485126)
		(end 46.8122 -134.8994)
		(width 0.127)
		(layer "In2.Cu")
		(net "CBL_PRSNT_N_3")
	)
	(segment
		(start 70.592188 -131.2926)
		(end 75.9206 -131.2926)
		(width 0.127)
		(layer "In2.Cu")
		(net "CBL_PRSNT_N_3")
	)
	(segment
		(start 67.493388 -134.3914)
		(end 70.592188 -131.2926)
		(width 0.127)
		(layer "In2.Cu")
		(net "CBL_PRSNT_N_3")
	)
	(segment
		(start 55.439818 -134.8994)
		(end 55.947818 -134.3914)
		(width 0.127)
		(layer "In2.Cu")
		(net "CBL_PRSNT_N_3")
	)
	(segment
		(start 55.947818 -134.3914)
		(end 67.493388 -134.3914)
		(width 0.127)
		(layer "In2.Cu")
		(net "CBL_PRSNT_N_3")
	)
	(segment
		(start 156.190696 -36.201096)
		(end 156.6926 -36.703)
		(width 0.127)
		(layer "In5.Cu")
		(net "CBL_PRSNT_N_3")
	)
	(segment
		(start 156.139134 -35.124898)
		(end 156.190696 -35.17646)
		(width 0.127)
		(layer "In5.Cu")
		(net "CBL_PRSNT_N_3")
	)
	(segment
		(start 156.190696 -35.17646)
		(end 156.190696 -36.201096)
		(width 0.127)
		(layer "In5.Cu")
		(net "CBL_PRSNT_N_3")
	)
	(segment
		(start 156.6926 -36.703)
		(end 156.718 -36.703)
		(width 0.127)
		(layer "In5.Cu")
		(net "CBL_PRSNT_N_3")
	)
	(segment
		(start 144.971516 -37.43071)
		(end 144.229074 -36.688268)
		(width 0.12065)
		(layer "F.Cu")
		(net "CBL_PRSNT_N_2")
	)
	(segment
		(start 144.229074 -36.683442)
		(end 143.898874 -36.353242)
		(width 0.12065)
		(layer "F.Cu")
		(net "CBL_PRSNT_N_2")
	)
	(segment
		(start 43.304714 -134.084822)
		(end 43.70451 -133.685026)
		(width 0.12065)
		(layer "F.Cu")
		(net "CBL_PRSNT_N_2")
	)
	(segment
		(start 144.229074 -36.688268)
		(end 144.229074 -36.683442)
		(width 0.12065)
		(layer "F.Cu")
		(net "CBL_PRSNT_N_2")
	)
	(via
		(at 143.898874 -36.353242)
		(size 0.508)
		(drill 0.254)
		(layers "F.Cu" "B.Cu")
		(net "CBL_PRSNT_N_2")
	)
	(via
		(at 144.971516 -37.43071)
		(size 0.508)
		(drill 0.254)
		(layers "F.Cu" "B.Cu")
		(net "CBL_PRSNT_N_2")
	)
	(via
		(at 91.201494 -85.093556)
		(size 0.7112)
		(drill 0.3556)
		(layers "F.Cu" "B.Cu")
		(net "CBL_PRSNT_N_2")
	)
	(via
		(at 43.70451 -133.685026)
		(size 0.4572)
		(drill 0.2032)
		(layers "F.Cu" "B.Cu")
		(net "CBL_PRSNT_N_2")
	)
	(via
		(at 77.1652 -128.2954)
		(size 0.508)
		(drill 0.254)
		(layers "F.Cu" "B.Cu")
		(net "CBL_PRSNT_N_2")
	)
	(segment
		(start 52.809648 -136.312148)
		(end 51.1556 -136.312148)
		(width 0.12065)
		(layer "B.Cu")
		(net "CBL_PRSNT_N_2")
	)
	(segment
		(start 100.538788 -43.94835)
		(end 102.390194 -43.94835)
		(width 0.12065)
		(layer "B.Cu")
		(net "CBL_PRSNT_N_2")
	)
	(segment
		(start 111.524796 -34.813748)
		(end 116.851176 -34.813748)
		(width 0.12065)
		(layer "B.Cu")
		(net "CBL_PRSNT_N_2")
	)
	(segment
		(start 76.473812 -122.274076)
		(end 76.473812 -127.604012)
		(width 0.12065)
		(layer "B.Cu")
		(net "CBL_PRSNT_N_2")
	)
	(segment
		(start 84.059268 -92.607638)
		(end 84.059268 -95.772732)
		(width 0.12065)
		(layer "B.Cu")
		(net "CBL_PRSNT_N_2")
	)
	(segment
		(start 76.473812 -127.604012)
		(end 77.1652 -128.2954)
		(width 0.12065)
		(layer "B.Cu")
		(net "CBL_PRSNT_N_2")
	)
	(segment
		(start 91.201494 -85.465412)
		(end 84.059268 -92.607638)
		(width 0.12065)
		(layer "B.Cu")
		(net "CBL_PRSNT_N_2")
	)
	(segment
		(start 95.0976 -61.3918)
		(end 94.01175 -60.30595)
		(width 0.12065)
		(layer "B.Cu")
		(net "CBL_PRSNT_N_2")
	)
	(segment
		(start 146.389344 -37.43071)
		(end 144.971516 -37.43071)
		(width 0.12065)
		(layer "B.Cu")
		(net "CBL_PRSNT_N_2")
	)
	(segment
		(start 76.6826 -110.7694)
		(end 74.981308 -112.470692)
		(width 0.12065)
		(layer "B.Cu")
		(net "CBL_PRSNT_N_2")
	)
	(segment
		(start 143.898874 -36.084256)
		(end 143.92021 -36.06292)
		(width 0.12065)
		(layer "B.Cu")
		(net "CBL_PRSNT_N_2")
	)
	(segment
		(start 147.946618 -33.98012)
		(end 147.7264 -34.200338)
		(width 0.12065)
		(layer "B.Cu")
		(net "CBL_PRSNT_N_2")
	)
	(segment
		(start 117.413278 -35.37585)
		(end 121.869454 -35.37585)
		(width 0.12065)
		(layer "B.Cu")
		(net "CBL_PRSNT_N_2")
	)
	(segment
		(start 133.685534 -37.182806)
		(end 141.853666 -37.182806)
		(width 0.12065)
		(layer "B.Cu")
		(net "CBL_PRSNT_N_2")
	)
	(segment
		(start 143.898874 -36.353242)
		(end 143.898874 -36.084256)
		(width 0.12065)
		(layer "B.Cu")
		(net "CBL_PRSNT_N_2")
	)
	(segment
		(start 43.95216 -133.685026)
		(end 43.70451 -133.685026)
		(width 0.12065)
		(layer "B.Cu")
		(net "CBL_PRSNT_N_2")
	)
	(segment
		(start 144.86763 -34.98723)
		(end 144.86763 -33.98012)
		(width 0.12065)
		(layer "B.Cu")
		(net "CBL_PRSNT_N_2")
	)
	(segment
		(start 94.01175 -60.30595)
		(end 94.01175 -50.475388)
		(width 0.12065)
		(layer "B.Cu")
		(net "CBL_PRSNT_N_2")
	)
	(segment
		(start 53.2765 -136.779)
		(end 52.809648 -136.312148)
		(width 0.12065)
		(layer "B.Cu")
		(net "CBL_PRSNT_N_2")
	)
	(segment
		(start 76.6826 -103.1494)
		(end 76.6826 -110.7694)
		(width 0.12065)
		(layer "B.Cu")
		(net "CBL_PRSNT_N_2")
	)
	(segment
		(start 142.486634 -37.516054)
		(end 142.486888 -37.5158)
		(width 0.12065)
		(layer "B.Cu")
		(net "CBL_PRSNT_N_2")
	)
	(segment
		(start 48.91913 -134.075678)
		(end 44.342812 -134.075678)
		(width 0.12065)
		(layer "B.Cu")
		(net "CBL_PRSNT_N_2")
	)
	(segment
		(start 74.981308 -112.470692)
		(end 74.981308 -118.359682)
		(width 0.12065)
		(layer "B.Cu")
		(net "CBL_PRSNT_N_2")
	)
	(segment
		(start 143.92021 -35.93465)
		(end 144.86763 -34.98723)
		(width 0.12065)
		(layer "B.Cu")
		(net "CBL_PRSNT_N_2")
	)
	(segment
		(start 91.201494 -85.093556)
		(end 95.0976 -81.19745)
		(width 0.12065)
		(layer "B.Cu")
		(net "CBL_PRSNT_N_2")
	)
	(segment
		(start 142.186914 -37.516054)
		(end 142.486634 -37.516054)
		(width 0.12065)
		(layer "B.Cu")
		(net "CBL_PRSNT_N_2")
	)
	(segment
		(start 141.853666 -37.182806)
		(end 142.186914 -37.516054)
		(width 0.12065)
		(layer "B.Cu")
		(net "CBL_PRSNT_N_2")
	)
	(segment
		(start 102.390194 -43.94835)
		(end 111.524796 -34.813748)
		(width 0.12065)
		(layer "B.Cu")
		(net "CBL_PRSNT_N_2")
	)
	(segment
		(start 121.869454 -35.37585)
		(end 124.568204 -38.0746)
		(width 0.12065)
		(layer "B.Cu")
		(net "CBL_PRSNT_N_2")
	)
	(segment
		(start 76.197206 -119.57558)
		(end 76.197206 -121.99747)
		(width 0.12065)
		(layer "B.Cu")
		(net "CBL_PRSNT_N_2")
	)
	(segment
		(start 116.851176 -34.813748)
		(end 117.413278 -35.37585)
		(width 0.12065)
		(layer "B.Cu")
		(net "CBL_PRSNT_N_2")
	)
	(segment
		(start 142.486888 -37.5158)
		(end 144.886426 -37.5158)
		(width 0.12065)
		(layer "B.Cu")
		(net "CBL_PRSNT_N_2")
	)
	(segment
		(start 74.981308 -118.359682)
		(end 76.197206 -119.57558)
		(width 0.12065)
		(layer "B.Cu")
		(net "CBL_PRSNT_N_2")
	)
	(segment
		(start 144.886426 -37.5158)
		(end 144.971516 -37.43071)
		(width 0.12065)
		(layer "B.Cu")
		(net "CBL_PRSNT_N_2")
	)
	(segment
		(start 95.0976 -81.19745)
		(end 95.0976 -61.3918)
		(width 0.12065)
		(layer "B.Cu")
		(net "CBL_PRSNT_N_2")
	)
	(segment
		(start 44.342812 -134.075678)
		(end 43.95216 -133.685026)
		(width 0.12065)
		(layer "B.Cu")
		(net "CBL_PRSNT_N_2")
	)
	(segment
		(start 76.197206 -121.99747)
		(end 76.473812 -122.274076)
		(width 0.12065)
		(layer "B.Cu")
		(net "CBL_PRSNT_N_2")
	)
	(segment
		(start 84.059268 -95.772732)
		(end 76.6826 -103.1494)
		(width 0.12065)
		(layer "B.Cu")
		(net "CBL_PRSNT_N_2")
	)
	(segment
		(start 51.1556 -136.312148)
		(end 48.91913 -134.075678)
		(width 0.12065)
		(layer "B.Cu")
		(net "CBL_PRSNT_N_2")
	)
	(segment
		(start 124.568204 -38.0746)
		(end 132.79374 -38.0746)
		(width 0.12065)
		(layer "B.Cu")
		(net "CBL_PRSNT_N_2")
	)
	(segment
		(start 132.79374 -38.0746)
		(end 133.685534 -37.182806)
		(width 0.12065)
		(layer "B.Cu")
		(net "CBL_PRSNT_N_2")
	)
	(segment
		(start 91.201494 -85.093556)
		(end 91.201494 -85.465412)
		(width 0.12065)
		(layer "B.Cu")
		(net "CBL_PRSNT_N_2")
	)
	(segment
		(start 147.7264 -36.093654)
		(end 146.389344 -37.43071)
		(width 0.12065)
		(layer "B.Cu")
		(net "CBL_PRSNT_N_2")
	)
	(segment
		(start 143.92021 -36.06292)
		(end 143.92021 -35.93465)
		(width 0.12065)
		(layer "B.Cu")
		(net "CBL_PRSNT_N_2")
	)
	(segment
		(start 147.7264 -34.200338)
		(end 147.7264 -36.093654)
		(width 0.12065)
		(layer "B.Cu")
		(net "CBL_PRSNT_N_2")
	)
	(segment
		(start 94.01175 -50.475388)
		(end 100.538788 -43.94835)
		(width 0.12065)
		(layer "B.Cu")
		(net "CBL_PRSNT_N_2")
	)
	(segment
		(start 55.73903 -133.9596)
		(end 55.050182 -133.9596)
		(width 0.127)
		(layer "In2.Cu")
		(net "CBL_PRSNT_N_2")
	)
	(segment
		(start 77.1652 -128.2954)
		(end 74.549 -130.9116)
		(width 0.127)
		(layer "In2.Cu")
		(net "CBL_PRSNT_N_2")
	)
	(segment
		(start 62.28588 -134.0104)
		(end 55.78983 -134.0104)
		(width 0.127)
		(layer "In2.Cu")
		(net "CBL_PRSNT_N_2")
	)
	(segment
		(start 44.106084 -134.0866)
		(end 43.70451 -133.685026)
		(width 0.127)
		(layer "In2.Cu")
		(net "CBL_PRSNT_N_2")
	)
	(segment
		(start 55.050182 -133.9596)
		(end 54.923182 -134.0866)
		(width 0.127)
		(layer "In2.Cu")
		(net "CBL_PRSNT_N_2")
	)
	(segment
		(start 68.278502 -133.067298)
		(end 63.228982 -133.067298)
		(width 0.127)
		(layer "In2.Cu")
		(net "CBL_PRSNT_N_2")
	)
	(segment
		(start 55.78983 -134.0104)
		(end 55.73903 -133.9596)
		(width 0.127)
		(layer "In2.Cu")
		(net "CBL_PRSNT_N_2")
	)
	(segment
		(start 70.4342 -130.9116)
		(end 68.278502 -133.067298)
		(width 0.127)
		(layer "In2.Cu")
		(net "CBL_PRSNT_N_2")
	)
	(segment
		(start 54.923182 -134.0866)
		(end 44.106084 -134.0866)
		(width 0.127)
		(layer "In2.Cu")
		(net "CBL_PRSNT_N_2")
	)
	(segment
		(start 74.549 -130.9116)
		(end 70.4342 -130.9116)
		(width 0.127)
		(layer "In2.Cu")
		(net "CBL_PRSNT_N_2")
	)
	(segment
		(start 63.228982 -133.067298)
		(end 62.28588 -134.0104)
		(width 0.127)
		(layer "In2.Cu")
		(net "CBL_PRSNT_N_2")
	)
	(segment
		(start 48.688752 -136.779)
		(end 51.6382 -136.779)
		(width 0.12065)
		(layer "F.Cu")
		(net "CBL_PRSNT_N_1")
	)
	(segment
		(start 46.50486 -134.884922)
		(end 46.794674 -134.884922)
		(width 0.12065)
		(layer "F.Cu")
		(net "CBL_PRSNT_N_1")
	)
	(segment
		(start 51.6382 -136.779)
		(end 52.6542 -135.763)
		(width 0.12065)
		(layer "F.Cu")
		(net "CBL_PRSNT_N_1")
	)
	(segment
		(start 46.794674 -134.884922)
		(end 48.688752 -136.779)
		(width 0.12065)
		(layer "F.Cu")
		(net "CBL_PRSNT_N_1")
	)
	(segment
		(start 52.6542 -135.763)
		(end 53.2765 -135.763)
		(width 0.12065)
		(layer "F.Cu")
		(net "CBL_PRSNT_N_1")
	)
	(via
		(at 75.152504 -132.2832)
		(size 0.508)
		(drill 0.254)
		(layers "F.Cu" "B.Cu")
		(net "CBL_PRSNT_N_1")
	)
	(via
		(at 134.8232 -31.4706)
		(size 0.508)
		(drill 0.254)
		(layers "F.Cu" "B.Cu")
		(net "CBL_PRSNT_N_1")
	)
	(via
		(at 129.379726 -35.955986)
		(size 0.508)
		(drill 0.254)
		(layers "F.Cu" "B.Cu")
		(net "CBL_PRSNT_N_1")
	)
	(via
		(at 51.6382 -136.779)
		(size 0.508)
		(drill 0.254)
		(layers "F.Cu" "B.Cu")
		(net "CBL_PRSNT_N_1")
	)
	(via
		(at 81.649316 -89.203784)
		(size 0.7112)
		(drill 0.3556)
		(layers "F.Cu" "B.Cu")
		(net "CBL_PRSNT_N_1")
	)
	(segment
		(start 125.076712 -36.84905)
		(end 124.930154 -36.702492)
		(width 0.12065)
		(layer "B.Cu")
		(net "CBL_PRSNT_N_1")
	)
	(segment
		(start 117.952012 -34.149792)
		(end 117.27942 -33.4772)
		(width 0.12065)
		(layer "B.Cu")
		(net "CBL_PRSNT_N_1")
	)
	(segment
		(start 132.969 -35.6616)
		(end 132.969 -36.144454)
		(width 0.12065)
		(layer "B.Cu")
		(net "CBL_PRSNT_N_1")
	)
	(segment
		(start 132.969 -36.144454)
		(end 132.264404 -36.84905)
		(width 0.12065)
		(layer "B.Cu")
		(net "CBL_PRSNT_N_1")
	)
	(segment
		(start 92.489528 -50.207926)
		(end 92.489528 -80.789272)
		(width 0.12065)
		(layer "B.Cu")
		(net "CBL_PRSNT_N_1")
	)
	(segment
		(start 80.433926 -92.67698)
		(end 80.433926 -90.419174)
		(width 0.12065)
		(layer "B.Cu")
		(net "CBL_PRSNT_N_1")
	)
	(segment
		(start 92.489528 -80.789272)
		(end 88.9762 -84.3026)
		(width 0.12065)
		(layer "B.Cu")
		(net "CBL_PRSNT_N_1")
	)
	(segment
		(start 111.12754 -33.4772)
		(end 101.88194 -42.7228)
		(width 0.12065)
		(layer "B.Cu")
		(net "CBL_PRSNT_N_1")
	)
	(segment
		(start 74.619104 -112.096296)
		(end 76.2762 -110.4392)
		(width 0.12065)
		(layer "B.Cu")
		(net "CBL_PRSNT_N_1")
	)
	(segment
		(start 130.51028 -34.341816)
		(end 130.51028 -33.99028)
		(width 0.12065)
		(layer "B.Cu")
		(net "CBL_PRSNT_N_1")
	)
	(segment
		(start 124.9299 -36.702492)
		(end 122.3772 -34.149792)
		(width 0.12065)
		(layer "B.Cu")
		(net "CBL_PRSNT_N_1")
	)
	(segment
		(start 133.55828 -33.99028)
		(end 132.783072 -34.765488)
		(width 0.12065)
		(layer "B.Cu")
		(net "CBL_PRSNT_N_1")
	)
	(segment
		(start 76.13015 -96.980756)
		(end 80.433926 -92.67698)
		(width 0.12065)
		(layer "B.Cu")
		(net "CBL_PRSNT_N_1")
	)
	(segment
		(start 80.433926 -90.419174)
		(end 81.649316 -89.203784)
		(width 0.12065)
		(layer "B.Cu")
		(net "CBL_PRSNT_N_1")
	)
	(segment
		(start 75.152504 -132.2832)
		(end 75.152504 -131.77266)
		(width 0.12065)
		(layer "B.Cu")
		(net "CBL_PRSNT_N_1")
	)
	(segment
		(start 76.13015 -103.63835)
		(end 76.13015 -96.980756)
		(width 0.12065)
		(layer "B.Cu")
		(net "CBL_PRSNT_N_1")
	)
	(segment
		(start 117.27942 -33.4772)
		(end 111.12754 -33.4772)
		(width 0.12065)
		(layer "B.Cu")
		(net "CBL_PRSNT_N_1")
	)
	(segment
		(start 76.111862 -122.42419)
		(end 75.835256 -122.147584)
		(width 0.12065)
		(layer "B.Cu")
		(net "CBL_PRSNT_N_1")
	)
	(segment
		(start 75.54595 -131.379722)
		(end 76.111862 -130.81381)
		(width 0.12065)
		(layer "B.Cu")
		(net "CBL_PRSNT_N_1")
	)
	(segment
		(start 132.783072 -35.475672)
		(end 132.969 -35.6616)
		(width 0.12065)
		(layer "B.Cu")
		(net "CBL_PRSNT_N_1")
	)
	(segment
		(start 75.835256 -119.725694)
		(end 74.619358 -118.509796)
		(width 0.12065)
		(layer "B.Cu")
		(net "CBL_PRSNT_N_1")
	)
	(segment
		(start 99.974654 -42.7228)
		(end 92.489528 -50.207926)
		(width 0.12065)
		(layer "B.Cu")
		(net "CBL_PRSNT_N_1")
	)
	(segment
		(start 76.2762 -103.7844)
		(end 76.13015 -103.63835)
		(width 0.12065)
		(layer "B.Cu")
		(net "CBL_PRSNT_N_1")
	)
	(segment
		(start 134.3914 -33.15716)
		(end 134.3914 -31.9024)
		(width 0.12065)
		(layer "B.Cu")
		(net "CBL_PRSNT_N_1")
	)
	(segment
		(start 74.619104 -116.024152)
		(end 74.619104 -112.096296)
		(width 0.12065)
		(layer "B.Cu")
		(net "CBL_PRSNT_N_1")
	)
	(segment
		(start 129.379726 -35.955986)
		(end 129.379726 -35.47237)
		(width 0.12065)
		(layer "B.Cu")
		(net "CBL_PRSNT_N_1")
	)
	(segment
		(start 76.2762 -110.4392)
		(end 76.2762 -103.7844)
		(width 0.12065)
		(layer "B.Cu")
		(net "CBL_PRSNT_N_1")
	)
	(segment
		(start 74.619358 -118.509796)
		(end 74.619104 -116.024152)
		(width 0.12065)
		(layer "B.Cu")
		(net "CBL_PRSNT_N_1")
	)
	(segment
		(start 88.9762 -84.3026)
		(end 86.5505 -84.3026)
		(width 0.12065)
		(layer "B.Cu")
		(net "CBL_PRSNT_N_1")
	)
	(segment
		(start 75.152504 -131.77266)
		(end 75.545442 -131.379722)
		(width 0.12065)
		(layer "B.Cu")
		(net "CBL_PRSNT_N_1")
	)
	(segment
		(start 76.111862 -130.81381)
		(end 76.111862 -122.42419)
		(width 0.12065)
		(layer "B.Cu")
		(net "CBL_PRSNT_N_1")
	)
	(segment
		(start 132.783072 -34.765488)
		(end 132.783072 -35.475672)
		(width 0.12065)
		(layer "B.Cu")
		(net "CBL_PRSNT_N_1")
	)
	(segment
		(start 75.835256 -122.147584)
		(end 75.835256 -119.725694)
		(width 0.12065)
		(layer "B.Cu")
		(net "CBL_PRSNT_N_1")
	)
	(segment
		(start 122.3772 -34.149792)
		(end 117.952012 -34.149792)
		(width 0.12065)
		(layer "B.Cu")
		(net "CBL_PRSNT_N_1")
	)
	(segment
		(start 101.88194 -42.7228)
		(end 99.974654 -42.7228)
		(width 0.12065)
		(layer "B.Cu")
		(net "CBL_PRSNT_N_1")
	)
	(segment
		(start 124.930154 -36.702492)
		(end 124.9299 -36.702492)
		(width 0.12065)
		(layer "B.Cu")
		(net "CBL_PRSNT_N_1")
	)
	(segment
		(start 75.545442 -131.379722)
		(end 75.54595 -131.379722)
		(width 0.12065)
		(layer "B.Cu")
		(net "CBL_PRSNT_N_1")
	)
	(segment
		(start 133.55828 -33.99028)
		(end 134.3914 -33.15716)
		(width 0.12065)
		(layer "B.Cu")
		(net "CBL_PRSNT_N_1")
	)
	(segment
		(start 132.264404 -36.84905)
		(end 125.076712 -36.84905)
		(width 0.12065)
		(layer "B.Cu")
		(net "CBL_PRSNT_N_1")
	)
	(segment
		(start 134.3914 -31.9024)
		(end 134.8232 -31.4706)
		(width 0.12065)
		(layer "B.Cu")
		(net "CBL_PRSNT_N_1")
	)
	(segment
		(start 86.5505 -84.3026)
		(end 81.649316 -89.203784)
		(width 0.12065)
		(layer "B.Cu")
		(net "CBL_PRSNT_N_1")
	)
	(segment
		(start 129.379726 -35.47237)
		(end 130.51028 -34.341816)
		(width 0.12065)
		(layer "B.Cu")
		(net "CBL_PRSNT_N_1")
	)
	(segment
		(start 52.3748 -136.0424)
		(end 51.6382 -136.779)
		(width 0.127)
		(layer "In2.Cu")
		(net "CBL_PRSNT_N_1")
	)
	(segment
		(start 75.152504 -132.2832)
		(end 71.901304 -135.5344)
		(width 0.127)
		(layer "In2.Cu")
		(net "CBL_PRSNT_N_1")
	)
	(segment
		(start 129.5654 -32.9946)
		(end 129.5654 -35.770312)
		(width 0.127)
		(layer "In2.Cu")
		(net "CBL_PRSNT_N_1")
	)
	(segment
		(start 134.8232 -31.4706)
		(end 131.0894 -31.4706)
		(width 0.127)
		(layer "In2.Cu")
		(net "CBL_PRSNT_N_1")
	)
	(segment
		(start 55.913782 -136.0424)
		(end 52.3748 -136.0424)
		(width 0.127)
		(layer "In2.Cu")
		(net "CBL_PRSNT_N_1")
	)
	(segment
		(start 129.5654 -35.770312)
		(end 129.379726 -35.955986)
		(width 0.127)
		(layer "In2.Cu")
		(net "CBL_PRSNT_N_1")
	)
	(segment
		(start 71.901304 -135.5344)
		(end 56.421782 -135.5344)
		(width 0.127)
		(layer "In2.Cu")
		(net "CBL_PRSNT_N_1")
	)
	(segment
		(start 56.421782 -135.5344)
		(end 55.913782 -136.0424)
		(width 0.127)
		(layer "In2.Cu")
		(net "CBL_PRSNT_N_1")
	)
	(segment
		(start 131.0894 -31.4706)
		(end 129.5654 -32.9946)
		(width 0.127)
		(layer "In2.Cu")
		(net "CBL_PRSNT_N_1")
	)
	(segment
		(start 39.89451 -100.414074)
		(end 39.9034 -100.422964)
		(width 0.12065)
		(layer "F.Cu")
		(net "BUS_SW_OE#")
	)
	(segment
		(start 39.1287 -101.5111)
		(end 39.1287 -102.1588)
		(width 0.12065)
		(layer "F.Cu")
		(net "BUS_SW_OE#")
	)
	(segment
		(start 39.9034 -100.422964)
		(end 39.9034 -100.7364)
		(width 0.12065)
		(layer "F.Cu")
		(net "BUS_SW_OE#")
	)
	(segment
		(start 39.9034 -100.7364)
		(end 39.1287 -101.5111)
		(width 0.12065)
		(layer "F.Cu")
		(net "BUS_SW_OE#")
	)
	(segment
		(start 39.89451 -100.06711)
		(end 39.89451 -100.414074)
		(width 0.12065)
		(layer "F.Cu")
		(net "BUS_SW_OE#")
	)
	(segment
		(start 39.629334 -99.801934)
		(end 39.89451 -100.06711)
		(width 0.12065)
		(layer "F.Cu")
		(net "BUS_SW_OE#")
	)
	(segment
		(start 38.1 -99.801934)
		(end 39.629334 -99.801934)
		(width 0.12065)
		(layer "F.Cu")
		(net "BUS_SW_OE#")
	)
	(via
		(at 39.89451 -100.414074)
		(size 0.7112)
		(drill 0.3556)
		(layers "F.Cu" "B.Cu")
		(net "BUS_SW_OE#")
	)
	(segment
		(start 41.5544 -192.405)
		(end 41.5925 -192.4431)
		(width 0.12065)
		(layer "F.Cu")
		(net "BUF_I2C9_CLKBUF2_SDA_R")
	)
	(segment
		(start 42.760646 -189.928754)
		(end 42.760646 -188.366654)
		(width 0.12065)
		(layer "F.Cu")
		(net "BUF_I2C9_CLKBUF2_SDA_R")
	)
	(segment
		(start 42.272712 -187.87872)
		(end 40.9067 -187.87872)
		(width 0.12065)
		(layer "F.Cu")
		(net "BUF_I2C9_CLKBUF2_SDA_R")
	)
	(segment
		(start 42.5323 -192.3796)
		(end 42.5323 -191.3636)
		(width 0.12065)
		(layer "F.Cu")
		(net "BUF_I2C9_CLKBUF2_SDA_R")
	)
	(segment
		(start 42.760646 -188.366654)
		(end 42.272712 -187.87872)
		(width 0.12065)
		(layer "F.Cu")
		(net "BUF_I2C9_CLKBUF2_SDA_R")
	)
	(segment
		(start 42.4688 -192.4431)
		(end 42.5323 -192.3796)
		(width 0.12065)
		(layer "F.Cu")
		(net "BUF_I2C9_CLKBUF2_SDA_R")
	)
	(segment
		(start 42.4688 -190.2206)
		(end 42.4688 -191.3001)
		(width 0.12065)
		(layer "F.Cu")
		(net "BUF_I2C9_CLKBUF2_SDA_R")
	)
	(segment
		(start 42.4688 -191.3001)
		(end 42.5323 -191.3636)
		(width 0.12065)
		(layer "F.Cu")
		(net "BUF_I2C9_CLKBUF2_SDA_R")
	)
	(segment
		(start 42.4688 -190.2206)
		(end 42.760646 -189.928754)
		(width 0.12065)
		(layer "F.Cu")
		(net "BUF_I2C9_CLKBUF2_SDA_R")
	)
	(segment
		(start 41.5925 -192.4431)
		(end 42.4688 -192.4431)
		(width 0.12065)
		(layer "F.Cu")
		(net "BUF_I2C9_CLKBUF2_SDA_R")
	)
	(via
		(at 41.5544 -192.405)
		(size 0.7112)
		(drill 0.3556)
		(layers "F.Cu" "B.Cu")
		(net "BUF_I2C9_CLKBUF2_SDA_R")
	)
	(segment
		(start 42.72915 -194.12585)
		(end 42.72915 -193.59245)
		(width 0.12065)
		(layer "F.Cu")
		(net "BUF_I2C9_CLKBUF2_SDA")
	)
	(segment
		(start 41.457372 -210.267804)
		(end 45.649388 -206.075788)
		(width 0.12065)
		(layer "F.Cu")
		(net "BUF_I2C9_CLKBUF2_SDA")
	)
	(segment
		(start 42.687748 -194.401948)
		(end 42.5704 -194.2846)
		(width 0.12065)
		(layer "F.Cu")
		(net "BUF_I2C9_CLKBUF2_SDA")
	)
	(segment
		(start 42.5704 -194.2846)
		(end 42.72915 -194.12585)
		(width 0.12065)
		(layer "F.Cu")
		(net "BUF_I2C9_CLKBUF2_SDA")
	)
	(segment
		(start 42.72915 -193.59245)
		(end 42.4688 -193.3321)
		(width 0.12065)
		(layer "F.Cu")
		(net "BUF_I2C9_CLKBUF2_SDA")
	)
	(segment
		(start 42.687748 -195.358512)
		(end 42.687748 -194.401948)
		(width 0.12065)
		(layer "F.Cu")
		(net "BUF_I2C9_CLKBUF2_SDA")
	)
	(segment
		(start 45.649388 -206.075788)
		(end 45.649388 -198.320152)
		(width 0.12065)
		(layer "F.Cu")
		(net "BUF_I2C9_CLKBUF2_SDA")
	)
	(segment
		(start 45.649388 -198.320152)
		(end 42.687748 -195.358512)
		(width 0.12065)
		(layer "F.Cu")
		(net "BUF_I2C9_CLKBUF2_SDA")
	)
	(segment
		(start 41.300146 -224.199958)
		(end 41.457372 -224.042732)
		(width 0.12065)
		(layer "F.Cu")
		(net "BUF_I2C9_CLKBUF2_SDA")
	)
	(segment
		(start 41.457372 -224.042732)
		(end 41.457372 -210.267804)
		(width 0.12065)
		(layer "F.Cu")
		(net "BUF_I2C9_CLKBUF2_SDA")
	)
	(segment
		(start 41.300146 -225.54438)
		(end 41.300146 -224.199958)
		(width 0.12065)
		(layer "F.Cu")
		(net "BUF_I2C9_CLKBUF2_SDA")
	)
	(via
		(at 42.44975 -192.809622)
		(size 0.7112)
		(drill 0.3556)
		(layers "F.Cu" "B.Cu")
		(net "BUF_I2C9_CLKBUF2_SDA")
	)
	(via
		(at 42.5704 -194.2846)
		(size 0.508)
		(drill 0.254)
		(layers "F.Cu" "B.Cu")
		(net "BUF_I2C9_CLKBUF2_SDA")
	)
	(segment
		(start 42.76852 -192.809622)
		(end 42.76852 -188.12002)
		(width 0.12065)
		(layer "B.Cu")
		(net "BUF_I2C9_CLKBUF2_SDA")
	)
	(segment
		(start 42.5704 -194.2846)
		(end 42.76852 -194.08648)
		(width 0.12065)
		(layer "B.Cu")
		(net "BUF_I2C9_CLKBUF2_SDA")
	)
	(segment
		(start 42.76852 -192.809622)
		(end 42.44975 -192.809622)
		(width 0.12065)
		(layer "B.Cu")
		(net "BUF_I2C9_CLKBUF2_SDA")
	)
	(segment
		(start 42.76852 -188.12002)
		(end 42.4942 -187.8457)
		(width 0.12065)
		(layer "B.Cu")
		(net "BUF_I2C9_CLKBUF2_SDA")
	)
	(segment
		(start 42.76852 -194.08648)
		(end 42.76852 -192.809622)
		(width 0.12065)
		(layer "B.Cu")
		(net "BUF_I2C9_CLKBUF2_SDA")
	)
	(segment
		(start 43.6118 -192.4431)
		(end 44.4881 -192.4431)
		(width 0.12065)
		(layer "F.Cu")
		(net "BUF_I2C9_CLKBUF2_SCL_R")
	)
	(segment
		(start 43.6118 -192.4431)
		(end 43.5483 -192.3796)
		(width 0.12065)
		(layer "F.Cu")
		(net "BUF_I2C9_CLKBUF2_SCL_R")
	)
	(segment
		(start 43.6118 -190.2206)
		(end 43.262296 -189.871096)
		(width 0.12065)
		(layer "F.Cu")
		(net "BUF_I2C9_CLKBUF2_SCL_R")
	)
	(segment
		(start 43.5483 -192.3796)
		(end 43.5483 -191.3636)
		(width 0.12065)
		(layer "F.Cu")
		(net "BUF_I2C9_CLKBUF2_SCL_R")
	)
	(segment
		(start 43.6118 -190.2206)
		(end 43.6118 -191.3001)
		(width 0.12065)
		(layer "F.Cu")
		(net "BUF_I2C9_CLKBUF2_SCL_R")
	)
	(segment
		(start 43.262296 -189.871096)
		(end 43.262296 -188.350906)
		(width 0.12065)
		(layer "F.Cu")
		(net "BUF_I2C9_CLKBUF2_SCL_R")
	)
	(segment
		(start 43.262296 -188.350906)
		(end 43.734482 -187.87872)
		(width 0.12065)
		(layer "F.Cu")
		(net "BUF_I2C9_CLKBUF2_SCL_R")
	)
	(segment
		(start 44.4881 -192.4431)
		(end 44.5262 -192.405)
		(width 0.12065)
		(layer "F.Cu")
		(net "BUF_I2C9_CLKBUF2_SCL_R")
	)
	(segment
		(start 43.734482 -187.87872)
		(end 45.0469 -187.87872)
		(width 0.12065)
		(layer "F.Cu")
		(net "BUF_I2C9_CLKBUF2_SCL_R")
	)
	(segment
		(start 43.6118 -191.3001)
		(end 43.5483 -191.3636)
		(width 0.12065)
		(layer "F.Cu")
		(net "BUF_I2C9_CLKBUF2_SCL_R")
	)
	(via
		(at 44.5262 -192.405)
		(size 0.7112)
		(drill 0.3556)
		(layers "F.Cu" "B.Cu")
		(net "BUF_I2C9_CLKBUF2_SCL_R")
	)
	(segment
		(start 43.2308 -194.0814)
		(end 43.2308 -193.7131)
		(width 0.12065)
		(layer "F.Cu")
		(net "BUF_I2C9_CLKBUF2_SCL")
	)
	(segment
		(start 43.189398 -195.150486)
		(end 43.189398 -194.529202)
		(width 0.12065)
		(layer "F.Cu")
		(net "BUF_I2C9_CLKBUF2_SCL")
	)
	(segment
		(start 41.959022 -210.47583)
		(end 46.151038 -206.283814)
		(width 0.12065)
		(layer "F.Cu")
		(net "BUF_I2C9_CLKBUF2_SCL")
	)
	(segment
		(start 46.151038 -198.112126)
		(end 43.189398 -195.150486)
		(width 0.12065)
		(layer "F.Cu")
		(net "BUF_I2C9_CLKBUF2_SCL")
	)
	(segment
		(start 43.189398 -194.529202)
		(end 43.434 -194.2846)
		(width 0.12065)
		(layer "F.Cu")
		(net "BUF_I2C9_CLKBUF2_SCL")
	)
	(segment
		(start 46.151038 -206.283814)
		(end 46.151038 -198.112126)
		(width 0.12065)
		(layer "F.Cu")
		(net "BUF_I2C9_CLKBUF2_SCL")
	)
	(segment
		(start 42.099992 -225.54438)
		(end 42.099992 -224.199958)
		(width 0.12065)
		(layer "F.Cu")
		(net "BUF_I2C9_CLKBUF2_SCL")
	)
	(segment
		(start 43.434 -194.2846)
		(end 43.2308 -194.0814)
		(width 0.12065)
		(layer "F.Cu")
		(net "BUF_I2C9_CLKBUF2_SCL")
	)
	(segment
		(start 43.2308 -193.7131)
		(end 43.6118 -193.3321)
		(width 0.12065)
		(layer "F.Cu")
		(net "BUF_I2C9_CLKBUF2_SCL")
	)
	(segment
		(start 42.099992 -224.199958)
		(end 41.959022 -224.058988)
		(width 0.12065)
		(layer "F.Cu")
		(net "BUF_I2C9_CLKBUF2_SCL")
	)
	(segment
		(start 41.959022 -224.058988)
		(end 41.959022 -210.47583)
		(width 0.12065)
		(layer "F.Cu")
		(net "BUF_I2C9_CLKBUF2_SCL")
	)
	(via
		(at 43.434 -194.2846)
		(size 0.508)
		(drill 0.254)
		(layers "F.Cu" "B.Cu")
		(net "BUF_I2C9_CLKBUF2_SCL")
	)
	(via
		(at 43.619166 -189.91453)
		(size 0.7112)
		(drill 0.3556)
		(layers "F.Cu" "B.Cu")
		(net "BUF_I2C9_CLKBUF2_SCL")
	)
	(segment
		(start 43.27017 -188.08573)
		(end 43.5102 -187.8457)
		(width 0.12065)
		(layer "B.Cu")
		(net "BUF_I2C9_CLKBUF2_SCL")
	)
	(segment
		(start 43.27017 -194.12077)
		(end 43.27017 -189.91453)
		(width 0.12065)
		(layer "B.Cu")
		(net "BUF_I2C9_CLKBUF2_SCL")
	)
	(segment
		(start 43.27017 -189.91453)
		(end 43.27017 -188.08573)
		(width 0.12065)
		(layer "B.Cu")
		(net "BUF_I2C9_CLKBUF2_SCL")
	)
	(segment
		(start 43.27017 -189.91453)
		(end 43.619166 -189.91453)
		(width 0.12065)
		(layer "B.Cu")
		(net "BUF_I2C9_CLKBUF2_SCL")
	)
	(segment
		(start 43.434 -194.2846)
		(end 43.27017 -194.12077)
		(width 0.12065)
		(layer "B.Cu")
		(net "BUF_I2C9_CLKBUF2_SCL")
	)
	(segment
		(start 50.673 -184.15)
		(end 50.981356 -183.841644)
		(width 0.12065)
		(layer "F.Cu")
		(net "BUF_I2C8_CLKBUF1_SDA_R")
	)
	(segment
		(start 50.7365 -185.293)
		(end 50.673 -185.2295)
		(width 0.12065)
		(layer "F.Cu")
		(net "BUF_I2C8_CLKBUF1_SDA_R")
	)
	(segment
		(start 50.673 -185.2295)
		(end 50.673 -184.15)
		(width 0.12065)
		(layer "F.Cu")
		(net "BUF_I2C8_CLKBUF1_SDA_R")
	)
	(segment
		(start 50.673 -186.3725)
		(end 50.7365 -186.309)
		(width 0.12065)
		(layer "F.Cu")
		(net "BUF_I2C8_CLKBUF1_SDA_R")
	)
	(segment
		(start 50.7365 -186.309)
		(end 50.7365 -185.293)
		(width 0.12065)
		(layer "F.Cu")
		(net "BUF_I2C8_CLKBUF1_SDA_R")
	)
	(segment
		(start 50.23612 -181.80812)
		(end 49.1109 -181.80812)
		(width 0.12065)
		(layer "F.Cu")
		(net "BUF_I2C8_CLKBUF1_SDA_R")
	)
	(segment
		(start 49.8475 -186.3725)
		(end 49.7586 -186.2836)
		(width 0.12065)
		(layer "F.Cu")
		(net "BUF_I2C8_CLKBUF1_SDA_R")
	)
	(segment
		(start 50.673 -186.3725)
		(end 49.8475 -186.3725)
		(width 0.12065)
		(layer "F.Cu")
		(net "BUF_I2C8_CLKBUF1_SDA_R")
	)
	(segment
		(start 50.981356 -182.553356)
		(end 50.23612 -181.80812)
		(width 0.12065)
		(layer "F.Cu")
		(net "BUF_I2C8_CLKBUF1_SDA_R")
	)
	(segment
		(start 50.981356 -183.841644)
		(end 50.981356 -182.553356)
		(width 0.12065)
		(layer "F.Cu")
		(net "BUF_I2C8_CLKBUF1_SDA_R")
	)
	(via
		(at 49.7586 -186.2836)
		(size 0.7112)
		(drill 0.3556)
		(layers "F.Cu" "B.Cu")
		(net "BUF_I2C8_CLKBUF1_SDA_R")
	)
	(segment
		(start 56.474868 -198.306182)
		(end 44.200572 -210.580478)
		(width 0.12065)
		(layer "F.Cu")
		(net "BUF_I2C8_CLKBUF1_SDA")
	)
	(segment
		(start 50.97272 -188.41212)
		(end 50.97272 -188.88075)
		(width 0.12065)
		(layer "F.Cu")
		(net "BUF_I2C8_CLKBUF1_SDA")
	)
	(segment
		(start 50.936906 -188.051694)
		(end 50.7746 -188.214)
		(width 0.12065)
		(layer "F.Cu")
		(net "BUF_I2C8_CLKBUF1_SDA")
	)
	(segment
		(start 54.356 -189.398148)
		(end 56.474868 -191.517016)
		(width 0.12065)
		(layer "F.Cu")
		(net "BUF_I2C8_CLKBUF1_SDA")
	)
	(segment
		(start 50.97272 -188.88075)
		(end 51.490118 -189.398148)
		(width 0.12065)
		(layer "F.Cu")
		(net "BUF_I2C8_CLKBUF1_SDA")
	)
	(segment
		(start 51.490118 -189.398148)
		(end 54.356 -189.398148)
		(width 0.12065)
		(layer "F.Cu")
		(net "BUF_I2C8_CLKBUF1_SDA")
	)
	(segment
		(start 50.7746 -188.214)
		(end 50.97272 -188.41212)
		(width 0.12065)
		(layer "F.Cu")
		(net "BUF_I2C8_CLKBUF1_SDA")
	)
	(segment
		(start 44.200572 -210.580478)
		(end 44.200572 -220.238828)
		(width 0.12065)
		(layer "F.Cu")
		(net "BUF_I2C8_CLKBUF1_SDA")
	)
	(segment
		(start 44.200572 -220.238828)
		(end 44.069 -220.3704)
		(width 0.12065)
		(layer "F.Cu")
		(net "BUF_I2C8_CLKBUF1_SDA")
	)
	(segment
		(start 50.936906 -187.525406)
		(end 50.936906 -188.051694)
		(width 0.12065)
		(layer "F.Cu")
		(net "BUF_I2C8_CLKBUF1_SDA")
	)
	(segment
		(start 50.673 -187.2615)
		(end 50.936906 -187.525406)
		(width 0.12065)
		(layer "F.Cu")
		(net "BUF_I2C8_CLKBUF1_SDA")
	)
	(segment
		(start 56.474868 -191.517016)
		(end 56.474868 -198.306182)
		(width 0.12065)
		(layer "F.Cu")
		(net "BUF_I2C8_CLKBUF1_SDA")
	)
	(via
		(at 50.650394 -183.268112)
		(size 0.7112)
		(drill 0.3556)
		(layers "F.Cu" "B.Cu")
		(net "BUF_I2C8_CLKBUF1_SDA")
	)
	(via
		(at 44.069 -220.3704)
		(size 0.508)
		(drill 0.254)
		(layers "F.Cu" "B.Cu")
		(net "BUF_I2C8_CLKBUF1_SDA")
	)
	(via
		(at 50.7746 -188.214)
		(size 0.508)
		(drill 0.254)
		(layers "F.Cu" "B.Cu")
		(net "BUF_I2C8_CLKBUF1_SDA")
	)
	(segment
		(start 45.454316 -222.734124)
		(end 44.232322 -221.51213)
		(width 0.12065)
		(layer "B.Cu")
		(net "BUF_I2C8_CLKBUF1_SDA")
	)
	(segment
		(start 45.300138 -224.199958)
		(end 45.454316 -224.04578)
		(width 0.12065)
		(layer "B.Cu")
		(net "BUF_I2C8_CLKBUF1_SDA")
	)
	(segment
		(start 45.454316 -224.04578)
		(end 45.454316 -222.734124)
		(width 0.12065)
		(layer "B.Cu")
		(net "BUF_I2C8_CLKBUF1_SDA")
	)
	(segment
		(start 50.969164 -183.268112)
		(end 50.969164 -182.223664)
		(width 0.12065)
		(layer "B.Cu")
		(net "BUF_I2C8_CLKBUF1_SDA")
	)
	(segment
		(start 45.300138 -225.92538)
		(end 45.300138 -224.199958)
		(width 0.12065)
		(layer "B.Cu")
		(net "BUF_I2C8_CLKBUF1_SDA")
	)
	(segment
		(start 50.969164 -182.223664)
		(end 50.673 -181.9275)
		(width 0.12065)
		(layer "B.Cu")
		(net "BUF_I2C8_CLKBUF1_SDA")
	)
	(segment
		(start 44.232322 -221.51213)
		(end 44.232322 -220.533722)
		(width 0.12065)
		(layer "B.Cu")
		(net "BUF_I2C8_CLKBUF1_SDA")
	)
	(segment
		(start 44.232322 -220.533722)
		(end 44.069 -220.3704)
		(width 0.12065)
		(layer "B.Cu")
		(net "BUF_I2C8_CLKBUF1_SDA")
	)
	(segment
		(start 50.969164 -188.019436)
		(end 50.969164 -183.268112)
		(width 0.12065)
		(layer "B.Cu")
		(net "BUF_I2C8_CLKBUF1_SDA")
	)
	(segment
		(start 50.7746 -188.214)
		(end 50.969164 -188.019436)
		(width 0.12065)
		(layer "B.Cu")
		(net "BUF_I2C8_CLKBUF1_SDA")
	)
	(segment
		(start 50.969164 -183.268112)
		(end 50.650394 -183.268112)
		(width 0.12065)
		(layer "B.Cu")
		(net "BUF_I2C8_CLKBUF1_SDA")
	)
	(segment
		(start 51.7525 -185.293)
		(end 51.816 -185.2295)
		(width 0.12065)
		(layer "F.Cu")
		(net "BUF_I2C8_CLKBUF1_SCL_R")
	)
	(segment
		(start 51.483006 -182.57774)
		(end 52.252626 -181.80812)
		(width 0.12065)
		(layer "F.Cu")
		(net "BUF_I2C8_CLKBUF1_SCL_R")
	)
	(segment
		(start 52.6669 -186.3725)
		(end 52.7304 -186.309)
		(width 0.12065)
		(layer "F.Cu")
		(net "BUF_I2C8_CLKBUF1_SCL_R")
	)
	(segment
		(start 51.816 -186.3725)
		(end 51.7525 -186.309)
		(width 0.12065)
		(layer "F.Cu")
		(net "BUF_I2C8_CLKBUF1_SCL_R")
	)
	(segment
		(start 51.483006 -183.817006)
		(end 51.483006 -182.57774)
		(width 0.12065)
		(layer "F.Cu")
		(net "BUF_I2C8_CLKBUF1_SCL_R")
	)
	(segment
		(start 51.7525 -186.309)
		(end 51.7525 -185.293)
		(width 0.12065)
		(layer "F.Cu")
		(net "BUF_I2C8_CLKBUF1_SCL_R")
	)
	(segment
		(start 51.816 -185.2295)
		(end 51.816 -184.15)
		(width 0.12065)
		(layer "F.Cu")
		(net "BUF_I2C8_CLKBUF1_SCL_R")
	)
	(segment
		(start 51.816 -186.3725)
		(end 52.6669 -186.3725)
		(width 0.12065)
		(layer "F.Cu")
		(net "BUF_I2C8_CLKBUF1_SCL_R")
	)
	(segment
		(start 52.252626 -181.80812)
		(end 53.2511 -181.80812)
		(width 0.12065)
		(layer "F.Cu")
		(net "BUF_I2C8_CLKBUF1_SCL_R")
	)
	(segment
		(start 51.816 -184.15)
		(end 51.483006 -183.817006)
		(width 0.12065)
		(layer "F.Cu")
		(net "BUF_I2C8_CLKBUF1_SCL_R")
	)
	(via
		(at 52.7304 -186.309)
		(size 0.7112)
		(drill 0.3556)
		(layers "F.Cu" "B.Cu")
		(net "BUF_I2C8_CLKBUF1_SCL_R")
	)
	(segment
		(start 51.47437 -188.672724)
		(end 51.698144 -188.896498)
		(width 0.12065)
		(layer "F.Cu")
		(net "BUF_I2C8_CLKBUF1_SCL")
	)
	(segment
		(start 56.976518 -198.514208)
		(end 44.702222 -210.788504)
		(width 0.12065)
		(layer "F.Cu")
		(net "BUF_I2C8_CLKBUF1_SCL")
	)
	(segment
		(start 51.698144 -188.896498)
		(end 54.564026 -188.896498)
		(width 0.12065)
		(layer "F.Cu")
		(net "BUF_I2C8_CLKBUF1_SCL")
	)
	(segment
		(start 44.702222 -210.788504)
		(end 44.702222 -220.140022)
		(width 0.12065)
		(layer "F.Cu")
		(net "BUF_I2C8_CLKBUF1_SCL")
	)
	(segment
		(start 51.438556 -188.014356)
		(end 51.6382 -188.214)
		(width 0.12065)
		(layer "F.Cu")
		(net "BUF_I2C8_CLKBUF1_SCL")
	)
	(segment
		(start 51.816 -187.2615)
		(end 51.438556 -187.638944)
		(width 0.12065)
		(layer "F.Cu")
		(net "BUF_I2C8_CLKBUF1_SCL")
	)
	(segment
		(start 51.438556 -187.638944)
		(end 51.438556 -188.014356)
		(width 0.12065)
		(layer "F.Cu")
		(net "BUF_I2C8_CLKBUF1_SCL")
	)
	(segment
		(start 51.47437 -188.37783)
		(end 51.47437 -188.672724)
		(width 0.12065)
		(layer "F.Cu")
		(net "BUF_I2C8_CLKBUF1_SCL")
	)
	(segment
		(start 44.702222 -220.140022)
		(end 44.9326 -220.3704)
		(width 0.12065)
		(layer "F.Cu")
		(net "BUF_I2C8_CLKBUF1_SCL")
	)
	(segment
		(start 51.6382 -188.214)
		(end 51.47437 -188.37783)
		(width 0.12065)
		(layer "F.Cu")
		(net "BUF_I2C8_CLKBUF1_SCL")
	)
	(segment
		(start 56.976518 -191.30899)
		(end 56.976518 -198.514208)
		(width 0.12065)
		(layer "F.Cu")
		(net "BUF_I2C8_CLKBUF1_SCL")
	)
	(segment
		(start 54.564026 -188.896498)
		(end 56.976518 -191.30899)
		(width 0.12065)
		(layer "F.Cu")
		(net "BUF_I2C8_CLKBUF1_SCL")
	)
	(via
		(at 51.81981 -186.29503)
		(size 0.7112)
		(drill 0.3556)
		(layers "F.Cu" "B.Cu")
		(net "BUF_I2C8_CLKBUF1_SCL")
	)
	(via
		(at 51.6382 -188.214)
		(size 0.508)
		(drill 0.254)
		(layers "F.Cu" "B.Cu")
		(net "BUF_I2C8_CLKBUF1_SCL")
	)
	(via
		(at 44.9326 -220.3704)
		(size 0.508)
		(drill 0.254)
		(layers "F.Cu" "B.Cu")
		(net "BUF_I2C8_CLKBUF1_SCL")
	)
	(segment
		(start 44.733972 -220.569028)
		(end 44.9326 -220.3704)
		(width 0.12065)
		(layer "B.Cu")
		(net "BUF_I2C8_CLKBUF1_SCL")
	)
	(segment
		(start 45.955966 -224.05594)
		(end 45.955966 -222.526098)
		(width 0.12065)
		(layer "B.Cu")
		(net "BUF_I2C8_CLKBUF1_SCL")
	)
	(segment
		(start 51.6382 -188.214)
		(end 51.470814 -188.046614)
		(width 0.12065)
		(layer "B.Cu")
		(net "BUF_I2C8_CLKBUF1_SCL")
	)
	(segment
		(start 46.099984 -224.199958)
		(end 45.955966 -224.05594)
		(width 0.12065)
		(layer "B.Cu")
		(net "BUF_I2C8_CLKBUF1_SCL")
	)
	(segment
		(start 51.470814 -186.29503)
		(end 51.470814 -182.145686)
		(width 0.12065)
		(layer "B.Cu")
		(net "BUF_I2C8_CLKBUF1_SCL")
	)
	(segment
		(start 44.733972 -221.304104)
		(end 44.733972 -220.569028)
		(width 0.12065)
		(layer "B.Cu")
		(net "BUF_I2C8_CLKBUF1_SCL")
	)
	(segment
		(start 46.099984 -225.92538)
		(end 46.099984 -224.199958)
		(width 0.12065)
		(layer "B.Cu")
		(net "BUF_I2C8_CLKBUF1_SCL")
	)
	(segment
		(start 51.470814 -186.29503)
		(end 51.81981 -186.29503)
		(width 0.12065)
		(layer "B.Cu")
		(net "BUF_I2C8_CLKBUF1_SCL")
	)
	(segment
		(start 51.470814 -182.145686)
		(end 51.689 -181.9275)
		(width 0.12065)
		(layer "B.Cu")
		(net "BUF_I2C8_CLKBUF1_SCL")
	)
	(segment
		(start 51.470814 -188.046614)
		(end 51.470814 -186.29503)
		(width 0.12065)
		(layer "B.Cu")
		(net "BUF_I2C8_CLKBUF1_SCL")
	)
	(segment
		(start 45.955966 -222.526098)
		(end 44.733972 -221.304104)
		(width 0.12065)
		(layer "B.Cu")
		(net "BUF_I2C8_CLKBUF1_SCL")
	)
	(segment
		(start 50.546 -195.90512)
		(end 50.988468 -196.347588)
		(width 0.12065)
		(layer "F.Cu")
		(net "BUF_I2C7_B_DPB_SDA_R")
	)
	(segment
		(start 49.7713 -200.4695)
		(end 49.7586 -200.4568)
		(width 0.12065)
		(layer "F.Cu")
		(net "BUF_I2C7_B_DPB_SDA_R")
	)
	(segment
		(start 50.673 -200.4695)
		(end 50.7365 -200.406)
		(width 0.12065)
		(layer "F.Cu")
		(net "BUF_I2C7_B_DPB_SDA_R")
	)
	(segment
		(start 50.673 -199.3265)
		(end 50.673 -198.247)
		(width 0.12065)
		(layer "F.Cu")
		(net "BUF_I2C7_B_DPB_SDA_R")
	)
	(segment
		(start 50.7365 -199.39)
		(end 50.673 -199.3265)
		(width 0.12065)
		(layer "F.Cu")
		(net "BUF_I2C7_B_DPB_SDA_R")
	)
	(segment
		(start 50.7365 -200.406)
		(end 50.7365 -199.39)
		(width 0.12065)
		(layer "F.Cu")
		(net "BUF_I2C7_B_DPB_SDA_R")
	)
	(segment
		(start 50.988468 -196.347588)
		(end 50.988468 -197.931278)
		(width 0.12065)
		(layer "F.Cu")
		(net "BUF_I2C7_B_DPB_SDA_R")
	)
	(segment
		(start 50.673 -200.4695)
		(end 49.7713 -200.4695)
		(width 0.12065)
		(layer "F.Cu")
		(net "BUF_I2C7_B_DPB_SDA_R")
	)
	(segment
		(start 49.1109 -195.90512)
		(end 50.546 -195.90512)
		(width 0.12065)
		(layer "F.Cu")
		(net "BUF_I2C7_B_DPB_SDA_R")
	)
	(segment
		(start 50.988468 -197.931278)
		(end 50.673 -198.247)
		(width 0.12065)
		(layer "F.Cu")
		(net "BUF_I2C7_B_DPB_SDA_R")
	)
	(via
		(at 49.7586 -200.4568)
		(size 0.7112)
		(drill 0.3556)
		(layers "F.Cu" "B.Cu")
		(net "BUF_I2C7_B_DPB_SDA_R")
	)
	(segment
		(start 50.673 -201.3585)
		(end 50.980848 -201.666348)
		(width 0.12065)
		(layer "F.Cu")
		(net "BUF_I2C7_B_DPB_SDA")
	)
	(segment
		(start 43.700192 -224.199958)
		(end 43.850814 -224.049336)
		(width 0.12065)
		(layer "F.Cu")
		(net "BUF_I2C7_B_DPB_SDA")
	)
	(segment
		(start 42.90695 -221.144084)
		(end 42.90695 -210.489292)
		(width 0.12065)
		(layer "F.Cu")
		(net "BUF_I2C7_B_DPB_SDA")
	)
	(segment
		(start 50.980848 -201.666348)
		(end 50.980848 -202.104752)
		(width 0.12065)
		(layer "F.Cu")
		(net "BUF_I2C7_B_DPB_SDA")
	)
	(segment
		(start 50.980848 -202.104752)
		(end 50.7746 -202.311)
		(width 0.12065)
		(layer "F.Cu")
		(net "BUF_I2C7_B_DPB_SDA")
	)
	(segment
		(start 43.850814 -222.087948)
		(end 42.90695 -221.144084)
		(width 0.12065)
		(layer "F.Cu")
		(net "BUF_I2C7_B_DPB_SDA")
	)
	(segment
		(start 50.84445 -202.38085)
		(end 50.7746 -202.311)
		(width 0.12065)
		(layer "F.Cu")
		(net "BUF_I2C7_B_DPB_SDA")
	)
	(segment
		(start 50.84445 -202.551792)
		(end 50.84445 -202.38085)
		(width 0.12065)
		(layer "F.Cu")
		(net "BUF_I2C7_B_DPB_SDA")
	)
	(segment
		(start 42.90695 -210.489292)
		(end 50.84445 -202.551792)
		(width 0.12065)
		(layer "F.Cu")
		(net "BUF_I2C7_B_DPB_SDA")
	)
	(segment
		(start 43.700192 -225.54438)
		(end 43.700192 -224.199958)
		(width 0.12065)
		(layer "F.Cu")
		(net "BUF_I2C7_B_DPB_SDA")
	)
	(segment
		(start 43.850814 -224.049336)
		(end 43.850814 -222.087948)
		(width 0.12065)
		(layer "F.Cu")
		(net "BUF_I2C7_B_DPB_SDA")
	)
	(via
		(at 50.65014 -200.755504)
		(size 0.7112)
		(drill 0.3556)
		(layers "F.Cu" "B.Cu")
		(net "BUF_I2C7_B_DPB_SDA")
	)
	(via
		(at 50.7746 -202.311)
		(size 0.508)
		(drill 0.254)
		(layers "F.Cu" "B.Cu")
		(net "BUF_I2C7_B_DPB_SDA")
	)
	(segment
		(start 50.96891 -200.755504)
		(end 50.65014 -200.755504)
		(width 0.12065)
		(layer "B.Cu")
		(net "BUF_I2C7_B_DPB_SDA")
	)
	(segment
		(start 50.96891 -200.755504)
		(end 50.96891 -196.32041)
		(width 0.12065)
		(layer "B.Cu")
		(net "BUF_I2C7_B_DPB_SDA")
	)
	(segment
		(start 50.96891 -202.11669)
		(end 50.96891 -200.755504)
		(width 0.12065)
		(layer "B.Cu")
		(net "BUF_I2C7_B_DPB_SDA")
	)
	(segment
		(start 50.96891 -196.32041)
		(end 50.673 -196.0245)
		(width 0.12065)
		(layer "B.Cu")
		(net "BUF_I2C7_B_DPB_SDA")
	)
	(segment
		(start 50.7746 -202.311)
		(end 50.96891 -202.11669)
		(width 0.12065)
		(layer "B.Cu")
		(net "BUF_I2C7_B_DPB_SDA")
	)
	(segment
		(start 51.816 -200.4695)
		(end 52.7177 -200.4695)
		(width 0.12065)
		(layer "F.Cu")
		(net "BUF_I2C7_B_DBP_SCL_R")
	)
	(segment
		(start 51.93665 -195.90512)
		(end 53.2511 -195.90512)
		(width 0.12065)
		(layer "F.Cu")
		(net "BUF_I2C7_B_DBP_SCL_R")
	)
	(segment
		(start 51.816 -198.247)
		(end 51.490118 -197.921118)
		(width 0.12065)
		(layer "F.Cu")
		(net "BUF_I2C7_B_DBP_SCL_R")
	)
	(segment
		(start 51.490118 -196.351652)
		(end 51.93665 -195.90512)
		(width 0.12065)
		(layer "F.Cu")
		(net "BUF_I2C7_B_DBP_SCL_R")
	)
	(segment
		(start 51.7525 -200.406)
		(end 51.7525 -199.39)
		(width 0.12065)
		(layer "F.Cu")
		(net "BUF_I2C7_B_DBP_SCL_R")
	)
	(segment
		(start 51.7525 -199.39)
		(end 51.816 -199.3265)
		(width 0.12065)
		(layer "F.Cu")
		(net "BUF_I2C7_B_DBP_SCL_R")
	)
	(segment
		(start 52.7177 -200.4695)
		(end 52.7304 -200.4568)
		(width 0.12065)
		(layer "F.Cu")
		(net "BUF_I2C7_B_DBP_SCL_R")
	)
	(segment
		(start 51.490118 -197.921118)
		(end 51.490118 -196.351652)
		(width 0.12065)
		(layer "F.Cu")
		(net "BUF_I2C7_B_DBP_SCL_R")
	)
	(segment
		(start 51.816 -199.3265)
		(end 51.816 -198.247)
		(width 0.12065)
		(layer "F.Cu")
		(net "BUF_I2C7_B_DBP_SCL_R")
	)
	(segment
		(start 51.816 -200.4695)
		(end 51.7525 -200.406)
		(width 0.12065)
		(layer "F.Cu")
		(net "BUF_I2C7_B_DBP_SCL_R")
	)
	(via
		(at 52.7304 -200.4568)
		(size 0.7112)
		(drill 0.3556)
		(layers "F.Cu" "B.Cu")
		(net "BUF_I2C7_B_DBP_SCL_R")
	)
	(segment
		(start 51.3461 -202.6031)
		(end 51.6382 -202.311)
		(width 0.12065)
		(layer "F.Cu")
		(net "BUF_I2C7_B_DBP_SCL")
	)
	(segment
		(start 44.500038 -225.54438)
		(end 44.500038 -224.199958)
		(width 0.12065)
		(layer "F.Cu")
		(net "BUF_I2C7_B_DBP_SCL")
	)
	(segment
		(start 51.482498 -201.692002)
		(end 51.482498 -202.155298)
		(width 0.12065)
		(layer "F.Cu")
		(net "BUF_I2C7_B_DBP_SCL")
	)
	(segment
		(start 51.3461 -202.759818)
		(end 51.3461 -202.6031)
		(width 0.12065)
		(layer "F.Cu")
		(net "BUF_I2C7_B_DBP_SCL")
	)
	(segment
		(start 51.816 -201.3585)
		(end 51.482498 -201.692002)
		(width 0.12065)
		(layer "F.Cu")
		(net "BUF_I2C7_B_DBP_SCL")
	)
	(segment
		(start 43.4086 -220.936058)
		(end 43.4086 -210.697318)
		(width 0.12065)
		(layer "F.Cu")
		(net "BUF_I2C7_B_DBP_SCL")
	)
	(segment
		(start 51.482498 -202.155298)
		(end 51.6382 -202.311)
		(width 0.12065)
		(layer "F.Cu")
		(net "BUF_I2C7_B_DBP_SCL")
	)
	(segment
		(start 44.500038 -224.199958)
		(end 44.352464 -224.052384)
		(width 0.12065)
		(layer "F.Cu")
		(net "BUF_I2C7_B_DBP_SCL")
	)
	(segment
		(start 44.352464 -224.052384)
		(end 44.352464 -221.879922)
		(width 0.12065)
		(layer "F.Cu")
		(net "BUF_I2C7_B_DBP_SCL")
	)
	(segment
		(start 43.4086 -210.697318)
		(end 51.3461 -202.759818)
		(width 0.12065)
		(layer "F.Cu")
		(net "BUF_I2C7_B_DBP_SCL")
	)
	(segment
		(start 44.352464 -221.879922)
		(end 43.4086 -220.936058)
		(width 0.12065)
		(layer "F.Cu")
		(net "BUF_I2C7_B_DBP_SCL")
	)
	(via
		(at 51.819556 -197.914768)
		(size 0.7112)
		(drill 0.3556)
		(layers "F.Cu" "B.Cu")
		(net "BUF_I2C7_B_DBP_SCL")
	)
	(via
		(at 51.6382 -202.311)
		(size 0.508)
		(drill 0.254)
		(layers "F.Cu" "B.Cu")
		(net "BUF_I2C7_B_DBP_SCL")
	)
	(segment
		(start 51.6382 -202.311)
		(end 51.47056 -202.14336)
		(width 0.12065)
		(layer "B.Cu")
		(net "BUF_I2C7_B_DBP_SCL")
	)
	(segment
		(start 51.47056 -196.24294)
		(end 51.689 -196.0245)
		(width 0.12065)
		(layer "B.Cu")
		(net "BUF_I2C7_B_DBP_SCL")
	)
	(segment
		(start 51.47056 -202.14336)
		(end 51.47056 -197.914768)
		(width 0.12065)
		(layer "B.Cu")
		(net "BUF_I2C7_B_DBP_SCL")
	)
	(segment
		(start 51.47056 -197.914768)
		(end 51.819556 -197.914768)
		(width 0.12065)
		(layer "B.Cu")
		(net "BUF_I2C7_B_DBP_SCL")
	)
	(segment
		(start 51.47056 -197.914768)
		(end 51.47056 -196.24294)
		(width 0.12065)
		(layer "B.Cu")
		(net "BUF_I2C7_B_DBP_SCL")
	)
	(segment
		(start 40.64 -205.2955)
		(end 40.64 -204.216)
		(width 0.12065)
		(layer "F.Cu")
		(net "BUF_I2C6_C_FCB_SDA_R")
	)
	(segment
		(start 40.905176 -203.950824)
		(end 40.64 -204.216)
		(width 0.12065)
		(layer "F.Cu")
		(net "BUF_I2C6_C_FCB_SDA_R")
	)
	(segment
		(start 40.6273 -206.4512)
		(end 39.7256 -206.4512)
		(width 0.12065)
		(layer "F.Cu")
		(net "BUF_I2C6_C_FCB_SDA_R")
	)
	(segment
		(start 40.7035 -206.375)
		(end 40.7035 -205.359)
		(width 0.12065)
		(layer "F.Cu")
		(net "BUF_I2C6_C_FCB_SDA_R")
	)
	(segment
		(start 40.905176 -202.588368)
		(end 40.905176 -203.950824)
		(width 0.12065)
		(layer "F.Cu")
		(net "BUF_I2C6_C_FCB_SDA_R")
	)
	(segment
		(start 40.7035 -205.359)
		(end 40.64 -205.2955)
		(width 0.12065)
		(layer "F.Cu")
		(net "BUF_I2C6_C_FCB_SDA_R")
	)
	(segment
		(start 40.191436 -201.87412)
		(end 40.905176 -202.588368)
		(width 0.12065)
		(layer "F.Cu")
		(net "BUF_I2C6_C_FCB_SDA_R")
	)
	(segment
		(start 40.64 -206.4385)
		(end 40.6273 -206.4512)
		(width 0.12065)
		(layer "F.Cu")
		(net "BUF_I2C6_C_FCB_SDA_R")
	)
	(segment
		(start 40.64 -206.4385)
		(end 40.7035 -206.375)
		(width 0.12065)
		(layer "F.Cu")
		(net "BUF_I2C6_C_FCB_SDA_R")
	)
	(segment
		(start 39.0779 -201.87412)
		(end 40.191436 -201.87412)
		(width 0.12065)
		(layer "F.Cu")
		(net "BUF_I2C6_C_FCB_SDA_R")
	)
	(via
		(at 39.7256 -206.4512)
		(size 0.7112)
		(drill 0.3556)
		(layers "F.Cu" "B.Cu")
		(net "BUF_I2C6_C_FCB_SDA_R")
	)
	(segment
		(start 38.9001 -225.54438)
		(end 38.9001 -224.199958)
		(width 0.12065)
		(layer "F.Cu")
		(net "BUF_I2C6_C_FCB_SDA")
	)
	(segment
		(start 38.9001 -224.199958)
		(end 39.036244 -224.063814)
		(width 0.12065)
		(layer "F.Cu")
		(net "BUF_I2C6_C_FCB_SDA")
	)
	(segment
		(start 40.64 -207.3275)
		(end 40.931846 -207.619346)
		(width 0.12065)
		(layer "F.Cu")
		(net "BUF_I2C6_C_FCB_SDA")
	)
	(segment
		(start 40.877998 -208.94421)
		(end 40.877998 -208.416398)
		(width 0.12065)
		(layer "F.Cu")
		(net "BUF_I2C6_C_FCB_SDA")
	)
	(segment
		(start 39.036244 -224.063814)
		(end 39.036244 -210.785964)
		(width 0.12065)
		(layer "F.Cu")
		(net "BUF_I2C6_C_FCB_SDA")
	)
	(segment
		(start 40.931846 -207.619346)
		(end 40.931846 -208.089754)
		(width 0.12065)
		(layer "F.Cu")
		(net "BUF_I2C6_C_FCB_SDA")
	)
	(segment
		(start 39.036244 -210.785964)
		(end 40.877998 -208.94421)
		(width 0.12065)
		(layer "F.Cu")
		(net "BUF_I2C6_C_FCB_SDA")
	)
	(segment
		(start 40.931846 -208.089754)
		(end 40.7416 -208.28)
		(width 0.12065)
		(layer "F.Cu")
		(net "BUF_I2C6_C_FCB_SDA")
	)
	(segment
		(start 40.877998 -208.416398)
		(end 40.7416 -208.28)
		(width 0.12065)
		(layer "F.Cu")
		(net "BUF_I2C6_C_FCB_SDA")
	)
	(via
		(at 40.598852 -206.595726)
		(size 0.7112)
		(drill 0.3556)
		(layers "F.Cu" "B.Cu")
		(net "BUF_I2C6_C_FCB_SDA")
	)
	(via
		(at 40.7416 -208.28)
		(size 0.508)
		(drill 0.254)
		(layers "F.Cu" "B.Cu")
		(net "BUF_I2C6_C_FCB_SDA")
	)
	(segment
		(start 40.917622 -206.595726)
		(end 40.917622 -202.271122)
		(width 0.12065)
		(layer "B.Cu")
		(net "BUF_I2C6_C_FCB_SDA")
	)
	(segment
		(start 40.917622 -202.271122)
		(end 40.64 -201.9935)
		(width 0.12065)
		(layer "B.Cu")
		(net "BUF_I2C6_C_FCB_SDA")
	)
	(segment
		(start 40.917622 -208.103978)
		(end 40.917622 -206.595726)
		(width 0.12065)
		(layer "B.Cu")
		(net "BUF_I2C6_C_FCB_SDA")
	)
	(segment
		(start 40.7416 -208.28)
		(end 40.917622 -208.103978)
		(width 0.12065)
		(layer "B.Cu")
		(net "BUF_I2C6_C_FCB_SDA")
	)
	(segment
		(start 40.917622 -206.595726)
		(end 40.598852 -206.595726)
		(width 0.12065)
		(layer "B.Cu")
		(net "BUF_I2C6_C_FCB_SDA")
	)
	(segment
		(start 41.783 -206.4385)
		(end 41.7195 -206.375)
		(width 0.12065)
		(layer "F.Cu")
		(net "BUF_I2C6_C_FCB_SCL_R")
	)
	(segment
		(start 42.151808 -201.87412)
		(end 41.406826 -202.619102)
		(width 0.12065)
		(layer "F.Cu")
		(net "BUF_I2C6_C_FCB_SCL_R")
	)
	(segment
		(start 43.2181 -201.87412)
		(end 42.151808 -201.87412)
		(width 0.12065)
		(layer "F.Cu")
		(net "BUF_I2C6_C_FCB_SCL_R")
	)
	(segment
		(start 41.7195 -205.359)
		(end 41.783 -205.2955)
		(width 0.12065)
		(layer "F.Cu")
		(net "BUF_I2C6_C_FCB_SCL_R")
	)
	(segment
		(start 41.406826 -202.619102)
		(end 41.406826 -203.839826)
		(width 0.12065)
		(layer "F.Cu")
		(net "BUF_I2C6_C_FCB_SCL_R")
	)
	(segment
		(start 41.406826 -203.839826)
		(end 41.783 -204.216)
		(width 0.12065)
		(layer "F.Cu")
		(net "BUF_I2C6_C_FCB_SCL_R")
	)
	(segment
		(start 41.783 -205.2955)
		(end 41.783 -204.216)
		(width 0.12065)
		(layer "F.Cu")
		(net "BUF_I2C6_C_FCB_SCL_R")
	)
	(segment
		(start 41.7195 -206.375)
		(end 41.7195 -205.359)
		(width 0.12065)
		(layer "F.Cu")
		(net "BUF_I2C6_C_FCB_SCL_R")
	)
	(segment
		(start 41.783 -206.4385)
		(end 41.7957 -206.4512)
		(width 0.12065)
		(layer "F.Cu")
		(net "BUF_I2C6_C_FCB_SCL_R")
	)
	(segment
		(start 41.7957 -206.4512)
		(end 42.6974 -206.4512)
		(width 0.12065)
		(layer "F.Cu")
		(net "BUF_I2C6_C_FCB_SCL_R")
	)
	(via
		(at 42.6974 -206.4512)
		(size 0.7112)
		(drill 0.3556)
		(layers "F.Cu" "B.Cu")
		(net "BUF_I2C6_C_FCB_SCL_R")
	)
	(segment
		(start 39.7002 -225.54438)
		(end 39.7002 -224.199704)
		(width 0.12065)
		(layer "F.Cu")
		(net "BUF_I2C6_C_FCB_SCL")
	)
	(segment
		(start 39.7002 -224.199704)
		(end 39.537894 -224.037398)
		(width 0.12065)
		(layer "F.Cu")
		(net "BUF_I2C6_C_FCB_SCL")
	)
	(segment
		(start 41.783 -207.3275)
		(end 41.433496 -207.677004)
		(width 0.12065)
		(layer "F.Cu")
		(net "BUF_I2C6_C_FCB_SCL")
	)
	(segment
		(start 41.379648 -208.505552)
		(end 41.6052 -208.28)
		(width 0.12065)
		(layer "F.Cu")
		(net "BUF_I2C6_C_FCB_SCL")
	)
	(segment
		(start 41.379648 -209.152236)
		(end 41.379648 -208.505552)
		(width 0.12065)
		(layer "F.Cu")
		(net "BUF_I2C6_C_FCB_SCL")
	)
	(segment
		(start 39.537894 -224.037398)
		(end 39.537894 -210.99399)
		(width 0.12065)
		(layer "F.Cu")
		(net "BUF_I2C6_C_FCB_SCL")
	)
	(segment
		(start 41.433496 -207.677004)
		(end 41.433496 -208.108296)
		(width 0.12065)
		(layer "F.Cu")
		(net "BUF_I2C6_C_FCB_SCL")
	)
	(segment
		(start 41.433496 -208.108296)
		(end 41.6052 -208.28)
		(width 0.12065)
		(layer "F.Cu")
		(net "BUF_I2C6_C_FCB_SCL")
	)
	(segment
		(start 39.537894 -210.99399)
		(end 41.379648 -209.152236)
		(width 0.12065)
		(layer "F.Cu")
		(net "BUF_I2C6_C_FCB_SCL")
	)
	(via
		(at 41.768268 -203.799186)
		(size 0.7112)
		(drill 0.3556)
		(layers "F.Cu" "B.Cu")
		(net "BUF_I2C6_C_FCB_SCL")
	)
	(via
		(at 41.6052 -208.28)
		(size 0.508)
		(drill 0.254)
		(layers "F.Cu" "B.Cu")
		(net "BUF_I2C6_C_FCB_SCL")
	)
	(segment
		(start 41.419272 -202.230228)
		(end 41.656 -201.9935)
		(width 0.12065)
		(layer "B.Cu")
		(net "BUF_I2C6_C_FCB_SCL")
	)
	(segment
		(start 41.6052 -208.28)
		(end 41.419272 -208.094072)
		(width 0.12065)
		(layer "B.Cu")
		(net "BUF_I2C6_C_FCB_SCL")
	)
	(segment
		(start 41.419272 -203.799186)
		(end 41.768268 -203.799186)
		(width 0.12065)
		(layer "B.Cu")
		(net "BUF_I2C6_C_FCB_SCL")
	)
	(segment
		(start 41.419272 -208.094072)
		(end 41.419272 -203.799186)
		(width 0.12065)
		(layer "B.Cu")
		(net "BUF_I2C6_C_FCB_SCL")
	)
	(segment
		(start 41.419272 -203.799186)
		(end 41.419272 -202.230228)
		(width 0.12065)
		(layer "B.Cu")
		(net "BUF_I2C6_C_FCB_SCL")
	)
	(segment
		(start 31.28772 -184.735216)
		(end 31.700216 -185.147712)
		(width 0.12065)
		(layer "F.Cu")
		(net "BUF_I2C5_SDA_R")
	)
	(segment
		(start 35.42792 -183.902858)
		(end 34.8361 -184.494678)
		(width 0.12065)
		(layer "F.Cu")
		(net "BUF_I2C5_SDA_R")
	)
	(segment
		(start 33.343088 -185.147712)
		(end 33.6296 -184.8612)
		(width 0.12065)
		(layer "F.Cu")
		(net "BUF_I2C5_SDA_R")
	)
	(segment
		(start 31.700216 -185.147712)
		(end 33.343088 -185.147712)
		(width 0.12065)
		(layer "F.Cu")
		(net "BUF_I2C5_SDA_R")
	)
	(segment
		(start 34.8361 -184.8612)
		(end 33.6296 -184.8612)
		(width 0.12065)
		(layer "F.Cu")
		(net "BUF_I2C5_SDA_R")
	)
	(segment
		(start 31.28772 -183.2991)
		(end 31.28772 -184.735216)
		(width 0.12065)
		(layer "F.Cu")
		(net "BUF_I2C5_SDA_R")
	)
	(segment
		(start 34.8361 -184.494678)
		(end 34.8361 -184.8612)
		(width 0.12065)
		(layer "F.Cu")
		(net "BUF_I2C5_SDA_R")
	)
	(via
		(at 35.42792 -183.902858)
		(size 0.7112)
		(drill 0.3556)
		(layers "F.Cu" "B.Cu")
		(net "BUF_I2C5_SDA_R")
	)
	(segment
		(start 34.8361 -186.0042)
		(end 33.6296 -186.0042)
		(width 0.12065)
		(layer "F.Cu")
		(net "BUF_I2C5_SCL_R")
	)
	(segment
		(start 31.28772 -186.053476)
		(end 31.28772 -187.4393)
		(width 0.12065)
		(layer "F.Cu")
		(net "BUF_I2C5_SCL_R")
	)
	(segment
		(start 33.274762 -185.649362)
		(end 31.691834 -185.649362)
		(width 0.12065)
		(layer "F.Cu")
		(net "BUF_I2C5_SCL_R")
	)
	(segment
		(start 31.691834 -185.649362)
		(end 31.28772 -186.053476)
		(width 0.12065)
		(layer "F.Cu")
		(net "BUF_I2C5_SCL_R")
	)
	(segment
		(start 34.8361 -186.39155)
		(end 34.8361 -186.0042)
		(width 0.12065)
		(layer "F.Cu")
		(net "BUF_I2C5_SCL_R")
	)
	(segment
		(start 35.469068 -187.024518)
		(end 34.8361 -186.39155)
		(width 0.12065)
		(layer "F.Cu")
		(net "BUF_I2C5_SCL_R")
	)
	(segment
		(start 33.6296 -186.0042)
		(end 33.274762 -185.649362)
		(width 0.12065)
		(layer "F.Cu")
		(net "BUF_I2C5_SCL_R")
	)
	(via
		(at 35.469068 -187.024518)
		(size 0.7112)
		(drill 0.3556)
		(layers "F.Cu" "B.Cu")
		(net "BUF_I2C5_SCL_R")
	)
	(segment
		(start 120.51792 -96.41332)
		(end 119.3927 -96.41332)
		(width 0.12065)
		(layer "F.Cu")
		(net "BUF_I2C_SDA_2_R")
	)
	(segment
		(start 120.9548 -99.8347)
		(end 121.0183 -99.8982)
		(width 0.12065)
		(layer "F.Cu")
		(net "BUF_I2C_SDA_2_R")
	)
	(segment
		(start 120.9548 -98.7552)
		(end 121.281952 -98.427794)
		(width 0.12065)
		(layer "F.Cu")
		(net "BUF_I2C_SDA_2_R")
	)
	(segment
		(start 121.281952 -98.427794)
		(end 121.281952 -97.177352)
		(width 0.12065)
		(layer "F.Cu")
		(net "BUF_I2C_SDA_2_R")
	)
	(segment
		(start 121.281952 -97.177352)
		(end 120.51792 -96.41332)
		(width 0.12065)
		(layer "F.Cu")
		(net "BUF_I2C_SDA_2_R")
	)
	(segment
		(start 120.9548 -100.9777)
		(end 120.0404 -100.9777)
		(width 0.12065)
		(layer "F.Cu")
		(net "BUF_I2C_SDA_2_R")
	)
	(segment
		(start 121.0183 -100.9142)
		(end 121.0183 -99.8982)
		(width 0.12065)
		(layer "F.Cu")
		(net "BUF_I2C_SDA_2_R")
	)
	(segment
		(start 120.9548 -100.9777)
		(end 121.0183 -100.9142)
		(width 0.12065)
		(layer "F.Cu")
		(net "BUF_I2C_SDA_2_R")
	)
	(segment
		(start 120.9548 -98.7552)
		(end 120.9548 -99.8347)
		(width 0.12065)
		(layer "F.Cu")
		(net "BUF_I2C_SDA_2_R")
	)
	(via
		(at 120.0404 -100.9777)
		(size 0.7112)
		(drill 0.3556)
		(layers "F.Cu" "B.Cu")
		(net "BUF_I2C_SDA_2_R")
	)
	(segment
		(start 122.0343 -100.9142)
		(end 122.0343 -99.8982)
		(width 0.12065)
		(layer "F.Cu")
		(net "BUF_I2C_SCL_2_R")
	)
	(segment
		(start 122.0978 -100.9777)
		(end 122.0343 -100.9142)
		(width 0.12065)
		(layer "F.Cu")
		(net "BUF_I2C_SCL_2_R")
	)
	(segment
		(start 121.783602 -97.164398)
		(end 122.53468 -96.41332)
		(width 0.12065)
		(layer "F.Cu")
		(net "BUF_I2C_SCL_2_R")
	)
	(segment
		(start 122.0978 -99.8347)
		(end 122.0343 -99.8982)
		(width 0.12065)
		(layer "F.Cu")
		(net "BUF_I2C_SCL_2_R")
	)
	(segment
		(start 122.53468 -96.41332)
		(end 123.5329 -96.41332)
		(width 0.12065)
		(layer "F.Cu")
		(net "BUF_I2C_SCL_2_R")
	)
	(segment
		(start 122.0978 -98.7552)
		(end 122.0978 -99.8347)
		(width 0.12065)
		(layer "F.Cu")
		(net "BUF_I2C_SCL_2_R")
	)
	(segment
		(start 121.783602 -98.441002)
		(end 121.783602 -97.164398)
		(width 0.12065)
		(layer "F.Cu")
		(net "BUF_I2C_SCL_2_R")
	)
	(segment
		(start 122.0978 -98.7552)
		(end 121.783602 -98.441002)
		(width 0.12065)
		(layer "F.Cu")
		(net "BUF_I2C_SCL_2_R")
	)
	(segment
		(start 122.0978 -100.9777)
		(end 123.0122 -100.9777)
		(width 0.12065)
		(layer "F.Cu")
		(net "BUF_I2C_SCL_2_R")
	)
	(via
		(at 123.0122 -100.9777)
		(size 0.7112)
		(drill 0.3556)
		(layers "F.Cu" "B.Cu")
		(net "BUF_I2C_SCL_2_R")
	)
	(segment
		(start 232.537 -22.7965)
		(end 232.537 -22.377654)
		(width 0.12065)
		(layer "F.Cu")
		(net "BOOTSTRAP9")
	)
	(segment
		(start 231.880156 -21.72081)
		(end 231.880156 -21.226526)
		(width 0.12065)
		(layer "F.Cu")
		(net "BOOTSTRAP9")
	)
	(segment
		(start 231.880156 -21.226526)
		(end 231.331516 -20.677886)
		(width 0.12065)
		(layer "F.Cu")
		(net "BOOTSTRAP9")
	)
	(segment
		(start 232.150666 -21.99132)
		(end 231.880156 -21.72081)
		(width 0.12065)
		(layer "F.Cu")
		(net "BOOTSTRAP9")
	)
	(segment
		(start 232.537 -22.377654)
		(end 232.150666 -21.99132)
		(width 0.12065)
		(layer "F.Cu")
		(net "BOOTSTRAP9")
	)
	(via
		(at 231.331516 -20.677886)
		(size 0.7112)
		(drill 0.3556)
		(layers "F.Cu" "B.Cu")
		(net "BOOTSTRAP9")
	)
	(via
		(at 232.150666 -21.99132)
		(size 0.508)
		(drill 0.254)
		(layers "F.Cu" "B.Cu")
		(net "BOOTSTRAP9")
	)
	(segment
		(start 232.537 -22.377654)
		(end 232.150666 -21.99132)
		(width 0.12065)
		(layer "B.Cu")
		(net "BOOTSTRAP9")
	)
	(segment
		(start 232.537 -20.8915)
		(end 232.537 -20.893786)
		(width 0.12065)
		(layer "B.Cu")
		(net "BOOTSTRAP9")
	)
	(segment
		(start 232.537 -22.7965)
		(end 232.537 -22.377654)
		(width 0.12065)
		(layer "B.Cu")
		(net "BOOTSTRAP9")
	)
	(segment
		(start 232.150666 -21.28012)
		(end 232.150666 -21.99132)
		(width 0.12065)
		(layer "B.Cu")
		(net "BOOTSTRAP9")
	)
	(segment
		(start 232.537 -20.893786)
		(end 232.150666 -21.28012)
		(width 0.12065)
		(layer "B.Cu")
		(net "BOOTSTRAP9")
	)
	(segment
		(start 233.258614 -21.717)
		(end 232.640632 -21.099018)
		(width 0.12065)
		(layer "F.Cu")
		(net "BOOTSTRAP8")
	)
	(segment
		(start 233.4387 -21.717)
		(end 233.258614 -21.717)
		(width 0.12065)
		(layer "F.Cu")
		(net "BOOTSTRAP8")
	)
	(segment
		(start 233.68 -22.7965)
		(end 233.4387 -22.5552)
		(width 0.12065)
		(layer "F.Cu")
		(net "BOOTSTRAP8")
	)
	(segment
		(start 233.4387 -22.5552)
		(end 233.4387 -21.717)
		(width 0.12065)
		(layer "F.Cu")
		(net "BOOTSTRAP8")
	)
	(via
		(at 232.640632 -21.099018)
		(size 0.7112)
		(drill 0.3556)
		(layers "F.Cu" "B.Cu")
		(net "BOOTSTRAP8")
	)
	(via
		(at 233.4387 -21.717)
		(size 0.508)
		(drill 0.254)
		(layers "F.Cu" "B.Cu")
		(net "BOOTSTRAP8")
	)
	(segment
		(start 233.68 -22.0853)
		(end 233.4387 -21.844)
		(width 0.12065)
		(layer "B.Cu")
		(net "BOOTSTRAP8")
	)
	(segment
		(start 233.68 -21.3995)
		(end 233.4387 -21.6408)
		(width 0.12065)
		(layer "B.Cu")
		(net "BOOTSTRAP8")
	)
	(segment
		(start 233.4387 -21.844)
		(end 233.4387 -21.717)
		(width 0.12065)
		(layer "B.Cu")
		(net "BOOTSTRAP8")
	)
	(segment
		(start 233.68 -22.7965)
		(end 233.68 -22.0853)
		(width 0.12065)
		(layer "B.Cu")
		(net "BOOTSTRAP8")
	)
	(segment
		(start 233.4387 -21.6408)
		(end 233.4387 -21.717)
		(width 0.12065)
		(layer "B.Cu")
		(net "BOOTSTRAP8")
	)
	(segment
		(start 233.68 -20.8915)
		(end 233.68 -21.3995)
		(width 0.12065)
		(layer "B.Cu")
		(net "BOOTSTRAP8")
	)
	(segment
		(start 237.433866 -20.96516)
		(end 237.433866 -21.031454)
		(width 0.12065)
		(layer "F.Cu")
		(net "BOOTSTRAP7")
	)
	(segment
		(start 236.601 -22.2885)
		(end 236.601 -21.798026)
		(width 0.12065)
		(layer "F.Cu")
		(net "BOOTSTRAP7")
	)
	(segment
		(start 237.347252 -22.0218)
		(end 237.433866 -21.935186)
		(width 0.12065)
		(layer "F.Cu")
		(net "BOOTSTRAP7")
	)
	(segment
		(start 236.601 -21.798026)
		(end 237.433866 -20.96516)
		(width 0.12065)
		(layer "F.Cu")
		(net "BOOTSTRAP7")
	)
	(segment
		(start 237.109 -22.7965)
		(end 236.601 -22.2885)
		(width 0.12065)
		(layer "F.Cu")
		(net "BOOTSTRAP7")
	)
	(segment
		(start 237.433866 -21.935186)
		(end 237.433866 -21.031454)
		(width 0.12065)
		(layer "F.Cu")
		(net "BOOTSTRAP7")
	)
	(via
		(at 237.433866 -21.031454)
		(size 0.7112)
		(drill 0.3556)
		(layers "F.Cu" "B.Cu")
		(net "BOOTSTRAP7")
	)
	(via
		(at 237.347252 -22.0218)
		(size 0.508)
		(drill 0.254)
		(layers "F.Cu" "B.Cu")
		(net "BOOTSTRAP7")
	)
	(segment
		(start 237.347252 -22.558248)
		(end 237.347252 -22.0218)
		(width 0.12065)
		(layer "B.Cu")
		(net "BOOTSTRAP7")
	)
	(segment
		(start 237.109 -20.8915)
		(end 237.347252 -21.129752)
		(width 0.12065)
		(layer "B.Cu")
		(net "BOOTSTRAP7")
	)
	(segment
		(start 237.347252 -21.129752)
		(end 237.347252 -22.0218)
		(width 0.12065)
		(layer "B.Cu")
		(net "BOOTSTRAP7")
	)
	(segment
		(start 237.109 -22.7965)
		(end 237.347252 -22.558248)
		(width 0.12065)
		(layer "B.Cu")
		(net "BOOTSTRAP7")
	)
	(segment
		(start 235.966 -22.048724)
		(end 236.020102 -21.994622)
		(width 0.12065)
		(layer "F.Cu")
		(net "BOOTSTRAP6")
	)
	(segment
		(start 236.020102 -21.055076)
		(end 235.98124 -21.016214)
		(width 0.12065)
		(layer "F.Cu")
		(net "BOOTSTRAP6")
	)
	(segment
		(start 236.020102 -21.994622)
		(end 236.020102 -21.055076)
		(width 0.12065)
		(layer "F.Cu")
		(net "BOOTSTRAP6")
	)
	(segment
		(start 235.966 -22.7965)
		(end 235.966 -22.048724)
		(width 0.12065)
		(layer "F.Cu")
		(net "BOOTSTRAP6")
	)
	(via
		(at 235.98124 -21.016214)
		(size 0.7112)
		(drill 0.3556)
		(layers "F.Cu" "B.Cu")
		(net "BOOTSTRAP6")
	)
	(via
		(at 236.020102 -21.994622)
		(size 0.508)
		(drill 0.254)
		(layers "F.Cu" "B.Cu")
		(net "BOOTSTRAP6")
	)
	(segment
		(start 236.064552 -22.069552)
		(end 236.020102 -22.025102)
		(width 0.12065)
		(layer "B.Cu")
		(net "BOOTSTRAP6")
	)
	(segment
		(start 236.020102 -22.025102)
		(end 236.020102 -21.994622)
		(width 0.12065)
		(layer "B.Cu")
		(net "BOOTSTRAP6")
	)
	(segment
		(start 235.966 -20.8915)
		(end 236.064552 -20.990052)
		(width 0.12065)
		(layer "B.Cu")
		(net "BOOTSTRAP6")
	)
	(segment
		(start 236.064552 -22.697948)
		(end 236.064552 -22.069552)
		(width 0.12065)
		(layer "B.Cu")
		(net "BOOTSTRAP6")
	)
	(segment
		(start 236.020102 -21.916898)
		(end 236.020102 -21.994622)
		(width 0.12065)
		(layer "B.Cu")
		(net "BOOTSTRAP6")
	)
	(segment
		(start 236.064552 -20.990052)
		(end 236.064552 -21.872448)
		(width 0.12065)
		(layer "B.Cu")
		(net "BOOTSTRAP6")
	)
	(segment
		(start 236.064552 -21.872448)
		(end 236.020102 -21.916898)
		(width 0.12065)
		(layer "B.Cu")
		(net "BOOTSTRAP6")
	)
	(segment
		(start 235.966 -22.7965)
		(end 236.064552 -22.697948)
		(width 0.12065)
		(layer "B.Cu")
		(net "BOOTSTRAP6")
	)
	(segment
		(start 242.138454 -21.791422)
		(end 242.138454 -21.39823)
		(width 0.12065)
		(layer "F.Cu")
		(net "BOOTSTRAP5")
	)
	(segment
		(start 242.903502 -20.633182)
		(end 242.903502 -20.655026)
		(width 0.12065)
		(layer "F.Cu")
		(net "BOOTSTRAP5")
	)
	(segment
		(start 241.681 -22.3012)
		(end 242.138454 -21.843746)
		(width 0.12065)
		(layer "F.Cu")
		(net "BOOTSTRAP5")
	)
	(segment
		(start 242.138454 -21.843746)
		(end 242.138454 -21.791422)
		(width 0.12065)
		(layer "F.Cu")
		(net "BOOTSTRAP5")
	)
	(segment
		(start 242.138454 -21.39823)
		(end 242.903502 -20.633182)
		(width 0.12065)
		(layer "F.Cu")
		(net "BOOTSTRAP5")
	)
	(segment
		(start 241.681 -22.7965)
		(end 241.681 -22.3012)
		(width 0.12065)
		(layer "F.Cu")
		(net "BOOTSTRAP5")
	)
	(via
		(at 242.903502 -20.655026)
		(size 0.7112)
		(drill 0.3556)
		(layers "F.Cu" "B.Cu")
		(net "BOOTSTRAP5")
	)
	(via
		(at 242.138454 -21.791422)
		(size 0.508)
		(drill 0.254)
		(layers "F.Cu" "B.Cu")
		(net "BOOTSTRAP5")
	)
	(segment
		(start 241.681 -22.3012)
		(end 242.138454 -21.843746)
		(width 0.12065)
		(layer "B.Cu")
		(net "BOOTSTRAP5")
	)
	(segment
		(start 241.681 -20.8915)
		(end 241.681 -21.2852)
		(width 0.12065)
		(layer "B.Cu")
		(net "BOOTSTRAP5")
	)
	(segment
		(start 241.681 -21.2852)
		(end 242.138454 -21.742654)
		(width 0.12065)
		(layer "B.Cu")
		(net "BOOTSTRAP5")
	)
	(segment
		(start 241.681 -22.7965)
		(end 241.681 -22.3012)
		(width 0.12065)
		(layer "B.Cu")
		(net "BOOTSTRAP5")
	)
	(segment
		(start 242.138454 -21.742654)
		(end 242.138454 -21.791422)
		(width 0.12065)
		(layer "B.Cu")
		(net "BOOTSTRAP5")
	)
	(segment
		(start 242.138454 -21.843746)
		(end 242.138454 -21.791422)
		(width 0.12065)
		(layer "B.Cu")
		(net "BOOTSTRAP5")
	)
	(segment
		(start 234.823 -22.7965)
		(end 234.823 -22.055328)
		(width 0.12065)
		(layer "F.Cu")
		(net "BOOTSTRAP4")
	)
	(segment
		(start 234.823 -22.055328)
		(end 235.227622 -21.650706)
		(width 0.12065)
		(layer "F.Cu")
		(net "BOOTSTRAP4")
	)
	(segment
		(start 234.729274 -21.650706)
		(end 234.19181 -21.113242)
		(width 0.12065)
		(layer "F.Cu")
		(net "BOOTSTRAP4")
	)
	(segment
		(start 235.227622 -21.650706)
		(end 234.729274 -21.650706)
		(width 0.12065)
		(layer "F.Cu")
		(net "BOOTSTRAP4")
	)
	(via
		(at 235.227622 -21.650706)
		(size 0.508)
		(drill 0.254)
		(layers "F.Cu" "B.Cu")
		(net "BOOTSTRAP4")
	)
	(via
		(at 234.19181 -21.113242)
		(size 0.7112)
		(drill 0.3556)
		(layers "F.Cu" "B.Cu")
		(net "BOOTSTRAP4")
	)
	(segment
		(start 235.227622 -21.296122)
		(end 235.227622 -21.650706)
		(width 0.12065)
		(layer "B.Cu")
		(net "BOOTSTRAP4")
	)
	(segment
		(start 234.823 -20.8915)
		(end 235.227622 -21.296122)
		(width 0.12065)
		(layer "B.Cu")
		(net "BOOTSTRAP4")
	)
	(segment
		(start 235.230924 -21.654008)
		(end 235.227622 -21.650706)
		(width 0.12065)
		(layer "B.Cu")
		(net "BOOTSTRAP4")
	)
	(segment
		(start 234.823 -22.7965)
		(end 235.230924 -22.388576)
		(width 0.12065)
		(layer "B.Cu")
		(net "BOOTSTRAP4")
	)
	(segment
		(start 235.230924 -22.388576)
		(end 235.230924 -21.654008)
		(width 0.12065)
		(layer "B.Cu")
		(net "BOOTSTRAP4")
	)
	(segment
		(start 240.538 -22.1234)
		(end 240.8428 -21.8186)
		(width 0.12065)
		(layer "F.Cu")
		(net "BOOTSTRAP3")
	)
	(segment
		(start 241.57178 -21.028914)
		(end 241.54638 -21.028914)
		(width 0.12065)
		(layer "F.Cu")
		(net "BOOTSTRAP3")
	)
	(segment
		(start 240.8428 -21.8186)
		(end 241.57178 -21.08962)
		(width 0.12065)
		(layer "F.Cu")
		(net "BOOTSTRAP3")
	)
	(segment
		(start 241.57178 -21.08962)
		(end 241.57178 -21.028914)
		(width 0.12065)
		(layer "F.Cu")
		(net "BOOTSTRAP3")
	)
	(segment
		(start 240.538 -22.7965)
		(end 240.538 -22.1234)
		(width 0.12065)
		(layer "F.Cu")
		(net "BOOTSTRAP3")
	)
	(via
		(at 240.8428 -21.8186)
		(size 0.508)
		(drill 0.254)
		(layers "F.Cu" "B.Cu")
		(net "BOOTSTRAP3")
	)
	(via
		(at 241.54638 -21.028914)
		(size 0.7112)
		(drill 0.3556)
		(layers "F.Cu" "B.Cu")
		(net "BOOTSTRAP3")
	)
	(segment
		(start 240.538 -21.5138)
		(end 240.8428 -21.8186)
		(width 0.12065)
		(layer "B.Cu")
		(net "BOOTSTRAP3")
	)
	(segment
		(start 240.538 -22.1234)
		(end 240.8428 -21.8186)
		(width 0.12065)
		(layer "B.Cu")
		(net "BOOTSTRAP3")
	)
	(segment
		(start 240.538 -22.7965)
		(end 240.538 -22.1234)
		(width 0.12065)
		(layer "B.Cu")
		(net "BOOTSTRAP3")
	)
	(segment
		(start 240.538 -20.8915)
		(end 240.538 -21.5138)
		(width 0.12065)
		(layer "B.Cu")
		(net "BOOTSTRAP3")
	)
	(segment
		(start 238.645192 -21.016468)
		(end 238.855758 -20.805902)
		(width 0.12065)
		(layer "F.Cu")
		(net "BOOTSTRAP2")
	)
	(segment
		(start 238.252 -22.7965)
		(end 238.252 -21.82368)
		(width 0.12065)
		(layer "F.Cu")
		(net "BOOTSTRAP2")
	)
	(segment
		(start 238.645192 -21.248624)
		(end 238.645192 -21.016468)
		(width 0.12065)
		(layer "F.Cu")
		(net "BOOTSTRAP2")
	)
	(segment
		(start 238.161068 -21.732748)
		(end 238.645192 -21.248624)
		(width 0.12065)
		(layer "F.Cu")
		(net "BOOTSTRAP2")
	)
	(segment
		(start 238.252 -21.82368)
		(end 238.161068 -21.732748)
		(width 0.12065)
		(layer "F.Cu")
		(net "BOOTSTRAP2")
	)
	(via
		(at 238.855758 -20.805902)
		(size 0.7112)
		(drill 0.3556)
		(layers "F.Cu" "B.Cu")
		(net "BOOTSTRAP2")
	)
	(via
		(at 238.161068 -21.732748)
		(size 0.508)
		(drill 0.254)
		(layers "F.Cu" "B.Cu")
		(net "BOOTSTRAP2")
	)
	(segment
		(start 238.252 -22.7965)
		(end 238.161068 -22.705568)
		(width 0.12065)
		(layer "B.Cu")
		(net "BOOTSTRAP2")
	)
	(segment
		(start 238.161068 -20.982432)
		(end 238.161068 -21.732748)
		(width 0.12065)
		(layer "B.Cu")
		(net "BOOTSTRAP2")
	)
	(segment
		(start 238.161068 -22.705568)
		(end 238.161068 -21.732748)
		(width 0.12065)
		(layer "B.Cu")
		(net "BOOTSTRAP2")
	)
	(segment
		(start 238.252 -20.8915)
		(end 238.161068 -20.982432)
		(width 0.12065)
		(layer "B.Cu")
		(net "BOOTSTRAP2")
	)
	(segment
		(start 230.18242 -21.6662)
		(end 230.1748 -21.65858)
		(width 0.12065)
		(layer "F.Cu")
		(net "BOOTSTRAP10")
	)
	(segment
		(start 231.14 -21.6662)
		(end 230.18242 -21.6662)
		(width 0.12065)
		(layer "F.Cu")
		(net "BOOTSTRAP10")
	)
	(segment
		(start 231.1654 -21.6662)
		(end 231.14 -21.6662)
		(width 0.12065)
		(layer "F.Cu")
		(net "BOOTSTRAP10")
	)
	(segment
		(start 231.394 -21.8948)
		(end 231.1654 -21.6662)
		(width 0.12065)
		(layer "F.Cu")
		(net "BOOTSTRAP10")
	)
	(segment
		(start 231.394 -22.7965)
		(end 231.394 -21.8948)
		(width 0.12065)
		(layer "F.Cu")
		(net "BOOTSTRAP10")
	)
	(via
		(at 231.14 -21.6662)
		(size 0.508)
		(drill 0.254)
		(layers "F.Cu" "B.Cu")
		(net "BOOTSTRAP10")
	)
	(via
		(at 230.1748 -21.65858)
		(size 0.7112)
		(drill 0.3556)
		(layers "F.Cu" "B.Cu")
		(net "BOOTSTRAP10")
	)
	(segment
		(start 231.1146 -22.5171)
		(end 231.1146 -21.6916)
		(width 0.12065)
		(layer "B.Cu")
		(net "BOOTSTRAP10")
	)
	(segment
		(start 231.1146 -21.6916)
		(end 231.14 -21.6662)
		(width 0.12065)
		(layer "B.Cu")
		(net "BOOTSTRAP10")
	)
	(segment
		(start 231.394 -20.8915)
		(end 231.394 -21.3868)
		(width 0.12065)
		(layer "B.Cu")
		(net "BOOTSTRAP10")
	)
	(segment
		(start 231.394 -22.7965)
		(end 231.1146 -22.5171)
		(width 0.12065)
		(layer "B.Cu")
		(net "BOOTSTRAP10")
	)
	(segment
		(start 231.14 -21.6408)
		(end 231.14 -21.6662)
		(width 0.12065)
		(layer "B.Cu")
		(net "BOOTSTRAP10")
	)
	(segment
		(start 231.394 -21.3868)
		(end 231.14 -21.6408)
		(width 0.12065)
		(layer "B.Cu")
		(net "BOOTSTRAP10")
	)
	(segment
		(start 239.395 -21.844)
		(end 239.4712 -21.7678)
		(width 0.12065)
		(layer "F.Cu")
		(net "BOOTSTRAP1")
	)
	(segment
		(start 239.4712 -21.7678)
		(end 240.17986 -21.05914)
		(width 0.12065)
		(layer "F.Cu")
		(net "BOOTSTRAP1")
	)
	(segment
		(start 239.395 -22.7965)
		(end 239.395 -21.844)
		(width 0.12065)
		(layer "F.Cu")
		(net "BOOTSTRAP1")
	)
	(segment
		(start 240.17986 -21.05914)
		(end 240.17986 -21.03882)
		(width 0.12065)
		(layer "F.Cu")
		(net "BOOTSTRAP1")
	)
	(via
		(at 239.4712 -21.7678)
		(size 0.508)
		(drill 0.254)
		(layers "F.Cu" "B.Cu")
		(net "BOOTSTRAP1")
	)
	(via
		(at 240.17986 -21.03882)
		(size 0.7112)
		(drill 0.3556)
		(layers "F.Cu" "B.Cu")
		(net "BOOTSTRAP1")
	)
	(segment
		(start 239.395 -21.844)
		(end 239.4712 -21.7678)
		(width 0.12065)
		(layer "B.Cu")
		(net "BOOTSTRAP1")
	)
	(segment
		(start 239.395 -21.6916)
		(end 239.4712 -21.7678)
		(width 0.12065)
		(layer "B.Cu")
		(net "BOOTSTRAP1")
	)
	(segment
		(start 239.395 -20.8915)
		(end 239.395 -21.6916)
		(width 0.12065)
		(layer "B.Cu")
		(net "BOOTSTRAP1")
	)
	(segment
		(start 239.395 -22.7965)
		(end 239.395 -21.844)
		(width 0.12065)
		(layer "B.Cu")
		(net "BOOTSTRAP1")
	)
	(segment
		(start 242.998498 -21.712428)
		(end 243.454428 -21.712428)
		(width 0.12065)
		(layer "F.Cu")
		(net "BOOTSTRAP0")
	)
	(segment
		(start 243.945918 -22.7965)
		(end 243.972588 -22.76983)
		(width 0.12065)
		(layer "F.Cu")
		(net "BOOTSTRAP0")
	)
	(segment
		(start 243.972588 -22.230588)
		(end 243.972588 -22.76983)
		(width 0.12065)
		(layer "F.Cu")
		(net "BOOTSTRAP0")
	)
	(segment
		(start 243.454428 -21.712428)
		(end 243.972588 -22.230588)
		(width 0.12065)
		(layer "F.Cu")
		(net "BOOTSTRAP0")
	)
	(segment
		(start 242.824 -22.7965)
		(end 243.945918 -22.7965)
		(width 0.12065)
		(layer "F.Cu")
		(net "BOOTSTRAP0")
	)
	(via
		(at 242.998498 -21.712428)
		(size 0.508)
		(drill 0.254)
		(layers "F.Cu" "B.Cu")
		(net "BOOTSTRAP0")
	)
	(via
		(at 243.972588 -22.76983)
		(size 0.7112)
		(drill 0.3556)
		(layers "F.Cu" "B.Cu")
		(net "BOOTSTRAP0")
	)
	(segment
		(start 242.951 -21.759926)
		(end 242.998498 -21.712428)
		(width 0.12065)
		(layer "B.Cu")
		(net "BOOTSTRAP0")
	)
	(segment
		(start 242.824 -20.8915)
		(end 242.824 -21.53793)
		(width 0.12065)
		(layer "B.Cu")
		(net "BOOTSTRAP0")
	)
	(segment
		(start 242.951 -21.8694)
		(end 242.951 -21.759926)
		(width 0.12065)
		(layer "B.Cu")
		(net "BOOTSTRAP0")
	)
	(segment
		(start 242.824 -21.9964)
		(end 242.951 -21.8694)
		(width 0.12065)
		(layer "B.Cu")
		(net "BOOTSTRAP0")
	)
	(segment
		(start 242.824 -21.53793)
		(end 242.998498 -21.712428)
		(width 0.12065)
		(layer "B.Cu")
		(net "BOOTSTRAP0")
	)
	(segment
		(start 242.824 -22.7965)
		(end 242.824 -21.9964)
		(width 0.12065)
		(layer "B.Cu")
		(net "BOOTSTRAP0")
	)
	(segment
		(start 239.599978 -39.99992)
		(end 239.100106 -39.500048)
		(width 0.12065)
		(layer "F.Cu")
		(net "BOOTSTRAP_R_9")
	)
	(via
		(at 240.03762 -39.654734)
		(size 0.7112)
		(drill 0.3556)
		(layers "F.Cu" "B.Cu")
		(net "BOOTSTRAP_R_9")
	)
	(via
		(at 239.100106 -39.500048)
		(size 0.4572)
		(drill 0.2032)
		(layers "F.Cu" "B.Cu")
		(net "BOOTSTRAP_R_9")
	)
	(segment
		(start 236.184186 -25.93975)
		(end 236.499654 -25.93975)
		(width 0.12065)
		(layer "B.Cu")
		(net "BOOTSTRAP_R_9")
	)
	(segment
		(start 238.706406 -39.106348)
		(end 239.100106 -39.500048)
		(width 0.1016)
		(layer "B.Cu")
		(net "BOOTSTRAP_R_9")
	)
	(segment
		(start 237.503462 -31.509462)
		(end 237.897416 -31.903416)
		(width 0.12065)
		(layer "B.Cu")
		(net "BOOTSTRAP_R_9")
	)
	(segment
		(start 238.503206 -32.747712)
		(end 238.852456 -33.096962)
		(width 0.1016)
		(layer "B.Cu")
		(net "BOOTSTRAP_R_9")
	)
	(segment
		(start 239.268 -33.096962)
		(end 239.493806 -33.322768)
		(width 0.1016)
		(layer "B.Cu")
		(net "BOOTSTRAP_R_9")
	)
	(segment
		(start 234.652312 -25.468834)
		(end 235.71327 -25.468834)
		(width 0.12065)
		(layer "B.Cu")
		(net "BOOTSTRAP_R_9")
	)
	(segment
		(start 238.943134 -38.1)
		(end 238.706406 -38.336728)
		(width 0.1016)
		(layer "B.Cu")
		(net "BOOTSTRAP_R_9")
	)
	(segment
		(start 239.9538 -37.534342)
		(end 239.815878 -37.672264)
		(width 0.1016)
		(layer "B.Cu")
		(net "BOOTSTRAP_R_9")
	)
	(segment
		(start 238.706406 -38.336728)
		(end 238.706406 -39.106348)
		(width 0.1016)
		(layer "B.Cu")
		(net "BOOTSTRAP_R_9")
	)
	(segment
		(start 238.503206 -32.154622)
		(end 238.503206 -32.747712)
		(width 0.1016)
		(layer "B.Cu")
		(net "BOOTSTRAP_R_9")
	)
	(segment
		(start 239.493806 -33.322768)
		(end 239.493806 -35.836606)
		(width 0.1016)
		(layer "B.Cu")
		(net "BOOTSTRAP_R_9")
	)
	(segment
		(start 239.9538 -36.2966)
		(end 239.9538 -37.534342)
		(width 0.1016)
		(layer "B.Cu")
		(net "BOOTSTRAP_R_9")
	)
	(segment
		(start 238.852456 -33.096962)
		(end 239.268 -33.096962)
		(width 0.1016)
		(layer "B.Cu")
		(net "BOOTSTRAP_R_9")
	)
	(segment
		(start 238.252 -31.903416)
		(end 238.503206 -32.154622)
		(width 0.1016)
		(layer "B.Cu")
		(net "BOOTSTRAP_R_9")
	)
	(segment
		(start 236.499654 -25.93975)
		(end 237.3122 -26.752296)
		(width 0.12065)
		(layer "B.Cu")
		(net "BOOTSTRAP_R_9")
	)
	(segment
		(start 239.100106 -39.500048)
		(end 239.882934 -39.500048)
		(width 0.12065)
		(layer "B.Cu")
		(net "BOOTSTRAP_R_9")
	)
	(segment
		(start 239.882934 -39.500048)
		(end 240.03762 -39.654734)
		(width 0.12065)
		(layer "B.Cu")
		(net "BOOTSTRAP_R_9")
	)
	(segment
		(start 232.537 -23.6855)
		(end 232.868978 -23.6855)
		(width 0.12065)
		(layer "B.Cu")
		(net "BOOTSTRAP_R_9")
	)
	(segment
		(start 237.3122 -27.65425)
		(end 236.82325 -28.1432)
		(width 0.12065)
		(layer "B.Cu")
		(net "BOOTSTRAP_R_9")
	)
	(segment
		(start 236.82325 -29.647388)
		(end 237.503462 -30.3276)
		(width 0.12065)
		(layer "B.Cu")
		(net "BOOTSTRAP_R_9")
	)
	(segment
		(start 239.493806 -35.836606)
		(end 239.9538 -36.2966)
		(width 0.1016)
		(layer "B.Cu")
		(net "BOOTSTRAP_R_9")
	)
	(segment
		(start 237.897416 -31.903416)
		(end 238.252 -31.903416)
		(width 0.12065)
		(layer "B.Cu")
		(net "BOOTSTRAP_R_9")
	)
	(segment
		(start 239.815878 -37.672264)
		(end 239.543336 -37.672264)
		(width 0.1016)
		(layer "B.Cu")
		(net "BOOTSTRAP_R_9")
	)
	(segment
		(start 236.82325 -28.1432)
		(end 236.82325 -29.647388)
		(width 0.12065)
		(layer "B.Cu")
		(net "BOOTSTRAP_R_9")
	)
	(segment
		(start 239.543336 -37.672264)
		(end 239.1156 -38.1)
		(width 0.1016)
		(layer "B.Cu")
		(net "BOOTSTRAP_R_9")
	)
	(segment
		(start 237.3122 -26.752296)
		(end 237.3122 -27.65425)
		(width 0.12065)
		(layer "B.Cu")
		(net "BOOTSTRAP_R_9")
	)
	(segment
		(start 235.71327 -25.468834)
		(end 236.184186 -25.93975)
		(width 0.12065)
		(layer "B.Cu")
		(net "BOOTSTRAP_R_9")
	)
	(segment
		(start 237.503462 -30.3276)
		(end 237.503462 -31.509462)
		(width 0.12065)
		(layer "B.Cu")
		(net "BOOTSTRAP_R_9")
	)
	(segment
		(start 239.1156 -38.1)
		(end 238.943134 -38.1)
		(width 0.1016)
		(layer "B.Cu")
		(net "BOOTSTRAP_R_9")
	)
	(segment
		(start 232.868978 -23.6855)
		(end 234.652312 -25.468834)
		(width 0.12065)
		(layer "B.Cu")
		(net "BOOTSTRAP_R_9")
	)
	(segment
		(start 239.599978 -38.999922)
		(end 239.100106 -38.50005)
		(width 0.12065)
		(layer "F.Cu")
		(net "BOOTSTRAP_R_8")
	)
	(via
		(at 237.4138 -29.0068)
		(size 0.7112)
		(drill 0.3556)
		(layers "F.Cu" "B.Cu")
		(net "BOOTSTRAP_R_8")
	)
	(via
		(at 239.100106 -38.50005)
		(size 0.4572)
		(drill 0.2032)
		(layers "F.Cu" "B.Cu")
		(net "BOOTSTRAP_R_8")
	)
	(segment
		(start 240.157 -36.212272)
		(end 239.697006 -35.752278)
		(width 0.1016)
		(layer "B.Cu")
		(net "BOOTSTRAP_R_8")
	)
	(segment
		(start 238.706406 -30.9626)
		(end 238.706406 -30.67685)
		(width 0.12065)
		(layer "B.Cu")
		(net "BOOTSTRAP_R_8")
	)
	(segment
		(start 239.100106 -38.50005)
		(end 239.676686 -37.92347)
		(width 0.1016)
		(layer "B.Cu")
		(net "BOOTSTRAP_R_8")
	)
	(segment
		(start 233.68 -23.6855)
		(end 233.68 -23.863808)
		(width 0.12065)
		(layer "B.Cu")
		(net "BOOTSTRAP_R_8")
	)
	(segment
		(start 238.706406 -30.67685)
		(end 238.696754 -30.667198)
		(width 0.12065)
		(layer "B.Cu")
		(net "BOOTSTRAP_R_8")
	)
	(segment
		(start 239.8522 -37.92347)
		(end 240.157 -37.61867)
		(width 0.1016)
		(layer "B.Cu")
		(net "BOOTSTRAP_R_8")
	)
	(segment
		(start 238.696754 -30.526228)
		(end 238.26724 -30.096714)
		(width 0.12065)
		(layer "B.Cu")
		(net "BOOTSTRAP_R_8")
	)
	(segment
		(start 235.980986 -25.10663)
		(end 237.5916 -26.717244)
		(width 0.12065)
		(layer "B.Cu")
		(net "BOOTSTRAP_R_8")
	)
	(segment
		(start 237.919514 -30.096714)
		(end 237.4138 -29.591)
		(width 0.12065)
		(layer "B.Cu")
		(net "BOOTSTRAP_R_8")
	)
	(segment
		(start 238.706406 -32.663384)
		(end 238.706406 -30.9626)
		(width 0.1016)
		(layer "B.Cu")
		(net "BOOTSTRAP_R_8")
	)
	(segment
		(start 239.697006 -35.752278)
		(end 239.697006 -33.23844)
		(width 0.1016)
		(layer "B.Cu")
		(net "BOOTSTRAP_R_8")
	)
	(segment
		(start 240.157 -37.61867)
		(end 240.157 -36.212272)
		(width 0.1016)
		(layer "B.Cu")
		(net "BOOTSTRAP_R_8")
	)
	(segment
		(start 233.68 -23.863808)
		(end 234.922822 -25.10663)
		(width 0.12065)
		(layer "B.Cu")
		(net "BOOTSTRAP_R_8")
	)
	(segment
		(start 234.922822 -25.10663)
		(end 235.980986 -25.10663)
		(width 0.12065)
		(layer "B.Cu")
		(net "BOOTSTRAP_R_8")
	)
	(segment
		(start 238.936784 -32.893762)
		(end 238.706406 -32.663384)
		(width 0.1016)
		(layer "B.Cu")
		(net "BOOTSTRAP_R_8")
	)
	(segment
		(start 237.5916 -28.2194)
		(end 237.4138 -28.3972)
		(width 0.12065)
		(layer "B.Cu")
		(net "BOOTSTRAP_R_8")
	)
	(segment
		(start 239.697006 -33.23844)
		(end 239.352328 -32.893762)
		(width 0.1016)
		(layer "B.Cu")
		(net "BOOTSTRAP_R_8")
	)
	(segment
		(start 237.5916 -26.717244)
		(end 237.5916 -28.2194)
		(width 0.12065)
		(layer "B.Cu")
		(net "BOOTSTRAP_R_8")
	)
	(segment
		(start 237.4138 -28.3972)
		(end 237.4138 -29.0068)
		(width 0.12065)
		(layer "B.Cu")
		(net "BOOTSTRAP_R_8")
	)
	(segment
		(start 239.352328 -32.893762)
		(end 238.936784 -32.893762)
		(width 0.1016)
		(layer "B.Cu")
		(net "BOOTSTRAP_R_8")
	)
	(segment
		(start 239.676686 -37.92347)
		(end 239.8522 -37.92347)
		(width 0.1016)
		(layer "B.Cu")
		(net "BOOTSTRAP_R_8")
	)
	(segment
		(start 237.4138 -29.591)
		(end 237.4138 -29.0068)
		(width 0.12065)
		(layer "B.Cu")
		(net "BOOTSTRAP_R_8")
	)
	(segment
		(start 238.26724 -30.096714)
		(end 237.919514 -30.096714)
		(width 0.12065)
		(layer "B.Cu")
		(net "BOOTSTRAP_R_8")
	)
	(segment
		(start 238.696754 -30.667198)
		(end 238.696754 -30.526228)
		(width 0.12065)
		(layer "B.Cu")
		(net "BOOTSTRAP_R_8")
	)
	(segment
		(start 240.599976 -35.999928)
		(end 241.099848 -35.500056)
		(width 0.12065)
		(layer "F.Cu")
		(net "BOOTSTRAP_R_7")
	)
	(via
		(at 240.806732 -34.606992)
		(size 0.7112)
		(drill 0.3556)
		(layers "F.Cu" "B.Cu")
		(net "BOOTSTRAP_R_7")
	)
	(via
		(at 241.099848 -35.500056)
		(size 0.4572)
		(drill 0.2032)
		(layers "F.Cu" "B.Cu")
		(net "BOOTSTRAP_R_7")
	)
	(segment
		(start 237.89513 -24.139652)
		(end 238.038894 -24.139652)
		(width 0.12065)
		(layer "B.Cu")
		(net "BOOTSTRAP_R_7")
	)
	(segment
		(start 241.099848 -34.900108)
		(end 240.806732 -34.606992)
		(width 0.12065)
		(layer "B.Cu")
		(net "BOOTSTRAP_R_7")
	)
	(segment
		(start 240.09096 -27.276298)
		(end 240.09096 -28.977082)
		(width 0.12065)
		(layer "B.Cu")
		(net "BOOTSTRAP_R_7")
	)
	(segment
		(start 237.109 -23.6855)
		(end 237.440978 -23.6855)
		(width 0.12065)
		(layer "B.Cu")
		(net "BOOTSTRAP_R_7")
	)
	(segment
		(start 237.440978 -23.6855)
		(end 237.89513 -24.139652)
		(width 0.12065)
		(layer "B.Cu")
		(net "BOOTSTRAP_R_7")
	)
	(segment
		(start 240.639092 -31.870396)
		(end 240.354358 -32.15513)
		(width 0.12065)
		(layer "B.Cu")
		(net "BOOTSTRAP_R_7")
	)
	(segment
		(start 240.09096 -28.977082)
		(end 240.639092 -29.525214)
		(width 0.12065)
		(layer "B.Cu")
		(net "BOOTSTRAP_R_7")
	)
	(segment
		(start 238.038894 -24.139652)
		(end 239.485678 -25.586436)
		(width 0.12065)
		(layer "B.Cu")
		(net "BOOTSTRAP_R_7")
	)
	(segment
		(start 239.485678 -25.586436)
		(end 239.485678 -26.671016)
		(width 0.12065)
		(layer "B.Cu")
		(net "BOOTSTRAP_R_7")
	)
	(segment
		(start 241.099848 -35.500056)
		(end 241.099848 -34.900108)
		(width 0.12065)
		(layer "B.Cu")
		(net "BOOTSTRAP_R_7")
	)
	(segment
		(start 240.354358 -34.154618)
		(end 240.806732 -34.606992)
		(width 0.12065)
		(layer "B.Cu")
		(net "BOOTSTRAP_R_7")
	)
	(segment
		(start 240.354358 -32.15513)
		(end 240.354358 -34.154618)
		(width 0.12065)
		(layer "B.Cu")
		(net "BOOTSTRAP_R_7")
	)
	(segment
		(start 239.485678 -26.671016)
		(end 240.09096 -27.276298)
		(width 0.12065)
		(layer "B.Cu")
		(net "BOOTSTRAP_R_7")
	)
	(segment
		(start 240.639092 -29.525214)
		(end 240.639092 -31.870396)
		(width 0.12065)
		(layer "B.Cu")
		(net "BOOTSTRAP_R_7")
	)
	(segment
		(start 240.599976 -39.99992)
		(end 241.099848 -39.500048)
		(width 0.12065)
		(layer "F.Cu")
		(net "BOOTSTRAP_R_6")
	)
	(via
		(at 241.099848 -39.500048)
		(size 0.4572)
		(drill 0.2032)
		(layers "F.Cu" "B.Cu")
		(net "BOOTSTRAP_R_6")
	)
	(via
		(at 238.603536 -27.054302)
		(size 0.7112)
		(drill 0.3556)
		(layers "F.Cu" "B.Cu")
		(net "BOOTSTRAP_R_6")
	)
	(segment
		(start 241.099848 -39.500048)
		(end 240.474246 -38.874446)
		(width 0.12065)
		(layer "B.Cu")
		(net "BOOTSTRAP_R_6")
	)
	(segment
		(start 235.966 -23.6855)
		(end 235.966 -23.92299)
		(width 0.12065)
		(layer "B.Cu")
		(net "BOOTSTRAP_R_6")
	)
	(segment
		(start 235.966 -23.92299)
		(end 238.47806 -26.43505)
		(width 0.12065)
		(layer "B.Cu")
		(net "BOOTSTRAP_R_6")
	)
	(segment
		(start 240.018062 -31.690056)
		(end 240.018062 -30.519116)
		(width 0.12065)
		(layer "B.Cu")
		(net "BOOTSTRAP_R_6")
	)
	(segment
		(start 239.725708 -31.98241)
		(end 240.018062 -31.690056)
		(width 0.12065)
		(layer "B.Cu")
		(net "BOOTSTRAP_R_6")
	)
	(segment
		(start 239.64646 -29.161486)
		(end 239.64646 -28.097226)
		(width 0.12065)
		(layer "B.Cu")
		(net "BOOTSTRAP_R_6")
	)
	(segment
		(start 238.47806 -26.43505)
		(end 238.47806 -26.928826)
		(width 0.12065)
		(layer "B.Cu")
		(net "BOOTSTRAP_R_6")
	)
	(segment
		(start 239.725708 -32.586168)
		(end 239.725708 -31.98241)
		(width 0.12065)
		(layer "B.Cu")
		(net "BOOTSTRAP_R_6")
	)
	(segment
		(start 240.474246 -38.874446)
		(end 240.474246 -36.228274)
		(width 0.12065)
		(layer "B.Cu")
		(net "BOOTSTRAP_R_6")
	)
	(segment
		(start 239.725708 -29.240734)
		(end 239.64646 -29.161486)
		(width 0.12065)
		(layer "B.Cu")
		(net "BOOTSTRAP_R_6")
	)
	(segment
		(start 240.474246 -36.228274)
		(end 239.909858 -35.663886)
		(width 0.12065)
		(layer "B.Cu")
		(net "BOOTSTRAP_R_6")
	)
	(segment
		(start 239.909858 -32.770318)
		(end 239.725708 -32.586168)
		(width 0.12065)
		(layer "B.Cu")
		(net "BOOTSTRAP_R_6")
	)
	(segment
		(start 239.64646 -28.097226)
		(end 238.603536 -27.054302)
		(width 0.12065)
		(layer "B.Cu")
		(net "BOOTSTRAP_R_6")
	)
	(segment
		(start 239.725708 -30.226762)
		(end 239.725708 -29.240734)
		(width 0.12065)
		(layer "B.Cu")
		(net "BOOTSTRAP_R_6")
	)
	(segment
		(start 240.018062 -30.519116)
		(end 239.725708 -30.226762)
		(width 0.12065)
		(layer "B.Cu")
		(net "BOOTSTRAP_R_6")
	)
	(segment
		(start 239.909858 -35.663886)
		(end 239.909858 -32.770318)
		(width 0.12065)
		(layer "B.Cu")
		(net "BOOTSTRAP_R_6")
	)
	(segment
		(start 238.47806 -26.928826)
		(end 238.603536 -27.054302)
		(width 0.12065)
		(layer "B.Cu")
		(net "BOOTSTRAP_R_6")
	)
	(segment
		(start 241.681 -25.781)
		(end 242.062 -26.162)
		(width 0.12065)
		(layer "F.Cu")
		(net "BOOTSTRAP_R_5")
	)
	(segment
		(start 242.062 -26.162)
		(end 242.062 -27.432)
		(width 0.12065)
		(layer "F.Cu")
		(net "BOOTSTRAP_R_5")
	)
	(segment
		(start 240.599976 -30.999938)
		(end 241.016028 -30.583886)
		(width 0.12065)
		(layer "F.Cu")
		(net "BOOTSTRAP_R_5")
	)
	(segment
		(start 241.681 -23.6855)
		(end 241.681 -25.781)
		(width 0.12065)
		(layer "F.Cu")
		(net "BOOTSTRAP_R_5")
	)
	(segment
		(start 241.016028 -30.583886)
		(end 241.016028 -29.493972)
		(width 0.12065)
		(layer "F.Cu")
		(net "BOOTSTRAP_R_5")
	)
	(segment
		(start 241.016028 -29.493972)
		(end 242.062 -28.448)
		(width 0.12065)
		(layer "F.Cu")
		(net "BOOTSTRAP_R_5")
	)
	(segment
		(start 242.062 -28.448)
		(end 242.062 -27.432)
		(width 0.12065)
		(layer "F.Cu")
		(net "BOOTSTRAP_R_5")
	)
	(via
		(at 242.062 -27.432)
		(size 0.7112)
		(drill 0.3556)
		(layers "F.Cu" "B.Cu")
		(net "BOOTSTRAP_R_5")
	)
	(segment
		(start 239.599978 -32.999934)
		(end 239.100106 -32.500062)
		(width 0.12065)
		(layer "F.Cu")
		(net "BOOTSTRAP_R_4")
	)
	(via
		(at 239.100106 -32.500062)
		(size 0.4572)
		(drill 0.2032)
		(layers "F.Cu" "B.Cu")
		(net "BOOTSTRAP_R_4")
	)
	(via
		(at 238.772954 -28.758388)
		(size 0.7112)
		(drill 0.3556)
		(layers "F.Cu" "B.Cu")
		(net "BOOTSTRAP_R_4")
	)
	(segment
		(start 239.228122 -29.0576)
		(end 239.072166 -29.0576)
		(width 0.12065)
		(layer "B.Cu")
		(net "BOOTSTRAP_R_4")
	)
	(segment
		(start 235.283248 -24.145748)
		(end 235.676694 -24.145748)
		(width 0.12065)
		(layer "B.Cu")
		(net "BOOTSTRAP_R_4")
	)
	(segment
		(start 237.88497 -26.354024)
		(end 237.88497 -27.870404)
		(width 0.12065)
		(layer "B.Cu")
		(net "BOOTSTRAP_R_4")
	)
	(segment
		(start 237.88497 -27.870404)
		(end 238.772954 -28.758388)
		(width 0.12065)
		(layer "B.Cu")
		(net "BOOTSTRAP_R_4")
	)
	(segment
		(start 235.676694 -24.145748)
		(end 237.88497 -26.354024)
		(width 0.12065)
		(layer "B.Cu")
		(net "BOOTSTRAP_R_4")
	)
	(segment
		(start 239.072166 -29.0576)
		(end 238.772954 -28.758388)
		(width 0.12065)
		(layer "B.Cu")
		(net "BOOTSTRAP_R_4")
	)
	(segment
		(start 239.503458 -32.09671)
		(end 239.503458 -29.332936)
		(width 0.12065)
		(layer "B.Cu")
		(net "BOOTSTRAP_R_4")
	)
	(segment
		(start 239.503458 -29.332936)
		(end 239.228122 -29.0576)
		(width 0.12065)
		(layer "B.Cu")
		(net "BOOTSTRAP_R_4")
	)
	(segment
		(start 239.100106 -32.500062)
		(end 239.503458 -32.09671)
		(width 0.12065)
		(layer "B.Cu")
		(net "BOOTSTRAP_R_4")
	)
	(segment
		(start 234.823 -23.6855)
		(end 235.283248 -24.145748)
		(width 0.12065)
		(layer "B.Cu")
		(net "BOOTSTRAP_R_4")
	)
	(segment
		(start 240.538 -23.6855)
		(end 240.538 -26.924)
		(width 0.12065)
		(layer "F.Cu")
		(net "BOOTSTRAP_R_3")
	)
	(segment
		(start 240.599976 -29.99994)
		(end 240.538 -29.937964)
		(width 0.12065)
		(layer "F.Cu")
		(net "BOOTSTRAP_R_3")
	)
	(segment
		(start 240.538 -29.937964)
		(end 240.538 -26.924)
		(width 0.12065)
		(layer "F.Cu")
		(net "BOOTSTRAP_R_3")
	)
	(via
		(at 240.538 -26.924)
		(size 0.7112)
		(drill 0.3556)
		(layers "F.Cu" "B.Cu")
		(net "BOOTSTRAP_R_3")
	)
	(segment
		(start 240.599976 -32.999934)
		(end 241.099848 -32.500062)
		(width 0.12065)
		(layer "F.Cu")
		(net "BOOTSTRAP_R_2")
	)
	(via
		(at 241.099848 -32.500062)
		(size 0.4572)
		(drill 0.2032)
		(layers "F.Cu" "B.Cu")
		(net "BOOTSTRAP_R_2")
	)
	(via
		(at 241.296698 -33.419034)
		(size 0.7112)
		(drill 0.3556)
		(layers "F.Cu" "B.Cu")
		(net "BOOTSTRAP_R_2")
	)
	(segment
		(start 241.099848 -32.500062)
		(end 241.229388 -32.629602)
		(width 0.12065)
		(layer "B.Cu")
		(net "BOOTSTRAP_R_2")
	)
	(segment
		(start 240.680748 -28.923488)
		(end 241.14633 -29.38907)
		(width 0.12065)
		(layer "B.Cu")
		(net "BOOTSTRAP_R_2")
	)
	(segment
		(start 239.164622 -24.241252)
		(end 239.842294 -24.241252)
		(width 0.12065)
		(layer "B.Cu")
		(net "BOOTSTRAP_R_2")
	)
	(segment
		(start 241.14633 -29.38907)
		(end 241.14633 -32.45358)
		(width 0.12065)
		(layer "B.Cu")
		(net "BOOTSTRAP_R_2")
	)
	(segment
		(start 239.842294 -24.241252)
		(end 240.395252 -24.79421)
		(width 0.12065)
		(layer "B.Cu")
		(net "BOOTSTRAP_R_2")
	)
	(segment
		(start 240.395252 -26.556462)
		(end 240.680748 -26.841958)
		(width 0.12065)
		(layer "B.Cu")
		(net "BOOTSTRAP_R_2")
	)
	(segment
		(start 241.229388 -32.629602)
		(end 241.229388 -33.351724)
		(width 0.12065)
		(layer "B.Cu")
		(net "BOOTSTRAP_R_2")
	)
	(segment
		(start 238.252 -23.6855)
		(end 238.60887 -23.6855)
		(width 0.12065)
		(layer "B.Cu")
		(net "BOOTSTRAP_R_2")
	)
	(segment
		(start 240.680748 -26.841958)
		(end 240.680748 -28.923488)
		(width 0.12065)
		(layer "B.Cu")
		(net "BOOTSTRAP_R_2")
	)
	(segment
		(start 241.229388 -33.351724)
		(end 241.296698 -33.419034)
		(width 0.12065)
		(layer "B.Cu")
		(net "BOOTSTRAP_R_2")
	)
	(segment
		(start 241.14633 -32.45358)
		(end 241.099848 -32.500062)
		(width 0.12065)
		(layer "B.Cu")
		(net "BOOTSTRAP_R_2")
	)
	(segment
		(start 240.395252 -24.79421)
		(end 240.395252 -26.556462)
		(width 0.12065)
		(layer "B.Cu")
		(net "BOOTSTRAP_R_2")
	)
	(segment
		(start 238.60887 -23.6855)
		(end 239.164622 -24.241252)
		(width 0.12065)
		(layer "B.Cu")
		(net "BOOTSTRAP_R_2")
	)
	(segment
		(start 238.59998 -39.99992)
		(end 238.100108 -39.500048)
		(width 0.12065)
		(layer "F.Cu")
		(net "BOOTSTRAP_R_10")
	)
	(via
		(at 232.49001 -24.78151)
		(size 0.7112)
		(drill 0.3556)
		(layers "F.Cu" "B.Cu")
		(net "BOOTSTRAP_R_10")
	)
	(via
		(at 238.100108 -39.500048)
		(size 0.4572)
		(drill 0.2032)
		(layers "F.Cu" "B.Cu")
		(net "BOOTSTRAP_R_10")
	)
	(segment
		(start 236.601 -27.957526)
		(end 236.999526 -27.559)
		(width 0.12065)
		(layer "B.Cu")
		(net "BOOTSTRAP_R_10")
	)
	(segment
		(start 235.952284 -26.0223)
		(end 233.7308 -26.0223)
		(width 0.12065)
		(layer "B.Cu")
		(net "BOOTSTRAP_R_10")
	)
	(segment
		(start 236.091984 -26.162)
		(end 235.952284 -26.0223)
		(width 0.12065)
		(layer "B.Cu")
		(net "BOOTSTRAP_R_10")
	)
	(segment
		(start 235.706412 -31.163006)
		(end 235.966 -30.903418)
		(width 0.1016)
		(layer "B.Cu")
		(net "BOOTSTRAP_R_10")
	)
	(segment
		(start 236.999526 -27.559)
		(end 236.999526 -26.754074)
		(width 0.12065)
		(layer "B.Cu")
		(net "BOOTSTRAP_R_10")
	)
	(segment
		(start 238.100108 -39.500048)
		(end 237.69701 -39.09695)
		(width 0.1016)
		(layer "B.Cu")
		(net "BOOTSTRAP_R_10")
	)
	(segment
		(start 236.407452 -26.162)
		(end 236.091984 -26.162)
		(width 0.12065)
		(layer "B.Cu")
		(net "BOOTSTRAP_R_10")
	)
	(segment
		(start 237.69701 -36.252404)
		(end 237.338362 -35.893756)
		(width 0.1016)
		(layer "B.Cu")
		(net "BOOTSTRAP_R_10")
	)
	(segment
		(start 236.601 -30.607)
		(end 236.601 -27.957526)
		(width 0.12065)
		(layer "B.Cu")
		(net "BOOTSTRAP_R_10")
	)
	(segment
		(start 236.304582 -30.903418)
		(end 236.601 -30.607)
		(width 0.12065)
		(layer "B.Cu")
		(net "BOOTSTRAP_R_10")
	)
	(segment
		(start 236.70641 -35.663378)
		(end 236.70641 -34.24301)
		(width 0.1016)
		(layer "B.Cu")
		(net "BOOTSTRAP_R_10")
	)
	(segment
		(start 236.70641 -34.24301)
		(end 236.35716 -33.89376)
		(width 0.1016)
		(layer "B.Cu")
		(net "BOOTSTRAP_R_10")
	)
	(segment
		(start 235.93679 -33.89376)
		(end 235.706412 -33.663382)
		(width 0.1016)
		(layer "B.Cu")
		(net "BOOTSTRAP_R_10")
	)
	(segment
		(start 236.35716 -33.89376)
		(end 235.93679 -33.89376)
		(width 0.1016)
		(layer "B.Cu")
		(net "BOOTSTRAP_R_10")
	)
	(segment
		(start 237.69701 -39.09695)
		(end 237.69701 -36.252404)
		(width 0.1016)
		(layer "B.Cu")
		(net "BOOTSTRAP_R_10")
	)
	(segment
		(start 233.7308 -26.0223)
		(end 232.49001 -24.78151)
		(width 0.12065)
		(layer "B.Cu")
		(net "BOOTSTRAP_R_10")
	)
	(segment
		(start 236.999526 -26.754074)
		(end 236.407452 -26.162)
		(width 0.12065)
		(layer "B.Cu")
		(net "BOOTSTRAP_R_10")
	)
	(segment
		(start 237.338362 -35.893756)
		(end 236.936788 -35.893756)
		(width 0.1016)
		(layer "B.Cu")
		(net "BOOTSTRAP_R_10")
	)
	(segment
		(start 236.936788 -35.893756)
		(end 236.70641 -35.663378)
		(width 0.1016)
		(layer "B.Cu")
		(net "BOOTSTRAP_R_10")
	)
	(segment
		(start 232.49001 -24.78151)
		(end 231.394 -23.6855)
		(width 0.12065)
		(layer "B.Cu")
		(net "BOOTSTRAP_R_10")
	)
	(segment
		(start 235.966 -30.903418)
		(end 236.304582 -30.903418)
		(width 0.12065)
		(layer "B.Cu")
		(net "BOOTSTRAP_R_10")
	)
	(segment
		(start 235.706412 -33.663382)
		(end 235.706412 -31.163006)
		(width 0.1016)
		(layer "B.Cu")
		(net "BOOTSTRAP_R_10")
	)
	(segment
		(start 239.395 -28.956)
		(end 239.395 -26.035)
		(width 0.12065)
		(layer "F.Cu")
		(net "BOOTSTRAP_R_1")
	)
	(segment
		(start 240.183924 -31.583884)
		(end 240.183924 -29.744924)
		(width 0.12065)
		(layer "F.Cu")
		(net "BOOTSTRAP_R_1")
	)
	(segment
		(start 239.395 -23.6855)
		(end 239.395 -26.035)
		(width 0.12065)
		(layer "F.Cu")
		(net "BOOTSTRAP_R_1")
	)
	(segment
		(start 240.599976 -31.999936)
		(end 240.183924 -31.583884)
		(width 0.12065)
		(layer "F.Cu")
		(net "BOOTSTRAP_R_1")
	)
	(segment
		(start 240.183924 -29.744924)
		(end 239.395 -28.956)
		(width 0.12065)
		(layer "F.Cu")
		(net "BOOTSTRAP_R_1")
	)
	(via
		(at 239.395 -26.035)
		(size 0.7112)
		(drill 0.3556)
		(layers "F.Cu" "B.Cu")
		(net "BOOTSTRAP_R_1")
	)
	(segment
		(start 241.599974 -32.999934)
		(end 242.099846 -32.500062)
		(width 0.12065)
		(layer "F.Cu")
		(net "BOOTSTRAP_R_0")
	)
	(via
		(at 242.099846 -32.500062)
		(size 0.4572)
		(drill 0.2032)
		(layers "F.Cu" "B.Cu")
		(net "BOOTSTRAP_R_0")
	)
	(via
		(at 243.84 -24.13)
		(size 0.7112)
		(drill 0.3556)
		(layers "F.Cu" "B.Cu")
		(net "BOOTSTRAP_R_0")
	)
	(segment
		(start 243.84 -24.511)
		(end 243.84 -24.13)
		(width 0.12065)
		(layer "B.Cu")
		(net "BOOTSTRAP_R_0")
	)
	(segment
		(start 242.824 -25.527)
		(end 243.84 -24.511)
		(width 0.12065)
		(layer "B.Cu")
		(net "BOOTSTRAP_R_0")
	)
	(segment
		(start 242.15725 -27.40025)
		(end 242.824 -26.7335)
		(width 0.12065)
		(layer "B.Cu")
		(net "BOOTSTRAP_R_0")
	)
	(segment
		(start 242.15725 -28.86075)
		(end 242.15725 -27.40025)
		(width 0.12065)
		(layer "B.Cu")
		(net "BOOTSTRAP_R_0")
	)
	(segment
		(start 243.3955 -23.6855)
		(end 243.84 -24.13)
		(width 0.12065)
		(layer "B.Cu")
		(net "BOOTSTRAP_R_0")
	)
	(segment
		(start 242.099846 -32.500062)
		(end 242.099846 -32.070548)
		(width 0.12065)
		(layer "B.Cu")
		(net "BOOTSTRAP_R_0")
	)
	(segment
		(start 242.099846 -32.070548)
		(end 241.696494 -31.667196)
		(width 0.12065)
		(layer "B.Cu")
		(net "BOOTSTRAP_R_0")
	)
	(segment
		(start 241.696494 -29.321506)
		(end 242.15725 -28.86075)
		(width 0.12065)
		(layer "B.Cu")
		(net "BOOTSTRAP_R_0")
	)
	(segment
		(start 242.824 -23.6855)
		(end 243.3955 -23.6855)
		(width 0.12065)
		(layer "B.Cu")
		(net "BOOTSTRAP_R_0")
	)
	(segment
		(start 241.696494 -31.667196)
		(end 241.696494 -29.321506)
		(width 0.12065)
		(layer "B.Cu")
		(net "BOOTSTRAP_R_0")
	)
	(segment
		(start 242.824 -26.7335)
		(end 242.824 -25.527)
		(width 0.12065)
		(layer "B.Cu")
		(net "BOOTSTRAP_R_0")
	)
	(segment
		(start 205.6765 -5.2197)
		(end 204.5462 -4.0894)
		(width 0.12065)
		(layer "F.Cu")
		(net "BOOT_RECOVERY_1")
	)
	(segment
		(start 207.137 -5.2197)
		(end 205.6765 -5.2197)
		(width 0.12065)
		(layer "F.Cu")
		(net "BOOT_RECOVERY_1")
	)
	(segment
		(start 199.4662 -4.8006)
		(end 201.1172 -6.4516)
		(width 0.12065)
		(layer "F.Cu")
		(net "BOOT_RECOVERY_0")
	)
	(segment
		(start 201.1172 -6.4516)
		(end 201.1172 -6.5659)
		(width 0.12065)
		(layer "F.Cu")
		(net "BOOT_RECOVERY_0")
	)
	(segment
		(start 199.4662 -4.0894)
		(end 199.4662 -4.8006)
		(width 0.12065)
		(layer "F.Cu")
		(net "BOOT_RECOVERY_0")
	)
	(segment
		(start 202.58024 -4.66344)
		(end 202.0062 -4.0894)
		(width 0.12065)
		(layer "F.Cu")
		(net "BOOT_RECOVERY#_R")
	)
	(segment
		(start 202.58024 -6.691122)
		(end 202.58024 -4.66344)
		(width 0.12065)
		(layer "F.Cu")
		(net "BOOT_RECOVERY#_R")
	)
	(segment
		(start 231.599994 -33.999932)
		(end 231.100122 -33.50006)
		(width 0.12065)
		(layer "F.Cu")
		(net "BOOT_RECOVERY#")
	)
	(segment
		(start 209.181954 -19.069304)
		(end 209.181954 -20.459954)
		(width 0.12065)
		(layer "F.Cu")
		(net "BOOT_RECOVERY#")
	)
	(segment
		(start 206.556356 -9.778238)
		(end 206.556356 -10.34669)
		(width 0.12065)
		(layer "F.Cu")
		(net "BOOT_RECOVERY#")
	)
	(segment
		(start 206.556356 -9.778238)
		(end 203.46924 -6.691122)
		(width 0.12065)
		(layer "F.Cu")
		(net "BOOT_RECOVERY#")
	)
	(segment
		(start 206.746348 -16.633698)
		(end 209.181954 -19.069304)
		(width 0.12065)
		(layer "F.Cu")
		(net "BOOT_RECOVERY#")
	)
	(segment
		(start 206.556356 -10.34669)
		(end 206.746348 -10.536682)
		(width 0.12065)
		(layer "F.Cu")
		(net "BOOT_RECOVERY#")
	)
	(segment
		(start 206.746348 -10.536682)
		(end 206.746348 -16.633698)
		(width 0.12065)
		(layer "F.Cu")
		(net "BOOT_RECOVERY#")
	)
	(via
		(at 206.556356 -9.778238)
		(size 0.7112)
		(drill 0.3556)
		(layers "F.Cu" "B.Cu")
		(net "BOOT_RECOVERY#")
	)
	(via
		(at 231.100122 -33.50006)
		(size 0.4572)
		(drill 0.2032)
		(layers "F.Cu" "B.Cu")
		(net "BOOT_RECOVERY#")
	)
	(via
		(at 209.181954 -20.459954)
		(size 0.508)
		(drill 0.254)
		(layers "F.Cu" "B.Cu")
		(net "BOOT_RECOVERY#")
	)
	(segment
		(start 220.620844 -20.933156)
		(end 225.534474 -20.933156)
		(width 0.127)
		(layer "In5.Cu")
		(net "BOOT_RECOVERY#")
	)
	(segment
		(start 231.394 -26.914094)
		(end 231.394 -29.083)
		(width 0.127)
		(layer "In5.Cu")
		(net "BOOT_RECOVERY#")
	)
	(segment
		(start 231.394 -29.083)
		(end 231.493822 -29.182822)
		(width 0.1016)
		(layer "In5.Cu")
		(net "BOOT_RECOVERY#")
	)
	(segment
		(start 226.616006 -22.1361)
		(end 231.394 -26.914094)
		(width 0.127)
		(layer "In5.Cu")
		(net "BOOT_RECOVERY#")
	)
	(segment
		(start 209.181954 -20.459954)
		(end 209.795872 -21.073872)
		(width 0.127)
		(layer "In5.Cu")
		(net "BOOT_RECOVERY#")
	)
	(segment
		(start 226.3267 -21.861018)
		(end 226.601782 -22.1361)
		(width 0.127)
		(layer "In5.Cu")
		(net "BOOT_RECOVERY#")
	)
	(segment
		(start 220.480128 -21.073872)
		(end 220.620844 -20.933156)
		(width 0.127)
		(layer "In5.Cu")
		(net "BOOT_RECOVERY#")
	)
	(segment
		(start 231.493822 -29.182822)
		(end 231.493822 -33.10636)
		(width 0.1016)
		(layer "In5.Cu")
		(net "BOOT_RECOVERY#")
	)
	(segment
		(start 209.795872 -21.073872)
		(end 220.480128 -21.073872)
		(width 0.127)
		(layer "In5.Cu")
		(net "BOOT_RECOVERY#")
	)
	(segment
		(start 226.601782 -22.1361)
		(end 226.616006 -22.1361)
		(width 0.127)
		(layer "In5.Cu")
		(net "BOOT_RECOVERY#")
	)
	(segment
		(start 225.534474 -20.933156)
		(end 226.3267 -21.725382)
		(width 0.127)
		(layer "In5.Cu")
		(net "BOOT_RECOVERY#")
	)
	(segment
		(start 226.3267 -21.725382)
		(end 226.3267 -21.861018)
		(width 0.127)
		(layer "In5.Cu")
		(net "BOOT_RECOVERY#")
	)
	(segment
		(start 231.493822 -33.10636)
		(end 231.100122 -33.50006)
		(width 0.1016)
		(layer "In5.Cu")
		(net "BOOT_RECOVERY#")
	)
	(segment
		(start 41.704768 -137.284968)
		(end 42.104564 -137.684764)
		(width 0.12065)
		(layer "F.Cu")
		(net "BMC0_TACH13")
	)
	(via
		(at 42.104564 -137.684764)
		(size 0.4572)
		(drill 0.2032)
		(layers "F.Cu" "B.Cu")
		(net "BMC0_TACH13")
	)
	(via
		(at 56.5912 -142.7734)
		(size 0.7112)
		(drill 0.3556)
		(layers "F.Cu" "B.Cu")
		(net "BMC0_TACH13")
	)
	(via
		(at 55.57012 -142.260828)
		(size 0.508)
		(drill 0.254)
		(layers "F.Cu" "B.Cu")
		(net "BMC0_TACH13")
	)
	(segment
		(start 56.146446 -142.7734)
		(end 56.5912 -142.7734)
		(width 0.12065)
		(layer "B.Cu")
		(net "BMC0_TACH13")
	)
	(segment
		(start 56.5912 -141.8717)
		(end 56.5912 -142.7734)
		(width 0.12065)
		(layer "B.Cu")
		(net "BMC0_TACH13")
	)
	(segment
		(start 55.57012 -142.260828)
		(end 55.633874 -142.260828)
		(width 0.12065)
		(layer "B.Cu")
		(net "BMC0_TACH13")
	)
	(segment
		(start 56.5785 -141.859)
		(end 56.5912 -141.8717)
		(width 0.12065)
		(layer "B.Cu")
		(net "BMC0_TACH13")
	)
	(segment
		(start 55.633874 -142.260828)
		(end 56.146446 -142.7734)
		(width 0.12065)
		(layer "B.Cu")
		(net "BMC0_TACH13")
	)
	(segment
		(start 55.351172 -142.260828)
		(end 55.57012 -142.260828)
		(width 0.127)
		(layer "In2.Cu")
		(net "BMC0_TACH13")
	)
	(segment
		(start 46.209204 -141.789404)
		(end 50.329084 -141.789404)
		(width 0.127)
		(layer "In2.Cu")
		(net "BMC0_TACH13")
	)
	(segment
		(start 55.25135 -142.36065)
		(end 55.351172 -142.260828)
		(width 0.127)
		(layer "In2.Cu")
		(net "BMC0_TACH13")
	)
	(segment
		(start 42.104564 -137.684764)
		(end 46.209204 -141.789404)
		(width 0.127)
		(layer "In2.Cu")
		(net "BMC0_TACH13")
	)
	(segment
		(start 52.73167 -142.36065)
		(end 55.25135 -142.36065)
		(width 0.127)
		(layer "In2.Cu")
		(net "BMC0_TACH13")
	)
	(segment
		(start 51.189382 -142.649702)
		(end 52.442618 -142.649702)
		(width 0.127)
		(layer "In2.Cu")
		(net "BMC0_TACH13")
	)
	(segment
		(start 50.329084 -141.789404)
		(end 51.189382 -142.649702)
		(width 0.127)
		(layer "In2.Cu")
		(net "BMC0_TACH13")
	)
	(segment
		(start 52.442618 -142.649702)
		(end 52.73167 -142.36065)
		(width 0.127)
		(layer "In2.Cu")
		(net "BMC0_TACH13")
	)
	(segment
		(start 44.104814 -122.884946)
		(end 43.705018 -122.48515)
		(width 0.12065)
		(layer "F.Cu")
		(net "BMC0_SMB9_DAT")
	)
	(via
		(at 48.43145 -119.011954)
		(size 0.7112)
		(drill 0.3556)
		(layers "F.Cu" "B.Cu")
		(net "BMC0_SMB9_DAT")
	)
	(via
		(at 43.705018 -122.48515)
		(size 0.4572)
		(drill 0.2032)
		(layers "F.Cu" "B.Cu")
		(net "BMC0_SMB9_DAT")
	)
	(segment
		(start 48.919892 -116.744496)
		(end 48.919892 -118.050564)
		(width 0.12065)
		(layer "B.Cu")
		(net "BMC0_SMB9_DAT")
	)
	(segment
		(start 48.194976 -118.77548)
		(end 48.43145 -119.011954)
		(width 0.12065)
		(layer "B.Cu")
		(net "BMC0_SMB9_DAT")
	)
	(segment
		(start 44.100496 -121.421652)
		(end 44.121578 -121.40057)
		(width 0.120396)
		(layer "B.Cu")
		(net "BMC0_SMB9_DAT")
	)
	(segment
		(start 49.1871 -116.477288)
		(end 48.919892 -116.744496)
		(width 0.12065)
		(layer "B.Cu")
		(net "BMC0_SMB9_DAT")
	)
	(segment
		(start 43.902376 -121.421652)
		(end 44.100496 -121.421652)
		(width 0.120396)
		(layer "B.Cu")
		(net "BMC0_SMB9_DAT")
	)
	(segment
		(start 43.415712 -122.774456)
		(end 43.307762 -122.774456)
		(width 0.120396)
		(layer "B.Cu")
		(net "BMC0_SMB9_DAT")
	)
	(segment
		(start 44.928282 -120.593866)
		(end 46.37659 -120.593866)
		(width 0.12065)
		(layer "B.Cu")
		(net "BMC0_SMB9_DAT")
	)
	(segment
		(start 43.705018 -122.48515)
		(end 43.415712 -122.774456)
		(width 0.120396)
		(layer "B.Cu")
		(net "BMC0_SMB9_DAT")
	)
	(segment
		(start 46.37659 -120.593866)
		(end 48.194976 -118.77548)
		(width 0.12065)
		(layer "B.Cu")
		(net "BMC0_SMB9_DAT")
	)
	(segment
		(start 43.307762 -122.774456)
		(end 43.187366 -122.653552)
		(width 0.120396)
		(layer "B.Cu")
		(net "BMC0_SMB9_DAT")
	)
	(segment
		(start 43.187366 -122.136662)
		(end 43.902376 -121.421652)
		(width 0.120396)
		(layer "B.Cu")
		(net "BMC0_SMB9_DAT")
	)
	(segment
		(start 44.121578 -121.40057)
		(end 44.928282 -120.593866)
		(width 0.12065)
		(layer "B.Cu")
		(net "BMC0_SMB9_DAT")
	)
	(segment
		(start 43.187366 -122.653552)
		(end 43.187366 -122.136662)
		(width 0.120396)
		(layer "B.Cu")
		(net "BMC0_SMB9_DAT")
	)
	(segment
		(start 48.919892 -118.050564)
		(end 48.194976 -118.77548)
		(width 0.12065)
		(layer "B.Cu")
		(net "BMC0_SMB9_DAT")
	)
	(segment
		(start 43.304714 -123.684792)
		(end 43.70451 -123.284996)
		(width 0.12065)
		(layer "F.Cu")
		(net "BMC0_SMB9_CLK")
	)
	(via
		(at 45.514768 -119.722646)
		(size 0.7112)
		(drill 0.3556)
		(layers "F.Cu" "B.Cu")
		(net "BMC0_SMB9_CLK")
	)
	(via
		(at 43.70451 -123.284996)
		(size 0.4572)
		(drill 0.2032)
		(layers "F.Cu" "B.Cu")
		(net "BMC0_SMB9_CLK")
	)
	(segment
		(start 45.514768 -120.092216)
		(end 44.720256 -120.092216)
		(width 0.12065)
		(layer "B.Cu")
		(net "BMC0_SMB9_CLK")
	)
	(segment
		(start 43.21556 -122.996452)
		(end 43.415712 -122.996452)
		(width 0.120396)
		(layer "B.Cu")
		(net "BMC0_SMB9_CLK")
	)
	(segment
		(start 43.415712 -122.996452)
		(end 43.70451 -123.284996)
		(width 0.120396)
		(layer "B.Cu")
		(net "BMC0_SMB9_CLK")
	)
	(segment
		(start 44.720256 -120.092216)
		(end 43.766486 -121.045986)
		(width 0.12065)
		(layer "B.Cu")
		(net "BMC0_SMB9_CLK")
	)
	(segment
		(start 43.745658 -121.264172)
		(end 42.96537 -122.04446)
		(width 0.120396)
		(layer "B.Cu")
		(net "BMC0_SMB9_CLK")
	)
	(segment
		(start 48.418242 -117.842538)
		(end 46.168564 -120.092216)
		(width 0.12065)
		(layer "B.Cu")
		(net "BMC0_SMB9_CLK")
	)
	(segment
		(start 43.215306 -122.996198)
		(end 43.21556 -122.996452)
		(width 0.120396)
		(layer "B.Cu")
		(net "BMC0_SMB9_CLK")
	)
	(segment
		(start 42.96537 -122.04446)
		(end 42.96537 -122.7455)
		(width 0.120396)
		(layer "B.Cu")
		(net "BMC0_SMB9_CLK")
	)
	(segment
		(start 42.96537 -122.7455)
		(end 43.215306 -122.996198)
		(width 0.120396)
		(layer "B.Cu")
		(net "BMC0_SMB9_CLK")
	)
	(segment
		(start 48.418242 -116.72443)
		(end 48.418242 -117.842538)
		(width 0.12065)
		(layer "B.Cu")
		(net "BMC0_SMB9_CLK")
	)
	(segment
		(start 48.1711 -116.477288)
		(end 48.418242 -116.72443)
		(width 0.12065)
		(layer "B.Cu")
		(net "BMC0_SMB9_CLK")
	)
	(segment
		(start 46.168564 -120.092216)
		(end 45.514768 -120.092216)
		(width 0.12065)
		(layer "B.Cu")
		(net "BMC0_SMB9_CLK")
	)
	(segment
		(start 45.514768 -120.092216)
		(end 45.514768 -119.722646)
		(width 0.12065)
		(layer "B.Cu")
		(net "BMC0_SMB9_CLK")
	)
	(segment
		(start 43.745404 -121.067068)
		(end 43.745658 -121.264172)
		(width 0.120396)
		(layer "B.Cu")
		(net "BMC0_SMB9_CLK")
	)
	(segment
		(start 43.766486 -121.045986)
		(end 43.745404 -121.067068)
		(width 0.120396)
		(layer "B.Cu")
		(net "BMC0_SMB9_CLK")
	)
	(segment
		(start 44.904914 -126.084838)
		(end 45.30471 -125.685042)
		(width 0.12065)
		(layer "F.Cu")
		(net "BMC0_SMB8_DAT")
	)
	(via
		(at 45.30471 -125.685042)
		(size 0.4572)
		(drill 0.2032)
		(layers "F.Cu" "B.Cu")
		(net "BMC0_SMB8_DAT")
	)
	(via
		(at 50.751486 -123.240546)
		(size 0.7112)
		(drill 0.3556)
		(layers "F.Cu" "B.Cu")
		(net "BMC0_SMB8_DAT")
	)
	(segment
		(start 52.687982 -123.548648)
		(end 53.034946 -123.201684)
		(width 0.12065)
		(layer "B.Cu")
		(net "BMC0_SMB8_DAT")
	)
	(segment
		(start 48.297338 -125.521212)
		(end 50.269902 -123.548648)
		(width 0.12065)
		(layer "B.Cu")
		(net "BMC0_SMB8_DAT")
	)
	(segment
		(start 53.246274 -123.201684)
		(end 53.587142 -122.860816)
		(width 0.12065)
		(layer "B.Cu")
		(net "BMC0_SMB8_DAT")
	)
	(segment
		(start 50.269902 -123.548648)
		(end 50.751486 -123.548648)
		(width 0.12065)
		(layer "B.Cu")
		(net "BMC0_SMB8_DAT")
	)
	(segment
		(start 50.751486 -123.548648)
		(end 50.751486 -123.240546)
		(width 0.12065)
		(layer "B.Cu")
		(net "BMC0_SMB8_DAT")
	)
	(segment
		(start 45.46854 -125.521212)
		(end 48.297338 -125.521212)
		(width 0.12065)
		(layer "B.Cu")
		(net "BMC0_SMB8_DAT")
	)
	(segment
		(start 50.751486 -123.548648)
		(end 52.687982 -123.548648)
		(width 0.12065)
		(layer "B.Cu")
		(net "BMC0_SMB8_DAT")
	)
	(segment
		(start 53.034946 -123.201684)
		(end 53.246274 -123.201684)
		(width 0.12065)
		(layer "B.Cu")
		(net "BMC0_SMB8_DAT")
	)
	(segment
		(start 45.30471 -125.685042)
		(end 45.46854 -125.521212)
		(width 0.12065)
		(layer "B.Cu")
		(net "BMC0_SMB8_DAT")
	)
	(segment
		(start 43.304714 -126.884938)
		(end 43.70451 -126.485142)
		(width 0.12065)
		(layer "F.Cu")
		(net "BMC0_SMB8_CLK")
	)
	(via
		(at 43.70451 -126.485142)
		(size 0.4572)
		(drill 0.2032)
		(layers "F.Cu" "B.Cu")
		(net "BMC0_SMB8_CLK")
	)
	(via
		(at 52.170838 -124.42698)
		(size 0.7112)
		(drill 0.3556)
		(layers "F.Cu" "B.Cu")
		(net "BMC0_SMB8_CLK")
	)
	(segment
		(start 53.242972 -123.703334)
		(end 52.896008 -124.050298)
		(width 0.12065)
		(layer "B.Cu")
		(net "BMC0_SMB8_CLK")
	)
	(segment
		(start 52.170838 -124.050298)
		(end 50.477928 -124.050298)
		(width 0.12065)
		(layer "B.Cu")
		(net "BMC0_SMB8_CLK")
	)
	(segment
		(start 46.454568 -126.09449)
		(end 44.095162 -126.09449)
		(width 0.12065)
		(layer "B.Cu")
		(net "BMC0_SMB8_CLK")
	)
	(segment
		(start 52.170838 -124.050298)
		(end 52.170838 -124.42698)
		(width 0.12065)
		(layer "B.Cu")
		(net "BMC0_SMB8_CLK")
	)
	(segment
		(start 46.526196 -126.022862)
		(end 46.454568 -126.09449)
		(width 0.12065)
		(layer "B.Cu")
		(net "BMC0_SMB8_CLK")
	)
	(segment
		(start 52.896008 -124.050298)
		(end 52.170838 -124.050298)
		(width 0.12065)
		(layer "B.Cu")
		(net "BMC0_SMB8_CLK")
	)
	(segment
		(start 53.41366 -123.703334)
		(end 53.242972 -123.703334)
		(width 0.12065)
		(layer "B.Cu")
		(net "BMC0_SMB8_CLK")
	)
	(segment
		(start 53.587142 -123.876816)
		(end 53.41366 -123.703334)
		(width 0.12065)
		(layer "B.Cu")
		(net "BMC0_SMB8_CLK")
	)
	(segment
		(start 48.505364 -126.022862)
		(end 46.526196 -126.022862)
		(width 0.12065)
		(layer "B.Cu")
		(net "BMC0_SMB8_CLK")
	)
	(segment
		(start 44.095162 -126.09449)
		(end 43.70451 -126.485142)
		(width 0.12065)
		(layer "B.Cu")
		(net "BMC0_SMB8_CLK")
	)
	(segment
		(start 50.477928 -124.050298)
		(end 48.505364 -126.022862)
		(width 0.12065)
		(layer "B.Cu")
		(net "BMC0_SMB8_CLK")
	)
	(segment
		(start 47.597568 -124.411994)
		(end 47.51324 -124.411994)
		(width 0.12065)
		(layer "F.Cu")
		(net "BMC0_SMB7_DAT")
	)
	(segment
		(start 46.610016 -124.590048)
		(end 46.50486 -124.484892)
		(width 0.12065)
		(layer "F.Cu")
		(net "BMC0_SMB7_DAT")
	)
	(segment
		(start 51.060096 -120.949466)
		(end 50.33772 -121.671842)
		(width 0.12065)
		(layer "F.Cu")
		(net "BMC0_SMB7_DAT")
	)
	(segment
		(start 47.335186 -124.590048)
		(end 46.610016 -124.590048)
		(width 0.12065)
		(layer "F.Cu")
		(net "BMC0_SMB7_DAT")
	)
	(segment
		(start 52.443634 -118.416832)
		(end 51.060096 -119.80037)
		(width 0.12065)
		(layer "F.Cu")
		(net "BMC0_SMB7_DAT")
	)
	(segment
		(start 50.33772 -121.671842)
		(end 50.095912 -121.430034)
		(width 0.12065)
		(layer "F.Cu")
		(net "BMC0_SMB7_DAT")
	)
	(segment
		(start 47.51324 -124.411994)
		(end 47.335186 -124.590048)
		(width 0.12065)
		(layer "F.Cu")
		(net "BMC0_SMB7_DAT")
	)
	(segment
		(start 52.969668 -118.416832)
		(end 52.443634 -118.416832)
		(width 0.12065)
		(layer "F.Cu")
		(net "BMC0_SMB7_DAT")
	)
	(segment
		(start 51.060096 -119.80037)
		(end 51.060096 -120.949466)
		(width 0.12065)
		(layer "F.Cu")
		(net "BMC0_SMB7_DAT")
	)
	(segment
		(start 50.33772 -121.671842)
		(end 47.597568 -124.411994)
		(width 0.12065)
		(layer "F.Cu")
		(net "BMC0_SMB7_DAT")
	)
	(segment
		(start 53.2765 -118.11)
		(end 52.969668 -118.416832)
		(width 0.12065)
		(layer "F.Cu")
		(net "BMC0_SMB7_DAT")
	)
	(via
		(at 50.095912 -121.430034)
		(size 0.7112)
		(drill 0.3556)
		(layers "F.Cu" "B.Cu")
		(net "BMC0_SMB7_DAT")
	)
	(segment
		(start 47.324772 -124.860558)
		(end 46.721522 -124.860558)
		(width 0.120396)
		(layer "F.Cu")
		(net "BMC0_SMB7_CLK")
	)
	(segment
		(start 46.13021 -124.859542)
		(end 45.70476 -125.284992)
		(width 0.12065)
		(layer "F.Cu")
		(net "BMC0_SMB7_CLK")
	)
	(segment
		(start 47.325788 -124.859542)
		(end 47.324772 -124.860558)
		(width 0.120396)
		(layer "F.Cu")
		(net "BMC0_SMB7_CLK")
	)
	(segment
		(start 46.170342 -124.86005)
		(end 46.169834 -124.859542)
		(width 0.120396)
		(layer "F.Cu")
		(net "BMC0_SMB7_CLK")
	)
	(segment
		(start 52.65166 -118.918482)
		(end 51.561746 -120.008396)
		(width 0.12065)
		(layer "F.Cu")
		(net "BMC0_SMB7_CLK")
	)
	(segment
		(start 46.721014 -124.86005)
		(end 46.170342 -124.86005)
		(width 0.120396)
		(layer "F.Cu")
		(net "BMC0_SMB7_CLK")
	)
	(segment
		(start 46.169834 -124.859542)
		(end 46.13021 -124.859542)
		(width 0.12065)
		(layer "F.Cu")
		(net "BMC0_SMB7_CLK")
	)
	(segment
		(start 53.2765 -119.126)
		(end 53.068982 -118.918482)
		(width 0.12065)
		(layer "F.Cu")
		(net "BMC0_SMB7_CLK")
	)
	(segment
		(start 47.859696 -124.859542)
		(end 47.85868 -124.859542)
		(width 0.12065)
		(layer "F.Cu")
		(net "BMC0_SMB7_CLK")
	)
	(segment
		(start 51.561746 -120.600216)
		(end 51.866292 -120.600216)
		(width 0.12065)
		(layer "F.Cu")
		(net "BMC0_SMB7_CLK")
	)
	(segment
		(start 51.561746 -120.600216)
		(end 51.561746 -121.157492)
		(width 0.12065)
		(layer "F.Cu")
		(net "BMC0_SMB7_CLK")
	)
	(segment
		(start 51.561746 -121.157492)
		(end 47.859696 -124.859542)
		(width 0.12065)
		(layer "F.Cu")
		(net "BMC0_SMB7_CLK")
	)
	(segment
		(start 53.068982 -118.918482)
		(end 52.65166 -118.918482)
		(width 0.12065)
		(layer "F.Cu")
		(net "BMC0_SMB7_CLK")
	)
	(segment
		(start 46.721522 -124.860558)
		(end 46.721014 -124.86005)
		(width 0.120396)
		(layer "F.Cu")
		(net "BMC0_SMB7_CLK")
	)
	(segment
		(start 47.85868 -124.859542)
		(end 47.325788 -124.859542)
		(width 0.120396)
		(layer "F.Cu")
		(net "BMC0_SMB7_CLK")
	)
	(segment
		(start 51.561746 -120.008396)
		(end 51.561746 -120.600216)
		(width 0.12065)
		(layer "F.Cu")
		(net "BMC0_SMB7_CLK")
	)
	(via
		(at 51.866292 -120.600216)
		(size 0.7112)
		(drill 0.3556)
		(layers "F.Cu" "B.Cu")
		(net "BMC0_SMB7_CLK")
	)
	(segment
		(start 44.104814 -126.084838)
		(end 44.50461 -125.685042)
		(width 0.12065)
		(layer "F.Cu")
		(net "BMC0_SMB6_DAT")
	)
	(via
		(at 65.1002 -124.46)
		(size 0.508)
		(drill 0.254)
		(layers "F.Cu" "B.Cu")
		(net "BMC0_SMB6_DAT")
	)
	(via
		(at 65.9892 -125.095)
		(size 0.7112)
		(drill 0.3556)
		(layers "F.Cu" "B.Cu")
		(net "BMC0_SMB6_DAT")
	)
	(via
		(at 44.50461 -125.685042)
		(size 0.4572)
		(drill 0.2032)
		(layers "F.Cu" "B.Cu")
		(net "BMC0_SMB6_DAT")
	)
	(segment
		(start 64.3255 -124.46)
		(end 65.1002 -124.46)
		(width 0.12065)
		(layer "B.Cu")
		(net "BMC0_SMB6_DAT")
	)
	(segment
		(start 65.9892 -125.095)
		(end 65.7098 -125.095)
		(width 0.12065)
		(layer "B.Cu")
		(net "BMC0_SMB6_DAT")
	)
	(segment
		(start 65.4304 -124.8156)
		(end 65.4304 -124.7902)
		(width 0.12065)
		(layer "B.Cu")
		(net "BMC0_SMB6_DAT")
	)
	(segment
		(start 65.4304 -124.7902)
		(end 65.1002 -124.46)
		(width 0.12065)
		(layer "B.Cu")
		(net "BMC0_SMB6_DAT")
	)
	(segment
		(start 65.7098 -125.095)
		(end 65.4304 -124.8156)
		(width 0.12065)
		(layer "B.Cu")
		(net "BMC0_SMB6_DAT")
	)
	(segment
		(start 65.1002 -124.46)
		(end 64.888618 -124.248418)
		(width 0.127)
		(layer "In2.Cu")
		(net "BMC0_SMB6_DAT")
	)
	(segment
		(start 63.0301 -121.369582)
		(end 60.405518 -118.745)
		(width 0.127)
		(layer "In2.Cu")
		(net "BMC0_SMB6_DAT")
	)
	(segment
		(start 63.0301 -123.549918)
		(end 63.0301 -121.369582)
		(width 0.127)
		(layer "In2.Cu")
		(net "BMC0_SMB6_DAT")
	)
	(segment
		(start 47.72787 -125.278896)
		(end 44.910756 -125.278896)
		(width 0.127)
		(layer "In2.Cu")
		(net "BMC0_SMB6_DAT")
	)
	(segment
		(start 44.910756 -125.278896)
		(end 44.50461 -125.685042)
		(width 0.127)
		(layer "In2.Cu")
		(net "BMC0_SMB6_DAT")
	)
	(segment
		(start 54.261766 -118.745)
		(end 47.72787 -125.278896)
		(width 0.127)
		(layer "In2.Cu")
		(net "BMC0_SMB6_DAT")
	)
	(segment
		(start 64.888618 -124.248418)
		(end 63.7286 -124.248418)
		(width 0.127)
		(layer "In2.Cu")
		(net "BMC0_SMB6_DAT")
	)
	(segment
		(start 60.405518 -118.745)
		(end 54.261766 -118.745)
		(width 0.127)
		(layer "In2.Cu")
		(net "BMC0_SMB6_DAT")
	)
	(segment
		(start 63.7286 -124.248418)
		(end 63.0301 -123.549918)
		(width 0.127)
		(layer "In2.Cu")
		(net "BMC0_SMB6_DAT")
	)
	(segment
		(start 46.50486 -123.684792)
		(end 46.904656 -124.084588)
		(width 0.12065)
		(layer "F.Cu")
		(net "BMC0_SMB6_CLK")
	)
	(via
		(at 46.904656 -124.084588)
		(size 0.4572)
		(drill 0.2032)
		(layers "F.Cu" "B.Cu")
		(net "BMC0_SMB6_CLK")
	)
	(via
		(at 66.167 -123.6472)
		(size 0.7112)
		(drill 0.3556)
		(layers "F.Cu" "B.Cu")
		(net "BMC0_SMB6_CLK")
	)
	(via
		(at 65.1002 -123.444)
		(size 0.508)
		(drill 0.254)
		(layers "F.Cu" "B.Cu")
		(net "BMC0_SMB6_CLK")
	)
	(segment
		(start 64.3255 -123.444)
		(end 65.1002 -123.444)
		(width 0.12065)
		(layer "B.Cu")
		(net "BMC0_SMB6_CLK")
	)
	(segment
		(start 65.1002 -123.444)
		(end 65.9638 -123.444)
		(width 0.12065)
		(layer "B.Cu")
		(net "BMC0_SMB6_CLK")
	)
	(segment
		(start 65.9638 -123.444)
		(end 66.167 -123.6472)
		(width 0.12065)
		(layer "B.Cu")
		(net "BMC0_SMB6_CLK")
	)
	(segment
		(start 47.116492 -124.770896)
		(end 46.904656 -124.55906)
		(width 0.127)
		(layer "In2.Cu")
		(net "BMC0_SMB6_CLK")
	)
	(segment
		(start 47.517304 -124.770896)
		(end 47.116492 -124.770896)
		(width 0.127)
		(layer "In2.Cu")
		(net "BMC0_SMB6_CLK")
	)
	(segment
		(start 65.1002 -123.444)
		(end 64.803782 -123.740418)
		(width 0.127)
		(layer "In2.Cu")
		(net "BMC0_SMB6_CLK")
	)
	(segment
		(start 46.904656 -124.55906)
		(end 46.904656 -124.084588)
		(width 0.127)
		(layer "In2.Cu")
		(net "BMC0_SMB6_CLK")
	)
	(segment
		(start 63.939166 -123.740418)
		(end 63.5381 -123.339352)
		(width 0.127)
		(layer "In2.Cu")
		(net "BMC0_SMB6_CLK")
	)
	(segment
		(start 63.5381 -121.159016)
		(end 60.616084 -118.237)
		(width 0.127)
		(layer "In2.Cu")
		(net "BMC0_SMB6_CLK")
	)
	(segment
		(start 60.616084 -118.237)
		(end 54.0512 -118.237)
		(width 0.127)
		(layer "In2.Cu")
		(net "BMC0_SMB6_CLK")
	)
	(segment
		(start 64.803782 -123.740418)
		(end 63.939166 -123.740418)
		(width 0.127)
		(layer "In2.Cu")
		(net "BMC0_SMB6_CLK")
	)
	(segment
		(start 63.5381 -123.339352)
		(end 63.5381 -121.159016)
		(width 0.127)
		(layer "In2.Cu")
		(net "BMC0_SMB6_CLK")
	)
	(segment
		(start 54.0512 -118.237)
		(end 47.517304 -124.770896)
		(width 0.127)
		(layer "In2.Cu")
		(net "BMC0_SMB6_CLK")
	)
	(segment
		(start 45.70476 -124.484892)
		(end 46.104556 -124.085096)
		(width 0.12065)
		(layer "F.Cu")
		(net "BMC0_SMB5_DAT")
	)
	(via
		(at 46.104556 -124.085096)
		(size 0.4572)
		(drill 0.2032)
		(layers "F.Cu" "B.Cu")
		(net "BMC0_SMB5_DAT")
	)
	(via
		(at 52.447698 -120.744742)
		(size 0.7112)
		(drill 0.3556)
		(layers "F.Cu" "B.Cu")
		(net "BMC0_SMB5_DAT")
	)
	(segment
		(start 51.270408 -121.06529)
		(end 47.849536 -124.486162)
		(width 0.12065)
		(layer "B.Cu")
		(net "BMC0_SMB5_DAT")
	)
	(segment
		(start 47.849536 -124.486162)
		(end 46.505622 -124.486162)
		(width 0.12065)
		(layer "B.Cu")
		(net "BMC0_SMB5_DAT")
	)
	(segment
		(start 52.447698 -121.06529)
		(end 52.447698 -120.744742)
		(width 0.12065)
		(layer "B.Cu")
		(net "BMC0_SMB5_DAT")
	)
	(segment
		(start 52.447698 -121.06529)
		(end 51.270408 -121.06529)
		(width 0.12065)
		(layer "B.Cu")
		(net "BMC0_SMB5_DAT")
	)
	(segment
		(start 53.272944 -121.06529)
		(end 52.447698 -121.06529)
		(width 0.12065)
		(layer "B.Cu")
		(net "BMC0_SMB5_DAT")
	)
	(segment
		(start 46.505622 -124.486162)
		(end 46.104556 -124.085096)
		(width 0.12065)
		(layer "B.Cu")
		(net "BMC0_SMB5_DAT")
	)
	(segment
		(start 53.531008 -120.807226)
		(end 53.272944 -121.06529)
		(width 0.12065)
		(layer "B.Cu")
		(net "BMC0_SMB5_DAT")
	)
	(segment
		(start 44.904914 -125.284992)
		(end 45.30471 -124.885196)
		(width 0.12065)
		(layer "F.Cu")
		(net "BMC0_SMB5_CLK")
	)
	(via
		(at 51.897026 -121.89333)
		(size 0.7112)
		(drill 0.3556)
		(layers "F.Cu" "B.Cu")
		(net "BMC0_SMB5_CLK")
	)
	(via
		(at 45.30471 -124.885196)
		(size 0.4572)
		(drill 0.2032)
		(layers "F.Cu" "B.Cu")
		(net "BMC0_SMB5_CLK")
	)
	(segment
		(start 51.897026 -121.56694)
		(end 51.478434 -121.56694)
		(width 0.12065)
		(layer "B.Cu")
		(net "BMC0_SMB5_CLK")
	)
	(segment
		(start 46.297596 -124.987812)
		(end 46.19498 -124.885196)
		(width 0.12065)
		(layer "B.Cu")
		(net "BMC0_SMB5_CLK")
	)
	(segment
		(start 53.274722 -121.56694)
		(end 53.531008 -121.823226)
		(width 0.12065)
		(layer "B.Cu")
		(net "BMC0_SMB5_CLK")
	)
	(segment
		(start 51.897026 -121.89333)
		(end 51.897026 -121.56694)
		(width 0.12065)
		(layer "B.Cu")
		(net "BMC0_SMB5_CLK")
	)
	(segment
		(start 51.478434 -121.56694)
		(end 48.057562 -124.987812)
		(width 0.12065)
		(layer "B.Cu")
		(net "BMC0_SMB5_CLK")
	)
	(segment
		(start 46.19498 -124.885196)
		(end 45.30471 -124.885196)
		(width 0.12065)
		(layer "B.Cu")
		(net "BMC0_SMB5_CLK")
	)
	(segment
		(start 48.057562 -124.987812)
		(end 46.297596 -124.987812)
		(width 0.12065)
		(layer "B.Cu")
		(net "BMC0_SMB5_CLK")
	)
	(segment
		(start 51.897026 -121.56694)
		(end 53.274722 -121.56694)
		(width 0.12065)
		(layer "B.Cu")
		(net "BMC0_SMB5_CLK")
	)
	(segment
		(start 43.304714 -126.084838)
		(end 43.70451 -125.685042)
		(width 0.12065)
		(layer "F.Cu")
		(net "BMC0_SMB4_DAT")
	)
	(via
		(at 43.056556 -125.178566)
		(size 0.7112)
		(drill 0.3556)
		(layers "F.Cu" "B.Cu")
		(net "BMC0_SMB4_DAT")
	)
	(via
		(at 43.70451 -125.685042)
		(size 0.4572)
		(drill 0.2032)
		(layers "F.Cu" "B.Cu")
		(net "BMC0_SMB4_DAT")
	)
	(via
		(at 65.3796 -122.335798)
		(size 0.508)
		(drill 0.254)
		(layers "F.Cu" "B.Cu")
		(net "BMC0_SMB4_DAT")
	)
	(segment
		(start 65.3796 -122.335798)
		(end 65.490598 -122.335798)
		(width 0.12065)
		(layer "B.Cu")
		(net "BMC0_SMB4_DAT")
	)
	(segment
		(start 64.836802 -122.043698)
		(end 65.18275 -122.043698)
		(width 0.12065)
		(layer "B.Cu")
		(net "BMC0_SMB4_DAT")
	)
	(segment
		(start 65.757044 -122.069352)
		(end 66.237104 -122.069352)
		(width 0.12065)
		(layer "B.Cu")
		(net "BMC0_SMB4_DAT")
	)
	(segment
		(start 65.490598 -122.335798)
		(end 65.757044 -122.069352)
		(width 0.12065)
		(layer "B.Cu")
		(net "BMC0_SMB4_DAT")
	)
	(segment
		(start 65.18275 -122.043698)
		(end 65.3796 -122.240548)
		(width 0.12065)
		(layer "B.Cu")
		(net "BMC0_SMB4_DAT")
	)
	(segment
		(start 43.563032 -125.685042)
		(end 43.056556 -125.178566)
		(width 0.12065)
		(layer "B.Cu")
		(net "BMC0_SMB4_DAT")
	)
	(segment
		(start 66.237104 -122.069352)
		(end 66.494152 -122.3264)
		(width 0.12065)
		(layer "B.Cu")
		(net "BMC0_SMB4_DAT")
	)
	(segment
		(start 64.5795 -122.301)
		(end 64.836802 -122.043698)
		(width 0.12065)
		(layer "B.Cu")
		(net "BMC0_SMB4_DAT")
	)
	(segment
		(start 65.3796 -122.240548)
		(end 65.3796 -122.335798)
		(width 0.12065)
		(layer "B.Cu")
		(net "BMC0_SMB4_DAT")
	)
	(segment
		(start 43.70451 -125.685042)
		(end 43.563032 -125.685042)
		(width 0.12065)
		(layer "B.Cu")
		(net "BMC0_SMB4_DAT")
	)
	(segment
		(start 56.755284 -117.1448)
		(end 54.490366 -117.1448)
		(width 0.127)
		(layer "In2.Cu")
		(net "BMC0_SMB4_DAT")
	)
	(segment
		(start 63.9318 -120.945402)
		(end 60.740798 -117.7544)
		(width 0.127)
		(layer "In2.Cu")
		(net "BMC0_SMB4_DAT")
	)
	(segment
		(start 44.10456 -125.284992)
		(end 43.70451 -125.685042)
		(width 0.127)
		(layer "In2.Cu")
		(net "BMC0_SMB4_DAT")
	)
	(segment
		(start 60.740798 -117.7544)
		(end 57.364884 -117.7544)
		(width 0.127)
		(layer "In2.Cu")
		(net "BMC0_SMB4_DAT")
	)
	(segment
		(start 65.186052 -122.047)
		(end 64.559434 -122.047)
		(width 0.127)
		(layer "In2.Cu")
		(net "BMC0_SMB4_DAT")
	)
	(segment
		(start 46.504606 -124.242068)
		(end 46.261528 -124.485146)
		(width 0.127)
		(layer "In2.Cu")
		(net "BMC0_SMB4_DAT")
	)
	(segment
		(start 57.364884 -117.7544)
		(end 56.755284 -117.1448)
		(width 0.127)
		(layer "In2.Cu")
		(net "BMC0_SMB4_DAT")
	)
	(segment
		(start 46.261528 -124.485146)
		(end 44.347638 -124.485146)
		(width 0.127)
		(layer "In2.Cu")
		(net "BMC0_SMB4_DAT")
	)
	(segment
		(start 65.3796 -122.335798)
		(end 65.3796 -122.240548)
		(width 0.127)
		(layer "In2.Cu")
		(net "BMC0_SMB4_DAT")
	)
	(segment
		(start 47.067978 -123.690888)
		(end 46.741334 -123.690888)
		(width 0.127)
		(layer "In2.Cu")
		(net "BMC0_SMB4_DAT")
	)
	(segment
		(start 65.3796 -122.240548)
		(end 65.186052 -122.047)
		(width 0.127)
		(layer "In2.Cu")
		(net "BMC0_SMB4_DAT")
	)
	(segment
		(start 63.9318 -121.419366)
		(end 63.9318 -120.945402)
		(width 0.127)
		(layer "In2.Cu")
		(net "BMC0_SMB4_DAT")
	)
	(segment
		(start 54.490366 -117.1448)
		(end 47.829978 -123.805188)
		(width 0.127)
		(layer "In2.Cu")
		(net "BMC0_SMB4_DAT")
	)
	(segment
		(start 64.559434 -122.047)
		(end 63.9318 -121.419366)
		(width 0.127)
		(layer "In2.Cu")
		(net "BMC0_SMB4_DAT")
	)
	(segment
		(start 47.829978 -123.805188)
		(end 47.182278 -123.805188)
		(width 0.127)
		(layer "In2.Cu")
		(net "BMC0_SMB4_DAT")
	)
	(segment
		(start 47.182278 -123.805188)
		(end 47.067978 -123.690888)
		(width 0.127)
		(layer "In2.Cu")
		(net "BMC0_SMB4_DAT")
	)
	(segment
		(start 46.504606 -123.927616)
		(end 46.504606 -124.242068)
		(width 0.127)
		(layer "In2.Cu")
		(net "BMC0_SMB4_DAT")
	)
	(segment
		(start 44.10456 -124.728224)
		(end 44.10456 -125.284992)
		(width 0.127)
		(layer "In2.Cu")
		(net "BMC0_SMB4_DAT")
	)
	(segment
		(start 46.741334 -123.690888)
		(end 46.504606 -123.927616)
		(width 0.127)
		(layer "In2.Cu")
		(net "BMC0_SMB4_DAT")
	)
	(segment
		(start 44.347638 -124.485146)
		(end 44.10456 -124.728224)
		(width 0.127)
		(layer "In2.Cu")
		(net "BMC0_SMB4_DAT")
	)
	(segment
		(start 46.904402 -123.284488)
		(end 46.904656 -123.284488)
		(width 0.12065)
		(layer "F.Cu")
		(net "BMC0_SMB4_CLK")
	)
	(segment
		(start 46.50486 -122.884946)
		(end 46.904402 -123.284488)
		(width 0.12065)
		(layer "F.Cu")
		(net "BMC0_SMB4_CLK")
	)
	(via
		(at 47.5742 -123.6726)
		(size 0.7112)
		(drill 0.3556)
		(layers "F.Cu" "B.Cu")
		(net "BMC0_SMB4_CLK")
	)
	(via
		(at 65.3796 -121.2342)
		(size 0.508)
		(drill 0.254)
		(layers "F.Cu" "B.Cu")
		(net "BMC0_SMB4_CLK")
	)
	(via
		(at 46.904656 -123.284488)
		(size 0.4572)
		(drill 0.2032)
		(layers "F.Cu" "B.Cu")
		(net "BMC0_SMB4_CLK")
	)
	(segment
		(start 64.5795 -121.285)
		(end 64.836548 -121.542048)
		(width 0.12065)
		(layer "B.Cu")
		(net "BMC0_SMB4_CLK")
	)
	(segment
		(start 46.904656 -123.284488)
		(end 47.186088 -123.284488)
		(width 0.12065)
		(layer "B.Cu")
		(net "BMC0_SMB4_CLK")
	)
	(segment
		(start 65.808352 -121.567702)
		(end 66.23685 -121.567702)
		(width 0.12065)
		(layer "B.Cu")
		(net "BMC0_SMB4_CLK")
	)
	(segment
		(start 64.836548 -121.542048)
		(end 65.18275 -121.542048)
		(width 0.12065)
		(layer "B.Cu")
		(net "BMC0_SMB4_CLK")
	)
	(segment
		(start 47.186088 -123.284488)
		(end 47.5742 -123.6726)
		(width 0.12065)
		(layer "B.Cu")
		(net "BMC0_SMB4_CLK")
	)
	(segment
		(start 65.18275 -121.542048)
		(end 65.3796 -121.345198)
		(width 0.12065)
		(layer "B.Cu")
		(net "BMC0_SMB4_CLK")
	)
	(segment
		(start 65.3796 -121.2342)
		(end 65.47485 -121.2342)
		(width 0.12065)
		(layer "B.Cu")
		(net "BMC0_SMB4_CLK")
	)
	(segment
		(start 65.3796 -121.345198)
		(end 65.3796 -121.2342)
		(width 0.12065)
		(layer "B.Cu")
		(net "BMC0_SMB4_CLK")
	)
	(segment
		(start 66.23685 -121.567702)
		(end 66.494152 -121.3104)
		(width 0.12065)
		(layer "B.Cu")
		(net "BMC0_SMB4_CLK")
	)
	(segment
		(start 65.47485 -121.2342)
		(end 65.808352 -121.567702)
		(width 0.12065)
		(layer "B.Cu")
		(net "BMC0_SMB4_CLK")
	)
	(segment
		(start 65.185798 -121.539)
		(end 64.77 -121.539)
		(width 0.127)
		(layer "In2.Cu")
		(net "BMC0_SMB4_CLK")
	)
	(segment
		(start 56.96585 -116.6368)
		(end 54.2798 -116.6368)
		(width 0.127)
		(layer "In2.Cu")
		(net "BMC0_SMB4_CLK")
	)
	(segment
		(start 64.77 -121.539)
		(end 64.4398 -121.2088)
		(width 0.127)
		(layer "In2.Cu")
		(net "BMC0_SMB4_CLK")
	)
	(segment
		(start 65.3796 -121.345198)
		(end 65.185798 -121.539)
		(width 0.127)
		(layer "In2.Cu")
		(net "BMC0_SMB4_CLK")
	)
	(segment
		(start 46.90491 -123.284742)
		(end 46.904656 -123.284488)
		(width 0.127)
		(layer "In2.Cu")
		(net "BMC0_SMB4_CLK")
	)
	(segment
		(start 65.3796 -121.2342)
		(end 65.3796 -121.345198)
		(width 0.127)
		(layer "In2.Cu")
		(net "BMC0_SMB4_CLK")
	)
	(segment
		(start 47.35957 -123.263914)
		(end 46.938946 -123.263914)
		(width 0.127)
		(layer "In2.Cu")
		(net "BMC0_SMB4_CLK")
	)
	(segment
		(start 46.918118 -123.284742)
		(end 46.90491 -123.284742)
		(width 0.127)
		(layer "In2.Cu")
		(net "BMC0_SMB4_CLK")
	)
	(segment
		(start 57.57545 -117.2464)
		(end 56.96585 -116.6368)
		(width 0.127)
		(layer "In2.Cu")
		(net "BMC0_SMB4_CLK")
	)
	(segment
		(start 64.4398 -120.734836)
		(end 60.951364 -117.2464)
		(width 0.127)
		(layer "In2.Cu")
		(net "BMC0_SMB4_CLK")
	)
	(segment
		(start 60.951364 -117.2464)
		(end 57.57545 -117.2464)
		(width 0.127)
		(layer "In2.Cu")
		(net "BMC0_SMB4_CLK")
	)
	(segment
		(start 64.4398 -121.2088)
		(end 64.4398 -120.734836)
		(width 0.127)
		(layer "In2.Cu")
		(net "BMC0_SMB4_CLK")
	)
	(segment
		(start 47.392844 -123.297188)
		(end 47.35957 -123.263914)
		(width 0.127)
		(layer "In2.Cu")
		(net "BMC0_SMB4_CLK")
	)
	(segment
		(start 54.2798 -116.6368)
		(end 47.619412 -123.297188)
		(width 0.127)
		(layer "In2.Cu")
		(net "BMC0_SMB4_CLK")
	)
	(segment
		(start 47.619412 -123.297188)
		(end 47.392844 -123.297188)
		(width 0.127)
		(layer "In2.Cu")
		(net "BMC0_SMB4_CLK")
	)
	(segment
		(start 46.938946 -123.263914)
		(end 46.918118 -123.284742)
		(width 0.127)
		(layer "In2.Cu")
		(net "BMC0_SMB4_CLK")
	)
	(segment
		(start 32.904938 -128.484884)
		(end 32.505142 -128.085088)
		(width 0.12065)
		(layer "F.Cu")
		(net "BMC0_SMB2_DAT")
	)
	(via
		(at 22.043898 -125.616462)
		(size 0.7112)
		(drill 0.3556)
		(layers "F.Cu" "B.Cu")
		(net "BMC0_SMB2_DAT")
	)
	(via
		(at 32.505142 -128.085088)
		(size 0.4572)
		(drill 0.2032)
		(layers "F.Cu" "B.Cu")
		(net "BMC0_SMB2_DAT")
	)
	(segment
		(start 28.431998 -128.26619)
		(end 28.450032 -128.284224)
		(width 0.1016)
		(layer "B.Cu")
		(net "BMC0_SMB2_DAT")
	)
	(segment
		(start 32.43834 -128.085088)
		(end 32.505142 -128.085088)
		(width 0.1016)
		(layer "B.Cu")
		(net "BMC0_SMB2_DAT")
	)
	(segment
		(start 31.745428 -128.778)
		(end 32.43834 -128.085088)
		(width 0.1016)
		(layer "B.Cu")
		(net "BMC0_SMB2_DAT")
	)
	(segment
		(start 20.845018 -125.497844)
		(end 21.10359 -125.239272)
		(width 0.12065)
		(layer "B.Cu")
		(net "BMC0_SMB2_DAT")
	)
	(segment
		(start 22.043898 -125.239272)
		(end 22.043898 -125.616462)
		(width 0.12065)
		(layer "B.Cu")
		(net "BMC0_SMB2_DAT")
	)
	(segment
		(start 27.943302 -127.777494)
		(end 28.431998 -128.26619)
		(width 0.12065)
		(layer "B.Cu")
		(net "BMC0_SMB2_DAT")
	)
	(segment
		(start 29.154628 -128.778)
		(end 31.745428 -128.778)
		(width 0.1016)
		(layer "B.Cu")
		(net "BMC0_SMB2_DAT")
	)
	(segment
		(start 25.884378 -125.491494)
		(end 27.943302 -127.550418)
		(width 0.12065)
		(layer "B.Cu")
		(net "BMC0_SMB2_DAT")
	)
	(segment
		(start 21.10359 -125.239272)
		(end 22.043898 -125.239272)
		(width 0.12065)
		(layer "B.Cu")
		(net "BMC0_SMB2_DAT")
	)
	(segment
		(start 27.943302 -127.550418)
		(end 27.943302 -127.777494)
		(width 0.12065)
		(layer "B.Cu")
		(net "BMC0_SMB2_DAT")
	)
	(segment
		(start 28.660852 -128.284224)
		(end 29.154628 -128.778)
		(width 0.1016)
		(layer "B.Cu")
		(net "BMC0_SMB2_DAT")
	)
	(segment
		(start 23.372064 -125.239272)
		(end 23.624286 -125.491494)
		(width 0.12065)
		(layer "B.Cu")
		(net "BMC0_SMB2_DAT")
	)
	(segment
		(start 28.450032 -128.284224)
		(end 28.660852 -128.284224)
		(width 0.1016)
		(layer "B.Cu")
		(net "BMC0_SMB2_DAT")
	)
	(segment
		(start 23.624286 -125.491494)
		(end 25.884378 -125.491494)
		(width 0.12065)
		(layer "B.Cu")
		(net "BMC0_SMB2_DAT")
	)
	(segment
		(start 22.043898 -125.239272)
		(end 23.372064 -125.239272)
		(width 0.12065)
		(layer "B.Cu")
		(net "BMC0_SMB2_DAT")
	)
	(segment
		(start 32.104838 -128.484884)
		(end 31.704788 -128.084834)
		(width 0.12065)
		(layer "F.Cu")
		(net "BMC0_SMB2_CLK")
	)
	(via
		(at 24.318468 -124.68098)
		(size 0.7112)
		(drill 0.3556)
		(layers "F.Cu" "B.Cu")
		(net "BMC0_SMB2_CLK")
	)
	(via
		(at 31.704788 -128.084834)
		(size 0.4572)
		(drill 0.2032)
		(layers "F.Cu" "B.Cu")
		(net "BMC0_SMB2_CLK")
	)
	(segment
		(start 21.100796 -124.737622)
		(end 23.58009 -124.737622)
		(width 0.12065)
		(layer "B.Cu")
		(net "BMC0_SMB2_CLK")
	)
	(segment
		(start 24.318468 -124.989844)
		(end 26.092404 -124.989844)
		(width 0.12065)
		(layer "B.Cu")
		(net "BMC0_SMB2_CLK")
	)
	(segment
		(start 29.238956 -128.5748)
		(end 31.6611 -128.5748)
		(width 0.1016)
		(layer "B.Cu")
		(net "BMC0_SMB2_CLK")
	)
	(segment
		(start 23.58009 -124.737622)
		(end 23.832312 -124.989844)
		(width 0.12065)
		(layer "B.Cu")
		(net "BMC0_SMB2_CLK")
	)
	(segment
		(start 28.92171 -128.257554)
		(end 29.238956 -128.5748)
		(width 0.1016)
		(layer "B.Cu")
		(net "BMC0_SMB2_CLK")
	)
	(segment
		(start 20.845018 -124.481844)
		(end 21.100796 -124.737622)
		(width 0.12065)
		(layer "B.Cu")
		(net "BMC0_SMB2_CLK")
	)
	(segment
		(start 24.318468 -124.989844)
		(end 24.318468 -124.68098)
		(width 0.12065)
		(layer "B.Cu")
		(net "BMC0_SMB2_CLK")
	)
	(segment
		(start 28.92171 -128.046226)
		(end 28.92171 -128.257554)
		(width 0.1016)
		(layer "B.Cu")
		(net "BMC0_SMB2_CLK")
	)
	(segment
		(start 23.832312 -124.989844)
		(end 24.318468 -124.989844)
		(width 0.12065)
		(layer "B.Cu")
		(net "BMC0_SMB2_CLK")
	)
	(segment
		(start 31.84271 -128.39319)
		(end 31.84271 -128.222756)
		(width 0.1016)
		(layer "B.Cu")
		(net "BMC0_SMB2_CLK")
	)
	(segment
		(start 28.444952 -127.342392)
		(end 28.444952 -127.569468)
		(width 0.12065)
		(layer "B.Cu")
		(net "BMC0_SMB2_CLK")
	)
	(segment
		(start 28.90393 -128.028446)
		(end 28.92171 -128.046226)
		(width 0.1016)
		(layer "B.Cu")
		(net "BMC0_SMB2_CLK")
	)
	(segment
		(start 28.444952 -127.569468)
		(end 28.90393 -128.028446)
		(width 0.12065)
		(layer "B.Cu")
		(net "BMC0_SMB2_CLK")
	)
	(segment
		(start 26.092404 -124.989844)
		(end 28.444952 -127.342392)
		(width 0.12065)
		(layer "B.Cu")
		(net "BMC0_SMB2_CLK")
	)
	(segment
		(start 31.6611 -128.5748)
		(end 31.84271 -128.39319)
		(width 0.1016)
		(layer "B.Cu")
		(net "BMC0_SMB2_CLK")
	)
	(segment
		(start 31.84271 -128.222756)
		(end 31.704788 -128.084834)
		(width 0.1016)
		(layer "B.Cu")
		(net "BMC0_SMB2_CLK")
	)
	(segment
		(start 44.904914 -127.684784)
		(end 45.30471 -127.284988)
		(width 0.12065)
		(layer "F.Cu")
		(net "BMC0_SMB14_SDA")
	)
	(via
		(at 49.313592 -127.30607)
		(size 0.7112)
		(drill 0.3556)
		(layers "F.Cu" "B.Cu")
		(net "BMC0_SMB14_SDA")
	)
	(via
		(at 45.30471 -127.284988)
		(size 0.4572)
		(drill 0.2032)
		(layers "F.Cu" "B.Cu")
		(net "BMC0_SMB14_SDA")
	)
	(segment
		(start 48.452532 -126.891034)
		(end 49.09058 -127.529082)
		(width 0.12065)
		(layer "B.Cu")
		(net "BMC0_SMB14_SDA")
	)
	(segment
		(start 49.313592 -127.30607)
		(end 49.09058 -127.529082)
		(width 0.12065)
		(layer "B.Cu")
		(net "BMC0_SMB14_SDA")
	)
	(segment
		(start 45.415708 -127.17399)
		(end 45.626528 -127.17399)
		(width 0.12065)
		(layer "B.Cu")
		(net "BMC0_SMB14_SDA")
	)
	(segment
		(start 49.537112 -127.975614)
		(end 50.827686 -127.975614)
		(width 0.12065)
		(layer "B.Cu")
		(net "BMC0_SMB14_SDA")
	)
	(segment
		(start 45.626528 -127.17399)
		(end 45.909484 -126.891034)
		(width 0.12065)
		(layer "B.Cu")
		(net "BMC0_SMB14_SDA")
	)
	(segment
		(start 45.909484 -126.891034)
		(end 48.452532 -126.891034)
		(width 0.12065)
		(layer "B.Cu")
		(net "BMC0_SMB14_SDA")
	)
	(segment
		(start 50.827686 -127.975614)
		(end 51.0921 -127.7112)
		(width 0.12065)
		(layer "B.Cu")
		(net "BMC0_SMB14_SDA")
	)
	(segment
		(start 45.30471 -127.284988)
		(end 45.415708 -127.17399)
		(width 0.12065)
		(layer "B.Cu")
		(net "BMC0_SMB14_SDA")
	)
	(segment
		(start 49.09058 -127.529082)
		(end 49.537112 -127.975614)
		(width 0.12065)
		(layer "B.Cu")
		(net "BMC0_SMB14_SDA")
	)
	(segment
		(start 44.104814 -127.684784)
		(end 44.50461 -127.284988)
		(width 0.12065)
		(layer "F.Cu")
		(net "BMC0_SMB14_CLK")
	)
	(via
		(at 46.87189 -127.73914)
		(size 0.7112)
		(drill 0.3556)
		(layers "F.Cu" "B.Cu")
		(net "BMC0_SMB14_CLK")
	)
	(via
		(at 44.50461 -127.284988)
		(size 0.4572)
		(drill 0.2032)
		(layers "F.Cu" "B.Cu")
		(net "BMC0_SMB14_CLK")
	)
	(segment
		(start 44.50461 -127.284988)
		(end 44.674028 -127.284988)
		(width 0.12065)
		(layer "B.Cu")
		(net "BMC0_SMB14_CLK")
	)
	(segment
		(start 50.842164 -128.477264)
		(end 51.0921 -128.7272)
		(width 0.12065)
		(layer "B.Cu")
		(net "BMC0_SMB14_CLK")
	)
	(segment
		(start 46.87189 -127.392684)
		(end 46.87189 -127.73914)
		(width 0.12065)
		(layer "B.Cu")
		(net "BMC0_SMB14_CLK")
	)
	(segment
		(start 46.11751 -127.392684)
		(end 46.87189 -127.392684)
		(width 0.12065)
		(layer "B.Cu")
		(net "BMC0_SMB14_CLK")
	)
	(segment
		(start 45.834554 -127.67564)
		(end 46.11751 -127.392684)
		(width 0.12065)
		(layer "B.Cu")
		(net "BMC0_SMB14_CLK")
	)
	(segment
		(start 46.87189 -127.392684)
		(end 48.244506 -127.392684)
		(width 0.12065)
		(layer "B.Cu")
		(net "BMC0_SMB14_CLK")
	)
	(segment
		(start 45.06468 -127.67564)
		(end 45.834554 -127.67564)
		(width 0.12065)
		(layer "B.Cu")
		(net "BMC0_SMB14_CLK")
	)
	(segment
		(start 49.329086 -128.477264)
		(end 50.842164 -128.477264)
		(width 0.12065)
		(layer "B.Cu")
		(net "BMC0_SMB14_CLK")
	)
	(segment
		(start 48.244506 -127.392684)
		(end 49.329086 -128.477264)
		(width 0.12065)
		(layer "B.Cu")
		(net "BMC0_SMB14_CLK")
	)
	(segment
		(start 44.674028 -127.284988)
		(end 45.06468 -127.67564)
		(width 0.12065)
		(layer "B.Cu")
		(net "BMC0_SMB14_CLK")
	)
	(segment
		(start 44.904914 -122.884946)
		(end 44.505118 -122.48515)
		(width 0.12065)
		(layer "F.Cu")
		(net "BMC0_SMB10_DAT")
	)
	(via
		(at 51.35499 -117.513862)
		(size 0.7112)
		(drill 0.3556)
		(layers "F.Cu" "B.Cu")
		(net "BMC0_SMB10_DAT")
	)
	(via
		(at 44.505118 -122.48515)
		(size 0.4572)
		(drill 0.2032)
		(layers "F.Cu" "B.Cu")
		(net "BMC0_SMB10_DAT")
	)
	(segment
		(start 45.45711 -121.208546)
		(end 46.742858 -121.208546)
		(width 0.1016)
		(layer "B.Cu")
		(net "BMC0_SMB10_DAT")
	)
	(segment
		(start 46.89221 -121.357898)
		(end 47.822104 -121.357898)
		(width 0.12065)
		(layer "B.Cu")
		(net "BMC0_SMB10_DAT")
	)
	(segment
		(start 51.001168 -116.584222)
		(end 51.001168 -117.513862)
		(width 0.12065)
		(layer "B.Cu")
		(net "BMC0_SMB10_DAT")
	)
	(segment
		(start 44.505118 -122.48515)
		(end 44.505118 -122.160538)
		(width 0.1016)
		(layer "B.Cu")
		(net "BMC0_SMB10_DAT")
	)
	(segment
		(start 46.742858 -121.208546)
		(end 46.89221 -121.357898)
		(width 0.1016)
		(layer "B.Cu")
		(net "BMC0_SMB10_DAT")
	)
	(segment
		(start 44.505118 -122.160538)
		(end 45.45711 -121.208546)
		(width 0.1016)
		(layer "B.Cu")
		(net "BMC0_SMB10_DAT")
	)
	(segment
		(start 51.2318 -116.35359)
		(end 51.001168 -116.584222)
		(width 0.12065)
		(layer "B.Cu")
		(net "BMC0_SMB10_DAT")
	)
	(segment
		(start 51.001168 -118.178834)
		(end 51.001168 -117.513862)
		(width 0.12065)
		(layer "B.Cu")
		(net "BMC0_SMB10_DAT")
	)
	(segment
		(start 47.822104 -121.357898)
		(end 51.001168 -118.178834)
		(width 0.12065)
		(layer "B.Cu")
		(net "BMC0_SMB10_DAT")
	)
	(segment
		(start 51.001168 -117.513862)
		(end 51.35499 -117.513862)
		(width 0.12065)
		(layer "B.Cu")
		(net "BMC0_SMB10_DAT")
	)
	(segment
		(start 44.104814 -123.684792)
		(end 44.50461 -123.284996)
		(width 0.12065)
		(layer "F.Cu")
		(net "BMC0_SMB10_CLK")
	)
	(via
		(at 47.733712 -120.301766)
		(size 0.7112)
		(drill 0.3556)
		(layers "F.Cu" "B.Cu")
		(net "BMC0_SMB10_CLK")
	)
	(via
		(at 44.50461 -123.284996)
		(size 0.4572)
		(drill 0.2032)
		(layers "F.Cu" "B.Cu")
		(net "BMC0_SMB10_CLK")
	)
	(segment
		(start 50.499518 -116.637308)
		(end 50.499518 -117.970808)
		(width 0.12065)
		(layer "B.Cu")
		(net "BMC0_SMB10_CLK")
	)
	(segment
		(start 47.614078 -120.856248)
		(end 46.89221 -120.856248)
		(width 0.12065)
		(layer "B.Cu")
		(net "BMC0_SMB10_CLK")
	)
	(segment
		(start 46.717712 -121.005346)
		(end 45.372782 -121.005346)
		(width 0.1016)
		(layer "B.Cu")
		(net "BMC0_SMB10_CLK")
	)
	(segment
		(start 50.2158 -116.35359)
		(end 50.499518 -116.637308)
		(width 0.12065)
		(layer "B.Cu")
		(net "BMC0_SMB10_CLK")
	)
	(segment
		(start 46.86681 -120.856248)
		(end 46.717712 -121.005346)
		(width 0.1016)
		(layer "B.Cu")
		(net "BMC0_SMB10_CLK")
	)
	(segment
		(start 44.124118 -122.25401)
		(end 44.124118 -122.904504)
		(width 0.1016)
		(layer "B.Cu")
		(net "BMC0_SMB10_CLK")
	)
	(segment
		(start 47.951136 -120.51919)
		(end 47.733712 -120.301766)
		(width 0.12065)
		(layer "B.Cu")
		(net "BMC0_SMB10_CLK")
	)
	(segment
		(start 46.89221 -120.856248)
		(end 46.86681 -120.856248)
		(width 0.1016)
		(layer "B.Cu")
		(net "BMC0_SMB10_CLK")
	)
	(segment
		(start 47.951136 -120.51919)
		(end 47.614078 -120.856248)
		(width 0.12065)
		(layer "B.Cu")
		(net "BMC0_SMB10_CLK")
	)
	(segment
		(start 45.372782 -121.005346)
		(end 44.124118 -122.25401)
		(width 0.1016)
		(layer "B.Cu")
		(net "BMC0_SMB10_CLK")
	)
	(segment
		(start 44.124118 -122.904504)
		(end 44.50461 -123.284996)
		(width 0.1016)
		(layer "B.Cu")
		(net "BMC0_SMB10_CLK")
	)
	(segment
		(start 50.499518 -117.970808)
		(end 47.951136 -120.51919)
		(width 0.12065)
		(layer "B.Cu")
		(net "BMC0_SMB10_CLK")
	)
	(segment
		(start 23.45182 -127.197358)
		(end 23.171658 -126.917196)
		(width 0.12065)
		(layer "F.Cu")
		(net "BMC0_SMB1_DAT")
	)
	(segment
		(start 21.277072 -126.917196)
		(end 20.10537 -125.745494)
		(width 0.12065)
		(layer "F.Cu")
		(net "BMC0_SMB1_DAT")
	)
	(segment
		(start 25.625044 -127.197358)
		(end 23.45182 -127.197358)
		(width 0.12065)
		(layer "F.Cu")
		(net "BMC0_SMB1_DAT")
	)
	(segment
		(start 27.285442 -127.49657)
		(end 25.924256 -127.49657)
		(width 0.12065)
		(layer "F.Cu")
		(net "BMC0_SMB1_DAT")
	)
	(segment
		(start 23.171658 -126.917196)
		(end 21.277072 -126.917196)
		(width 0.12065)
		(layer "F.Cu")
		(net "BMC0_SMB1_DAT")
	)
	(segment
		(start 16.53159 -122.11939)
		(end 16.53159 -120.526556)
		(width 0.12065)
		(layer "F.Cu")
		(net "BMC0_SMB1_DAT")
	)
	(segment
		(start 16.53159 -120.526556)
		(end 16.468344 -120.227852)
		(width 0.12065)
		(layer "F.Cu")
		(net "BMC0_SMB1_DAT")
	)
	(segment
		(start 29.406596 -129.285238)
		(end 27.617928 -127.49657)
		(width 0.12065)
		(layer "F.Cu")
		(net "BMC0_SMB1_DAT")
	)
	(segment
		(start 20.10537 -125.745494)
		(end 19.243294 -125.745494)
		(width 0.12065)
		(layer "F.Cu")
		(net "BMC0_SMB1_DAT")
	)
	(segment
		(start 25.924256 -127.49657)
		(end 25.625044 -127.197358)
		(width 0.12065)
		(layer "F.Cu")
		(net "BMC0_SMB1_DAT")
	)
	(segment
		(start 16.9672 -122.555)
		(end 16.53159 -122.11939)
		(width 0.12065)
		(layer "F.Cu")
		(net "BMC0_SMB1_DAT")
	)
	(segment
		(start 29.704792 -129.284984)
		(end 29.704538 -129.285238)
		(width 0.12065)
		(layer "F.Cu")
		(net "BMC0_SMB1_DAT")
	)
	(segment
		(start 29.704538 -129.285238)
		(end 29.406596 -129.285238)
		(width 0.12065)
		(layer "F.Cu")
		(net "BMC0_SMB1_DAT")
	)
	(segment
		(start 16.007842 -119.76735)
		(end 15.81785 -119.76735)
		(width 0.12065)
		(layer "F.Cu")
		(net "BMC0_SMB1_DAT")
	)
	(segment
		(start 15.81785 -119.76735)
		(end 15.4559 -119.4054)
		(width 0.12065)
		(layer "F.Cu")
		(net "BMC0_SMB1_DAT")
	)
	(segment
		(start 16.9672 -123.4694)
		(end 16.9672 -122.555)
		(width 0.12065)
		(layer "F.Cu")
		(net "BMC0_SMB1_DAT")
	)
	(segment
		(start 16.468344 -120.227852)
		(end 16.007842 -119.76735)
		(width 0.12065)
		(layer "F.Cu")
		(net "BMC0_SMB1_DAT")
	)
	(segment
		(start 19.243294 -125.745494)
		(end 16.9672 -123.4694)
		(width 0.12065)
		(layer "F.Cu")
		(net "BMC0_SMB1_DAT")
	)
	(segment
		(start 27.285442 -127.49657)
		(end 27.285442 -127.170688)
		(width 0.12065)
		(layer "F.Cu")
		(net "BMC0_SMB1_DAT")
	)
	(segment
		(start 27.617928 -127.49657)
		(end 27.285442 -127.49657)
		(width 0.12065)
		(layer "F.Cu")
		(net "BMC0_SMB1_DAT")
	)
	(via
		(at 27.285442 -127.170688)
		(size 0.7112)
		(drill 0.3556)
		(layers "F.Cu" "B.Cu")
		(net "BMC0_SMB1_DAT")
	)
	(segment
		(start 22.963632 -127.418846)
		(end 21.069046 -127.418846)
		(width 0.12065)
		(layer "F.Cu")
		(net "BMC0_SMB1_CLK")
	)
	(segment
		(start 16.46555 -122.763026)
		(end 16.02994 -122.327416)
		(width 0.12065)
		(layer "F.Cu")
		(net "BMC0_SMB1_CLK")
	)
	(segment
		(start 15.6337 -120.269)
		(end 15.4559 -120.4468)
		(width 0.12065)
		(layer "F.Cu")
		(net "BMC0_SMB1_CLK")
	)
	(segment
		(start 30.430216 -129.284984)
		(end 30.03042 -129.68478)
		(width 0.12065)
		(layer "F.Cu")
		(net "BMC0_SMB1_CLK")
	)
	(segment
		(start 19.897344 -126.247144)
		(end 19.035268 -126.247144)
		(width 0.12065)
		(layer "F.Cu")
		(net "BMC0_SMB1_CLK")
	)
	(segment
		(start 29.096462 -129.68478)
		(end 27.409902 -127.99822)
		(width 0.12065)
		(layer "F.Cu")
		(net "BMC0_SMB1_CLK")
	)
	(segment
		(start 16.46555 -123.677426)
		(end 16.46555 -122.763026)
		(width 0.12065)
		(layer "F.Cu")
		(net "BMC0_SMB1_CLK")
	)
	(segment
		(start 16.02994 -120.579134)
		(end 16.008096 -120.477534)
		(width 0.12065)
		(layer "F.Cu")
		(net "BMC0_SMB1_CLK")
	)
	(segment
		(start 26.68143 -127.99822)
		(end 25.71623 -127.99822)
		(width 0.12065)
		(layer "F.Cu")
		(net "BMC0_SMB1_CLK")
	)
	(segment
		(start 16.02994 -122.327416)
		(end 16.02994 -120.579134)
		(width 0.12065)
		(layer "F.Cu")
		(net "BMC0_SMB1_CLK")
	)
	(segment
		(start 26.68143 -127.99822)
		(end 26.68143 -128.344168)
		(width 0.12065)
		(layer "F.Cu")
		(net "BMC0_SMB1_CLK")
	)
	(segment
		(start 30.504892 -129.284984)
		(end 30.430216 -129.284984)
		(width 0.12065)
		(layer "F.Cu")
		(net "BMC0_SMB1_CLK")
	)
	(segment
		(start 25.71623 -127.99822)
		(end 25.417018 -127.699008)
		(width 0.12065)
		(layer "F.Cu")
		(net "BMC0_SMB1_CLK")
	)
	(segment
		(start 16.008096 -120.477534)
		(end 15.799816 -120.269)
		(width 0.12065)
		(layer "F.Cu")
		(net "BMC0_SMB1_CLK")
	)
	(segment
		(start 19.035268 -126.247144)
		(end 16.46555 -123.677426)
		(width 0.12065)
		(layer "F.Cu")
		(net "BMC0_SMB1_CLK")
	)
	(segment
		(start 21.069046 -127.418846)
		(end 19.897344 -126.247144)
		(width 0.12065)
		(layer "F.Cu")
		(net "BMC0_SMB1_CLK")
	)
	(segment
		(start 23.243794 -127.699008)
		(end 22.963632 -127.418846)
		(width 0.12065)
		(layer "F.Cu")
		(net "BMC0_SMB1_CLK")
	)
	(segment
		(start 27.409902 -127.99822)
		(end 26.68143 -127.99822)
		(width 0.12065)
		(layer "F.Cu")
		(net "BMC0_SMB1_CLK")
	)
	(segment
		(start 15.799816 -120.269)
		(end 15.6337 -120.269)
		(width 0.12065)
		(layer "F.Cu")
		(net "BMC0_SMB1_CLK")
	)
	(segment
		(start 25.417018 -127.699008)
		(end 23.243794 -127.699008)
		(width 0.12065)
		(layer "F.Cu")
		(net "BMC0_SMB1_CLK")
	)
	(segment
		(start 30.03042 -129.68478)
		(end 29.096462 -129.68478)
		(width 0.12065)
		(layer "F.Cu")
		(net "BMC0_SMB1_CLK")
	)
	(via
		(at 26.68143 -128.344168)
		(size 0.7112)
		(drill 0.3556)
		(layers "F.Cu" "B.Cu")
		(net "BMC0_SMB1_CLK")
	)
	(segment
		(start 46.50486 -122.084846)
		(end 47.693834 -122.084846)
		(width 0.12065)
		(layer "F.Cu")
		(net "BMC0_SDA13_R")
	)
	(segment
		(start 53.457348 -115.9256)
		(end 53.457348 -115.471448)
		(width 0.12065)
		(layer "F.Cu")
		(net "BMC0_SDA13_R")
	)
	(segment
		(start 50.902108 -118.48084)
		(end 50.67554 -118.254272)
		(width 0.12065)
		(layer "F.Cu")
		(net "BMC0_SDA13_R")
	)
	(segment
		(start 49.35855 -120.024398)
		(end 50.902108 -118.48084)
		(width 0.12065)
		(layer "F.Cu")
		(net "BMC0_SDA13_R")
	)
	(segment
		(start 49.35855 -120.42013)
		(end 49.35855 -120.024398)
		(width 0.12065)
		(layer "F.Cu")
		(net "BMC0_SDA13_R")
	)
	(segment
		(start 50.902108 -118.48084)
		(end 53.457348 -115.9256)
		(width 0.12065)
		(layer "F.Cu")
		(net "BMC0_SDA13_R")
	)
	(segment
		(start 53.457348 -115.471448)
		(end 53.1876 -115.2017)
		(width 0.12065)
		(layer "F.Cu")
		(net "BMC0_SDA13_R")
	)
	(segment
		(start 47.693834 -122.084846)
		(end 49.35855 -120.42013)
		(width 0.12065)
		(layer "F.Cu")
		(net "BMC0_SDA13_R")
	)
	(via
		(at 50.67554 -118.254272)
		(size 0.7112)
		(drill 0.3556)
		(layers "F.Cu" "B.Cu")
		(net "BMC0_SDA13_R")
	)
	(segment
		(start 64.3636 -114.5413)
		(end 63.324994 -114.5413)
		(width 0.12065)
		(layer "F.Cu")
		(net "BMC0_SDA11_R")
	)
	(segment
		(start 64.62395 -115.711224)
		(end 64.338708 -115.996466)
		(width 0.12065)
		(layer "F.Cu")
		(net "BMC0_SDA11_R")
	)
	(segment
		(start 64.3636 -114.5413)
		(end 64.62395 -114.80165)
		(width 0.12065)
		(layer "F.Cu")
		(net "BMC0_SDA11_R")
	)
	(segment
		(start 64.62395 -114.80165)
		(end 64.62395 -115.711224)
		(width 0.12065)
		(layer "F.Cu")
		(net "BMC0_SDA11_R")
	)
	(segment
		(start 43.304714 -125.284992)
		(end 43.70451 -124.885196)
		(width 0.12065)
		(layer "F.Cu")
		(net "BMC0_SDA11_R")
	)
	(via
		(at 43.70451 -124.885196)
		(size 0.4572)
		(drill 0.2032)
		(layers "F.Cu" "B.Cu")
		(net "BMC0_SDA11_R")
	)
	(via
		(at 64.338708 -115.996466)
		(size 0.508)
		(drill 0.254)
		(layers "F.Cu" "B.Cu")
		(net "BMC0_SDA11_R")
	)
	(via
		(at 63.324994 -114.5413)
		(size 0.7112)
		(drill 0.3556)
		(layers "F.Cu" "B.Cu")
		(net "BMC0_SDA11_R")
	)
	(segment
		(start 44.111164 -124.235464)
		(end 43.70451 -124.642118)
		(width 0.127)
		(layer "In2.Cu")
		(net "BMC0_SDA11_R")
	)
	(segment
		(start 44.898818 -123.44781)
		(end 44.667932 -123.678696)
		(width 0.127)
		(layer "In2.Cu")
		(net "BMC0_SDA11_R")
	)
	(segment
		(start 57.918604 -116.332)
		(end 57.334404 -115.7478)
		(width 0.127)
		(layer "In2.Cu")
		(net "BMC0_SDA11_R")
	)
	(segment
		(start 44.667932 -123.678696)
		(end 44.353988 -123.678696)
		(width 0.127)
		(layer "In2.Cu")
		(net "BMC0_SDA11_R")
	)
	(segment
		(start 51.808634 -116.713)
		(end 49.979834 -118.5418)
		(width 0.127)
		(layer "In2.Cu")
		(net "BMC0_SDA11_R")
	)
	(segment
		(start 45.596556 -121.45645)
		(end 44.898818 -122.154188)
		(width 0.127)
		(layer "In2.Cu")
		(net "BMC0_SDA11_R")
	)
	(segment
		(start 44.111164 -123.92152)
		(end 44.111164 -124.235464)
		(width 0.127)
		(layer "In2.Cu")
		(net "BMC0_SDA11_R")
	)
	(segment
		(start 44.898818 -122.154188)
		(end 44.898818 -123.44781)
		(width 0.127)
		(layer "In2.Cu")
		(net "BMC0_SDA11_R")
	)
	(segment
		(start 57.334404 -115.7478)
		(end 53.911246 -115.7478)
		(width 0.127)
		(layer "In2.Cu")
		(net "BMC0_SDA11_R")
	)
	(segment
		(start 64.003174 -116.332)
		(end 57.918604 -116.332)
		(width 0.127)
		(layer "In2.Cu")
		(net "BMC0_SDA11_R")
	)
	(segment
		(start 45.596556 -120.668034)
		(end 45.596556 -121.45645)
		(width 0.127)
		(layer "In2.Cu")
		(net "BMC0_SDA11_R")
	)
	(segment
		(start 44.353988 -123.678696)
		(end 44.111164 -123.92152)
		(width 0.127)
		(layer "In2.Cu")
		(net "BMC0_SDA11_R")
	)
	(segment
		(start 49.979834 -118.5418)
		(end 47.72279 -118.5418)
		(width 0.127)
		(layer "In2.Cu")
		(net "BMC0_SDA11_R")
	)
	(segment
		(start 64.338708 -115.996466)
		(end 64.003174 -116.332)
		(width 0.127)
		(layer "In2.Cu")
		(net "BMC0_SDA11_R")
	)
	(segment
		(start 52.946046 -116.713)
		(end 51.808634 -116.713)
		(width 0.127)
		(layer "In2.Cu")
		(net "BMC0_SDA11_R")
	)
	(segment
		(start 47.72279 -118.5418)
		(end 45.596556 -120.668034)
		(width 0.127)
		(layer "In2.Cu")
		(net "BMC0_SDA11_R")
	)
	(segment
		(start 43.70451 -124.642118)
		(end 43.70451 -124.885196)
		(width 0.127)
		(layer "In2.Cu")
		(net "BMC0_SDA11_R")
	)
	(segment
		(start 53.911246 -115.7478)
		(end 52.946046 -116.713)
		(width 0.127)
		(layer "In2.Cu")
		(net "BMC0_SDA11_R")
	)
	(segment
		(start 45.70476 -122.884946)
		(end 45.814488 -122.884946)
		(width 0.120396)
		(layer "F.Cu")
		(net "BMC0_SCL13_R")
	)
	(segment
		(start 53.958998 -116.133626)
		(end 53.958998 -115.471702)
		(width 0.12065)
		(layer "F.Cu")
		(net "BMC0_SCL13_R")
	)
	(segment
		(start 50.146204 -119.94642)
		(end 50.361596 -120.161812)
		(width 0.12065)
		(layer "F.Cu")
		(net "BMC0_SCL13_R")
	)
	(segment
		(start 49.8602 -120.628156)
		(end 49.8602 -120.232424)
		(width 0.12065)
		(layer "F.Cu")
		(net "BMC0_SCL13_R")
	)
	(segment
		(start 46.204886 -122.494548)
		(end 46.666658 -122.494548)
		(width 0.120396)
		(layer "F.Cu")
		(net "BMC0_SCL13_R")
	)
	(segment
		(start 53.958998 -115.471702)
		(end 54.229 -115.2017)
		(width 0.12065)
		(layer "F.Cu")
		(net "BMC0_SCL13_R")
	)
	(segment
		(start 50.146204 -119.94642)
		(end 53.958998 -116.133626)
		(width 0.12065)
		(layer "F.Cu")
		(net "BMC0_SCL13_R")
	)
	(segment
		(start 46.790864 -122.586496)
		(end 47.90186 -122.586496)
		(width 0.12065)
		(layer "F.Cu")
		(net "BMC0_SCL13_R")
	)
	(segment
		(start 46.758606 -122.586496)
		(end 46.790864 -122.586496)
		(width 0.120396)
		(layer "F.Cu")
		(net "BMC0_SCL13_R")
	)
	(segment
		(start 47.90186 -122.586496)
		(end 49.8602 -120.628156)
		(width 0.12065)
		(layer "F.Cu")
		(net "BMC0_SCL13_R")
	)
	(segment
		(start 46.666658 -122.494548)
		(end 46.758606 -122.586496)
		(width 0.120396)
		(layer "F.Cu")
		(net "BMC0_SCL13_R")
	)
	(segment
		(start 45.814488 -122.884946)
		(end 46.204886 -122.494548)
		(width 0.120396)
		(layer "F.Cu")
		(net "BMC0_SCL13_R")
	)
	(segment
		(start 49.8602 -120.232424)
		(end 50.146204 -119.94642)
		(width 0.12065)
		(layer "F.Cu")
		(net "BMC0_SCL13_R")
	)
	(via
		(at 50.361596 -120.161812)
		(size 0.7112)
		(drill 0.3556)
		(layers "F.Cu" "B.Cu")
		(net "BMC0_SCL13_R")
	)
	(segment
		(start 65.1256 -115.718844)
		(end 65.403222 -115.996466)
		(width 0.12065)
		(layer "F.Cu")
		(net "BMC0_SCL11_R")
	)
	(segment
		(start 45.70476 -122.084846)
		(end 46.104556 -121.68505)
		(width 0.12065)
		(layer "F.Cu")
		(net "BMC0_SCL11_R")
	)
	(segment
		(start 65.405 -114.550952)
		(end 65.1256 -114.830352)
		(width 0.12065)
		(layer "F.Cu")
		(net "BMC0_SCL11_R")
	)
	(segment
		(start 65.1256 -114.830352)
		(end 65.1256 -115.718844)
		(width 0.12065)
		(layer "F.Cu")
		(net "BMC0_SCL11_R")
	)
	(segment
		(start 65.405 -114.550952)
		(end 66.382646 -114.550952)
		(width 0.12065)
		(layer "F.Cu")
		(net "BMC0_SCL11_R")
	)
	(via
		(at 66.382646 -114.550952)
		(size 0.7112)
		(drill 0.3556)
		(layers "F.Cu" "B.Cu")
		(net "BMC0_SCL11_R")
	)
	(via
		(at 46.104556 -121.68505)
		(size 0.4572)
		(drill 0.2032)
		(layers "F.Cu" "B.Cu")
		(net "BMC0_SCL11_R")
	)
	(via
		(at 65.403222 -115.996466)
		(size 0.508)
		(drill 0.254)
		(layers "F.Cu" "B.Cu")
		(net "BMC0_SCL11_R")
	)
	(segment
		(start 53.156612 -117.221)
		(end 52.0192 -117.221)
		(width 0.127)
		(layer "In2.Cu")
		(net "BMC0_SCL11_R")
	)
	(segment
		(start 64.559942 -116.839746)
		(end 64.55918 -116.84)
		(width 0.127)
		(layer "In2.Cu")
		(net "BMC0_SCL11_R")
	)
	(segment
		(start 65.403222 -115.996466)
		(end 64.559942 -116.839746)
		(width 0.127)
		(layer "In2.Cu")
		(net "BMC0_SCL11_R")
	)
	(segment
		(start 50.1904 -119.0498)
		(end 47.933356 -119.0498)
		(width 0.127)
		(layer "In2.Cu")
		(net "BMC0_SCL11_R")
	)
	(segment
		(start 47.933356 -119.0498)
		(end 46.104556 -120.8786)
		(width 0.127)
		(layer "In2.Cu")
		(net "BMC0_SCL11_R")
	)
	(segment
		(start 52.0192 -117.221)
		(end 50.1904 -119.0498)
		(width 0.127)
		(layer "In2.Cu")
		(net "BMC0_SCL11_R")
	)
	(segment
		(start 54.121812 -116.2558)
		(end 53.156612 -117.221)
		(width 0.127)
		(layer "In2.Cu")
		(net "BMC0_SCL11_R")
	)
	(segment
		(start 57.123838 -116.2558)
		(end 54.121812 -116.2558)
		(width 0.127)
		(layer "In2.Cu")
		(net "BMC0_SCL11_R")
	)
	(segment
		(start 46.104556 -120.8786)
		(end 46.104556 -121.68505)
		(width 0.127)
		(layer "In2.Cu")
		(net "BMC0_SCL11_R")
	)
	(segment
		(start 57.708038 -116.84)
		(end 57.123838 -116.2558)
		(width 0.127)
		(layer "In2.Cu")
		(net "BMC0_SCL11_R")
	)
	(segment
		(start 64.55918 -116.84)
		(end 57.708038 -116.84)
		(width 0.127)
		(layer "In2.Cu")
		(net "BMC0_SCL11_R")
	)
	(segment
		(start 51.46294 -143.14932)
		(end 52.197 -143.88338)
		(width 0.12065)
		(layer "F.Cu")
		(net "BMC0_LED_DR_R_LED0")
	)
	(segment
		(start 49.834038 -142.035022)
		(end 49.549812 -141.750796)
		(width 0.12065)
		(layer "F.Cu")
		(net "BMC0_LED_DR_R_LED0")
	)
	(segment
		(start 51.119024 -142.805404)
		(end 50.582576 -142.805404)
		(width 0.12065)
		(layer "F.Cu")
		(net "BMC0_LED_DR_R_LED0")
	)
	(segment
		(start 46.662086 -138.884914)
		(end 46.50486 -138.884914)
		(width 0.12065)
		(layer "F.Cu")
		(net "BMC0_LED_DR_R_LED0")
	)
	(segment
		(start 52.197 -143.88338)
		(end 52.197 -144.9705)
		(width 0.12065)
		(layer "F.Cu")
		(net "BMC0_LED_DR_R_LED0")
	)
	(segment
		(start 50.582576 -142.805404)
		(end 49.834038 -142.056866)
		(width 0.12065)
		(layer "F.Cu")
		(net "BMC0_LED_DR_R_LED0")
	)
	(segment
		(start 49.549812 -141.750796)
		(end 49.527968 -141.750796)
		(width 0.12065)
		(layer "F.Cu")
		(net "BMC0_LED_DR_R_LED0")
	)
	(segment
		(start 49.527968 -141.750796)
		(end 46.662086 -138.884914)
		(width 0.12065)
		(layer "F.Cu")
		(net "BMC0_LED_DR_R_LED0")
	)
	(segment
		(start 49.834038 -142.056866)
		(end 49.834038 -142.035022)
		(width 0.12065)
		(layer "F.Cu")
		(net "BMC0_LED_DR_R_LED0")
	)
	(segment
		(start 51.46294 -143.14932)
		(end 51.119024 -142.805404)
		(width 0.12065)
		(layer "F.Cu")
		(net "BMC0_LED_DR_R_LED0")
	)
	(via
		(at 51.46294 -143.14932)
		(size 0.7112)
		(drill 0.3556)
		(layers "F.Cu" "B.Cu")
		(net "BMC0_LED_DR_R_LED0")
	)
	(segment
		(start 61.61405 -125.11405)
		(end 62.6872 -126.1872)
		(width 0.12065)
		(layer "F.Cu")
		(net "BMC0_JTAG_RTCK")
	)
	(segment
		(start 60.071 -116.586)
		(end 61.61405 -118.12905)
		(width 0.12065)
		(layer "F.Cu")
		(net "BMC0_JTAG_RTCK")
	)
	(segment
		(start 59.817 -116.586)
		(end 60.071 -116.586)
		(width 0.12065)
		(layer "F.Cu")
		(net "BMC0_JTAG_RTCK")
	)
	(segment
		(start 44.104814 -126.884938)
		(end 44.50461 -126.485142)
		(width 0.12065)
		(layer "F.Cu")
		(net "BMC0_JTAG_RTCK")
	)
	(segment
		(start 61.61405 -118.12905)
		(end 61.61405 -125.11405)
		(width 0.12065)
		(layer "F.Cu")
		(net "BMC0_JTAG_RTCK")
	)
	(via
		(at 52.5018 -126.492)
		(size 0.508)
		(drill 0.254)
		(layers "F.Cu" "B.Cu")
		(net "BMC0_JTAG_RTCK")
	)
	(via
		(at 44.50461 -126.485142)
		(size 0.4572)
		(drill 0.2032)
		(layers "F.Cu" "B.Cu")
		(net "BMC0_JTAG_RTCK")
	)
	(via
		(at 62.6872 -126.1872)
		(size 0.508)
		(drill 0.254)
		(layers "F.Cu" "B.Cu")
		(net "BMC0_JTAG_RTCK")
	)
	(segment
		(start 45.673518 -126.668784)
		(end 45.466508 -126.875794)
		(width 0.12065)
		(layer "B.Cu")
		(net "BMC0_JTAG_RTCK")
	)
	(segment
		(start 45.142912 -126.875794)
		(end 45.024548 -126.75743)
		(width 0.12065)
		(layer "B.Cu")
		(net "BMC0_JTAG_RTCK")
	)
	(segment
		(start 50.630582 -126.668784)
		(end 45.673518 -126.668784)
		(width 0.12065)
		(layer "B.Cu")
		(net "BMC0_JTAG_RTCK")
	)
	(segment
		(start 53.074824 -125.918976)
		(end 52.5018 -126.492)
		(width 0.12065)
		(layer "B.Cu")
		(net "BMC0_JTAG_RTCK")
	)
	(segment
		(start 50.76952 -126.529846)
		(end 51.468274 -127.2286)
		(width 0.12065)
		(layer "B.Cu")
		(net "BMC0_JTAG_RTCK")
	)
	(segment
		(start 45.466508 -126.875794)
		(end 45.142912 -126.875794)
		(width 0.12065)
		(layer "B.Cu")
		(net "BMC0_JTAG_RTCK")
	)
	(segment
		(start 53.34 -125.918976)
		(end 53.074824 -125.918976)
		(width 0.12065)
		(layer "B.Cu")
		(net "BMC0_JTAG_RTCK")
	)
	(segment
		(start 52.1208 -127.2286)
		(end 52.5018 -126.8476)
		(width 0.12065)
		(layer "B.Cu")
		(net "BMC0_JTAG_RTCK")
	)
	(segment
		(start 52.5018 -126.8476)
		(end 52.5018 -126.492)
		(width 0.12065)
		(layer "B.Cu")
		(net "BMC0_JTAG_RTCK")
	)
	(segment
		(start 50.76952 -126.529846)
		(end 50.630582 -126.668784)
		(width 0.12065)
		(layer "B.Cu")
		(net "BMC0_JTAG_RTCK")
	)
	(segment
		(start 51.468274 -127.2286)
		(end 52.1208 -127.2286)
		(width 0.12065)
		(layer "B.Cu")
		(net "BMC0_JTAG_RTCK")
	)
	(segment
		(start 44.776898 -126.75743)
		(end 44.50461 -126.485142)
		(width 0.12065)
		(layer "B.Cu")
		(net "BMC0_JTAG_RTCK")
	)
	(segment
		(start 45.024548 -126.75743)
		(end 44.776898 -126.75743)
		(width 0.12065)
		(layer "B.Cu")
		(net "BMC0_JTAG_RTCK")
	)
	(segment
		(start 55.2196 -125.4506)
		(end 53.7972 -125.4506)
		(width 0.127)
		(layer "In2.Cu")
		(net "BMC0_JTAG_RTCK")
	)
	(segment
		(start 60.866782 -126.3777)
		(end 60.828682 -126.4158)
		(width 0.127)
		(layer "In2.Cu")
		(net "BMC0_JTAG_RTCK")
	)
	(segment
		(start 57.097676 -126.0602)
		(end 56.970676 -125.9332)
		(width 0.127)
		(layer "In2.Cu")
		(net "BMC0_JTAG_RTCK")
	)
	(segment
		(start 55.634382 -125.8697)
		(end 55.3593 -125.594618)
		(width 0.127)
		(layer "In2.Cu")
		(net "BMC0_JTAG_RTCK")
	)
	(segment
		(start 55.3593 -125.594618)
		(end 55.3593 -125.5903)
		(width 0.127)
		(layer "In2.Cu")
		(net "BMC0_JTAG_RTCK")
	)
	(segment
		(start 55.6387 -125.8697)
		(end 55.634382 -125.8697)
		(width 0.127)
		(layer "In2.Cu")
		(net "BMC0_JTAG_RTCK")
	)
	(segment
		(start 52.842414 -126.405386)
		(end 52.588414 -126.405386)
		(width 0.127)
		(layer "In2.Cu")
		(net "BMC0_JTAG_RTCK")
	)
	(segment
		(start 53.7972 -125.4506)
		(end 52.842414 -126.405386)
		(width 0.127)
		(layer "In2.Cu")
		(net "BMC0_JTAG_RTCK")
	)
	(segment
		(start 60.622942 -126.524258)
		(end 58.744866 -126.524258)
		(width 0.127)
		(layer "In2.Cu")
		(net "BMC0_JTAG_RTCK")
	)
	(segment
		(start 52.588414 -126.405386)
		(end 52.5018 -126.492)
		(width 0.127)
		(layer "In2.Cu")
		(net "BMC0_JTAG_RTCK")
	)
	(segment
		(start 62.6872 -126.1872)
		(end 62.4967 -126.3777)
		(width 0.127)
		(layer "In2.Cu")
		(net "BMC0_JTAG_RTCK")
	)
	(segment
		(start 58.280808 -126.0602)
		(end 57.097676 -126.0602)
		(width 0.127)
		(layer "In2.Cu")
		(net "BMC0_JTAG_RTCK")
	)
	(segment
		(start 60.828682 -126.4158)
		(end 60.7314 -126.4158)
		(width 0.127)
		(layer "In2.Cu")
		(net "BMC0_JTAG_RTCK")
	)
	(segment
		(start 62.4967 -126.3777)
		(end 60.866782 -126.3777)
		(width 0.127)
		(layer "In2.Cu")
		(net "BMC0_JTAG_RTCK")
	)
	(segment
		(start 60.7314 -126.4158)
		(end 60.622942 -126.524258)
		(width 0.127)
		(layer "In2.Cu")
		(net "BMC0_JTAG_RTCK")
	)
	(segment
		(start 58.744866 -126.524258)
		(end 58.280808 -126.0602)
		(width 0.127)
		(layer "In2.Cu")
		(net "BMC0_JTAG_RTCK")
	)
	(segment
		(start 55.3593 -125.5903)
		(end 55.2196 -125.4506)
		(width 0.127)
		(layer "In2.Cu")
		(net "BMC0_JTAG_RTCK")
	)
	(segment
		(start 55.7022 -125.9332)
		(end 55.6387 -125.8697)
		(width 0.127)
		(layer "In2.Cu")
		(net "BMC0_JTAG_RTCK")
	)
	(segment
		(start 56.970676 -125.9332)
		(end 55.7022 -125.9332)
		(width 0.127)
		(layer "In2.Cu")
		(net "BMC0_JTAG_RTCK")
	)
	(segment
		(start 44.104814 -125.284992)
		(end 44.50461 -124.885196)
		(width 0.12065)
		(layer "F.Cu")
		(net "BMC0_ENTEST1")
	)
	(via
		(at 44.50461 -124.885196)
		(size 0.4572)
		(drill 0.2032)
		(layers "F.Cu" "B.Cu")
		(net "BMC0_ENTEST1")
	)
	(via
		(at 41.750234 -125.64872)
		(size 0.7112)
		(drill 0.3556)
		(layers "F.Cu" "B.Cu")
		(net "BMC0_ENTEST1")
	)
	(segment
		(start 43.468544 -124.48413)
		(end 43.472608 -124.488194)
		(width 0.12065)
		(layer "B.Cu")
		(net "BMC0_ENTEST1")
	)
	(segment
		(start 41.750234 -125.64872)
		(end 41.893998 -125.64872)
		(width 0.12065)
		(layer "B.Cu")
		(net "BMC0_ENTEST1")
	)
	(segment
		(start 42.503344 -124.89561)
		(end 42.503344 -124.82195)
		(width 0.12065)
		(layer "B.Cu")
		(net "BMC0_ENTEST1")
	)
	(segment
		(start 43.472608 -124.488194)
		(end 44.107608 -124.488194)
		(width 0.12065)
		(layer "B.Cu")
		(net "BMC0_ENTEST1")
	)
	(segment
		(start 41.021 -126.377954)
		(end 41.750234 -125.64872)
		(width 0.12065)
		(layer "B.Cu")
		(net "BMC0_ENTEST1")
	)
	(segment
		(start 41.021 -126.5555)
		(end 41.021 -126.377954)
		(width 0.12065)
		(layer "B.Cu")
		(net "BMC0_ENTEST1")
	)
	(segment
		(start 44.107608 -124.488194)
		(end 44.50461 -124.885196)
		(width 0.12065)
		(layer "B.Cu")
		(net "BMC0_ENTEST1")
	)
	(segment
		(start 42.495724 -124.90323)
		(end 42.503344 -124.89561)
		(width 0.12065)
		(layer "B.Cu")
		(net "BMC0_ENTEST1")
	)
	(segment
		(start 42.495724 -125.046994)
		(end 42.495724 -124.90323)
		(width 0.12065)
		(layer "B.Cu")
		(net "BMC0_ENTEST1")
	)
	(segment
		(start 41.893998 -125.64872)
		(end 42.495724 -125.046994)
		(width 0.12065)
		(layer "B.Cu")
		(net "BMC0_ENTEST1")
	)
	(segment
		(start 42.841164 -124.48413)
		(end 43.468544 -124.48413)
		(width 0.12065)
		(layer "B.Cu")
		(net "BMC0_ENTEST1")
	)
	(segment
		(start 42.503344 -124.82195)
		(end 42.841164 -124.48413)
		(width 0.12065)
		(layer "B.Cu")
		(net "BMC0_ENTEST1")
	)
	(segment
		(start 29.561536 -140.593318)
		(end 29.85135 -140.303504)
		(width 0.136652)
		(layer "F.Cu")
		(net "BMC_USB2_HDP")
	)
	(segment
		(start 30.361382 -139.793726)
		(end 30.9118 -139.243308)
		(width 0.136652)
		(layer "F.Cu")
		(net "BMC_USB2_HDP")
	)
	(segment
		(start 30.141418 -139.793726)
		(end 30.361382 -139.793726)
		(width 0.136652)
		(layer "F.Cu")
		(net "BMC_USB2_HDP")
	)
	(segment
		(start 29.031946 -142.748)
		(end 29.0322 -142.748254)
		(width 0.136652)
		(layer "F.Cu")
		(net "BMC_USB2_HDP")
	)
	(segment
		(start 30.9118 -139.243308)
		(end 30.9118 -138.9634)
		(width 0.136652)
		(layer "F.Cu")
		(net "BMC_USB2_HDP")
	)
	(segment
		(start 30.833314 -138.884914)
		(end 30.504892 -138.884914)
		(width 0.136652)
		(layer "F.Cu")
		(net "BMC_USB2_HDP")
	)
	(segment
		(start 28.840684 -142.939516)
		(end 29.031946 -142.748)
		(width 0.136652)
		(layer "F.Cu")
		(net "BMC_USB2_HDP")
	)
	(segment
		(start 30.9118 -138.9634)
		(end 30.833314 -138.884914)
		(width 0.136652)
		(layer "F.Cu")
		(net "BMC_USB2_HDP")
	)
	(segment
		(start 29.2862 -142.1384)
		(end 29.2862 -141.258036)
		(width 0.136652)
		(layer "F.Cu")
		(net "BMC_USB2_HDP")
	)
	(segment
		(start 29.0322 -142.748254)
		(end 29.034486 -142.745714)
		(width 0.136652)
		(layer "F.Cu")
		(net "BMC_USB2_HDP")
	)
	(segment
		(start 28.5242 -142.9766)
		(end 28.751022 -142.9766)
		(width 0.136652)
		(layer "F.Cu")
		(net "BMC_USB2_HDP")
	)
	(segment
		(start 29.85135 -140.08354)
		(end 30.141418 -139.793726)
		(width 0.136652)
		(layer "F.Cu")
		(net "BMC_USB2_HDP")
	)
	(segment
		(start 29.85135 -140.303504)
		(end 29.85135 -140.08354)
		(width 0.136652)
		(layer "F.Cu")
		(net "BMC_USB2_HDP")
	)
	(arc
		(start 28.751022 -142.9766)
		(mid 28.79954 -142.966967)
		(end 28.840684 -142.939516)
		(width 0.136652)
		(layer "F.Cu")
		(net "BMC_USB2_HDP")
	)
	(arc
		(start 28.1305 -142.621)
		(mid 28.258937 -142.874545)
		(end 28.5242 -142.9766)
		(width 0.136652)
		(layer "F.Cu")
		(net "BMC_USB2_HDP")
	)
	(arc
		(start 29.034486 -142.745714)
		(mid 29.220749 -142.467091)
		(end 29.2862 -142.1384)
		(width 0.136652)
		(layer "F.Cu")
		(net "BMC_USB2_HDP")
	)
	(arc
		(start 29.2862 -141.258036)
		(mid 29.357772 -140.898307)
		(end 29.561536 -140.593318)
		(width 0.136652)
		(layer "F.Cu")
		(net "BMC_USB2_HDP")
	)
	(segment
		(start 29.250132 -142.96136)
		(end 29.05633 -143.155416)
		(width 0.136652)
		(layer "F.Cu")
		(net "BMC_USB2_HDN")
	)
	(segment
		(start 29.591 -141.258544)
		(end 29.591 -142.138654)
		(width 0.136652)
		(layer "F.Cu")
		(net "BMC_USB2_HDN")
	)
	(segment
		(start 31.2166 -139.3698)
		(end 29.776928 -140.809472)
		(width 0.136652)
		(layer "F.Cu")
		(net "BMC_USB2_HDN")
	)
	(segment
		(start 31.2166 -139.1158)
		(end 31.2166 -139.3698)
		(width 0.136652)
		(layer "F.Cu")
		(net "BMC_USB2_HDN")
	)
	(segment
		(start 28.751022 -143.2814)
		(end 28.5242 -143.2814)
		(width 0.136652)
		(layer "F.Cu")
		(net "BMC_USB2_HDN")
	)
	(arc
		(start 29.05633 -143.155416)
		(mid 28.916195 -143.248739)
		(end 28.751022 -143.2814)
		(width 0.136652)
		(layer "F.Cu")
		(net "BMC_USB2_HDN")
	)
	(arc
		(start 29.591 -142.138654)
		(mid 29.50236 -142.583895)
		(end 29.250132 -142.96136)
		(width 0.136652)
		(layer "F.Cu")
		(net "BMC_USB2_HDN")
	)
	(arc
		(start 28.5242 -143.2814)
		(mid 28.258943 -143.383461)
		(end 28.1305 -143.637)
		(width 0.136652)
		(layer "F.Cu")
		(net "BMC_USB2_HDN")
	)
	(arc
		(start 29.776928 -140.809472)
		(mid 29.639259 -141.015508)
		(end 29.591 -141.258544)
		(width 0.136652)
		(layer "F.Cu")
		(net "BMC_USB2_HDN")
	)
	(arc
		(start 31.304738 -138.884914)
		(mid 31.239379 -138.99223)
		(end 31.2166 -139.1158)
		(width 0.136652)
		(layer "F.Cu")
		(net "BMC_USB2_HDN")
	)
	(segment
		(start 44.104814 -129.284984)
		(end 44.50461 -128.885188)
		(width 0.136652)
		(layer "F.Cu")
		(net "BMC_USB1_HDP2")
	)
	(via
		(at 44.50461 -128.885188)
		(size 0.4572)
		(drill 0.2032)
		(layers "F.Cu" "B.Cu")
		(net "BMC_USB1_HDP2")
	)
	(segment
		(start 51.0921 -129.7686)
		(end 49.662588 -129.7686)
		(width 0.136652)
		(layer "B.Cu")
		(net "BMC_USB1_HDP2")
	)
	(segment
		(start 44.677584 -128.712214)
		(end 44.50461 -128.885188)
		(width 0.136652)
		(layer "B.Cu")
		(net "BMC_USB1_HDP2")
	)
	(segment
		(start 44.688506 -128.701038)
		(end 44.677584 -128.712214)
		(width 0.136652)
		(layer "B.Cu")
		(net "BMC_USB1_HDP2")
	)
	(segment
		(start 48.378364 -128.484376)
		(end 45.212 -128.484376)
		(width 0.136652)
		(layer "B.Cu")
		(net "BMC_USB1_HDP2")
	)
	(segment
		(start 49.662588 -129.7686)
		(end 48.378364 -128.484376)
		(width 0.136652)
		(layer "B.Cu")
		(net "BMC_USB1_HDP2")
	)
	(arc
		(start 45.212 -128.484376)
		(mid 44.928701 -128.540634)
		(end 44.688506 -128.701038)
		(width 0.136652)
		(layer "B.Cu")
		(net "BMC_USB1_HDP2")
	)
	(segment
		(start 52.803044 -127.635254)
		(end 52.803044 -128.01727)
		(width 0.136652)
		(layer "F.Cu")
		(net "BMC_USB1_HDP")
	)
	(segment
		(start 47.724314 -128.55321)
		(end 47.558706 -128.387602)
		(width 0.136652)
		(layer "F.Cu")
		(net "BMC_USB1_HDP")
	)
	(segment
		(start 52.803044 -128.01727)
		(end 52.601114 -128.2192)
		(width 0.136652)
		(layer "F.Cu")
		(net "BMC_USB1_HDP")
	)
	(segment
		(start 48.709834 -128.387602)
		(end 48.299878 -128.387602)
		(width 0.136652)
		(layer "F.Cu")
		(net "BMC_USB1_HDP")
	)
	(segment
		(start 49.451006 -128.387602)
		(end 49.285398 -128.55321)
		(width 0.136652)
		(layer "F.Cu")
		(net "BMC_USB1_HDP")
	)
	(segment
		(start 53.2765 -127.508)
		(end 52.930298 -127.508)
		(width 0.136652)
		(layer "F.Cu")
		(net "BMC_USB1_HDP")
	)
	(segment
		(start 48.13427 -128.55321)
		(end 47.724314 -128.55321)
		(width 0.136652)
		(layer "F.Cu")
		(net "BMC_USB1_HDP")
	)
	(segment
		(start 46.983142 -128.55321)
		(end 46.573186 -128.55321)
		(width 0.136652)
		(layer "F.Cu")
		(net "BMC_USB1_HDP")
	)
	(segment
		(start 49.285398 -128.55321)
		(end 48.875442 -128.55321)
		(width 0.136652)
		(layer "F.Cu")
		(net "BMC_USB1_HDP")
	)
	(segment
		(start 47.14875 -128.387602)
		(end 46.983142 -128.55321)
		(width 0.136652)
		(layer "F.Cu")
		(net "BMC_USB1_HDP")
	)
	(segment
		(start 52.930298 -127.508)
		(end 52.803044 -127.635254)
		(width 0.136652)
		(layer "F.Cu")
		(net "BMC_USB1_HDP")
	)
	(segment
		(start 49.860962 -128.387602)
		(end 49.451006 -128.387602)
		(width 0.136652)
		(layer "F.Cu")
		(net "BMC_USB1_HDP")
	)
	(segment
		(start 48.875442 -128.55321)
		(end 48.709834 -128.387602)
		(width 0.136652)
		(layer "F.Cu")
		(net "BMC_USB1_HDP")
	)
	(segment
		(start 46.573186 -128.55321)
		(end 46.50486 -128.484884)
		(width 0.136652)
		(layer "F.Cu")
		(net "BMC_USB1_HDP")
	)
	(segment
		(start 52.172108 -128.2192)
		(end 51.838098 -128.55321)
		(width 0.136652)
		(layer "F.Cu")
		(net "BMC_USB1_HDP")
	)
	(segment
		(start 47.558706 -128.387602)
		(end 47.14875 -128.387602)
		(width 0.136652)
		(layer "F.Cu")
		(net "BMC_USB1_HDP")
	)
	(segment
		(start 52.601114 -128.2192)
		(end 52.172108 -128.2192)
		(width 0.136652)
		(layer "F.Cu")
		(net "BMC_USB1_HDP")
	)
	(segment
		(start 48.299878 -128.387602)
		(end 48.13427 -128.55321)
		(width 0.136652)
		(layer "F.Cu")
		(net "BMC_USB1_HDP")
	)
	(segment
		(start 50.02657 -128.55321)
		(end 49.860962 -128.387602)
		(width 0.136652)
		(layer "F.Cu")
		(net "BMC_USB1_HDP")
	)
	(segment
		(start 51.838098 -128.55321)
		(end 50.02657 -128.55321)
		(width 0.136652)
		(layer "F.Cu")
		(net "BMC_USB1_HDP")
	)
	(segment
		(start 44.904914 -129.284984)
		(end 45.30471 -128.885188)
		(width 0.136652)
		(layer "F.Cu")
		(net "BMC_USB1_HDN2")
	)
	(via
		(at 45.30471 -128.885188)
		(size 0.4572)
		(drill 0.2032)
		(layers "F.Cu" "B.Cu")
		(net "BMC_USB1_HDN2")
	)
	(segment
		(start 48.736504 -129.273808)
		(end 48.736504 -129.493518)
		(width 0.136652)
		(layer "B.Cu")
		(net "BMC_USB1_HDN2")
	)
	(segment
		(start 48.251872 -128.789176)
		(end 48.736504 -129.273808)
		(width 0.136652)
		(layer "B.Cu")
		(net "BMC_USB1_HDN2")
	)
	(segment
		(start 45.946568 -128.789176)
		(end 46.102016 -128.944624)
		(width 0.136652)
		(layer "B.Cu")
		(net "BMC_USB1_HDN2")
	)
	(segment
		(start 49.246282 -129.783586)
		(end 49.536096 -130.0734)
		(width 0.136652)
		(layer "B.Cu")
		(net "BMC_USB1_HDN2")
	)
	(segment
		(start 48.736504 -129.493518)
		(end 49.026318 -129.783586)
		(width 0.136652)
		(layer "B.Cu")
		(net "BMC_USB1_HDN2")
	)
	(segment
		(start 49.536096 -130.0734)
		(end 50.17897 -130.0734)
		(width 0.136652)
		(layer "B.Cu")
		(net "BMC_USB1_HDN2")
	)
	(segment
		(start 47.64278 -128.944624)
		(end 47.798228 -128.789176)
		(width 0.136652)
		(layer "B.Cu")
		(net "BMC_USB1_HDN2")
	)
	(segment
		(start 46.66742 -128.789176)
		(end 47.077376 -128.789176)
		(width 0.136652)
		(layer "B.Cu")
		(net "BMC_USB1_HDN2")
	)
	(segment
		(start 45.536612 -128.789176)
		(end 45.946568 -128.789176)
		(width 0.136652)
		(layer "B.Cu")
		(net "BMC_USB1_HDN2")
	)
	(segment
		(start 49.026318 -129.783586)
		(end 49.246282 -129.783586)
		(width 0.136652)
		(layer "B.Cu")
		(net "BMC_USB1_HDN2")
	)
	(segment
		(start 47.232824 -128.944624)
		(end 47.64278 -128.944624)
		(width 0.136652)
		(layer "B.Cu")
		(net "BMC_USB1_HDN2")
	)
	(segment
		(start 47.077376 -128.789176)
		(end 47.232824 -128.944624)
		(width 0.136652)
		(layer "B.Cu")
		(net "BMC_USB1_HDN2")
	)
	(segment
		(start 47.798228 -128.789176)
		(end 48.251872 -128.789176)
		(width 0.136652)
		(layer "B.Cu")
		(net "BMC_USB1_HDN2")
	)
	(segment
		(start 50.417476 -130.297682)
		(end 50.417476 -130.541776)
		(width 0.136652)
		(layer "B.Cu")
		(net "BMC_USB1_HDN2")
	)
	(segment
		(start 50.6603 -130.7846)
		(end 51.0921 -130.7846)
		(width 0.136652)
		(layer "B.Cu")
		(net "BMC_USB1_HDN2")
	)
	(segment
		(start 46.102016 -128.944624)
		(end 46.511972 -128.944624)
		(width 0.136652)
		(layer "B.Cu")
		(net "BMC_USB1_HDN2")
	)
	(segment
		(start 46.511972 -128.944624)
		(end 46.66742 -128.789176)
		(width 0.136652)
		(layer "B.Cu")
		(net "BMC_USB1_HDN2")
	)
	(arc
		(start 50.17897 -130.0734)
		(mid 50.342686 -130.138274)
		(end 50.417476 -130.297682)
		(width 0.136652)
		(layer "B.Cu")
		(net "BMC_USB1_HDN2")
	)
	(arc
		(start 45.30471 -128.885188)
		(mid 45.343408 -128.85215)
		(end 45.386752 -128.825498)
		(width 0.136652)
		(layer "B.Cu")
		(net "BMC_USB1_HDN2")
	)
	(arc
		(start 50.488596 -130.71348)
		(mid 50.567374 -130.766118)
		(end 50.6603 -130.7846)
		(width 0.136652)
		(layer "B.Cu")
		(net "BMC_USB1_HDN2")
	)
	(arc
		(start 50.417476 -130.541776)
		(mid 50.43596 -130.634701)
		(end 50.488596 -130.71348)
		(width 0.136652)
		(layer "B.Cu")
		(net "BMC_USB1_HDN2")
	)
	(arc
		(start 45.386752 -128.825498)
		(mid 45.459514 -128.798379)
		(end 45.536612 -128.789176)
		(width 0.136652)
		(layer "B.Cu")
		(net "BMC_USB1_HDN2")
	)
	(segment
		(start 53.2765 -128.524)
		(end 52.2986 -128.524)
		(width 0.136652)
		(layer "F.Cu")
		(net "BMC_USB1_HDN")
	)
	(segment
		(start 46.350174 -128.85801)
		(end 45.977048 -128.484884)
		(width 0.136652)
		(layer "F.Cu")
		(net "BMC_USB1_HDN")
	)
	(segment
		(start 45.977048 -128.484884)
		(end 45.70476 -128.484884)
		(width 0.136652)
		(layer "F.Cu")
		(net "BMC_USB1_HDN")
	)
	(segment
		(start 51.96459 -128.85801)
		(end 46.350174 -128.85801)
		(width 0.136652)
		(layer "F.Cu")
		(net "BMC_USB1_HDN")
	)
	(segment
		(start 52.2986 -128.524)
		(end 51.96459 -128.85801)
		(width 0.136652)
		(layer "F.Cu")
		(net "BMC_USB1_HDN")
	)
	(segment
		(start 43.457876 -61.966094)
		(end 43.457876 -62.863476)
		(width 0.12065)
		(layer "F.Cu")
		(net "BMC_USB_EN_1")
	)
	(segment
		(start 48.773842 -116.352828)
		(end 47.7901 -117.33657)
		(width 0.12065)
		(layer "F.Cu")
		(net "BMC_USB_EN_1")
	)
	(segment
		(start 49.844706 -117.414548)
		(end 49.844706 -117.243352)
		(width 0.12065)
		(layer "F.Cu")
		(net "BMC_USB_EN_1")
	)
	(segment
		(start 48.954182 -116.352828)
		(end 48.773842 -116.352828)
		(width 0.12065)
		(layer "F.Cu")
		(net "BMC_USB_EN_1")
	)
	(segment
		(start 43.457876 -62.863476)
		(end 43.4594 -62.865)
		(width 0.12065)
		(layer "F.Cu")
		(net "BMC_USB_EN_1")
	)
	(segment
		(start 49.844706 -117.243352)
		(end 48.954182 -116.352828)
		(width 0.12065)
		(layer "F.Cu")
		(net "BMC_USB_EN_1")
	)
	(via
		(at 43.4594 -62.865)
		(size 0.508)
		(drill 0.254)
		(layers "F.Cu" "B.Cu")
		(net "BMC_USB_EN_1")
	)
	(via
		(at 44.435522 -81.53781)
		(size 0.508)
		(drill 0.254)
		(layers "F.Cu" "B.Cu")
		(net "BMC_USB_EN_1")
	)
	(via
		(at 49.844706 -117.414548)
		(size 0.508)
		(drill 0.254)
		(layers "F.Cu" "B.Cu")
		(net "BMC_USB_EN_1")
	)
	(via
		(at 44.012358 -80.24368)
		(size 0.7112)
		(drill 0.3556)
		(layers "F.Cu" "B.Cu")
		(net "BMC_USB_EN_1")
	)
	(segment
		(start 43.4594 -62.865)
		(end 43.4594 -64.218312)
		(width 0.12065)
		(layer "B.Cu")
		(net "BMC_USB_EN_1")
	)
	(segment
		(start 43.4594 -64.218312)
		(end 41.6306 -66.047112)
		(width 0.12065)
		(layer "B.Cu")
		(net "BMC_USB_EN_1")
	)
	(segment
		(start 43.7134 -79.944722)
		(end 44.012358 -80.24368)
		(width 0.12065)
		(layer "B.Cu")
		(net "BMC_USB_EN_1")
	)
	(segment
		(start 41.6306 -75.7936)
		(end 42.545 -76.708)
		(width 0.12065)
		(layer "B.Cu")
		(net "BMC_USB_EN_1")
	)
	(segment
		(start 44.380658 -81.482946)
		(end 44.435522 -81.53781)
		(width 0.12065)
		(layer "B.Cu")
		(net "BMC_USB_EN_1")
	)
	(segment
		(start 42.545 -76.708)
		(end 43.20667 -76.708)
		(width 0.12065)
		(layer "B.Cu")
		(net "BMC_USB_EN_1")
	)
	(segment
		(start 44.012358 -80.24368)
		(end 44.380658 -80.61198)
		(width 0.12065)
		(layer "B.Cu")
		(net "BMC_USB_EN_1")
	)
	(segment
		(start 43.20667 -76.708)
		(end 43.7134 -77.21473)
		(width 0.12065)
		(layer "B.Cu")
		(net "BMC_USB_EN_1")
	)
	(segment
		(start 44.380658 -80.61198)
		(end 44.380658 -81.482946)
		(width 0.12065)
		(layer "B.Cu")
		(net "BMC_USB_EN_1")
	)
	(segment
		(start 41.6306 -66.047112)
		(end 41.6306 -75.7936)
		(width 0.12065)
		(layer "B.Cu")
		(net "BMC_USB_EN_1")
	)
	(segment
		(start 43.7134 -77.21473)
		(end 43.7134 -79.944722)
		(width 0.12065)
		(layer "B.Cu")
		(net "BMC_USB_EN_1")
	)
	(segment
		(start 49.674272 -114.256058)
		(end 49.674272 -117.16131)
		(width 0.127)
		(layer "In5.Cu")
		(net "BMC_USB_EN_1")
	)
	(segment
		(start 49.674272 -117.16131)
		(end 49.844706 -117.331744)
		(width 0.127)
		(layer "In5.Cu")
		(net "BMC_USB_EN_1")
	)
	(segment
		(start 44.435522 -82.635344)
		(end 45.69968 -83.899502)
		(width 0.127)
		(layer "In5.Cu")
		(net "BMC_USB_EN_1")
	)
	(segment
		(start 46.1772 -90.45956)
		(end 46.1772 -110.758986)
		(width 0.127)
		(layer "In5.Cu")
		(net "BMC_USB_EN_1")
	)
	(segment
		(start 45.69968 -83.899502)
		(end 45.69968 -89.98204)
		(width 0.127)
		(layer "In5.Cu")
		(net "BMC_USB_EN_1")
	)
	(segment
		(start 45.69968 -89.98204)
		(end 46.1772 -90.45956)
		(width 0.127)
		(layer "In5.Cu")
		(net "BMC_USB_EN_1")
	)
	(segment
		(start 44.435522 -81.53781)
		(end 44.435522 -82.635344)
		(width 0.127)
		(layer "In5.Cu")
		(net "BMC_USB_EN_1")
	)
	(segment
		(start 49.844706 -117.331744)
		(end 49.844706 -117.414548)
		(width 0.127)
		(layer "In5.Cu")
		(net "BMC_USB_EN_1")
	)
	(segment
		(start 46.1772 -110.758986)
		(end 49.674272 -114.256058)
		(width 0.127)
		(layer "In5.Cu")
		(net "BMC_USB_EN_1")
	)
	(segment
		(start 45.31995 -143.662146)
		(end 45.31995 -140.930884)
		(width 0.12065)
		(layer "F.Cu")
		(net "BMC_UART_SWITCH_1")
	)
	(segment
		(start 45.76064 -147.91436)
		(end 45.974 -147.701)
		(width 0.12065)
		(layer "F.Cu")
		(net "BMC_UART_SWITCH_1")
	)
	(segment
		(start 45.31995 -140.930884)
		(end 43.639232 -139.250166)
		(width 0.12065)
		(layer "F.Cu")
		(net "BMC_UART_SWITCH_1")
	)
	(segment
		(start 219.2782 -5.98805)
		(end 220.12275 -5.1435)
		(width 0.12065)
		(layer "F.Cu")
		(net "BMC_UART_SWITCH_1")
	)
	(segment
		(start 44.141898 -144.840198)
		(end 45.31995 -143.662146)
		(width 0.12065)
		(layer "F.Cu")
		(net "BMC_UART_SWITCH_1")
	)
	(segment
		(start 42.87012 -138.966702)
		(end 42.87012 -138.450066)
		(width 0.12065)
		(layer "F.Cu")
		(net "BMC_UART_SWITCH_1")
	)
	(segment
		(start 44.54144 -147.54606)
		(end 44.90974 -147.91436)
		(width 0.12065)
		(layer "F.Cu")
		(net "BMC_UART_SWITCH_1")
	)
	(segment
		(start 220.345 -5.1435)
		(end 220.345 -4.1275)
		(width 0.12065)
		(layer "F.Cu")
		(net "BMC_UART_SWITCH_1")
	)
	(segment
		(start 42.87012 -138.450066)
		(end 42.504868 -138.084814)
		(width 0.12065)
		(layer "F.Cu")
		(net "BMC_UART_SWITCH_1")
	)
	(segment
		(start 43.153584 -139.250166)
		(end 42.87012 -138.966702)
		(width 0.12065)
		(layer "F.Cu")
		(net "BMC_UART_SWITCH_1")
	)
	(segment
		(start 43.639232 -139.250166)
		(end 43.153584 -139.250166)
		(width 0.12065)
		(layer "F.Cu")
		(net "BMC_UART_SWITCH_1")
	)
	(segment
		(start 44.141898 -147.146518)
		(end 44.141898 -144.840198)
		(width 0.12065)
		(layer "F.Cu")
		(net "BMC_UART_SWITCH_1")
	)
	(segment
		(start 44.54144 -147.54606)
		(end 44.141898 -147.146518)
		(width 0.12065)
		(layer "F.Cu")
		(net "BMC_UART_SWITCH_1")
	)
	(segment
		(start 220.12275 -5.1435)
		(end 220.345 -5.1435)
		(width 0.12065)
		(layer "F.Cu")
		(net "BMC_UART_SWITCH_1")
	)
	(segment
		(start 44.90974 -147.91436)
		(end 45.76064 -147.91436)
		(width 0.12065)
		(layer "F.Cu")
		(net "BMC_UART_SWITCH_1")
	)
	(via
		(at 219.2782 -5.98805)
		(size 0.508)
		(drill 0.254)
		(layers "F.Cu" "B.Cu")
		(net "BMC_UART_SWITCH_1")
	)
	(via
		(at 44.54144 -147.54606)
		(size 0.7112)
		(drill 0.3556)
		(layers "F.Cu" "B.Cu")
		(net "BMC_UART_SWITCH_1")
	)
	(via
		(at 83.188048 -129.441448)
		(size 0.508)
		(drill 0.254)
		(layers "F.Cu" "B.Cu")
		(net "BMC_UART_SWITCH_1")
	)
	(via
		(at 45.974 -147.701)
		(size 0.508)
		(drill 0.254)
		(layers "F.Cu" "B.Cu")
		(net "BMC_UART_SWITCH_1")
	)
	(via
		(at 94.1578 -89.8906)
		(size 0.508)
		(drill 0.254)
		(layers "F.Cu" "B.Cu")
		(net "BMC_UART_SWITCH_1")
	)
	(segment
		(start 83.961224 -118.306088)
		(end 82.740754 -119.526558)
		(width 0.12065)
		(layer "B.Cu")
		(net "BMC_UART_SWITCH_1")
	)
	(segment
		(start 94.1578 -95.464376)
		(end 83.961224 -105.660952)
		(width 0.12065)
		(layer "B.Cu")
		(net "BMC_UART_SWITCH_1")
	)
	(segment
		(start 83.961224 -105.660952)
		(end 83.961224 -118.306088)
		(width 0.12065)
		(layer "B.Cu")
		(net "BMC_UART_SWITCH_1")
	)
	(segment
		(start 94.1578 -89.8906)
		(end 94.1578 -95.464376)
		(width 0.12065)
		(layer "B.Cu")
		(net "BMC_UART_SWITCH_1")
	)
	(segment
		(start 82.740754 -119.526558)
		(end 82.740754 -128.994154)
		(width 0.12065)
		(layer "B.Cu")
		(net "BMC_UART_SWITCH_1")
	)
	(segment
		(start 82.740754 -128.994154)
		(end 83.188048 -129.441448)
		(width 0.12065)
		(layer "B.Cu")
		(net "BMC_UART_SWITCH_1")
	)
	(segment
		(start 216.842594 -7.39648)
		(end 207.669384 -7.39648)
		(width 0.127)
		(layer "In2.Cu")
		(net "BMC_UART_SWITCH_1")
	)
	(segment
		(start 76.991718 -134.48411)
		(end 76.1746 -135.301228)
		(width 0.127)
		(layer "In2.Cu")
		(net "BMC_UART_SWITCH_1")
	)
	(segment
		(start 118.622318 -21.143976)
		(end 118.622064 -21.143722)
		(width 0.127)
		(layer "In2.Cu")
		(net "BMC_UART_SWITCH_1")
	)
	(segment
		(start 103.3526 -71.943722)
		(end 103.352346 -74.861928)
		(width 0.127)
		(layer "In2.Cu")
		(net "BMC_UART_SWITCH_1")
	)
	(segment
		(start 65.323466 -147.192746)
		(end 61.945266 -147.192746)
		(width 0.127)
		(layer "In2.Cu")
		(net "BMC_UART_SWITCH_1")
	)
	(segment
		(start 134.445502 -6.963664)
		(end 120.396508 -21.008848)
		(width 0.127)
		(layer "In2.Cu")
		(net "BMC_UART_SWITCH_1")
	)
	(segment
		(start 76.1746 -142.4686)
		(end 75.1205 -143.5227)
		(width 0.127)
		(layer "In2.Cu")
		(net "BMC_UART_SWITCH_1")
	)
	(segment
		(start 115.99545 -21.143722)
		(end 100.70719 -36.431982)
		(width 0.127)
		(layer "In2.Cu")
		(net "BMC_UART_SWITCH_1")
	)
	(segment
		(start 188.164978 -7.553198)
		(end 178.191414 -7.553198)
		(width 0.127)
		(layer "In2.Cu")
		(net "BMC_UART_SWITCH_1")
	)
	(segment
		(start 103.352346 -76.905612)
		(end 100.7364 -79.522574)
		(width 0.127)
		(layer "In2.Cu")
		(net "BMC_UART_SWITCH_1")
	)
	(segment
		(start 189.42558 -8.8138)
		(end 188.164978 -7.553198)
		(width 0.127)
		(layer "In2.Cu")
		(net "BMC_UART_SWITCH_1")
	)
	(segment
		(start 219.2782 -5.98805)
		(end 218.251024 -5.98805)
		(width 0.127)
		(layer "In2.Cu")
		(net "BMC_UART_SWITCH_1")
	)
	(segment
		(start 54.356 -149.987)
		(end 52.07 -147.701)
		(width 0.127)
		(layer "In2.Cu")
		(net "BMC_UART_SWITCH_1")
	)
	(segment
		(start 75.039982 -143.5227)
		(end 74.951082 -143.6116)
		(width 0.127)
		(layer "In2.Cu")
		(net "BMC_UART_SWITCH_1")
	)
	(segment
		(start 193.25209 -9.86409)
		(end 192.2018 -8.8138)
		(width 0.127)
		(layer "In2.Cu")
		(net "BMC_UART_SWITCH_1")
	)
	(segment
		(start 83.188048 -129.441448)
		(end 81.095596 -131.5339)
		(width 0.127)
		(layer "In2.Cu")
		(net "BMC_UART_SWITCH_1")
	)
	(segment
		(start 100.7364 -83.312)
		(end 94.1578 -89.8906)
		(width 0.127)
		(layer "In2.Cu")
		(net "BMC_UART_SWITCH_1")
	)
	(segment
		(start 177.601626 -6.96341)
		(end 135.883142 -6.96341)
		(width 0.127)
		(layer "In2.Cu")
		(net "BMC_UART_SWITCH_1")
	)
	(segment
		(start 103.352346 -74.861928)
		(end 103.352346 -76.905612)
		(width 0.127)
		(layer "In2.Cu")
		(net "BMC_UART_SWITCH_1")
	)
	(segment
		(start 192.2018 -8.8138)
		(end 189.42558 -8.8138)
		(width 0.127)
		(layer "In2.Cu")
		(net "BMC_UART_SWITCH_1")
	)
	(segment
		(start 135.092948 -6.963664)
		(end 134.445502 -6.963664)
		(width 0.127)
		(layer "In2.Cu")
		(net "BMC_UART_SWITCH_1")
	)
	(segment
		(start 79.666592 -131.808982)
		(end 76.991718 -134.48411)
		(width 0.127)
		(layer "In2.Cu")
		(net "BMC_UART_SWITCH_1")
	)
	(segment
		(start 75.1205 -143.5227)
		(end 75.039982 -143.5227)
		(width 0.127)
		(layer "In2.Cu")
		(net "BMC_UART_SWITCH_1")
	)
	(segment
		(start 118.622064 -21.143722)
		(end 115.99545 -21.143722)
		(width 0.127)
		(layer "In2.Cu")
		(net "BMC_UART_SWITCH_1")
	)
	(segment
		(start 68.537328 -145.8849)
		(end 66.631312 -145.8849)
		(width 0.127)
		(layer "In2.Cu")
		(net "BMC_UART_SWITCH_1")
	)
	(segment
		(start 100.7364 -79.522574)
		(end 100.7364 -83.312)
		(width 0.127)
		(layer "In2.Cu")
		(net "BMC_UART_SWITCH_1")
	)
	(segment
		(start 178.191414 -7.553198)
		(end 177.601626 -6.96341)
		(width 0.127)
		(layer "In2.Cu")
		(net "BMC_UART_SWITCH_1")
	)
	(segment
		(start 120.396508 -21.008848)
		(end 120.26138 -21.143976)
		(width 0.127)
		(layer "In2.Cu")
		(net "BMC_UART_SWITCH_1")
	)
	(segment
		(start 135.883142 -6.96341)
		(end 135.092948 -6.963664)
		(width 0.127)
		(layer "In2.Cu")
		(net "BMC_UART_SWITCH_1")
	)
	(segment
		(start 70.810628 -143.6116)
		(end 68.537328 -145.8849)
		(width 0.127)
		(layer "In2.Cu")
		(net "BMC_UART_SWITCH_1")
	)
	(segment
		(start 52.07 -147.701)
		(end 45.974 -147.701)
		(width 0.127)
		(layer "In2.Cu")
		(net "BMC_UART_SWITCH_1")
	)
	(segment
		(start 74.951082 -143.6116)
		(end 70.810628 -143.6116)
		(width 0.127)
		(layer "In2.Cu")
		(net "BMC_UART_SWITCH_1")
	)
	(segment
		(start 59.151012 -149.987)
		(end 54.356 -149.987)
		(width 0.127)
		(layer "In2.Cu")
		(net "BMC_UART_SWITCH_1")
	)
	(segment
		(start 205.201774 -9.86409)
		(end 193.25209 -9.86409)
		(width 0.127)
		(layer "In2.Cu")
		(net "BMC_UART_SWITCH_1")
	)
	(segment
		(start 100.70719 -44.57319)
		(end 103.3526 -47.2186)
		(width 0.127)
		(layer "In2.Cu")
		(net "BMC_UART_SWITCH_1")
	)
	(segment
		(start 207.669384 -7.39648)
		(end 205.201774 -9.86409)
		(width 0.127)
		(layer "In2.Cu")
		(net "BMC_UART_SWITCH_1")
	)
	(segment
		(start 103.3526 -47.2186)
		(end 103.3526 -71.943722)
		(width 0.127)
		(layer "In2.Cu")
		(net "BMC_UART_SWITCH_1")
	)
	(segment
		(start 61.945266 -147.192746)
		(end 59.151012 -149.987)
		(width 0.127)
		(layer "In2.Cu")
		(net "BMC_UART_SWITCH_1")
	)
	(segment
		(start 76.1746 -135.301228)
		(end 76.1746 -142.4686)
		(width 0.127)
		(layer "In2.Cu")
		(net "BMC_UART_SWITCH_1")
	)
	(segment
		(start 66.631312 -145.8849)
		(end 65.323466 -147.192746)
		(width 0.127)
		(layer "In2.Cu")
		(net "BMC_UART_SWITCH_1")
	)
	(segment
		(start 100.70719 -36.431982)
		(end 100.70719 -44.57319)
		(width 0.127)
		(layer "In2.Cu")
		(net "BMC_UART_SWITCH_1")
	)
	(segment
		(start 79.941674 -131.5339)
		(end 79.666592 -131.808982)
		(width 0.127)
		(layer "In2.Cu")
		(net "BMC_UART_SWITCH_1")
	)
	(segment
		(start 120.26138 -21.143976)
		(end 118.622318 -21.143976)
		(width 0.127)
		(layer "In2.Cu")
		(net "BMC_UART_SWITCH_1")
	)
	(segment
		(start 218.251024 -5.98805)
		(end 216.842594 -7.39648)
		(width 0.127)
		(layer "In2.Cu")
		(net "BMC_UART_SWITCH_1")
	)
	(segment
		(start 81.095596 -131.5339)
		(end 79.941674 -131.5339)
		(width 0.127)
		(layer "In2.Cu")
		(net "BMC_UART_SWITCH_1")
	)
	(segment
		(start 69.202808 -127.526796)
		(end 69.021452 -127.34544)
		(width 0.12065)
		(layer "F.Cu")
		(net "BMC_TXD5_R")
	)
	(segment
		(start 69.510148 -129.14376)
		(end 69.202808 -128.83642)
		(width 0.12065)
		(layer "F.Cu")
		(net "BMC_TXD5_R")
	)
	(segment
		(start 62.108334 -126.867666)
		(end 62.910212 -126.867666)
		(width 0.12065)
		(layer "F.Cu")
		(net "BMC_TXD5_R")
	)
	(segment
		(start 69.202808 -128.83642)
		(end 69.202808 -127.526796)
		(width 0.12065)
		(layer "F.Cu")
		(net "BMC_TXD5_R")
	)
	(segment
		(start 43.304714 -127.684784)
		(end 43.70451 -127.284988)
		(width 0.12065)
		(layer "F.Cu")
		(net "BMC_TXD5_R")
	)
	(segment
		(start 66.459608 -126.073154)
		(end 66.66992 -126.283466)
		(width 0.12065)
		(layer "F.Cu")
		(net "BMC_TXD5_R")
	)
	(segment
		(start 62.910212 -126.867666)
		(end 63.704724 -126.073154)
		(width 0.12065)
		(layer "F.Cu")
		(net "BMC_TXD5_R")
	)
	(segment
		(start 67.382136 -127.339852)
		(end 67.570858 -127.339852)
		(width 0.12065)
		(layer "F.Cu")
		(net "BMC_TXD5_R")
	)
	(segment
		(start 70.2056 -129.14376)
		(end 69.510148 -129.14376)
		(width 0.12065)
		(layer "F.Cu")
		(net "BMC_TXD5_R")
	)
	(segment
		(start 66.66992 -126.627636)
		(end 67.382136 -127.339852)
		(width 0.12065)
		(layer "F.Cu")
		(net "BMC_TXD5_R")
	)
	(segment
		(start 69.021452 -127.34544)
		(end 68.326 -127.34544)
		(width 0.12065)
		(layer "F.Cu")
		(net "BMC_TXD5_R")
	)
	(segment
		(start 67.570858 -127.339852)
		(end 67.576446 -127.34544)
		(width 0.12065)
		(layer "F.Cu")
		(net "BMC_TXD5_R")
	)
	(segment
		(start 67.576446 -127.34544)
		(end 68.326 -127.34544)
		(width 0.12065)
		(layer "F.Cu")
		(net "BMC_TXD5_R")
	)
	(segment
		(start 62.0014 -126.9746)
		(end 62.108334 -126.867666)
		(width 0.12065)
		(layer "F.Cu")
		(net "BMC_TXD5_R")
	)
	(segment
		(start 63.704724 -126.073154)
		(end 66.459608 -126.073154)
		(width 0.12065)
		(layer "F.Cu")
		(net "BMC_TXD5_R")
	)
	(segment
		(start 66.66992 -126.283466)
		(end 66.66992 -126.627636)
		(width 0.12065)
		(layer "F.Cu")
		(net "BMC_TXD5_R")
	)
	(via
		(at 62.0014 -126.9746)
		(size 0.508)
		(drill 0.254)
		(layers "F.Cu" "B.Cu")
		(net "BMC_TXD5_R")
	)
	(via
		(at 42.318432 -127.422656)
		(size 0.7112)
		(drill 0.3556)
		(layers "F.Cu" "B.Cu")
		(net "BMC_TXD5_R")
	)
	(via
		(at 43.70451 -127.284988)
		(size 0.4572)
		(drill 0.2032)
		(layers "F.Cu" "B.Cu")
		(net "BMC_TXD5_R")
	)
	(segment
		(start 63.1698 -126.4158)
		(end 62.9158 -126.6698)
		(width 0.12065)
		(layer "B.Cu")
		(net "BMC_TXD5_R")
	)
	(segment
		(start 62.3062 -126.6698)
		(end 62.0014 -126.9746)
		(width 0.12065)
		(layer "B.Cu")
		(net "BMC_TXD5_R")
	)
	(segment
		(start 42.399204 -127.341884)
		(end 42.318432 -127.422656)
		(width 0.12065)
		(layer "B.Cu")
		(net "BMC_TXD5_R")
	)
	(segment
		(start 63.4365 -125.5014)
		(end 63.1698 -125.7681)
		(width 0.12065)
		(layer "B.Cu")
		(net "BMC_TXD5_R")
	)
	(segment
		(start 43.647614 -127.341884)
		(end 42.399204 -127.341884)
		(width 0.12065)
		(layer "B.Cu")
		(net "BMC_TXD5_R")
	)
	(segment
		(start 43.70451 -127.284988)
		(end 43.647614 -127.341884)
		(width 0.12065)
		(layer "B.Cu")
		(net "BMC_TXD5_R")
	)
	(segment
		(start 63.1698 -125.7681)
		(end 63.1698 -126.4158)
		(width 0.12065)
		(layer "B.Cu")
		(net "BMC_TXD5_R")
	)
	(segment
		(start 62.9158 -126.6698)
		(end 62.3062 -126.6698)
		(width 0.12065)
		(layer "B.Cu")
		(net "BMC_TXD5_R")
	)
	(segment
		(start 52.8193 -127.3429)
		(end 51.2318 -127.3429)
		(width 0.127)
		(layer "In2.Cu")
		(net "BMC_TXD5_R")
	)
	(segment
		(start 55.434484 -127.1016)
		(end 54.598316 -127.1016)
		(width 0.127)
		(layer "In2.Cu")
		(net "BMC_TXD5_R")
	)
	(segment
		(start 43.70451 -127.042164)
		(end 43.70451 -127.284988)
		(width 0.127)
		(layer "In2.Cu")
		(net "BMC_TXD5_R")
	)
	(segment
		(start 51.2318 -127.3429)
		(end 49.980342 -126.091442)
		(width 0.127)
		(layer "In2.Cu")
		(net "BMC_TXD5_R")
	)
	(segment
		(start 57.937654 -126.9746)
		(end 55.561484 -126.9746)
		(width 0.127)
		(layer "In2.Cu")
		(net "BMC_TXD5_R")
	)
	(segment
		(start 44.11091 -126.635764)
		(end 43.70451 -127.042164)
		(width 0.127)
		(layer "In2.Cu")
		(net "BMC_TXD5_R")
	)
	(segment
		(start 44.341288 -126.091442)
		(end 44.11091 -126.32182)
		(width 0.127)
		(layer "In2.Cu")
		(net "BMC_TXD5_R")
	)
	(segment
		(start 55.561484 -126.9746)
		(end 55.434484 -127.1016)
		(width 0.127)
		(layer "In2.Cu")
		(net "BMC_TXD5_R")
	)
	(segment
		(start 54.598316 -127.1016)
		(end 54.471316 -126.9746)
		(width 0.127)
		(layer "In2.Cu")
		(net "BMC_TXD5_R")
	)
	(segment
		(start 54.471316 -126.9746)
		(end 53.1876 -126.9746)
		(width 0.127)
		(layer "In2.Cu")
		(net "BMC_TXD5_R")
	)
	(segment
		(start 62.0014 -126.9746)
		(end 61.562742 -127.413258)
		(width 0.127)
		(layer "In2.Cu")
		(net "BMC_TXD5_R")
	)
	(segment
		(start 58.376312 -127.413258)
		(end 57.937654 -126.9746)
		(width 0.127)
		(layer "In2.Cu")
		(net "BMC_TXD5_R")
	)
	(segment
		(start 53.1876 -126.9746)
		(end 52.8193 -127.3429)
		(width 0.127)
		(layer "In2.Cu")
		(net "BMC_TXD5_R")
	)
	(segment
		(start 49.980342 -126.091442)
		(end 44.341288 -126.091442)
		(width 0.127)
		(layer "In2.Cu")
		(net "BMC_TXD5_R")
	)
	(segment
		(start 61.562742 -127.413258)
		(end 58.376312 -127.413258)
		(width 0.127)
		(layer "In2.Cu")
		(net "BMC_TXD5_R")
	)
	(segment
		(start 44.11091 -126.32182)
		(end 44.11091 -126.635764)
		(width 0.127)
		(layer "In2.Cu")
		(net "BMC_TXD5_R")
	)
	(segment
		(start 71.1454 -123.698254)
		(end 71.536306 -123.307348)
		(width 0.12065)
		(layer "F.Cu")
		(net "BMC_TXD5")
	)
	(segment
		(start 74.802746 -58.2676)
		(end 91.366848 -58.2676)
		(width 0.12065)
		(layer "F.Cu")
		(net "BMC_TXD5")
	)
	(segment
		(start 225.16338 -1.13538)
		(end 224.79 -0.762)
		(width 0.12065)
		(layer "F.Cu")
		(net "BMC_TXD5")
	)
	(segment
		(start 225.8441 -1.13538)
		(end 225.16338 -1.13538)
		(width 0.12065)
		(layer "F.Cu")
		(net "BMC_TXD5")
	)
	(segment
		(start 48.04918 -73.178924)
		(end 48.04918 -71.501762)
		(width 0.12065)
		(layer "F.Cu")
		(net "BMC_TXD5")
	)
	(segment
		(start 93.852746 -67.5132)
		(end 96.9518 -67.5132)
		(width 0.12065)
		(layer "F.Cu")
		(net "BMC_TXD5")
	)
	(segment
		(start 56.11622 -57.242456)
		(end 56.62422 -56.734456)
		(width 0.12065)
		(layer "F.Cu")
		(net "BMC_TXD5")
	)
	(segment
		(start 224.00641 -0.63881)
		(end 223.9518 -0.5842)
		(width 0.12065)
		(layer "F.Cu")
		(net "BMC_TXD5")
	)
	(segment
		(start 56.05653 -68.31203)
		(end 57.4802 -66.88836)
		(width 0.12065)
		(layer "F.Cu")
		(net "BMC_TXD5")
	)
	(segment
		(start 72.134222 -55.599076)
		(end 74.802746 -58.2676)
		(width 0.12065)
		(layer "F.Cu")
		(net "BMC_TXD5")
	)
	(segment
		(start 48.351948 -71.198994)
		(end 48.351948 -69.318378)
		(width 0.12065)
		(layer "F.Cu")
		(net "BMC_TXD5")
	)
	(segment
		(start 48.40351 -73.533254)
		(end 48.04918 -73.178924)
		(width 0.12065)
		(layer "F.Cu")
		(net "BMC_TXD5")
	)
	(segment
		(start 48.351948 -69.318378)
		(end 49.358296 -68.31203)
		(width 0.12065)
		(layer "F.Cu")
		(net "BMC_TXD5")
	)
	(segment
		(start 91.86545 -58.766202)
		(end 91.86545 -65.525904)
		(width 0.12065)
		(layer "F.Cu")
		(net "BMC_TXD5")
	)
	(segment
		(start 71.536306 -123.307348)
		(end 72.272398 -123.307348)
		(width 0.12065)
		(layer "F.Cu")
		(net "BMC_TXD5")
	)
	(segment
		(start 224.79 -0.762)
		(end 224.783904 -0.762)
		(width 0.12065)
		(layer "F.Cu")
		(net "BMC_TXD5")
	)
	(segment
		(start 57.4802 -66.88836)
		(end 57.4802 -62.11697)
		(width 0.12065)
		(layer "F.Cu")
		(net "BMC_TXD5")
	)
	(segment
		(start 65.1002 -125.603)
		(end 65.47739 -125.22581)
		(width 0.12065)
		(layer "F.Cu")
		(net "BMC_TXD5")
	)
	(segment
		(start 73.156826 -129.302002)
		(end 70.95236 -131.506468)
		(width 0.12065)
		(layer "F.Cu")
		(net "BMC_TXD5")
	)
	(segment
		(start 49.358296 -68.31203)
		(end 56.05653 -68.31203)
		(width 0.12065)
		(layer "F.Cu")
		(net "BMC_TXD5")
	)
	(segment
		(start 56.62422 -56.734456)
		(end 57.639966 -56.734456)
		(width 0.12065)
		(layer "F.Cu")
		(net "BMC_TXD5")
	)
	(segment
		(start 68.326 -131.035552)
		(end 68.326 -130.44424)
		(width 0.12065)
		(layer "F.Cu")
		(net "BMC_TXD5")
	)
	(segment
		(start 56.11622 -60.75299)
		(end 56.11622 -57.242456)
		(width 0.12065)
		(layer "F.Cu")
		(net "BMC_TXD5")
	)
	(segment
		(start 91.366848 -58.2676)
		(end 91.86545 -58.766202)
		(width 0.12065)
		(layer "F.Cu")
		(net "BMC_TXD5")
	)
	(segment
		(start 68.796916 -131.506468)
		(end 68.326 -131.035552)
		(width 0.12065)
		(layer "F.Cu")
		(net "BMC_TXD5")
	)
	(segment
		(start 57.639966 -56.734456)
		(end 58.775346 -55.599076)
		(width 0.12065)
		(layer "F.Cu")
		(net "BMC_TXD5")
	)
	(segment
		(start 70.95236 -131.506468)
		(end 68.796916 -131.506468)
		(width 0.12065)
		(layer "F.Cu")
		(net "BMC_TXD5")
	)
	(segment
		(start 71.1454 -123.987814)
		(end 71.1454 -123.698254)
		(width 0.12065)
		(layer "F.Cu")
		(net "BMC_TXD5")
	)
	(segment
		(start 57.4802 -62.11697)
		(end 56.11622 -60.75299)
		(width 0.12065)
		(layer "F.Cu")
		(net "BMC_TXD5")
	)
	(segment
		(start 224.783904 -0.762)
		(end 224.660714 -0.63881)
		(width 0.12065)
		(layer "F.Cu")
		(net "BMC_TXD5")
	)
	(segment
		(start 224.660714 -0.63881)
		(end 224.00641 -0.63881)
		(width 0.12065)
		(layer "F.Cu")
		(net "BMC_TXD5")
	)
	(segment
		(start 48.04918 -71.501762)
		(end 48.351948 -71.198994)
		(width 0.12065)
		(layer "F.Cu")
		(net "BMC_TXD5")
	)
	(segment
		(start 91.86545 -65.525904)
		(end 93.852746 -67.5132)
		(width 0.12065)
		(layer "F.Cu")
		(net "BMC_TXD5")
	)
	(segment
		(start 69.907404 -125.22581)
		(end 71.1454 -123.987814)
		(width 0.12065)
		(layer "F.Cu")
		(net "BMC_TXD5")
	)
	(segment
		(start 65.47739 -125.22581)
		(end 69.907404 -125.22581)
		(width 0.12065)
		(layer "F.Cu")
		(net "BMC_TXD5")
	)
	(segment
		(start 72.272398 -123.307348)
		(end 73.156826 -124.191776)
		(width 0.12065)
		(layer "F.Cu")
		(net "BMC_TXD5")
	)
	(segment
		(start 58.775346 -55.599076)
		(end 72.134222 -55.599076)
		(width 0.12065)
		(layer "F.Cu")
		(net "BMC_TXD5")
	)
	(segment
		(start 73.156826 -124.191776)
		(end 73.156826 -129.302002)
		(width 0.12065)
		(layer "F.Cu")
		(net "BMC_TXD5")
	)
	(via
		(at 96.9518 -67.5132)
		(size 0.508)
		(drill 0.254)
		(layers "F.Cu" "B.Cu")
		(net "BMC_TXD5")
	)
	(via
		(at 223.9518 -0.5842)
		(size 0.508)
		(drill 0.254)
		(layers "F.Cu" "B.Cu")
		(net "BMC_TXD5")
	)
	(via
		(at 65.1002 -125.603)
		(size 0.508)
		(drill 0.254)
		(layers "F.Cu" "B.Cu")
		(net "BMC_TXD5")
	)
	(via
		(at 223.09328 -1.1049)
		(size 0.7112)
		(drill 0.3556)
		(layers "F.Cu" "B.Cu")
		(net "BMC_TXD5")
	)
	(segment
		(start 63.754 -126.5301)
		(end 64.1731 -126.5301)
		(width 0.12065)
		(layer "B.Cu")
		(net "BMC_TXD5")
	)
	(segment
		(start 223.434148 -1.101852)
		(end 223.9518 -0.5842)
		(width 0.12065)
		(layer "B.Cu")
		(net "BMC_TXD5")
	)
	(segment
		(start 63.754 -126.0729)
		(end 64.3255 -125.5014)
		(width 0.12065)
		(layer "B.Cu")
		(net "BMC_TXD5")
	)
	(segment
		(start 63.754 -126.5301)
		(end 63.754 -126.0729)
		(width 0.12065)
		(layer "B.Cu")
		(net "BMC_TXD5")
	)
	(segment
		(start 223.09328 -1.1049)
		(end 223.096328 -1.101852)
		(width 0.12065)
		(layer "B.Cu")
		(net "BMC_TXD5")
	)
	(segment
		(start 64.1731 -126.5301)
		(end 65.1002 -125.603)
		(width 0.12065)
		(layer "B.Cu")
		(net "BMC_TXD5")
	)
	(segment
		(start 223.096328 -1.101852)
		(end 223.434148 -1.101852)
		(width 0.12065)
		(layer "B.Cu")
		(net "BMC_TXD5")
	)
	(segment
		(start 178.643788 0.287528)
		(end 178.644042 0.287274)
		(width 0.127)
		(layer "In2.Cu")
		(net "BMC_TXD5")
	)
	(segment
		(start 124.320808 -8.038846)
		(end 131.623816 -0.740156)
		(width 0.127)
		(layer "In2.Cu")
		(net "BMC_TXD5")
	)
	(segment
		(start 188.927486 -0.459486)
		(end 189.34811 -0.459486)
		(width 0.127)
		(layer "In2.Cu")
		(net "BMC_TXD5")
	)
	(segment
		(start 189.348364 -0.459232)
		(end 196.877686 -0.459232)
		(width 0.127)
		(layer "In2.Cu")
		(net "BMC_TXD5")
	)
	(segment
		(start 188.180726 0.287274)
		(end 188.927486 -0.459486)
		(width 0.127)
		(layer "In2.Cu")
		(net "BMC_TXD5")
	)
	(segment
		(start 189.34811 -0.459486)
		(end 189.348364 -0.459232)
		(width 0.127)
		(layer "In2.Cu")
		(net "BMC_TXD5")
	)
	(segment
		(start 96.9518 -67.5132)
		(end 96.9518 -51.9938)
		(width 0.127)
		(layer "In2.Cu")
		(net "BMC_TXD5")
	)
	(segment
		(start 131.623816 -0.740156)
		(end 176.563528 -0.740156)
		(width 0.127)
		(layer "In2.Cu")
		(net "BMC_TXD5")
	)
	(segment
		(start 205.585568 2.043684)
		(end 205.58633 2.043938)
		(width 0.127)
		(layer "In2.Cu")
		(net "BMC_TXD5")
	)
	(segment
		(start 120.799098 -8.038846)
		(end 124.320808 -8.038846)
		(width 0.127)
		(layer "In2.Cu")
		(net "BMC_TXD5")
	)
	(segment
		(start 202.093576 -1.4478)
		(end 205.585568 2.043684)
		(width 0.127)
		(layer "In2.Cu")
		(net "BMC_TXD5")
	)
	(segment
		(start 94.86519 -33.972754)
		(end 120.799098 -8.038846)
		(width 0.127)
		(layer "In2.Cu")
		(net "BMC_TXD5")
	)
	(segment
		(start 196.877686 -0.459232)
		(end 197.866254 -1.4478)
		(width 0.127)
		(layer "In2.Cu")
		(net "BMC_TXD5")
	)
	(segment
		(start 178.644042 0.287274)
		(end 188.180726 0.287274)
		(width 0.127)
		(layer "In2.Cu")
		(net "BMC_TXD5")
	)
	(segment
		(start 177.591212 0.287528)
		(end 178.643788 0.287528)
		(width 0.127)
		(layer "In2.Cu")
		(net "BMC_TXD5")
	)
	(segment
		(start 205.58633 2.043938)
		(end 221.323662 2.043938)
		(width 0.127)
		(layer "In2.Cu")
		(net "BMC_TXD5")
	)
	(segment
		(start 176.563528 -0.740156)
		(end 177.591212 0.287528)
		(width 0.127)
		(layer "In2.Cu")
		(net "BMC_TXD5")
	)
	(segment
		(start 197.866254 -1.4478)
		(end 202.093576 -1.4478)
		(width 0.127)
		(layer "In2.Cu")
		(net "BMC_TXD5")
	)
	(segment
		(start 221.323662 2.043938)
		(end 223.9518 -0.5842)
		(width 0.127)
		(layer "In2.Cu")
		(net "BMC_TXD5")
	)
	(segment
		(start 94.86519 -49.90719)
		(end 94.86519 -33.972754)
		(width 0.127)
		(layer "In2.Cu")
		(net "BMC_TXD5")
	)
	(segment
		(start 96.9518 -51.9938)
		(end 94.86519 -49.90719)
		(width 0.127)
		(layer "In2.Cu")
		(net "BMC_TXD5")
	)
	(segment
		(start 76.0857 -68.0339)
		(end 68.672964 -75.446636)
		(width 0.127)
		(layer "In5.Cu")
		(net "BMC_TXD5")
	)
	(segment
		(start 68.089018 -76.8223)
		(end 68.081144 -76.8223)
		(width 0.127)
		(layer "In5.Cu")
		(net "BMC_TXD5")
	)
	(segment
		(start 67.8053 -117.292882)
		(end 64.6303 -120.467882)
		(width 0.127)
		(layer "In5.Cu")
		(net "BMC_TXD5")
	)
	(segment
		(start 68.672964 -75.446636)
		(end 68.672964 -76.23048)
		(width 0.127)
		(layer "In5.Cu")
		(net "BMC_TXD5")
	)
	(segment
		(start 64.6303 -120.467882)
		(end 64.6303 -125.1331)
		(width 0.127)
		(layer "In5.Cu")
		(net "BMC_TXD5")
	)
	(segment
		(start 67.8053 -94.457266)
		(end 67.8053 -117.292882)
		(width 0.127)
		(layer "In5.Cu")
		(net "BMC_TXD5")
	)
	(segment
		(start 96.9518 -67.5132)
		(end 96.4311 -68.0339)
		(width 0.127)
		(layer "In5.Cu")
		(net "BMC_TXD5")
	)
	(segment
		(start 66.9036 -78.000098)
		(end 66.9036 -93.555566)
		(width 0.127)
		(layer "In5.Cu")
		(net "BMC_TXD5")
	)
	(segment
		(start 68.081144 -76.8223)
		(end 66.9036 -78.000098)
		(width 0.127)
		(layer "In5.Cu")
		(net "BMC_TXD5")
	)
	(segment
		(start 96.4311 -68.0339)
		(end 76.0857 -68.0339)
		(width 0.127)
		(layer "In5.Cu")
		(net "BMC_TXD5")
	)
	(segment
		(start 64.6303 -125.1331)
		(end 65.1002 -125.603)
		(width 0.127)
		(layer "In5.Cu")
		(net "BMC_TXD5")
	)
	(segment
		(start 68.3641 -76.539344)
		(end 68.3641 -76.547218)
		(width 0.127)
		(layer "In5.Cu")
		(net "BMC_TXD5")
	)
	(segment
		(start 68.672964 -76.23048)
		(end 68.3641 -76.539344)
		(width 0.127)
		(layer "In5.Cu")
		(net "BMC_TXD5")
	)
	(segment
		(start 68.3641 -76.547218)
		(end 68.089018 -76.8223)
		(width 0.127)
		(layer "In5.Cu")
		(net "BMC_TXD5")
	)
	(segment
		(start 66.9036 -93.555566)
		(end 67.8053 -94.457266)
		(width 0.127)
		(layer "In5.Cu")
		(net "BMC_TXD5")
	)
	(segment
		(start 43.304714 -136.484868)
		(end 43.70451 -136.085072)
		(width 0.12065)
		(layer "F.Cu")
		(net "BMC_SELF_TRAY_R")
	)
	(via
		(at 43.70451 -136.085072)
		(size 0.4572)
		(drill 0.2032)
		(layers "F.Cu" "B.Cu")
		(net "BMC_SELF_TRAY_R")
	)
	(via
		(at 56.5658 -138.811)
		(size 0.7112)
		(drill 0.3556)
		(layers "F.Cu" "B.Cu")
		(net "BMC_SELF_TRAY_R")
	)
	(via
		(at 55.8038 -139.827)
		(size 0.508)
		(drill 0.254)
		(layers "F.Cu" "B.Cu")
		(net "BMC_SELF_TRAY_R")
	)
	(segment
		(start 56.5785 -139.827)
		(end 56.5658 -139.8143)
		(width 0.12065)
		(layer "B.Cu")
		(net "BMC_SELF_TRAY_R")
	)
	(segment
		(start 55.8038 -139.0396)
		(end 55.8038 -139.827)
		(width 0.12065)
		(layer "B.Cu")
		(net "BMC_SELF_TRAY_R")
	)
	(segment
		(start 56.5658 -138.811)
		(end 56.0324 -138.811)
		(width 0.12065)
		(layer "B.Cu")
		(net "BMC_SELF_TRAY_R")
	)
	(segment
		(start 56.5658 -139.8143)
		(end 56.5658 -138.811)
		(width 0.12065)
		(layer "B.Cu")
		(net "BMC_SELF_TRAY_R")
	)
	(segment
		(start 56.0324 -138.811)
		(end 55.8038 -139.0396)
		(width 0.12065)
		(layer "B.Cu")
		(net "BMC_SELF_TRAY_R")
	)
	(segment
		(start 55.1307 -140.5001)
		(end 55.8038 -139.827)
		(width 0.127)
		(layer "In2.Cu")
		(net "BMC_SELF_TRAY_R")
	)
	(segment
		(start 46.308772 -136.478772)
		(end 49.8221 -139.9921)
		(width 0.127)
		(layer "In2.Cu")
		(net "BMC_SELF_TRAY_R")
	)
	(segment
		(start 44.09821 -136.478772)
		(end 46.308772 -136.478772)
		(width 0.127)
		(layer "In2.Cu")
		(net "BMC_SELF_TRAY_R")
	)
	(segment
		(start 53.116988 -139.9921)
		(end 53.624988 -140.5001)
		(width 0.127)
		(layer "In2.Cu")
		(net "BMC_SELF_TRAY_R")
	)
	(segment
		(start 49.8221 -139.9921)
		(end 53.116988 -139.9921)
		(width 0.127)
		(layer "In2.Cu")
		(net "BMC_SELF_TRAY_R")
	)
	(segment
		(start 53.624988 -140.5001)
		(end 55.1307 -140.5001)
		(width 0.127)
		(layer "In2.Cu")
		(net "BMC_SELF_TRAY_R")
	)
	(segment
		(start 43.70451 -136.085072)
		(end 44.09821 -136.478772)
		(width 0.127)
		(layer "In2.Cu")
		(net "BMC_SELF_TRAY_R")
	)
	(via
		(at 55.144416 -202.284584)
		(size 0.7112)
		(drill 0.3556)
		(layers "F.Cu" "B.Cu")
		(net "BMC_SELF_TRAY")
	)
	(via
		(at 59.633358 -139.844526)
		(size 0.508)
		(drill 0.254)
		(layers "F.Cu" "B.Cu")
		(net "BMC_SELF_TRAY")
	)
	(via
		(at 55.626 -176.276)
		(size 0.508)
		(drill 0.254)
		(layers "F.Cu" "B.Cu")
		(net "BMC_SELF_TRAY")
	)
	(segment
		(start 39.51605 -215.525858)
		(end 39.515796 -215.525604)
		(width 0.12065)
		(layer "B.Cu")
		(net "BMC_SELF_TRAY")
	)
	(segment
		(start 39.515796 -215.525604)
		(end 39.515796 -212.508084)
		(width 0.12065)
		(layer "B.Cu")
		(net "BMC_SELF_TRAY")
	)
	(segment
		(start 39.51605 -223.593914)
		(end 39.51605 -215.525858)
		(width 0.12065)
		(layer "B.Cu")
		(net "BMC_SELF_TRAY")
	)
	(segment
		(start 39.7002 -225.92538)
		(end 39.7002 -223.778064)
		(width 0.12065)
		(layer "B.Cu")
		(net "BMC_SELF_TRAY")
	)
	(segment
		(start 52.959 -204.47)
		(end 55.144416 -202.284584)
		(width 0.12065)
		(layer "B.Cu")
		(net "BMC_SELF_TRAY")
	)
	(segment
		(start 56.2991 -176.9491)
		(end 56.2991 -201.1299)
		(width 0.12065)
		(layer "B.Cu")
		(net "BMC_SELF_TRAY")
	)
	(segment
		(start 39.515796 -212.508084)
		(end 47.55388 -204.47)
		(width 0.12065)
		(layer "B.Cu")
		(net "BMC_SELF_TRAY")
	)
	(segment
		(start 59.633358 -139.844526)
		(end 59.615832 -139.827)
		(width 0.12065)
		(layer "B.Cu")
		(net "BMC_SELF_TRAY")
	)
	(segment
		(start 55.626 -176.276)
		(end 56.2991 -176.9491)
		(width 0.12065)
		(layer "B.Cu")
		(net "BMC_SELF_TRAY")
	)
	(segment
		(start 57.4675 -139.827)
		(end 57.4675 -140.843)
		(width 0.12065)
		(layer "B.Cu")
		(net "BMC_SELF_TRAY")
	)
	(segment
		(start 56.2991 -201.1299)
		(end 55.144416 -202.284584)
		(width 0.12065)
		(layer "B.Cu")
		(net "BMC_SELF_TRAY")
	)
	(segment
		(start 47.55388 -204.47)
		(end 52.959 -204.47)
		(width 0.12065)
		(layer "B.Cu")
		(net "BMC_SELF_TRAY")
	)
	(segment
		(start 39.7002 -223.778064)
		(end 39.51605 -223.593914)
		(width 0.12065)
		(layer "B.Cu")
		(net "BMC_SELF_TRAY")
	)
	(segment
		(start 59.615832 -139.827)
		(end 57.4675 -139.827)
		(width 0.12065)
		(layer "B.Cu")
		(net "BMC_SELF_TRAY")
	)
	(segment
		(start 57.15254 -171.54779)
		(end 57.15254 -171.517056)
		(width 0.127)
		(layer "In5.Cu")
		(net "BMC_SELF_TRAY")
	)
	(segment
		(start 59.634882 -145.521934)
		(end 59.633358 -141.295628)
		(width 0.127)
		(layer "In5.Cu")
		(net "BMC_SELF_TRAY")
	)
	(segment
		(start 57.15254 -171.517056)
		(end 57.213246 -171.45635)
		(width 0.127)
		(layer "In5.Cu")
		(net "BMC_SELF_TRAY")
	)
	(segment
		(start 55.626 -173.07433)
		(end 57.15254 -171.54779)
		(width 0.127)
		(layer "In5.Cu")
		(net "BMC_SELF_TRAY")
	)
	(segment
		(start 57.213246 -148.234908)
		(end 59.634882 -145.813272)
		(width 0.127)
		(layer "In5.Cu")
		(net "BMC_SELF_TRAY")
	)
	(segment
		(start 59.634882 -145.813272)
		(end 59.634882 -145.521934)
		(width 0.127)
		(layer "In5.Cu")
		(net "BMC_SELF_TRAY")
	)
	(segment
		(start 59.633358 -141.295628)
		(end 59.633358 -139.844526)
		(width 0.127)
		(layer "In5.Cu")
		(net "BMC_SELF_TRAY")
	)
	(segment
		(start 57.213246 -171.45635)
		(end 57.213246 -148.234908)
		(width 0.127)
		(layer "In5.Cu")
		(net "BMC_SELF_TRAY")
	)
	(segment
		(start 55.626 -176.276)
		(end 55.626 -173.07433)
		(width 0.127)
		(layer "In5.Cu")
		(net "BMC_SELF_TRAY")
	)
	(segment
		(start 72.1868 -121.1834)
		(end 71.9836 -121.3866)
		(width 0.12065)
		(layer "F.Cu")
		(net "BMC_RXD5_R")
	)
	(segment
		(start 51.4858 -125.8316)
		(end 50.730912 -125.076712)
		(width 0.12065)
		(layer "F.Cu")
		(net "BMC_RXD5_R")
	)
	(segment
		(start 51.4858 -125.8316)
		(end 51.816 -125.5014)
		(width 0.12065)
		(layer "F.Cu")
		(net "BMC_RXD5_R")
	)
	(segment
		(start 52.343304 -124.97435)
		(end 53.90007 -124.97435)
		(width 0.12065)
		(layer "F.Cu")
		(net "BMC_RXD5_R")
	)
	(segment
		(start 72.71766 -120.5357)
		(end 72.9234 -120.74144)
		(width 0.12065)
		(layer "F.Cu")
		(net "BMC_RXD5_R")
	)
	(segment
		(start 72.1868 -120.5357)
		(end 72.71766 -120.5357)
		(width 0.12065)
		(layer "F.Cu")
		(net "BMC_RXD5_R")
	)
	(segment
		(start 53.90007 -124.97435)
		(end 53.928772 -124.945648)
		(width 0.12065)
		(layer "F.Cu")
		(net "BMC_RXD5_R")
	)
	(segment
		(start 53.928772 -124.945648)
		(end 54.663594 -124.945648)
		(width 0.12065)
		(layer "F.Cu")
		(net "BMC_RXD5_R")
	)
	(segment
		(start 54.860952 -124.74829)
		(end 54.860952 -124.170948)
		(width 0.12065)
		(layer "F.Cu")
		(net "BMC_RXD5_R")
	)
	(segment
		(start 72.1868 -120.5357)
		(end 72.1868 -121.1834)
		(width 0.12065)
		(layer "F.Cu")
		(net "BMC_RXD5_R")
	)
	(segment
		(start 73.914508 -122.8471)
		(end 73.914508 -121.43994)
		(width 0.12065)
		(layer "F.Cu")
		(net "BMC_RXD5_R")
	)
	(segment
		(start 73.917048 -121.4374)
		(end 73.917048 -120.74144)
		(width 0.12065)
		(layer "F.Cu")
		(net "BMC_RXD5_R")
	)
	(segment
		(start 49.834292 -124.67463)
		(end 47.623984 -126.884938)
		(width 0.12065)
		(layer "F.Cu")
		(net "BMC_RXD5_R")
	)
	(segment
		(start 54.860952 -124.170948)
		(end 55.4355 -123.5964)
		(width 0.12065)
		(layer "F.Cu")
		(net "BMC_RXD5_R")
	)
	(segment
		(start 50.472086 -125.076712)
		(end 50.070004 -124.67463)
		(width 0.12065)
		(layer "F.Cu")
		(net "BMC_RXD5_R")
	)
	(segment
		(start 73.914508 -121.43994)
		(end 73.917048 -121.4374)
		(width 0.12065)
		(layer "F.Cu")
		(net "BMC_RXD5_R")
	)
	(segment
		(start 50.730912 -125.076712)
		(end 50.472086 -125.076712)
		(width 0.12065)
		(layer "F.Cu")
		(net "BMC_RXD5_R")
	)
	(segment
		(start 50.070004 -124.67463)
		(end 49.834292 -124.67463)
		(width 0.12065)
		(layer "F.Cu")
		(net "BMC_RXD5_R")
	)
	(segment
		(start 47.623984 -126.884938)
		(end 46.50486 -126.884938)
		(width 0.12065)
		(layer "F.Cu")
		(net "BMC_RXD5_R")
	)
	(segment
		(start 51.816 -125.5014)
		(end 51.816254 -125.5014)
		(width 0.12065)
		(layer "F.Cu")
		(net "BMC_RXD5_R")
	)
	(segment
		(start 51.816254 -125.5014)
		(end 52.343304 -124.97435)
		(width 0.12065)
		(layer "F.Cu")
		(net "BMC_RXD5_R")
	)
	(segment
		(start 72.9234 -120.74144)
		(end 73.917048 -120.74144)
		(width 0.12065)
		(layer "F.Cu")
		(net "BMC_RXD5_R")
	)
	(segment
		(start 54.663594 -124.945648)
		(end 54.860952 -124.74829)
		(width 0.12065)
		(layer "F.Cu")
		(net "BMC_RXD5_R")
	)
	(via
		(at 71.9836 -121.3866)
		(size 0.508)
		(drill 0.254)
		(layers "F.Cu" "B.Cu")
		(net "BMC_RXD5_R")
	)
	(via
		(at 51.4858 -125.8316)
		(size 0.508)
		(drill 0.254)
		(layers "F.Cu" "B.Cu")
		(net "BMC_RXD5_R")
	)
	(via
		(at 50.070004 -124.67463)
		(size 0.7112)
		(drill 0.3556)
		(layers "F.Cu" "B.Cu")
		(net "BMC_RXD5_R")
	)
	(segment
		(start 63.4492 -124.8156)
		(end 62.5094 -124.8156)
		(width 0.127)
		(layer "In2.Cu")
		(net "BMC_RXD5_R")
	)
	(segment
		(start 62.5094 -124.8156)
		(end 59.5376 -121.8438)
		(width 0.127)
		(layer "In2.Cu")
		(net "BMC_RXD5_R")
	)
	(segment
		(start 65.377568 -124.9299)
		(end 63.5635 -124.9299)
		(width 0.127)
		(layer "In2.Cu")
		(net "BMC_RXD5_R")
	)
	(segment
		(start 53.039518 -121.751344)
		(end 52.997862 -121.793)
		(width 0.127)
		(layer "In2.Cu")
		(net "BMC_RXD5_R")
	)
	(segment
		(start 52.997862 -121.793)
		(end 52.31257 -121.793)
		(width 0.127)
		(layer "In2.Cu")
		(net "BMC_RXD5_R")
	)
	(segment
		(start 63.5635 -124.9299)
		(end 63.4492 -124.8156)
		(width 0.127)
		(layer "In2.Cu")
		(net "BMC_RXD5_R")
	)
	(segment
		(start 56.099964 -121.8438)
		(end 56.007508 -121.751344)
		(width 0.127)
		(layer "In2.Cu")
		(net "BMC_RXD5_R")
	)
	(segment
		(start 51.2318 -122.87377)
		(end 51.2318 -123.7996)
		(width 0.127)
		(layer "In2.Cu")
		(net "BMC_RXD5_R")
	)
	(segment
		(start 51.4858 -125.3617)
		(end 51.4858 -125.8316)
		(width 0.127)
		(layer "In2.Cu")
		(net "BMC_RXD5_R")
	)
	(segment
		(start 51.2318 -123.7996)
		(end 51.6509 -124.2187)
		(width 0.127)
		(layer "In2.Cu")
		(net "BMC_RXD5_R")
	)
	(segment
		(start 71.703946 -121.666)
		(end 68.641468 -121.666)
		(width 0.127)
		(layer "In2.Cu")
		(net "BMC_RXD5_R")
	)
	(segment
		(start 59.5376 -121.8438)
		(end 56.099964 -121.8438)
		(width 0.127)
		(layer "In2.Cu")
		(net "BMC_RXD5_R")
	)
	(segment
		(start 51.6509 -124.2187)
		(end 51.6509 -125.1966)
		(width 0.127)
		(layer "In2.Cu")
		(net "BMC_RXD5_R")
	)
	(segment
		(start 51.6509 -125.1966)
		(end 51.4858 -125.3617)
		(width 0.127)
		(layer "In2.Cu")
		(net "BMC_RXD5_R")
	)
	(segment
		(start 68.641468 -121.666)
		(end 65.377568 -124.9299)
		(width 0.127)
		(layer "In2.Cu")
		(net "BMC_RXD5_R")
	)
	(segment
		(start 52.31257 -121.793)
		(end 51.2318 -122.87377)
		(width 0.127)
		(layer "In2.Cu")
		(net "BMC_RXD5_R")
	)
	(segment
		(start 71.9836 -121.3866)
		(end 71.703946 -121.666)
		(width 0.127)
		(layer "In2.Cu")
		(net "BMC_RXD5_R")
	)
	(segment
		(start 56.007508 -121.751344)
		(end 53.039518 -121.751344)
		(width 0.127)
		(layer "In2.Cu")
		(net "BMC_RXD5_R")
	)
	(segment
		(start 50.94224 -73.496424)
		(end 50.92954 -73.483724)
		(width 0.12065)
		(layer "F.Cu")
		(net "BMC_RXD5")
	)
	(segment
		(start 73.872852 -127.4064)
		(end 74.4728 -127.4064)
		(width 0.12065)
		(layer "F.Cu")
		(net "BMC_RXD5")
	)
	(segment
		(start 75.184 -126.6952)
		(end 75.184 -126.365)
		(width 0.12065)
		(layer "F.Cu")
		(net "BMC_RXD5")
	)
	(segment
		(start 54.5846 -79.248)
		(end 50.92954 -75.59294)
		(width 0.12065)
		(layer "F.Cu")
		(net "BMC_RXD5")
	)
	(segment
		(start 50.94224 -73.950576)
		(end 50.94224 -73.496424)
		(width 0.12065)
		(layer "F.Cu")
		(net "BMC_RXD5")
	)
	(segment
		(start 74.4728 -127.4064)
		(end 75.184 -126.6952)
		(width 0.12065)
		(layer "F.Cu")
		(net "BMC_RXD5")
	)
	(segment
		(start 56.3245 -123.8885)
		(end 55.8038 -124.4092)
		(width 0.12065)
		(layer "F.Cu")
		(net "BMC_RXD5")
	)
	(segment
		(start 55.598568 -88.52154)
		(end 54.5846 -87.507572)
		(width 0.12065)
		(layer "F.Cu")
		(net "BMC_RXD5")
	)
	(segment
		(start 65.659 -97.028508)
		(end 57.152032 -88.52154)
		(width 0.12065)
		(layer "F.Cu")
		(net "BMC_RXD5")
	)
	(segment
		(start 57.152032 -88.52154)
		(end 55.598568 -88.52154)
		(width 0.12065)
		(layer "F.Cu")
		(net "BMC_RXD5")
	)
	(segment
		(start 225.8441 -0.13462)
		(end 224.74682 -0.13462)
		(width 0.12065)
		(layer "F.Cu")
		(net "BMC_RXD5")
	)
	(segment
		(start 54.5846 -87.507572)
		(end 54.5846 -79.248)
		(width 0.12065)
		(layer "F.Cu")
		(net "BMC_RXD5")
	)
	(segment
		(start 74.564748 -125.745748)
		(end 75.184 -126.365)
		(width 0.12065)
		(layer "F.Cu")
		(net "BMC_RXD5")
	)
	(segment
		(start 50.92954 -75.59294)
		(end 50.92954 -73.963276)
		(width 0.12065)
		(layer "F.Cu")
		(net "BMC_RXD5")
	)
	(segment
		(start 224.74682 -0.13462)
		(end 224.4852 0.127)
		(width 0.12065)
		(layer "F.Cu")
		(net "BMC_RXD5")
	)
	(segment
		(start 74.564748 -124.4981)
		(end 74.564748 -125.745748)
		(width 0.12065)
		(layer "F.Cu")
		(net "BMC_RXD5")
	)
	(segment
		(start 56.3245 -123.5964)
		(end 56.3245 -123.8885)
		(width 0.12065)
		(layer "F.Cu")
		(net "BMC_RXD5")
	)
	(segment
		(start 65.659 -99.3648)
		(end 65.659 -97.028508)
		(width 0.12065)
		(layer "F.Cu")
		(net "BMC_RXD5")
	)
	(segment
		(start 50.92954 -73.963276)
		(end 50.94224 -73.950576)
		(width 0.12065)
		(layer "F.Cu")
		(net "BMC_RXD5")
	)
	(via
		(at 65.659 -99.3648)
		(size 0.508)
		(drill 0.254)
		(layers "F.Cu" "B.Cu")
		(net "BMC_RXD5")
	)
	(via
		(at 73.872852 -127.4064)
		(size 0.508)
		(drill 0.254)
		(layers "F.Cu" "B.Cu")
		(net "BMC_RXD5")
	)
	(via
		(at 224.4852 0.127)
		(size 0.508)
		(drill 0.254)
		(layers "F.Cu" "B.Cu")
		(net "BMC_RXD5")
	)
	(via
		(at 75.184 -126.365)
		(size 0.7112)
		(drill 0.3556)
		(layers "F.Cu" "B.Cu")
		(net "BMC_RXD5")
	)
	(via
		(at 95.6564 -66.3829)
		(size 0.508)
		(drill 0.254)
		(layers "F.Cu" "B.Cu")
		(net "BMC_RXD5")
	)
	(via
		(at 55.8038 -124.4092)
		(size 0.508)
		(drill 0.254)
		(layers "F.Cu" "B.Cu")
		(net "BMC_RXD5")
	)
	(segment
		(start 73.406 -126.939548)
		(end 73.872852 -127.4064)
		(width 0.12065)
		(layer "B.Cu")
		(net "BMC_RXD5")
	)
	(segment
		(start 73.406 -122.8852)
		(end 73.406 -126.939548)
		(width 0.12065)
		(layer "B.Cu")
		(net "BMC_RXD5")
	)
	(segment
		(start 73.674732 -127.4064)
		(end 71.311008 -129.770124)
		(width 0.12065)
		(layer "B.Cu")
		(net "BMC_RXD5")
	)
	(segment
		(start 72.517 -119.6594)
		(end 72.517 -121.9962)
		(width 0.12065)
		(layer "B.Cu")
		(net "BMC_RXD5")
	)
	(segment
		(start 65.659 -99.3648)
		(end 70.5358 -104.2416)
		(width 0.12065)
		(layer "B.Cu")
		(net "BMC_RXD5")
	)
	(segment
		(start 70.5358 -104.2416)
		(end 70.5358 -117.6782)
		(width 0.12065)
		(layer "B.Cu")
		(net "BMC_RXD5")
	)
	(segment
		(start 57.6834 -124.4092)
		(end 55.8038 -124.4092)
		(width 0.12065)
		(layer "B.Cu")
		(net "BMC_RXD5")
	)
	(segment
		(start 72.517 -121.9962)
		(end 73.406 -122.8852)
		(width 0.12065)
		(layer "B.Cu")
		(net "BMC_RXD5")
	)
	(segment
		(start 70.5358 -117.6782)
		(end 72.517 -119.6594)
		(width 0.12065)
		(layer "B.Cu")
		(net "BMC_RXD5")
	)
	(segment
		(start 73.872852 -127.4064)
		(end 73.674732 -127.4064)
		(width 0.12065)
		(layer "B.Cu")
		(net "BMC_RXD5")
	)
	(segment
		(start 71.311008 -129.770124)
		(end 71.116952 -129.770124)
		(width 0.12065)
		(layer "B.Cu")
		(net "BMC_RXD5")
	)
	(segment
		(start 71.116952 -129.770124)
		(end 70.256908 -130.630168)
		(width 0.12065)
		(layer "B.Cu")
		(net "BMC_RXD5")
	)
	(segment
		(start 60.988956 -127.714756)
		(end 57.6834 -124.4092)
		(width 0.12065)
		(layer "B.Cu")
		(net "BMC_RXD5")
	)
	(segment
		(start 61.540644 -127.714756)
		(end 60.988956 -127.714756)
		(width 0.12065)
		(layer "B.Cu")
		(net "BMC_RXD5")
	)
	(segment
		(start 70.256908 -130.630168)
		(end 64.456056 -130.630168)
		(width 0.12065)
		(layer "B.Cu")
		(net "BMC_RXD5")
	)
	(segment
		(start 64.456056 -130.630168)
		(end 61.540644 -127.714756)
		(width 0.12065)
		(layer "B.Cu")
		(net "BMC_RXD5")
	)
	(segment
		(start 222.610426 2.551938)
		(end 205.374748 2.551938)
		(width 0.127)
		(layer "In2.Cu")
		(net "BMC_RXD5")
	)
	(segment
		(start 93.84919 -50.328322)
		(end 95.6564 -52.135532)
		(width 0.127)
		(layer "In2.Cu")
		(net "BMC_RXD5")
	)
	(segment
		(start 184.32907 1.50749)
		(end 129.729484 1.50749)
		(width 0.127)
		(layer "In2.Cu")
		(net "BMC_RXD5")
	)
	(segment
		(start 184.48655 1.35001)
		(end 184.32907 1.50749)
		(width 0.127)
		(layer "In2.Cu")
		(net "BMC_RXD5")
	)
	(segment
		(start 198.553832 0.048768)
		(end 189.137798 0.048768)
		(width 0.127)
		(layer "In2.Cu")
		(net "BMC_RXD5")
	)
	(segment
		(start 95.6564 -52.135532)
		(end 95.6564 -66.3829)
		(width 0.127)
		(layer "In2.Cu")
		(net "BMC_RXD5")
	)
	(segment
		(start 129.729484 1.50749)
		(end 121.450608 -6.771386)
		(width 0.127)
		(layer "In2.Cu")
		(net "BMC_RXD5")
	)
	(segment
		(start 224.4852 0.677164)
		(end 222.610426 2.551938)
		(width 0.127)
		(layer "In2.Cu")
		(net "BMC_RXD5")
	)
	(segment
		(start 205.374748 2.551938)
		(end 202.09891 -0.7239)
		(width 0.127)
		(layer "In2.Cu")
		(net "BMC_RXD5")
	)
	(segment
		(start 189.137798 0.048768)
		(end 187.836556 1.35001)
		(width 0.127)
		(layer "In2.Cu")
		(net "BMC_RXD5")
	)
	(segment
		(start 120.534176 -6.771386)
		(end 93.84919 -33.456372)
		(width 0.127)
		(layer "In2.Cu")
		(net "BMC_RXD5")
	)
	(segment
		(start 93.84919 -33.456372)
		(end 93.84919 -50.328322)
		(width 0.127)
		(layer "In2.Cu")
		(net "BMC_RXD5")
	)
	(segment
		(start 187.836556 1.35001)
		(end 184.48655 1.35001)
		(width 0.127)
		(layer "In2.Cu")
		(net "BMC_RXD5")
	)
	(segment
		(start 121.450608 -6.771386)
		(end 120.534176 -6.771386)
		(width 0.127)
		(layer "In2.Cu")
		(net "BMC_RXD5")
	)
	(segment
		(start 224.4852 0.127)
		(end 224.4852 0.677164)
		(width 0.127)
		(layer "In2.Cu")
		(net "BMC_RXD5")
	)
	(segment
		(start 199.3265 -0.7239)
		(end 198.553832 0.048768)
		(width 0.127)
		(layer "In2.Cu")
		(net "BMC_RXD5")
	)
	(segment
		(start 202.09891 -0.7239)
		(end 199.3265 -0.7239)
		(width 0.127)
		(layer "In2.Cu")
		(net "BMC_RXD5")
	)
	(segment
		(start 65.4812 -95.377)
		(end 65.4812 -99.187)
		(width 0.127)
		(layer "In5.Cu")
		(net "BMC_RXD5")
	)
	(segment
		(start 95.6564 -66.3829)
		(end 75.352402 -66.3829)
		(width 0.127)
		(layer "In5.Cu")
		(net "BMC_RXD5")
	)
	(segment
		(start 64.26454 -77.470762)
		(end 64.26454 -94.16034)
		(width 0.127)
		(layer "In5.Cu")
		(net "BMC_RXD5")
	)
	(segment
		(start 75.352402 -66.3829)
		(end 64.26454 -77.470762)
		(width 0.127)
		(layer "In5.Cu")
		(net "BMC_RXD5")
	)
	(segment
		(start 65.4812 -99.187)
		(end 65.659 -99.3648)
		(width 0.127)
		(layer "In5.Cu")
		(net "BMC_RXD5")
	)
	(segment
		(start 64.26454 -94.16034)
		(end 65.4812 -95.377)
		(width 0.127)
		(layer "In5.Cu")
		(net "BMC_RXD5")
	)
	(segment
		(start 38.504876 -125.284992)
		(end 38.10508 -124.885196)
		(width 0.12065)
		(layer "F.Cu")
		(net "BMC_RXCK_R")
	)
	(via
		(at 38.10508 -124.885196)
		(size 0.4572)
		(drill 0.2032)
		(layers "F.Cu" "B.Cu")
		(net "BMC_RXCK_R")
	)
	(via
		(at 37.058854 -112.080548)
		(size 0.508)
		(drill 0.254)
		(layers "F.Cu" "B.Cu")
		(net "BMC_RXCK_R")
	)
	(via
		(at 38.1254 -125.6538)
		(size 0.7112)
		(drill 0.3556)
		(layers "F.Cu" "B.Cu")
		(net "BMC_RXCK_R")
	)
	(segment
		(start 36.219384 -109.319314)
		(end 36.219384 -111.018574)
		(width 0.12065)
		(layer "B.Cu")
		(net "BMC_RXCK_R")
	)
	(segment
		(start 37.058854 -111.858044)
		(end 37.058854 -112.080548)
		(width 0.12065)
		(layer "B.Cu")
		(net "BMC_RXCK_R")
	)
	(segment
		(start 36.219384 -111.018574)
		(end 37.058854 -111.858044)
		(width 0.12065)
		(layer "B.Cu")
		(net "BMC_RXCK_R")
	)
	(segment
		(start 38.1254 -124.905516)
		(end 38.1254 -125.6538)
		(width 0.12065)
		(layer "B.Cu")
		(net "BMC_RXCK_R")
	)
	(segment
		(start 38.10508 -124.885196)
		(end 38.1254 -124.905516)
		(width 0.12065)
		(layer "B.Cu")
		(net "BMC_RXCK_R")
	)
	(segment
		(start 38.49878 -124.491496)
		(end 38.10508 -124.885196)
		(width 0.127)
		(layer "In2.Cu")
		(net "BMC_RXCK_R")
	)
	(segment
		(start 37.058854 -112.080548)
		(end 37.59581 -112.617504)
		(width 0.127)
		(layer "In2.Cu")
		(net "BMC_RXCK_R")
	)
	(segment
		(start 38.49878 -115.853464)
		(end 38.49878 -124.491496)
		(width 0.127)
		(layer "In2.Cu")
		(net "BMC_RXCK_R")
	)
	(segment
		(start 37.588952 -113.20018)
		(end 37.588952 -114.943636)
		(width 0.127)
		(layer "In2.Cu")
		(net "BMC_RXCK_R")
	)
	(segment
		(start 37.59581 -112.617504)
		(end 37.59581 -113.193322)
		(width 0.127)
		(layer "In2.Cu")
		(net "BMC_RXCK_R")
	)
	(segment
		(start 37.588952 -114.943636)
		(end 38.49878 -115.853464)
		(width 0.127)
		(layer "In2.Cu")
		(net "BMC_RXCK_R")
	)
	(segment
		(start 37.59581 -113.193322)
		(end 37.588952 -113.20018)
		(width 0.127)
		(layer "In2.Cu")
		(net "BMC_RXCK_R")
	)
	(segment
		(start 49.29251 -73.533254)
		(end 49.2506 -73.491344)
		(width 0.12065)
		(layer "F.Cu")
		(net "BMC_R_TXD5")
	)
	(segment
		(start 49.2506 -73.491344)
		(end 49.2506 -69.690488)
		(width 0.12065)
		(layer "F.Cu")
		(net "BMC_R_TXD5")
	)
	(segment
		(start 51.81854 -73.483724)
		(end 51.81854 -69.718428)
		(width 0.12065)
		(layer "F.Cu")
		(net "BMC_R_RXD5")
	)
	(segment
		(start 51.81854 -69.718428)
		(end 51.7906 -69.690488)
		(width 0.12065)
		(layer "F.Cu")
		(net "BMC_R_RXD5")
	)
	(segment
		(start 27.46756 -123.319286)
		(end 26.790904 -122.90933)
		(width 0.136652)
		(layer "F.Cu")
		(net "BMC_PETXP")
	)
	(segment
		(start 21.747988 -115.010438)
		(end 21.85162 -114.906806)
		(width 0.136652)
		(layer "F.Cu")
		(net "BMC_PETXP")
	)
	(segment
		(start 29.50464 -125.212094)
		(end 28.135326 -123.84278)
		(width 0.136652)
		(layer "F.Cu")
		(net "BMC_PETXP")
	)
	(segment
		(start 20.789138 -116.48694)
		(end 21.747988 -115.010438)
		(width 0.136652)
		(layer "F.Cu")
		(net "BMC_PETXP")
	)
	(segment
		(start 21.164296 -120.96115)
		(end 20.697444 -120.24233)
		(width 0.136652)
		(layer "F.Cu")
		(net "BMC_PETXP")
	)
	(segment
		(start 22.66569 -122.086116)
		(end 21.59127 -121.388124)
		(width 0.136652)
		(layer "F.Cu")
		(net "BMC_PETXP")
	)
	(segment
		(start 22.94763 -114.89563)
		(end 23.1648 -115.1128)
		(width 0.136652)
		(layer "F.Cu")
		(net "BMC_PETXP")
	)
	(segment
		(start 24.997918 -122.1994)
		(end 23.04796 -122.1994)
		(width 0.136652)
		(layer "F.Cu")
		(net "BMC_PETXP")
	)
	(segment
		(start 20.508214 -119.785638)
		(end 20.303236 -118.820438)
		(width 0.136652)
		(layer "F.Cu")
		(net "BMC_PETXP")
	)
	(segment
		(start 20.303236 -118.386098)
		(end 20.61972 -116.89588)
		(width 0.136652)
		(layer "F.Cu")
		(net "BMC_PETXP")
	)
	(segment
		(start 22.377146 -114.71783)
		(end 22.581362 -114.71783)
		(width 0.136652)
		(layer "F.Cu")
		(net "BMC_PETXP")
	)
	(segment
		(start 22.692868 -114.739928)
		(end 22.75078 -114.764058)
		(width 0.136652)
		(layer "F.Cu")
		(net "BMC_PETXP")
	)
	(segment
		(start 26.790904 -122.90933)
		(end 24.997918 -122.1994)
		(width 0.136652)
		(layer "F.Cu")
		(net "BMC_PETXP")
	)
	(via
		(at 23.1648 -115.1128)
		(size 0.508)
		(drill 0.254)
		(layers "F.Cu" "B.Cu")
		(net "BMC_PETXP")
	)
	(via
		(at 203.7588 -49.784)
		(size 0.508)
		(drill 0.254)
		(layers "F.Cu" "B.Cu")
		(net "BMC_PETXP")
	)
	(arc
		(start 23.04796 -122.1994)
		(mid 22.84861 -122.170481)
		(end 22.66569 -122.086116)
		(width 0.136652)
		(layer "F.Cu")
		(net "BMC_PETXP")
	)
	(arc
		(start 21.85162 -114.906806)
		(mid 21.857556 -114.901289)
		(end 21.863812 -114.896138)
		(width 0.136652)
		(layer "F.Cu")
		(net "BMC_PETXP")
	)
	(arc
		(start 21.863812 -114.896138)
		(mid 21.926381 -114.851348)
		(end 21.992844 -114.812572)
		(width 0.136652)
		(layer "F.Cu")
		(net "BMC_PETXP")
	)
	(arc
		(start 21.59127 -121.388124)
		(mid 21.355352 -121.197068)
		(end 21.164296 -120.96115)
		(width 0.136652)
		(layer "F.Cu")
		(net "BMC_PETXP")
	)
	(arc
		(start 29.687774 -125.284484)
		(mid 29.589307 -125.265737)
		(end 29.50464 -125.212094)
		(width 0.136652)
		(layer "F.Cu")
		(net "BMC_PETXP")
	)
	(arc
		(start 20.697444 -120.24233)
		(mid 20.581839 -120.02268)
		(end 20.508214 -119.785638)
		(width 0.136652)
		(layer "F.Cu")
		(net "BMC_PETXP")
	)
	(arc
		(start 22.581362 -114.71783)
		(mid 22.638206 -114.723379)
		(end 22.692868 -114.739928)
		(width 0.136652)
		(layer "F.Cu")
		(net "BMC_PETXP")
	)
	(arc
		(start 20.303236 -118.820438)
		(mid 20.280425 -118.603268)
		(end 20.303236 -118.386098)
		(width 0.136652)
		(layer "F.Cu")
		(net "BMC_PETXP")
	)
	(arc
		(start 20.61972 -116.89588)
		(mid 20.685636 -116.683624)
		(end 20.789138 -116.48694)
		(width 0.136652)
		(layer "F.Cu")
		(net "BMC_PETXP")
	)
	(arc
		(start 28.135326 -123.84278)
		(mid 27.817227 -123.560899)
		(end 27.46756 -123.319286)
		(width 0.136652)
		(layer "F.Cu")
		(net "BMC_PETXP")
	)
	(arc
		(start 22.75078 -114.764058)
		(mid 22.855674 -114.820164)
		(end 22.94763 -114.89563)
		(width 0.136652)
		(layer "F.Cu")
		(net "BMC_PETXP")
	)
	(arc
		(start 21.992844 -114.812572)
		(mid 22.179406 -114.742541)
		(end 22.377146 -114.71783)
		(width 0.136652)
		(layer "F.Cu")
		(net "BMC_PETXP")
	)
	(arc
		(start 29.704792 -125.284992)
		(mid 29.69628 -125.284853)
		(end 29.687774 -125.284484)
		(width 0.136652)
		(layer "F.Cu")
		(net "BMC_PETXP")
	)
	(segment
		(start 209.998564 -45.3517)
		(end 210.382866 -45.3517)
		(width 0.136652)
		(layer "B.Cu")
		(net "BMC_PETXP")
	)
	(segment
		(start 206.397352 -46.491144)
		(end 209.998564 -45.3517)
		(width 0.136652)
		(layer "B.Cu")
		(net "BMC_PETXP")
	)
	(segment
		(start 205.020672 -47.460662)
		(end 205.730094 -46.963838)
		(width 0.136652)
		(layer "B.Cu")
		(net "BMC_PETXP")
	)
	(segment
		(start 203.5048 -49.170844)
		(end 203.5048 -48.89246)
		(width 0.136652)
		(layer "B.Cu")
		(net "BMC_PETXP")
	)
	(segment
		(start 206.387192 -46.501304)
		(end 206.397352 -46.491144)
		(width 0.136652)
		(layer "B.Cu")
		(net "BMC_PETXP")
	)
	(segment
		(start 203.6826 -48.4632)
		(end 203.902056 -48.243744)
		(width 0.136652)
		(layer "B.Cu")
		(net "BMC_PETXP")
	)
	(segment
		(start 205.730094 -46.963838)
		(end 206.368396 -46.517306)
		(width 0.136652)
		(layer "B.Cu")
		(net "BMC_PETXP")
	)
	(segment
		(start 203.902056 -48.243744)
		(end 205.020672 -47.460662)
		(width 0.136652)
		(layer "B.Cu")
		(net "BMC_PETXP")
	)
	(arc
		(start 210.382866 -45.3517)
		(mid 210.651055 -45.431124)
		(end 210.8327 -45.6438)
		(width 0.136652)
		(layer "B.Cu")
		(net "BMC_PETXP")
	)
	(arc
		(start 203.7588 -49.784)
		(mid 203.570829 -49.502682)
		(end 203.5048 -49.170844)
		(width 0.136652)
		(layer "B.Cu")
		(net "BMC_PETXP")
	)
	(arc
		(start 206.368396 -46.517306)
		(mid 206.378156 -46.50973)
		(end 206.387192 -46.501304)
		(width 0.136652)
		(layer "B.Cu")
		(net "BMC_PETXP")
	)
	(arc
		(start 203.5048 -48.89246)
		(mid 203.55101 -48.660148)
		(end 203.6826 -48.4632)
		(width 0.136652)
		(layer "B.Cu")
		(net "BMC_PETXP")
	)
	(segment
		(start 42.226738 -104.465374)
		(end 42.629074 -104.379776)
		(width 0.1397)
		(layer "In2.Cu")
		(net "BMC_PETXP")
	)
	(segment
		(start 142.855696 -103.96601)
		(end 147.872196 -103.081582)
		(width 0.1397)
		(layer "In2.Cu")
		(net "BMC_PETXP")
	)
	(segment
		(start 158.002224 -104.86771)
		(end 158.154878 -105.085642)
		(width 0.1397)
		(layer "In2.Cu")
		(net "BMC_PETXP")
	)
	(segment
		(start 155.198064 -104.373426)
		(end 156.806646 -104.65689)
		(width 0.1397)
		(layer "In2.Cu")
		(net "BMC_PETXP")
	)
	(segment
		(start 153.784808 -104.315006)
		(end 154.002486 -104.162606)
		(width 0.1397)
		(layer "In2.Cu")
		(net "BMC_PETXP")
	)
	(segment
		(start 126.458726 -110.4646)
		(end 135.955278 -108.446062)
		(width 0.1397)
		(layer "In2.Cu")
		(net "BMC_PETXP")
	)
	(segment
		(start 44.158916 -103.55834)
		(end 45.295566 -102.82047)
		(width 0.1397)
		(layer "In2.Cu")
		(net "BMC_PETXP")
	)
	(segment
		(start 48.031146 -102.252018)
		(end 48.441356 -102.166674)
		(width 0.1397)
		(layer "In2.Cu")
		(net "BMC_PETXP")
	)
	(segment
		(start 135.955278 -108.446062)
		(end 142.855696 -103.96601)
		(width 0.1397)
		(layer "In2.Cu")
		(net "BMC_PETXP")
	)
	(segment
		(start 149.450552 -103.55072)
		(end 149.863302 -103.623618)
		(width 0.1397)
		(layer "In2.Cu")
		(net "BMC_PETXP")
	)
	(segment
		(start 166.783258 -105.42397)
		(end 168.230042 -105.168954)
		(width 0.1397)
		(layer "In2.Cu")
		(net "BMC_PETXP")
	)
	(segment
		(start 27.42184 -112.57661)
		(end 27.766518 -112.338358)
		(width 0.1397)
		(layer "In2.Cu")
		(net "BMC_PETXP")
	)
	(segment
		(start 39.892478 -103.969312)
		(end 42.226738 -104.465374)
		(width 0.1397)
		(layer "In2.Cu")
		(net "BMC_PETXP")
	)
	(segment
		(start 59.157108 -104.740456)
		(end 62.844934 -105.390188)
		(width 0.1397)
		(layer "In2.Cu")
		(net "BMC_PETXP")
	)
	(segment
		(start 196.089524 -55.584598)
		(end 201.269854 -51.957224)
		(width 0.1397)
		(layer "In2.Cu")
		(net "BMC_PETXP")
	)
	(segment
		(start 28.403804 -111.897922)
		(end 29.351478 -111.242602)
		(width 0.1397)
		(layer "In2.Cu")
		(net "BMC_PETXP")
	)
	(segment
		(start 43.022774 -104.29621)
		(end 44.158916 -103.55834)
		(width 0.1397)
		(layer "In2.Cu")
		(net "BMC_PETXP")
	)
	(segment
		(start 23.1648 -115.1128)
		(end 23.517606 -114.759994)
		(width 0.1397)
		(layer "In2.Cu")
		(net "BMC_PETXP")
	)
	(segment
		(start 170.331892 -104.798368)
		(end 172.505878 -104.415082)
		(width 0.1397)
		(layer "In2.Cu")
		(net "BMC_PETXP")
	)
	(segment
		(start 23.616412 -114.7191)
		(end 24.079454 -114.7191)
		(width 0.1397)
		(layer "In2.Cu")
		(net "BMC_PETXP")
	)
	(segment
		(start 29.351732 -111.242094)
		(end 29.352494 -111.241332)
		(width 0.1397)
		(layer "In2.Cu")
		(net "BMC_PETXP")
	)
	(segment
		(start 161.384742 -105.65511)
		(end 161.60242 -105.50271)
		(width 0.1397)
		(layer "In2.Cu")
		(net "BMC_PETXP")
	)
	(segment
		(start 117.405658 -110.197138)
		(end 121.302526 -109.36859)
		(width 0.1397)
		(layer "In2.Cu")
		(net "BMC_PETXP")
	)
	(segment
		(start 175.339502 -102.43058)
		(end 193.470276 -76.554584)
		(width 0.1397)
		(layer "In2.Cu")
		(net "BMC_PETXP")
	)
	(segment
		(start 159.980884 -105.216706)
		(end 160.819592 -105.364534)
		(width 0.1397)
		(layer "In2.Cu")
		(net "BMC_PETXP")
	)
	(segment
		(start 154.567636 -104.453182)
		(end 154.980386 -104.525826)
		(width 0.1397)
		(layer "In2.Cu")
		(net "BMC_PETXP")
	)
	(segment
		(start 159.350456 -105.296462)
		(end 159.763206 -105.369106)
		(width 0.1397)
		(layer "In2.Cu")
		(net "BMC_PETXP")
	)
	(segment
		(start 154.002486 -104.162606)
		(end 154.415236 -104.23525)
		(width 0.1397)
		(layer "In2.Cu")
		(net "BMC_PETXP")
	)
	(segment
		(start 158.785306 -105.005886)
		(end 159.198056 -105.07853)
		(width 0.1397)
		(layer "In2.Cu")
		(net "BMC_PETXP")
	)
	(segment
		(start 157.371796 -104.947466)
		(end 157.589474 -104.795066)
		(width 0.1397)
		(layer "In2.Cu")
		(net "BMC_PETXP")
	)
	(segment
		(start 47.48276 -102.547674)
		(end 47.893224 -102.46233)
		(width 0.1397)
		(layer "In2.Cu")
		(net "BMC_PETXP")
	)
	(segment
		(start 33.934146 -104.908858)
		(end 34.752788 -104.374442)
		(width 0.1397)
		(layer "In2.Cu")
		(net "BMC_PETXP")
	)
	(segment
		(start 156.959046 -104.874822)
		(end 157.371796 -104.947466)
		(width 0.1397)
		(layer "In2.Cu")
		(net "BMC_PETXP")
	)
	(segment
		(start 62.844934 -105.390188)
		(end 69.450966 -103.986584)
		(width 0.1397)
		(layer "In2.Cu")
		(net "BMC_PETXP")
	)
	(segment
		(start 158.567628 -105.158286)
		(end 158.785306 -105.005886)
		(width 0.1397)
		(layer "In2.Cu")
		(net "BMC_PETXP")
	)
	(segment
		(start 55.954422 -102.497382)
		(end 55.955184 -102.498144)
		(width 0.1397)
		(layer "In2.Cu")
		(net "BMC_PETXP")
	)
	(segment
		(start 48.441356 -102.166674)
		(end 48.651668 -102.304596)
		(width 0.1397)
		(layer "In2.Cu")
		(net "BMC_PETXP")
	)
	(segment
		(start 49.062132 -102.219506)
		(end 49.200054 -102.009194)
		(width 0.1397)
		(layer "In2.Cu")
		(net "BMC_PETXP")
	)
	(segment
		(start 154.415236 -104.23525)
		(end 154.567636 -104.453182)
		(width 0.1397)
		(layer "In2.Cu")
		(net "BMC_PETXP")
	)
	(segment
		(start 203.641198 -49.901348)
		(end 203.7588 -49.784)
		(width 0.1397)
		(layer "In2.Cu")
		(net "BMC_PETXP")
	)
	(segment
		(start 168.230042 -105.168954)
		(end 170.331892 -104.798368)
		(width 0.1397)
		(layer "In2.Cu")
		(net "BMC_PETXP")
	)
	(segment
		(start 45.295566 -102.82047)
		(end 47.272702 -102.409752)
		(width 0.1397)
		(layer "In2.Cu")
		(net "BMC_PETXP")
	)
	(segment
		(start 49.200054 -102.009194)
		(end 51.028092 -101.62921)
		(width 0.1397)
		(layer "In2.Cu")
		(net "BMC_PETXP")
	)
	(segment
		(start 203.5048 -50.502058)
		(end 203.5048 -50.23104)
		(width 0.1397)
		(layer "In2.Cu")
		(net "BMC_PETXP")
	)
	(segment
		(start 159.763206 -105.369106)
		(end 159.980884 -105.216706)
		(width 0.1397)
		(layer "In2.Cu")
		(net "BMC_PETXP")
	)
	(segment
		(start 151.689308 -103.754682)
		(end 153.219404 -104.02443)
		(width 0.1397)
		(layer "In2.Cu")
		(net "BMC_PETXP")
	)
	(segment
		(start 193.470276 -76.554584)
		(end 195.269104 -66.349118)
		(width 0.1397)
		(layer "In2.Cu")
		(net "BMC_PETXP")
	)
	(segment
		(start 194.275964 -60.715144)
		(end 194.87388 -57.319672)
		(width 0.1397)
		(layer "In2.Cu")
		(net "BMC_PETXP")
	)
	(segment
		(start 55.955184 -102.498144)
		(end 59.157108 -104.740456)
		(width 0.1397)
		(layer "In2.Cu")
		(net "BMC_PETXP")
	)
	(segment
		(start 195.269104 -66.349118)
		(end 194.275964 -60.715144)
		(width 0.1397)
		(layer "In2.Cu")
		(net "BMC_PETXP")
	)
	(segment
		(start 172.505878 -104.415082)
		(end 175.339502 -102.43058)
		(width 0.1397)
		(layer "In2.Cu")
		(net "BMC_PETXP")
	)
	(segment
		(start 160.819592 -105.364534)
		(end 160.971992 -105.582212)
		(width 0.1397)
		(layer "In2.Cu")
		(net "BMC_PETXP")
	)
	(segment
		(start 24.607012 -114.522758)
		(end 26.784554 -113.0173)
		(width 0.1397)
		(layer "In2.Cu")
		(net "BMC_PETXP")
	)
	(segment
		(start 150.08098 -103.470964)
		(end 150.90648 -103.616506)
		(width 0.1397)
		(layer "In2.Cu")
		(net "BMC_PETXP")
	)
	(segment
		(start 69.450966 -103.986584)
		(end 75.705716 -105.31602)
		(width 0.1397)
		(layer "In2.Cu")
		(net "BMC_PETXP")
	)
	(segment
		(start 47.893224 -102.46233)
		(end 48.031146 -102.252018)
		(width 0.1397)
		(layer "In2.Cu")
		(net "BMC_PETXP")
	)
	(segment
		(start 149.298152 -103.333042)
		(end 149.450552 -103.55072)
		(width 0.1397)
		(layer "In2.Cu")
		(net "BMC_PETXP")
	)
	(segment
		(start 121.302526 -109.36859)
		(end 126.458726 -110.4646)
		(width 0.1397)
		(layer "In2.Cu")
		(net "BMC_PETXP")
	)
	(segment
		(start 157.589474 -104.795066)
		(end 158.002224 -104.86771)
		(width 0.1397)
		(layer "In2.Cu")
		(net "BMC_PETXP")
	)
	(segment
		(start 29.351478 -111.242602)
		(end 29.351732 -111.242348)
		(width 0.1397)
		(layer "In2.Cu")
		(net "BMC_PETXP")
	)
	(segment
		(start 29.352494 -111.241332)
		(end 33.66135 -105.087166)
		(width 0.1397)
		(layer "In2.Cu")
		(net "BMC_PETXP")
	)
	(segment
		(start 29.351732 -111.242348)
		(end 29.351732 -111.242094)
		(width 0.1397)
		(layer "In2.Cu")
		(net "BMC_PETXP")
	)
	(segment
		(start 35.306 -104.25684)
		(end 36.922456 -104.600756)
		(width 0.1397)
		(layer "In2.Cu")
		(net "BMC_PETXP")
	)
	(segment
		(start 24.606758 -114.522758)
		(end 24.607012 -114.522758)
		(width 0.1397)
		(layer "In2.Cu")
		(net "BMC_PETXP")
	)
	(segment
		(start 159.198056 -105.07853)
		(end 159.350456 -105.296462)
		(width 0.1397)
		(layer "In2.Cu")
		(net "BMC_PETXP")
	)
	(segment
		(start 48.651668 -102.304596)
		(end 49.062132 -102.219506)
		(width 0.1397)
		(layer "In2.Cu")
		(net "BMC_PETXP")
	)
	(segment
		(start 160.971992 -105.582212)
		(end 161.384742 -105.65511)
		(width 0.1397)
		(layer "In2.Cu")
		(net "BMC_PETXP")
	)
	(segment
		(start 149.863302 -103.623618)
		(end 150.08098 -103.470964)
		(width 0.1397)
		(layer "In2.Cu")
		(net "BMC_PETXP")
	)
	(segment
		(start 27.376628 -112.824006)
		(end 27.42184 -112.57661)
		(width 0.1397)
		(layer "In2.Cu")
		(net "BMC_PETXP")
	)
	(segment
		(start 161.60242 -105.50271)
		(end 163.969192 -105.920032)
		(width 0.1397)
		(layer "In2.Cu")
		(net "BMC_PETXP")
	)
	(segment
		(start 87.366348 -104.90073)
		(end 117.405658 -110.197138)
		(width 0.1397)
		(layer "In2.Cu")
		(net "BMC_PETXP")
	)
	(segment
		(start 27.03195 -113.062512)
		(end 27.376628 -112.824006)
		(width 0.1397)
		(layer "In2.Cu")
		(net "BMC_PETXP")
	)
	(segment
		(start 42.629074 -104.379776)
		(end 43.022774 -104.29621)
		(width 0.1397)
		(layer "In2.Cu")
		(net "BMC_PETXP")
	)
	(segment
		(start 28.358592 -112.145064)
		(end 28.403804 -111.897922)
		(width 0.1397)
		(layer "In2.Cu")
		(net "BMC_PETXP")
	)
	(segment
		(start 151.47163 -103.907082)
		(end 151.689308 -103.754682)
		(width 0.1397)
		(layer "In2.Cu")
		(net "BMC_PETXP")
	)
	(segment
		(start 27.766518 -112.338358)
		(end 28.013914 -112.38357)
		(width 0.1397)
		(layer "In2.Cu")
		(net "BMC_PETXP")
	)
	(segment
		(start 151.05888 -103.834438)
		(end 151.47163 -103.907082)
		(width 0.1397)
		(layer "In2.Cu")
		(net "BMC_PETXP")
	)
	(segment
		(start 83.320636 -105.76052)
		(end 87.366348 -104.90073)
		(width 0.1397)
		(layer "In2.Cu")
		(net "BMC_PETXP")
	)
	(segment
		(start 201.269854 -51.957224)
		(end 202.372976 -51.957224)
		(width 0.1397)
		(layer "In2.Cu")
		(net "BMC_PETXP")
	)
	(segment
		(start 147.872196 -103.081582)
		(end 149.298152 -103.333042)
		(width 0.1397)
		(layer "In2.Cu")
		(net "BMC_PETXP")
	)
	(segment
		(start 154.980386 -104.525826)
		(end 155.198064 -104.373426)
		(width 0.1397)
		(layer "In2.Cu")
		(net "BMC_PETXP")
	)
	(segment
		(start 47.272702 -102.409752)
		(end 47.48276 -102.547674)
		(width 0.1397)
		(layer "In2.Cu")
		(net "BMC_PETXP")
	)
	(segment
		(start 78.467204 -104.729026)
		(end 83.320636 -105.76052)
		(width 0.1397)
		(layer "In2.Cu")
		(net "BMC_PETXP")
	)
	(segment
		(start 158.154878 -105.085642)
		(end 158.567628 -105.158286)
		(width 0.1397)
		(layer "In2.Cu")
		(net "BMC_PETXP")
	)
	(segment
		(start 36.922456 -104.600756)
		(end 39.892478 -103.969312)
		(width 0.1397)
		(layer "In2.Cu")
		(net "BMC_PETXP")
	)
	(segment
		(start 194.87388 -57.319672)
		(end 196.089524 -55.584598)
		(width 0.1397)
		(layer "In2.Cu")
		(net "BMC_PETXP")
	)
	(segment
		(start 153.372058 -104.242362)
		(end 153.784808 -104.315006)
		(width 0.1397)
		(layer "In2.Cu")
		(net "BMC_PETXP")
	)
	(segment
		(start 163.969192 -105.920032)
		(end 166.783258 -105.42397)
		(width 0.1397)
		(layer "In2.Cu")
		(net "BMC_PETXP")
	)
	(segment
		(start 26.784554 -113.0173)
		(end 27.03195 -113.062512)
		(width 0.1397)
		(layer "In2.Cu")
		(net "BMC_PETXP")
	)
	(segment
		(start 202.372976 -51.957224)
		(end 203.2762 -51.054)
		(width 0.1397)
		(layer "In2.Cu")
		(net "BMC_PETXP")
	)
	(segment
		(start 150.90648 -103.616506)
		(end 151.05888 -103.834438)
		(width 0.1397)
		(layer "In2.Cu")
		(net "BMC_PETXP")
	)
	(segment
		(start 153.219404 -104.02443)
		(end 153.372058 -104.242362)
		(width 0.1397)
		(layer "In2.Cu")
		(net "BMC_PETXP")
	)
	(segment
		(start 34.752788 -104.374442)
		(end 35.306 -104.25684)
		(width 0.1397)
		(layer "In2.Cu")
		(net "BMC_PETXP")
	)
	(segment
		(start 33.66135 -105.087166)
		(end 33.934146 -104.908858)
		(width 0.1397)
		(layer "In2.Cu")
		(net "BMC_PETXP")
	)
	(segment
		(start 156.806646 -104.65689)
		(end 156.959046 -104.874822)
		(width 0.1397)
		(layer "In2.Cu")
		(net "BMC_PETXP")
	)
	(segment
		(start 51.028092 -101.62921)
		(end 55.954422 -102.497382)
		(width 0.1397)
		(layer "In2.Cu")
		(net "BMC_PETXP")
	)
	(segment
		(start 28.013914 -112.38357)
		(end 28.358592 -112.145064)
		(width 0.1397)
		(layer "In2.Cu")
		(net "BMC_PETXP")
	)
	(segment
		(start 75.705716 -105.31602)
		(end 78.467204 -104.729026)
		(width 0.1397)
		(layer "In2.Cu")
		(net "BMC_PETXP")
	)
	(arc
		(start 24.137874 -114.714274)
		(mid 24.382748 -114.644051)
		(end 24.606758 -114.522758)
		(width 0.1397)
		(layer "In2.Cu")
		(net "BMC_PETXP")
	)
	(arc
		(start 203.5048 -50.23104)
		(mid 203.540196 -50.052621)
		(end 203.641198 -49.901348)
		(width 0.1397)
		(layer "In2.Cu")
		(net "BMC_PETXP")
	)
	(arc
		(start 24.079454 -114.7191)
		(mid 24.108771 -114.717982)
		(end 24.137874 -114.714274)
		(width 0.1397)
		(layer "In2.Cu")
		(net "BMC_PETXP")
	)
	(arc
		(start 203.2762 -51.054)
		(mid 203.445405 -50.800767)
		(end 203.5048 -50.502058)
		(width 0.1397)
		(layer "In2.Cu")
		(net "BMC_PETXP")
	)
	(arc
		(start 23.517606 -114.759994)
		(mid 23.562939 -114.729704)
		(end 23.616412 -114.7191)
		(width 0.1397)
		(layer "In2.Cu")
		(net "BMC_PETXP")
	)
	(segment
		(start 20.53336 -116.320824)
		(end 21.509736 -114.817398)
		(width 0.136652)
		(layer "F.Cu")
		(net "BMC_PETXN")
	)
	(segment
		(start 22.3774 -114.41303)
		(end 22.5044 -114.41303)
		(width 0.136652)
		(layer "F.Cu")
		(net "BMC_PETXN")
	)
	(segment
		(start 22.61616 -114.402108)
		(end 22.639274 -114.398806)
		(width 0.136652)
		(layer "F.Cu")
		(net "BMC_PETXN")
	)
	(segment
		(start 22.68347 -114.384582)
		(end 22.771862 -114.337338)
		(width 0.136652)
		(layer "F.Cu")
		(net "BMC_PETXN")
	)
	(segment
		(start 20.908518 -121.127266)
		(end 20.441666 -120.408446)
		(width 0.136652)
		(layer "F.Cu")
		(net "BMC_PETXN")
	)
	(segment
		(start 30.504892 -125.284992)
		(end 30.261052 -125.447806)
		(width 0.136652)
		(layer "F.Cu")
		(net "BMC_PETXN")
	)
	(segment
		(start 21.509736 -114.817398)
		(end 21.635974 -114.69116)
		(width 0.136652)
		(layer "F.Cu")
		(net "BMC_PETXN")
	)
	(segment
		(start 27.309572 -123.580144)
		(end 26.65476 -123.183396)
		(width 0.136652)
		(layer "F.Cu")
		(net "BMC_PETXN")
	)
	(segment
		(start 20.210018 -119.848884)
		(end 20.00504 -118.883684)
		(width 0.136652)
		(layer "F.Cu")
		(net "BMC_PETXN")
	)
	(segment
		(start 22.968966 -114.191288)
		(end 23.1648 -113.9952)
		(width 0.136652)
		(layer "F.Cu")
		(net "BMC_PETXN")
	)
	(segment
		(start 26.65476 -123.183396)
		(end 24.939752 -122.5042)
		(width 0.136652)
		(layer "F.Cu")
		(net "BMC_PETXN")
	)
	(segment
		(start 29.74848 -125.658118)
		(end 29.6672 -125.658118)
		(width 0.136652)
		(layer "F.Cu")
		(net "BMC_PETXN")
	)
	(segment
		(start 20.00504 -118.322852)
		(end 20.321524 -116.832634)
		(width 0.136652)
		(layer "F.Cu")
		(net "BMC_PETXN")
	)
	(segment
		(start 30.019752 -125.576838)
		(end 29.892752 -125.629416)
		(width 0.136652)
		(layer "F.Cu")
		(net "BMC_PETXN")
	)
	(segment
		(start 22.499574 -122.341894)
		(end 21.425154 -121.643902)
		(width 0.136652)
		(layer "F.Cu")
		(net "BMC_PETXN")
	)
	(segment
		(start 24.939752 -122.5042)
		(end 23.04796 -122.5042)
		(width 0.136652)
		(layer "F.Cu")
		(net "BMC_PETXN")
	)
	(segment
		(start 29.41447 -125.55347)
		(end 27.91968 -124.058426)
		(width 0.136652)
		(layer "F.Cu")
		(net "BMC_PETXN")
	)
	(via
		(at 23.1648 -113.9952)
		(size 0.508)
		(drill 0.254)
		(layers "F.Cu" "B.Cu")
		(net "BMC_PETXN")
	)
	(via
		(at 202.946 -49.784)
		(size 0.508)
		(drill 0.254)
		(layers "F.Cu" "B.Cu")
		(net "BMC_PETXN")
	)
	(arc
		(start 29.6672 -125.658118)
		(mid 29.530437 -125.630914)
		(end 29.41447 -125.55347)
		(width 0.136652)
		(layer "F.Cu")
		(net "BMC_PETXN")
	)
	(arc
		(start 20.00504 -118.883684)
		(mid 19.975595 -118.603268)
		(end 20.00504 -118.322852)
		(width 0.136652)
		(layer "F.Cu")
		(net "BMC_PETXN")
	)
	(arc
		(start 21.851366 -114.542316)
		(mid 22.10655 -114.445803)
		(end 22.3774 -114.41303)
		(width 0.136652)
		(layer "F.Cu")
		(net "BMC_PETXN")
	)
	(arc
		(start 21.674836 -114.656616)
		(mid 21.760438 -114.595352)
		(end 21.851366 -114.542316)
		(width 0.136652)
		(layer "F.Cu")
		(net "BMC_PETXN")
	)
	(arc
		(start 27.91968 -124.058426)
		(mid 27.629048 -123.800889)
		(end 27.309572 -123.580144)
		(width 0.136652)
		(layer "F.Cu")
		(net "BMC_PETXN")
	)
	(arc
		(start 22.5044 -114.41303)
		(mid 22.560543 -114.41026)
		(end 22.61616 -114.402108)
		(width 0.136652)
		(layer "F.Cu")
		(net "BMC_PETXN")
	)
	(arc
		(start 29.892752 -125.629416)
		(mid 29.82203 -125.650873)
		(end 29.74848 -125.658118)
		(width 0.136652)
		(layer "F.Cu")
		(net "BMC_PETXN")
	)
	(arc
		(start 23.04796 -122.5042)
		(mid 22.762002 -122.462803)
		(end 22.499574 -122.341894)
		(width 0.136652)
		(layer "F.Cu")
		(net "BMC_PETXN")
	)
	(arc
		(start 20.321524 -116.832634)
		(mid 20.403895 -116.56698)
		(end 20.53336 -116.320824)
		(width 0.136652)
		(layer "F.Cu")
		(net "BMC_PETXN")
	)
	(arc
		(start 21.635974 -114.69116)
		(mid 21.654893 -114.673312)
		(end 21.674836 -114.656616)
		(width 0.136652)
		(layer "F.Cu")
		(net "BMC_PETXN")
	)
	(arc
		(start 21.425154 -121.643902)
		(mid 21.139693 -121.412727)
		(end 20.908518 -121.127266)
		(width 0.136652)
		(layer "F.Cu")
		(net "BMC_PETXN")
	)
	(arc
		(start 20.441666 -120.408446)
		(mid 20.300123 -120.139312)
		(end 20.210018 -119.848884)
		(width 0.136652)
		(layer "F.Cu")
		(net "BMC_PETXN")
	)
	(arc
		(start 22.771862 -114.337338)
		(mid 22.875837 -114.271632)
		(end 22.968966 -114.191288)
		(width 0.136652)
		(layer "F.Cu")
		(net "BMC_PETXN")
	)
	(arc
		(start 22.639274 -114.398806)
		(mid 22.661989 -114.393616)
		(end 22.68347 -114.384582)
		(width 0.136652)
		(layer "F.Cu")
		(net "BMC_PETXN")
	)
	(arc
		(start 30.261052 -125.447806)
		(mid 30.143575 -125.518256)
		(end 30.019752 -125.576838)
		(width 0.136652)
		(layer "F.Cu")
		(net "BMC_PETXN")
	)
	(segment
		(start 203.4921 -48.222154)
		(end 203.487274 -48.227234)
		(width 0.136652)
		(layer "B.Cu")
		(net "BMC_PETXN")
	)
	(segment
		(start 206.181706 -46.275498)
		(end 205.555088 -46.713902)
		(width 0.136652)
		(layer "B.Cu")
		(net "BMC_PETXN")
	)
	(segment
		(start 203.487274 -48.227234)
		(end 203.466954 -48.247554)
		(width 0.136652)
		(layer "B.Cu")
		(net "BMC_PETXN")
	)
	(segment
		(start 210.382866 -45.0469)
		(end 209.95132 -45.0469)
		(width 0.136652)
		(layer "B.Cu")
		(net "BMC_PETXN")
	)
	(segment
		(start 206.234284 -46.222666)
		(end 206.181706 -46.275498)
		(width 0.136652)
		(layer "B.Cu")
		(net "BMC_PETXN")
	)
	(segment
		(start 203.2 -48.89246)
		(end 203.2 -49.171098)
		(width 0.136652)
		(layer "B.Cu")
		(net "BMC_PETXN")
	)
	(segment
		(start 203.705206 -48.009048)
		(end 203.4921 -48.222154)
		(width 0.136652)
		(layer "B.Cu")
		(net "BMC_PETXN")
	)
	(segment
		(start 205.555088 -46.713902)
		(end 203.705206 -48.009048)
		(width 0.136652)
		(layer "B.Cu")
		(net "BMC_PETXN")
	)
	(segment
		(start 209.95132 -45.0469)
		(end 206.234284 -46.222666)
		(width 0.136652)
		(layer "B.Cu")
		(net "BMC_PETXN")
	)
	(arc
		(start 210.8327 -44.7548)
		(mid 210.651028 -44.967434)
		(end 210.382866 -45.0469)
		(width 0.136652)
		(layer "B.Cu")
		(net "BMC_PETXN")
	)
	(arc
		(start 203.2 -49.171098)
		(mid 203.133943 -49.502808)
		(end 202.946 -49.784)
		(width 0.136652)
		(layer "B.Cu")
		(net "BMC_PETXN")
	)
	(arc
		(start 203.466954 -48.247554)
		(mid 203.269333 -48.543454)
		(end 203.2 -48.89246)
		(width 0.136652)
		(layer "B.Cu")
		(net "BMC_PETXN")
	)
	(segment
		(start 29.115004 -111.004604)
		(end 24.419052 -114.250978)
		(width 0.1397)
		(layer "In2.Cu")
		(net "BMC_PETXN")
	)
	(segment
		(start 23.517606 -114.348006)
		(end 23.1648 -113.9952)
		(width 0.1397)
		(layer "In2.Cu")
		(net "BMC_PETXN")
	)
	(segment
		(start 193.94043 -60.715144)
		(end 194.93357 -66.349118)
		(width 0.1397)
		(layer "In2.Cu")
		(net "BMC_PETXN")
	)
	(segment
		(start 201.165714 -51.627024)
		(end 195.852542 -55.347362)
		(width 0.1397)
		(layer "In2.Cu")
		(net "BMC_PETXN")
	)
	(segment
		(start 56.084724 -102.18547)
		(end 56.084724 -102.184962)
		(width 0.1397)
		(layer "In2.Cu")
		(net "BMC_PETXN")
	)
	(segment
		(start 117.399816 -109.860588)
		(end 87.360506 -104.56418)
		(width 0.1397)
		(layer "In2.Cu")
		(net "BMC_PETXN")
	)
	(segment
		(start 87.360506 -104.56418)
		(end 85.340444 -104.993694)
		(width 0.1397)
		(layer "In2.Cu")
		(net "BMC_PETXN")
	)
	(segment
		(start 45.16755 -102.509574)
		(end 42.89425 -103.985822)
		(width 0.1397)
		(layer "In2.Cu")
		(net "BMC_PETXN")
	)
	(segment
		(start 59.286648 -104.427782)
		(end 57.74563 -103.348536)
		(width 0.1397)
		(layer "In2.Cu")
		(net "BMC_PETXN")
	)
	(segment
		(start 24.081486 -114.3889)
		(end 23.616412 -114.3889)
		(width 0.1397)
		(layer "In2.Cu")
		(net "BMC_PETXN")
	)
	(segment
		(start 175.102266 -102.193344)
		(end 172.376338 -104.102408)
		(width 0.1397)
		(layer "In2.Cu")
		(net "BMC_PETXN")
	)
	(segment
		(start 172.376338 -104.102408)
		(end 163.969192 -105.584498)
		(width 0.1397)
		(layer "In2.Cu")
		(net "BMC_PETXN")
	)
	(segment
		(start 194.93357 -66.349118)
		(end 193.157602 -76.425044)
		(width 0.1397)
		(layer "In2.Cu")
		(net "BMC_PETXN")
	)
	(segment
		(start 203.04252 -50.82032)
		(end 203.04252 -50.820574)
		(width 0.1397)
		(layer "In2.Cu")
		(net "BMC_PETXN")
	)
	(segment
		(start 75.705716 -104.9782)
		(end 69.450966 -103.648764)
		(width 0.1397)
		(layer "In2.Cu")
		(net "BMC_PETXN")
	)
	(segment
		(start 121.302526 -109.03077)
		(end 117.399816 -109.860588)
		(width 0.1397)
		(layer "In2.Cu")
		(net "BMC_PETXN")
	)
	(segment
		(start 62.839092 -105.053638)
		(end 59.286648 -104.427782)
		(width 0.1397)
		(layer "In2.Cu")
		(net "BMC_PETXN")
	)
	(segment
		(start 163.969192 -105.584498)
		(end 147.872196 -102.746048)
		(width 0.1397)
		(layer "In2.Cu")
		(net "BMC_PETXN")
	)
	(segment
		(start 42.89425 -103.985822)
		(end 42.226738 -104.127554)
		(width 0.1397)
		(layer "In2.Cu")
		(net "BMC_PETXN")
	)
	(segment
		(start 24.081486 -114.388646)
		(end 24.081486 -114.3889)
		(width 0.1397)
		(layer "In2.Cu")
		(net "BMC_PETXN")
	)
	(segment
		(start 33.427162 -104.845358)
		(end 29.115004 -111.004604)
		(width 0.1397)
		(layer "In2.Cu")
		(net "BMC_PETXN")
	)
	(segment
		(start 69.450966 -103.648764)
		(end 62.839092 -105.053638)
		(width 0.1397)
		(layer "In2.Cu")
		(net "BMC_PETXN")
	)
	(segment
		(start 126.458726 -110.12678)
		(end 121.302526 -109.03077)
		(width 0.1397)
		(layer "In2.Cu")
		(net "BMC_PETXN")
	)
	(segment
		(start 202.23607 -51.627024)
		(end 201.165714 -51.627024)
		(width 0.1397)
		(layer "In2.Cu")
		(net "BMC_PETXN")
	)
	(segment
		(start 51.023012 -101.292914)
		(end 45.16755 -102.509574)
		(width 0.1397)
		(layer "In2.Cu")
		(net "BMC_PETXN")
	)
	(segment
		(start 195.852542 -55.347362)
		(end 194.561206 -57.190132)
		(width 0.1397)
		(layer "In2.Cu")
		(net "BMC_PETXN")
	)
	(segment
		(start 78.467204 -104.391206)
		(end 75.705716 -104.9782)
		(width 0.1397)
		(layer "In2.Cu")
		(net "BMC_PETXN")
	)
	(segment
		(start 34.623756 -104.064054)
		(end 33.427162 -104.845358)
		(width 0.1397)
		(layer "In2.Cu")
		(net "BMC_PETXN")
	)
	(segment
		(start 203.1746 -50.502312)
		(end 203.174346 -50.502058)
		(width 0.1397)
		(layer "In2.Cu")
		(net "BMC_PETXN")
	)
	(segment
		(start 35.306 -103.91902)
		(end 34.623756 -104.064054)
		(width 0.1397)
		(layer "In2.Cu")
		(net "BMC_PETXN")
	)
	(segment
		(start 39.892478 -103.631492)
		(end 36.922456 -104.262936)
		(width 0.1397)
		(layer "In2.Cu")
		(net "BMC_PETXN")
	)
	(segment
		(start 24.08174 -114.388646)
		(end 24.081486 -114.388646)
		(width 0.1397)
		(layer "In2.Cu")
		(net "BMC_PETXN")
	)
	(segment
		(start 203.04252 -50.820574)
		(end 202.23607 -51.627024)
		(width 0.1397)
		(layer "In2.Cu")
		(net "BMC_PETXN")
	)
	(segment
		(start 83.320636 -105.4227)
		(end 78.467204 -104.391206)
		(width 0.1397)
		(layer "In2.Cu")
		(net "BMC_PETXN")
	)
	(segment
		(start 56.084724 -102.184962)
		(end 51.023012 -101.292914)
		(width 0.1397)
		(layer "In2.Cu")
		(net "BMC_PETXN")
	)
	(segment
		(start 42.226738 -104.127554)
		(end 39.892478 -103.631492)
		(width 0.1397)
		(layer "In2.Cu")
		(net "BMC_PETXN")
	)
	(segment
		(start 194.561206 -57.190132)
		(end 193.94043 -60.715144)
		(width 0.1397)
		(layer "In2.Cu")
		(net "BMC_PETXN")
	)
	(segment
		(start 142.732252 -103.65232)
		(end 135.826754 -108.135674)
		(width 0.1397)
		(layer "In2.Cu")
		(net "BMC_PETXN")
	)
	(segment
		(start 36.922456 -104.262936)
		(end 35.306 -103.91902)
		(width 0.1397)
		(layer "In2.Cu")
		(net "BMC_PETXN")
	)
	(segment
		(start 203.1746 -50.335942)
		(end 203.1746 -50.502312)
		(width 0.1397)
		(layer "In2.Cu")
		(net "BMC_PETXN")
	)
	(segment
		(start 85.340444 -104.993694)
		(end 83.320636 -105.4227)
		(width 0.1397)
		(layer "In2.Cu")
		(net "BMC_PETXN")
	)
	(segment
		(start 147.872196 -102.746048)
		(end 142.732252 -103.65232)
		(width 0.1397)
		(layer "In2.Cu")
		(net "BMC_PETXN")
	)
	(segment
		(start 135.826754 -108.135674)
		(end 126.458726 -110.12678)
		(width 0.1397)
		(layer "In2.Cu")
		(net "BMC_PETXN")
	)
	(segment
		(start 57.74563 -103.348536)
		(end 56.084724 -102.18547)
		(width 0.1397)
		(layer "In2.Cu")
		(net "BMC_PETXN")
	)
	(segment
		(start 193.157602 -76.425044)
		(end 175.102266 -102.193344)
		(width 0.1397)
		(layer "In2.Cu")
		(net "BMC_PETXN")
	)
	(arc
		(start 203.174346 -50.502058)
		(mid 203.140085 -50.674299)
		(end 203.04252 -50.82032)
		(width 0.1397)
		(layer "In2.Cu")
		(net "BMC_PETXN")
	)
	(arc
		(start 23.616412 -114.3889)
		(mid 23.562951 -114.378266)
		(end 23.517606 -114.348006)
		(width 0.1397)
		(layer "In2.Cu")
		(net "BMC_PETXN")
	)
	(arc
		(start 24.419052 -114.250978)
		(mid 24.257879 -114.33814)
		(end 24.08174 -114.388646)
		(width 0.1397)
		(layer "In2.Cu")
		(net "BMC_PETXN")
	)
	(arc
		(start 202.946 -49.784)
		(mid 203.115205 -50.037233)
		(end 203.1746 -50.335942)
		(width 0.1397)
		(layer "In2.Cu")
		(net "BMC_PETXN")
	)
	(segment
		(start 333.915512 -183.736488)
		(end 334.01 -183.642)
		(width 0.12065)
		(layer "F.Cu")
		(net "BMC_PERST#15")
	)
	(segment
		(start 334.210152 -181.601618)
		(end 334.210152 -183.441848)
		(width 0.12065)
		(layer "F.Cu")
		(net "BMC_PERST#15")
	)
	(segment
		(start 333.915512 -184.433718)
		(end 333.915512 -183.736488)
		(width 0.12065)
		(layer "F.Cu")
		(net "BMC_PERST#15")
	)
	(segment
		(start 334.210152 -183.441848)
		(end 334.01 -183.642)
		(width 0.12065)
		(layer "F.Cu")
		(net "BMC_PERST#15")
	)
	(via
		(at 334.829912 -184.277)
		(size 0.7112)
		(drill 0.3556)
		(layers "F.Cu" "B.Cu")
		(net "BMC_PERST#15")
	)
	(via
		(at 334.01 -183.642)
		(size 0.508)
		(drill 0.254)
		(layers "F.Cu" "B.Cu")
		(net "BMC_PERST#15")
	)
	(segment
		(start 333.915512 -184.433718)
		(end 334.673194 -184.433718)
		(width 0.12065)
		(layer "B.Cu")
		(net "BMC_PERST#15")
	)
	(segment
		(start 334.01 -183.642)
		(end 334.645 -183.642)
		(width 0.12065)
		(layer "B.Cu")
		(net "BMC_PERST#15")
	)
	(segment
		(start 334.673194 -184.433718)
		(end 334.829912 -184.277)
		(width 0.12065)
		(layer "B.Cu")
		(net "BMC_PERST#15")
	)
	(segment
		(start 334.645 -183.642)
		(end 334.829912 -183.826912)
		(width 0.12065)
		(layer "B.Cu")
		(net "BMC_PERST#15")
	)
	(segment
		(start 334.829912 -183.826912)
		(end 334.829912 -184.277)
		(width 0.12065)
		(layer "B.Cu")
		(net "BMC_PERST#15")
	)
	(segment
		(start 17.035272 -128.651)
		(end 17.9705 -128.651)
		(width 0.12065)
		(layer "F.Cu")
		(net "BMC_PERST#_R")
	)
	(segment
		(start 21.343366 -89.5604)
		(end 24.326596 -89.5604)
		(width 0.12065)
		(layer "F.Cu")
		(net "BMC_PERST#_R")
	)
	(segment
		(start 24.326596 -89.5604)
		(end 25.371298 -88.515698)
		(width 0.12065)
		(layer "F.Cu")
		(net "BMC_PERST#_R")
	)
	(segment
		(start 33.056068 -128.850136)
		(end 33.27019 -128.636014)
		(width 0.12065)
		(layer "F.Cu")
		(net "BMC_PERST#_R")
	)
	(segment
		(start 333.915512 -185.322718)
		(end 333.915512 -186.182)
		(width 0.12065)
		(layer "F.Cu")
		(net "BMC_PERST#_R")
	)
	(segment
		(start 15.71498 -129.971292)
		(end 17.035272 -128.651)
		(width 0.12065)
		(layer "F.Cu")
		(net "BMC_PERST#_R")
	)
	(segment
		(start 33.27019 -128.636014)
		(end 33.27019 -128.0922)
		(width 0.12065)
		(layer "F.Cu")
		(net "BMC_PERST#_R")
	)
	(segment
		(start 25.371298 -88.515698)
		(end 25.371298 -87.45855)
		(width 0.12065)
		(layer "F.Cu")
		(net "BMC_PERST#_R")
	)
	(segment
		(start 32.539686 -128.850136)
		(end 33.056068 -128.850136)
		(width 0.12065)
		(layer "F.Cu")
		(net "BMC_PERST#_R")
	)
	(segment
		(start 20.18157 -90.722196)
		(end 21.343366 -89.5604)
		(width 0.12065)
		(layer "F.Cu")
		(net "BMC_PERST#_R")
	)
	(segment
		(start 15.71498 -130.98018)
		(end 15.71498 -129.971292)
		(width 0.12065)
		(layer "F.Cu")
		(net "BMC_PERST#_R")
	)
	(segment
		(start 32.104838 -129.284984)
		(end 32.539686 -128.850136)
		(width 0.12065)
		(layer "F.Cu")
		(net "BMC_PERST#_R")
	)
	(via
		(at 333.915512 -186.182)
		(size 0.508)
		(drill 0.254)
		(layers "F.Cu" "B.Cu")
		(net "BMC_PERST#_R")
	)
	(via
		(at 20.18157 -90.722196)
		(size 0.508)
		(drill 0.254)
		(layers "F.Cu" "B.Cu")
		(net "BMC_PERST#_R")
	)
	(via
		(at 11.0744 -169.0878)
		(size 0.508)
		(drill 0.254)
		(layers "F.Cu" "B.Cu")
		(net "BMC_PERST#_R")
	)
	(via
		(at 33.27019 -128.0922)
		(size 0.4572)
		(drill 0.2032)
		(layers "F.Cu" "B.Cu")
		(net "BMC_PERST#_R")
	)
	(via
		(at 15.71498 -130.98018)
		(size 0.508)
		(drill 0.254)
		(layers "F.Cu" "B.Cu")
		(net "BMC_PERST#_R")
	)
	(via
		(at 329.819 -186.648852)
		(size 0.7112)
		(drill 0.3556)
		(layers "F.Cu" "B.Cu")
		(net "BMC_PERST#_R")
	)
	(segment
		(start 329.751182 -169.122852)
		(end 327.55586 -171.318174)
		(width 0.12065)
		(layer "B.Cu")
		(net "BMC_PERST#_R")
	)
	(segment
		(start 52.91455 -167.833548)
		(end 53.279802 -168.1988)
		(width 0.12065)
		(layer "B.Cu")
		(net "BMC_PERST#_R")
	)
	(segment
		(start 328.642218 -186.648852)
		(end 329.819 -186.648852)
		(width 0.12065)
		(layer "B.Cu")
		(net "BMC_PERST#_R")
	)
	(segment
		(start 225.35261 -153.349198)
		(end 322.411344 -153.349198)
		(width 0.12065)
		(layer "B.Cu")
		(net "BMC_PERST#_R")
	)
	(segment
		(start 327.55586 -171.318174)
		(end 327.55586 -185.562494)
		(width 0.12065)
		(layer "B.Cu")
		(net "BMC_PERST#_R")
	)
	(segment
		(start 334.713072 -169.122852)
		(end 329.751182 -169.122852)
		(width 0.12065)
		(layer "B.Cu")
		(net "BMC_PERST#_R")
	)
	(segment
		(start 53.279802 -168.1988)
		(end 210.503008 -168.1988)
		(width 0.12065)
		(layer "B.Cu")
		(net "BMC_PERST#_R")
	)
	(segment
		(start 11.0744 -169.0878)
		(end 11.43635 -168.72585)
		(width 0.12065)
		(layer "B.Cu")
		(net "BMC_PERST#_R")
	)
	(segment
		(start 15.7099 -129.730246)
		(end 14.376908 -128.397254)
		(width 0.12065)
		(layer "B.Cu")
		(net "BMC_PERST#_R")
	)
	(segment
		(start 20.1168 -90.786966)
		(end 20.18157 -90.722196)
		(width 0.12065)
		(layer "B.Cu")
		(net "BMC_PERST#_R")
	)
	(segment
		(start 20.1168 -91.67368)
		(end 20.1168 -90.786966)
		(width 0.12065)
		(layer "B.Cu")
		(net "BMC_PERST#_R")
	)
	(segment
		(start 14.3764 -128.342898)
		(end 12.268708 -126.235206)
		(width 0.12065)
		(layer "B.Cu")
		(net "BMC_PERST#_R")
	)
	(segment
		(start 15.7099 -130.9751)
		(end 15.7099 -129.730246)
		(width 0.12065)
		(layer "B.Cu")
		(net "BMC_PERST#_R")
	)
	(segment
		(start 16.897858 -94.892368)
		(end 17.018508 -94.771718)
		(width 0.12065)
		(layer "B.Cu")
		(net "BMC_PERST#_R")
	)
	(segment
		(start 17.018508 -94.771718)
		(end 17.018762 -94.771718)
		(width 0.12065)
		(layer "B.Cu")
		(net "BMC_PERST#_R")
	)
	(segment
		(start 10.8458 -115.602258)
		(end 16.897858 -109.5502)
		(width 0.12065)
		(layer "B.Cu")
		(net "BMC_PERST#_R")
	)
	(segment
		(start 333.915512 -186.182)
		(end 333.44866 -186.648852)
		(width 0.12065)
		(layer "B.Cu")
		(net "BMC_PERST#_R")
	)
	(segment
		(start 14.3764 -128.397254)
		(end 14.3764 -128.342898)
		(width 0.12065)
		(layer "B.Cu")
		(net "BMC_PERST#_R")
	)
	(segment
		(start 334.98663 -168.849294)
		(end 334.713072 -169.122852)
		(width 0.12065)
		(layer "B.Cu")
		(net "BMC_PERST#_R")
	)
	(segment
		(start 334.98663 -165.924484)
		(end 334.98663 -168.849294)
		(width 0.12065)
		(layer "B.Cu")
		(net "BMC_PERST#_R")
	)
	(segment
		(start 16.897858 -109.5502)
		(end 16.897858 -94.892368)
		(width 0.12065)
		(layer "B.Cu")
		(net "BMC_PERST#_R")
	)
	(segment
		(start 10.8458 -124.6124)
		(end 10.8458 -115.602258)
		(width 0.12065)
		(layer "B.Cu")
		(net "BMC_PERST#_R")
	)
	(segment
		(start 322.411344 -153.349198)
		(end 334.98663 -165.924484)
		(width 0.12065)
		(layer "B.Cu")
		(net "BMC_PERST#_R")
	)
	(segment
		(start 12.268708 -126.235206)
		(end 12.268708 -126.035308)
		(width 0.12065)
		(layer "B.Cu")
		(net "BMC_PERST#_R")
	)
	(segment
		(start 17.018762 -94.771718)
		(end 20.1168 -91.67368)
		(width 0.12065)
		(layer "B.Cu")
		(net "BMC_PERST#_R")
	)
	(segment
		(start 35.632644 -167.833548)
		(end 52.91455 -167.833548)
		(width 0.12065)
		(layer "B.Cu")
		(net "BMC_PERST#_R")
	)
	(segment
		(start 327.55586 -185.562494)
		(end 328.642218 -186.648852)
		(width 0.12065)
		(layer "B.Cu")
		(net "BMC_PERST#_R")
	)
	(segment
		(start 210.503008 -168.1988)
		(end 225.35261 -153.349198)
		(width 0.12065)
		(layer "B.Cu")
		(net "BMC_PERST#_R")
	)
	(segment
		(start 34.740342 -168.72585)
		(end 35.632644 -167.833548)
		(width 0.12065)
		(layer "B.Cu")
		(net "BMC_PERST#_R")
	)
	(segment
		(start 333.44866 -186.648852)
		(end 329.819 -186.648852)
		(width 0.12065)
		(layer "B.Cu")
		(net "BMC_PERST#_R")
	)
	(segment
		(start 12.268708 -126.035308)
		(end 10.8458 -124.6124)
		(width 0.12065)
		(layer "B.Cu")
		(net "BMC_PERST#_R")
	)
	(segment
		(start 14.376908 -128.397254)
		(end 14.3764 -128.397254)
		(width 0.12065)
		(layer "B.Cu")
		(net "BMC_PERST#_R")
	)
	(segment
		(start 11.43635 -168.72585)
		(end 34.740342 -168.72585)
		(width 0.12065)
		(layer "B.Cu")
		(net "BMC_PERST#_R")
	)
	(segment
		(start 15.71498 -130.98018)
		(end 15.7099 -130.9751)
		(width 0.12065)
		(layer "B.Cu")
		(net "BMC_PERST#_R")
	)
	(segment
		(start 32.34817 -129.01422)
		(end 33.27019 -128.0922)
		(width 0.127)
		(layer "In2.Cu")
		(net "BMC_PERST#_R")
	)
	(segment
		(start 15.71498 -130.98018)
		(end 16.820388 -129.874772)
		(width 0.127)
		(layer "In2.Cu")
		(net "BMC_PERST#_R")
	)
	(segment
		(start 30.39618 -129.01422)
		(end 32.34817 -129.01422)
		(width 0.127)
		(layer "In2.Cu")
		(net "BMC_PERST#_R")
	)
	(segment
		(start 29.535628 -129.874772)
		(end 30.39618 -129.01422)
		(width 0.127)
		(layer "In2.Cu")
		(net "BMC_PERST#_R")
	)
	(segment
		(start 16.820388 -129.874772)
		(end 29.535628 -129.874772)
		(width 0.127)
		(layer "In2.Cu")
		(net "BMC_PERST#_R")
	)
	(segment
		(start 15.059152 -131.636008)
		(end 13.780008 -131.636008)
		(width 0.127)
		(layer "In5.Cu")
		(net "BMC_PERST#_R")
	)
	(segment
		(start 13.780008 -131.636008)
		(end 11.049 -134.367016)
		(width 0.127)
		(layer "In5.Cu")
		(net "BMC_PERST#_R")
	)
	(segment
		(start 11.049 -134.367016)
		(end 11.049 -169.0624)
		(width 0.127)
		(layer "In5.Cu")
		(net "BMC_PERST#_R")
	)
	(segment
		(start 11.049 -169.0624)
		(end 11.0744 -169.0878)
		(width 0.127)
		(layer "In5.Cu")
		(net "BMC_PERST#_R")
	)
	(segment
		(start 15.71498 -130.98018)
		(end 15.059152 -131.636008)
		(width 0.127)
		(layer "In5.Cu")
		(net "BMC_PERST#_R")
	)
	(segment
		(start 31.304738 -124.484892)
		(end 30.904942 -124.884688)
		(width 0.12065)
		(layer "F.Cu")
		(net "BMC_PEREXT")
	)
	(via
		(at 29.938218 -124.1933)
		(size 0.7112)
		(drill 0.3556)
		(layers "F.Cu" "B.Cu")
		(net "BMC_PEREXT")
	)
	(via
		(at 30.904942 -124.884688)
		(size 0.4572)
		(drill 0.2032)
		(layers "F.Cu" "B.Cu")
		(net "BMC_PEREXT")
	)
	(segment
		(start 30.213554 -124.1933)
		(end 29.938218 -124.1933)
		(width 0.12065)
		(layer "B.Cu")
		(net "BMC_PEREXT")
	)
	(segment
		(start 26.4414 -121.720102)
		(end 26.706576 -121.720102)
		(width 0.12065)
		(layer "B.Cu")
		(net "BMC_PEREXT")
	)
	(segment
		(start 24.710898 -119.9896)
		(end 26.4414 -121.720102)
		(width 0.12065)
		(layer "B.Cu")
		(net "BMC_PEREXT")
	)
	(segment
		(start 30.904942 -124.884688)
		(end 30.213554 -124.1933)
		(width 0.12065)
		(layer "B.Cu")
		(net "BMC_PEREXT")
	)
	(segment
		(start 24.5745 -119.9896)
		(end 24.710898 -119.9896)
		(width 0.12065)
		(layer "B.Cu")
		(net "BMC_PEREXT")
	)
	(segment
		(start 26.706576 -121.720102)
		(end 29.179774 -124.1933)
		(width 0.12065)
		(layer "B.Cu")
		(net "BMC_PEREXT")
	)
	(segment
		(start 29.179774 -124.1933)
		(end 29.938218 -124.1933)
		(width 0.12065)
		(layer "B.Cu")
		(net "BMC_PEREXT")
	)
	(segment
		(start 42.939462 -122.519694)
		(end 43.304714 -122.884946)
		(width 0.12065)
		(layer "F.Cu")
		(net "BMC_JTAG_L_EN_R")
	)
	(segment
		(start 42.939462 -121.933716)
		(end 42.939462 -122.519694)
		(width 0.12065)
		(layer "F.Cu")
		(net "BMC_JTAG_L_EN_R")
	)
	(segment
		(start 47.0408 -118.364)
		(end 47.0408 -117.638576)
		(width 0.12065)
		(layer "F.Cu")
		(net "BMC_JTAG_L_EN_R")
	)
	(segment
		(start 45.464984 -119.939816)
		(end 44.933362 -119.939816)
		(width 0.12065)
		(layer "F.Cu")
		(net "BMC_JTAG_L_EN_R")
	)
	(segment
		(start 47.0408 -117.638576)
		(end 46.765464 -117.36324)
		(width 0.12065)
		(layer "F.Cu")
		(net "BMC_JTAG_L_EN_R")
	)
	(segment
		(start 44.933362 -119.939816)
		(end 42.939462 -121.933716)
		(width 0.12065)
		(layer "F.Cu")
		(net "BMC_JTAG_L_EN_R")
	)
	(segment
		(start 47.0408 -118.364)
		(end 45.464984 -119.939816)
		(width 0.12065)
		(layer "F.Cu")
		(net "BMC_JTAG_L_EN_R")
	)
	(via
		(at 47.0408 -118.364)
		(size 0.7112)
		(drill 0.3556)
		(layers "F.Cu" "B.Cu")
		(net "BMC_JTAG_L_EN_R")
	)
	(segment
		(start 46.377606 -114.489738)
		(end 46.377606 -113.458498)
		(width 0.12065)
		(layer "F.Cu")
		(net "BMC_JTAG_L_EN")
	)
	(segment
		(start 46.377606 -113.458498)
		(end 46.381416 -113.454688)
		(width 0.12065)
		(layer "F.Cu")
		(net "BMC_JTAG_L_EN")
	)
	(segment
		(start 46.360334 -116.06911)
		(end 46.360334 -114.50701)
		(width 0.12065)
		(layer "F.Cu")
		(net "BMC_JTAG_L_EN")
	)
	(segment
		(start 46.360334 -114.50701)
		(end 46.377606 -114.489738)
		(width 0.12065)
		(layer "F.Cu")
		(net "BMC_JTAG_L_EN")
	)
	(segment
		(start 46.765464 -116.47424)
		(end 46.360334 -116.06911)
		(width 0.12065)
		(layer "F.Cu")
		(net "BMC_JTAG_L_EN")
	)
	(segment
		(start 46.381416 -113.454688)
		(end 46.381416 -112.484916)
		(width 0.12065)
		(layer "F.Cu")
		(net "BMC_JTAG_L_EN")
	)
	(via
		(at 46.381416 -112.484916)
		(size 0.7112)
		(drill 0.3556)
		(layers "F.Cu" "B.Cu")
		(net "BMC_JTAG_L_EN")
	)
	(segment
		(start 209.325972 -12.986766)
		(end 209.325972 -13.999464)
		(width 0.12065)
		(layer "F.Cu")
		(net "BMC_ID_LED_R")
	)
	(segment
		(start 209.325972 -15.162022)
		(end 209.4103 -15.24635)
		(width 0.12065)
		(layer "F.Cu")
		(net "BMC_ID_LED_R")
	)
	(segment
		(start 209.325972 -13.999464)
		(end 209.325972 -15.162022)
		(width 0.12065)
		(layer "F.Cu")
		(net "BMC_ID_LED_R")
	)
	(segment
		(start 209.325972 -12.986766)
		(end 208.284572 -12.986766)
		(width 0.12065)
		(layer "F.Cu")
		(net "BMC_ID_LED_R")
	)
	(via
		(at 209.325972 -13.999464)
		(size 0.7112)
		(drill 0.3556)
		(layers "F.Cu" "B.Cu")
		(net "BMC_ID_LED_R")
	)
	(segment
		(start 41.294558 -113.721134)
		(end 41.51376 -113.940336)
		(width 0.12065)
		(layer "F.Cu")
		(net "BMC_ID_LED")
	)
	(segment
		(start 41.51376 -113.940336)
		(end 41.51376 -115.06708)
		(width 0.12065)
		(layer "F.Cu")
		(net "BMC_ID_LED")
	)
	(segment
		(start 41.704768 -123.684792)
		(end 41.304972 -123.284996)
		(width 0.12065)
		(layer "F.Cu")
		(net "BMC_ID_LED")
	)
	(segment
		(start 209.325972 -12.097766)
		(end 209.325972 -11.277092)
		(width 0.12065)
		(layer "F.Cu")
		(net "BMC_ID_LED")
	)
	(segment
		(start 209.325972 -11.277092)
		(end 209.294984 -11.246104)
		(width 0.12065)
		(layer "F.Cu")
		(net "BMC_ID_LED")
	)
	(via
		(at 78.86319 -79.92618)
		(size 0.508)
		(drill 0.254)
		(layers "F.Cu" "B.Cu")
		(net "BMC_ID_LED")
	)
	(via
		(at 74.6252 -110.7694)
		(size 0.508)
		(drill 0.254)
		(layers "F.Cu" "B.Cu")
		(net "BMC_ID_LED")
	)
	(via
		(at 209.294984 -11.246104)
		(size 0.508)
		(drill 0.254)
		(layers "F.Cu" "B.Cu")
		(net "BMC_ID_LED")
	)
	(via
		(at 41.51376 -115.06708)
		(size 0.508)
		(drill 0.254)
		(layers "F.Cu" "B.Cu")
		(net "BMC_ID_LED")
	)
	(via
		(at 200.6981 0.3556)
		(size 0.508)
		(drill 0.254)
		(layers "F.Cu" "B.Cu")
		(net "BMC_ID_LED")
	)
	(via
		(at 41.304972 -123.284996)
		(size 0.4572)
		(drill 0.2032)
		(layers "F.Cu" "B.Cu")
		(net "BMC_ID_LED")
	)
	(via
		(at 207.257904 -8.198104)
		(size 0.7112)
		(drill 0.3556)
		(layers "F.Cu" "B.Cu")
		(net "BMC_ID_LED")
	)
	(segment
		(start 209.1944 -11.14552)
		(end 209.294984 -11.246104)
		(width 0.12065)
		(layer "B.Cu")
		(net "BMC_ID_LED")
	)
	(segment
		(start 203.4794 -3.653536)
		(end 203.4794 -4.4196)
		(width 0.12065)
		(layer "B.Cu")
		(net "BMC_ID_LED")
	)
	(segment
		(start 78.86319 -80.860392)
		(end 78.86319 -79.92618)
		(width 0.12065)
		(layer "B.Cu")
		(net "BMC_ID_LED")
	)
	(segment
		(start 203.4794 -4.4196)
		(end 207.257904 -8.198104)
		(width 0.12065)
		(layer "B.Cu")
		(net "BMC_ID_LED")
	)
	(segment
		(start 75.7682 -96.830642)
		(end 78.393798 -94.205044)
		(width 0.12065)
		(layer "B.Cu")
		(net "BMC_ID_LED")
	)
	(segment
		(start 200.6981 0.3556)
		(end 200.6981 -0.872236)
		(width 0.12065)
		(layer "B.Cu")
		(net "BMC_ID_LED")
	)
	(segment
		(start 74.6252 -110.7694)
		(end 75.7682 -109.6264)
		(width 0.12065)
		(layer "B.Cu")
		(net "BMC_ID_LED")
	)
	(segment
		(start 75.7682 -109.6264)
		(end 75.7682 -96.830642)
		(width 0.12065)
		(layer "B.Cu")
		(net "BMC_ID_LED")
	)
	(segment
		(start 78.393798 -94.205044)
		(end 78.393798 -81.329784)
		(width 0.12065)
		(layer "B.Cu")
		(net "BMC_ID_LED")
	)
	(segment
		(start 200.6981 -0.872236)
		(end 203.4794 -3.653536)
		(width 0.12065)
		(layer "B.Cu")
		(net "BMC_ID_LED")
	)
	(segment
		(start 78.393798 -81.329784)
		(end 78.86319 -80.860392)
		(width 0.12065)
		(layer "B.Cu")
		(net "BMC_ID_LED")
	)
	(segment
		(start 209.1944 -10.1346)
		(end 209.1944 -11.14552)
		(width 0.12065)
		(layer "B.Cu")
		(net "BMC_ID_LED")
	)
	(segment
		(start 207.257904 -8.198104)
		(end 209.1944 -10.1346)
		(width 0.12065)
		(layer "B.Cu")
		(net "BMC_ID_LED")
	)
	(segment
		(start 51.728624 -110.599982)
		(end 51.72837 -110.600236)
		(width 0.127)
		(layer "In2.Cu")
		(net "BMC_ID_LED")
	)
	(segment
		(start 52.044346 -110.599728)
		(end 52.044092 -110.599982)
		(width 0.127)
		(layer "In2.Cu")
		(net "BMC_ID_LED")
	)
	(segment
		(start 46.377352 -109.7661)
		(end 41.829736 -114.313716)
		(width 0.127)
		(layer "In2.Cu")
		(net "BMC_ID_LED")
	)
	(segment
		(start 200.6981 0.744982)
		(end 200.725532 0.772414)
		(width 0.127)
		(layer "In2.Cu")
		(net "BMC_ID_LED")
	)
	(segment
		(start 41.51376 -115.06708)
		(end 41.304972 -115.275868)
		(width 0.127)
		(layer "In2.Cu")
		(net "BMC_ID_LED")
	)
	(segment
		(start 89.6493 -47.3583)
		(end 90.4748 -48.1838)
		(width 0.127)
		(layer "In2.Cu")
		(net "BMC_ID_LED")
	)
	(segment
		(start 90.4748 -60.579)
		(end 84.52104 -66.53276)
		(width 0.127)
		(layer "In2.Cu")
		(net "BMC_ID_LED")
	)
	(segment
		(start 120.766332 -5.120132)
		(end 119.8499 -5.120132)
		(width 0.127)
		(layer "In2.Cu")
		(net "BMC_ID_LED")
	)
	(segment
		(start 51.096926 -110.600236)
		(end 50.26279 -109.7661)
		(width 0.127)
		(layer "In2.Cu")
		(net "BMC_ID_LED")
	)
	(segment
		(start 89.6493 -35.320732)
		(end 89.6493 -47.3583)
		(width 0.127)
		(layer "In2.Cu")
		(net "BMC_ID_LED")
	)
	(segment
		(start 129.044954 3.15849)
		(end 120.766332 -5.120132)
		(width 0.127)
		(layer "In2.Cu")
		(net "BMC_ID_LED")
	)
	(segment
		(start 200.6981 0.3556)
		(end 200.6981 0.744982)
		(width 0.127)
		(layer "In2.Cu")
		(net "BMC_ID_LED")
	)
	(segment
		(start 200.725532 0.772414)
		(end 200.725532 1.292352)
		(width 0.127)
		(layer "In2.Cu")
		(net "BMC_ID_LED")
	)
	(segment
		(start 51.72837 -110.600236)
		(end 51.096926 -110.600236)
		(width 0.127)
		(layer "In2.Cu")
		(net "BMC_ID_LED")
	)
	(segment
		(start 41.829736 -114.313716)
		(end 41.829736 -114.751104)
		(width 0.127)
		(layer "In2.Cu")
		(net "BMC_ID_LED")
	)
	(segment
		(start 41.829736 -114.751104)
		(end 41.51376 -115.06708)
		(width 0.127)
		(layer "In2.Cu")
		(net "BMC_ID_LED")
	)
	(segment
		(start 41.304972 -115.275868)
		(end 41.304972 -123.284996)
		(width 0.127)
		(layer "In2.Cu")
		(net "BMC_ID_LED")
	)
	(segment
		(start 84.52104 -66.53276)
		(end 84.52104 -72.334628)
		(width 0.127)
		(layer "In2.Cu")
		(net "BMC_ID_LED")
	)
	(segment
		(start 74.6252 -110.7694)
		(end 74.455528 -110.599728)
		(width 0.127)
		(layer "In2.Cu")
		(net "BMC_ID_LED")
	)
	(segment
		(start 200.725532 1.292352)
		(end 198.859394 3.15849)
		(width 0.127)
		(layer "In2.Cu")
		(net "BMC_ID_LED")
	)
	(segment
		(start 74.455528 -110.599728)
		(end 52.044346 -110.599728)
		(width 0.127)
		(layer "In2.Cu")
		(net "BMC_ID_LED")
	)
	(segment
		(start 78.123796 -76.988162)
		(end 76.623418 -78.48854)
		(width 0.127)
		(layer "In2.Cu")
		(net "BMC_ID_LED")
	)
	(segment
		(start 119.8499 -5.120132)
		(end 89.6493 -35.320732)
		(width 0.127)
		(layer "In2.Cu")
		(net "BMC_ID_LED")
	)
	(segment
		(start 52.044092 -110.599982)
		(end 51.728624 -110.599982)
		(width 0.127)
		(layer "In2.Cu")
		(net "BMC_ID_LED")
	)
	(segment
		(start 76.623418 -78.48854)
		(end 76.623418 -78.878176)
		(width 0.127)
		(layer "In2.Cu")
		(net "BMC_ID_LED")
	)
	(segment
		(start 77.671422 -79.92618)
		(end 78.86319 -79.92618)
		(width 0.127)
		(layer "In2.Cu")
		(net "BMC_ID_LED")
	)
	(segment
		(start 84.52104 -72.334628)
		(end 79.867506 -76.988162)
		(width 0.127)
		(layer "In2.Cu")
		(net "BMC_ID_LED")
	)
	(segment
		(start 79.867506 -76.988162)
		(end 78.123796 -76.988162)
		(width 0.127)
		(layer "In2.Cu")
		(net "BMC_ID_LED")
	)
	(segment
		(start 50.26279 -109.7661)
		(end 46.377352 -109.7661)
		(width 0.127)
		(layer "In2.Cu")
		(net "BMC_ID_LED")
	)
	(segment
		(start 90.4748 -48.1838)
		(end 90.4748 -60.579)
		(width 0.127)
		(layer "In2.Cu")
		(net "BMC_ID_LED")
	)
	(segment
		(start 198.859394 3.15849)
		(end 129.044954 3.15849)
		(width 0.127)
		(layer "In2.Cu")
		(net "BMC_ID_LED")
	)
	(segment
		(start 76.623418 -78.878176)
		(end 77.671422 -79.92618)
		(width 0.127)
		(layer "In2.Cu")
		(net "BMC_ID_LED")
	)
	(segment
		(start 42.4688 -183.6801)
		(end 42.085768 -183.6801)
		(width 0.12065)
		(layer "F.Cu")
		(net "BMC_I2C9_CLKBUF2_SDA_R")
	)
	(segment
		(start 42.15892 -187.22848)
		(end 40.9067 -187.22848)
		(width 0.12065)
		(layer "F.Cu")
		(net "BMC_I2C9_CLKBUF2_SDA_R")
	)
	(segment
		(start 42.704766 -186.682634)
		(end 42.15892 -187.22848)
		(width 0.12065)
		(layer "F.Cu")
		(net "BMC_I2C9_CLKBUF2_SDA_R")
	)
	(segment
		(start 42.4688 -184.8866)
		(end 42.704766 -185.122566)
		(width 0.12065)
		(layer "F.Cu")
		(net "BMC_I2C9_CLKBUF2_SDA_R")
	)
	(segment
		(start 42.704766 -185.122566)
		(end 42.704766 -186.682634)
		(width 0.12065)
		(layer "F.Cu")
		(net "BMC_I2C9_CLKBUF2_SDA_R")
	)
	(segment
		(start 42.4688 -183.6801)
		(end 42.4688 -184.8866)
		(width 0.12065)
		(layer "F.Cu")
		(net "BMC_I2C9_CLKBUF2_SDA_R")
	)
	(segment
		(start 42.085768 -183.6801)
		(end 41.45915 -183.053482)
		(width 0.12065)
		(layer "F.Cu")
		(net "BMC_I2C9_CLKBUF2_SDA_R")
	)
	(via
		(at 41.45915 -183.053482)
		(size 0.7112)
		(drill 0.3556)
		(layers "F.Cu" "B.Cu")
		(net "BMC_I2C9_CLKBUF2_SDA_R")
	)
	(segment
		(start 42.752772 -182.507128)
		(end 42.752772 -182.020972)
		(width 0.12065)
		(layer "F.Cu")
		(net "BMC_I2C9_CLKBUF2_SDA")
	)
	(segment
		(start 42.752772 -182.020972)
		(end 42.5704 -181.8386)
		(width 0.12065)
		(layer "F.Cu")
		(net "BMC_I2C9_CLKBUF2_SDA")
	)
	(segment
		(start 42.4688 -182.7911)
		(end 42.752772 -182.507128)
		(width 0.12065)
		(layer "F.Cu")
		(net "BMC_I2C9_CLKBUF2_SDA")
	)
	(via
		(at 42.424858 -185.546746)
		(size 0.7112)
		(drill 0.3556)
		(layers "F.Cu" "B.Cu")
		(net "BMC_I2C9_CLKBUF2_SDA")
	)
	(via
		(at 42.5704 -181.8386)
		(size 0.508)
		(drill 0.254)
		(layers "F.Cu" "B.Cu")
		(net "BMC_I2C9_CLKBUF2_SDA")
	)
	(via
		(at 49.204372 -114.654076)
		(size 0.508)
		(drill 0.254)
		(layers "F.Cu" "B.Cu")
		(net "BMC_I2C9_CLKBUF2_SDA")
	)
	(segment
		(start 49.1871 -115.588288)
		(end 48.904398 -115.305586)
		(width 0.12065)
		(layer "B.Cu")
		(net "BMC_I2C9_CLKBUF2_SDA")
	)
	(segment
		(start 42.4942 -186.9567)
		(end 42.743628 -186.707272)
		(width 0.12065)
		(layer "B.Cu")
		(net "BMC_I2C9_CLKBUF2_SDA")
	)
	(segment
		(start 48.904398 -114.95405)
		(end 49.204372 -114.654076)
		(width 0.12065)
		(layer "B.Cu")
		(net "BMC_I2C9_CLKBUF2_SDA")
	)
	(segment
		(start 48.917098 -114.366802)
		(end 48.917098 -113.833402)
		(width 0.12065)
		(layer "B.Cu")
		(net "BMC_I2C9_CLKBUF2_SDA")
	)
	(segment
		(start 42.743628 -185.546746)
		(end 42.424858 -185.546746)
		(width 0.12065)
		(layer "B.Cu")
		(net "BMC_I2C9_CLKBUF2_SDA")
	)
	(segment
		(start 48.917098 -113.833402)
		(end 49.1744 -113.5761)
		(width 0.12065)
		(layer "B.Cu")
		(net "BMC_I2C9_CLKBUF2_SDA")
	)
	(segment
		(start 42.743628 -185.546746)
		(end 42.743628 -182.011828)
		(width 0.12065)
		(layer "B.Cu")
		(net "BMC_I2C9_CLKBUF2_SDA")
	)
	(segment
		(start 49.204372 -114.654076)
		(end 48.917098 -114.366802)
		(width 0.12065)
		(layer "B.Cu")
		(net "BMC_I2C9_CLKBUF2_SDA")
	)
	(segment
		(start 42.743628 -182.011828)
		(end 42.5704 -181.8386)
		(width 0.12065)
		(layer "B.Cu")
		(net "BMC_I2C9_CLKBUF2_SDA")
	)
	(segment
		(start 48.904398 -115.305586)
		(end 48.904398 -114.95405)
		(width 0.12065)
		(layer "B.Cu")
		(net "BMC_I2C9_CLKBUF2_SDA")
	)
	(segment
		(start 42.743628 -186.707272)
		(end 42.743628 -185.546746)
		(width 0.12065)
		(layer "B.Cu")
		(net "BMC_I2C9_CLKBUF2_SDA")
	)
	(segment
		(start 49.897792 -120.880886)
		(end 49.897792 -141.529562)
		(width 0.127)
		(layer "In5.Cu")
		(net "BMC_I2C9_CLKBUF2_SDA")
	)
	(segment
		(start 42.6974 -181.9656)
		(end 42.5704 -181.8386)
		(width 0.127)
		(layer "In5.Cu")
		(net "BMC_I2C9_CLKBUF2_SDA")
	)
	(segment
		(start 42.6974 -182.887366)
		(end 42.6974 -181.9656)
		(width 0.127)
		(layer "In5.Cu")
		(net "BMC_I2C9_CLKBUF2_SDA")
	)
	(segment
		(start 51.435508 -143.067278)
		(end 51.435508 -167.734742)
		(width 0.127)
		(layer "In5.Cu")
		(net "BMC_I2C9_CLKBUF2_SDA")
	)
	(segment
		(start 48.903636 -119.88673)
		(end 49.897792 -120.880886)
		(width 0.127)
		(layer "In5.Cu")
		(net "BMC_I2C9_CLKBUF2_SDA")
	)
	(segment
		(start 44.82719 -182.713376)
		(end 44.152566 -183.388)
		(width 0.127)
		(layer "In5.Cu")
		(net "BMC_I2C9_CLKBUF2_SDA")
	)
	(segment
		(start 44.152566 -183.388)
		(end 43.198034 -183.388)
		(width 0.127)
		(layer "In5.Cu")
		(net "BMC_I2C9_CLKBUF2_SDA")
	)
	(segment
		(start 49.897792 -141.529562)
		(end 51.435508 -143.067278)
		(width 0.127)
		(layer "In5.Cu")
		(net "BMC_I2C9_CLKBUF2_SDA")
	)
	(segment
		(start 49.204372 -114.654076)
		(end 48.903636 -114.954812)
		(width 0.127)
		(layer "In5.Cu")
		(net "BMC_I2C9_CLKBUF2_SDA")
	)
	(segment
		(start 51.435508 -167.734742)
		(end 44.82719 -174.34306)
		(width 0.127)
		(layer "In5.Cu")
		(net "BMC_I2C9_CLKBUF2_SDA")
	)
	(segment
		(start 44.82719 -174.34306)
		(end 44.82719 -182.713376)
		(width 0.127)
		(layer "In5.Cu")
		(net "BMC_I2C9_CLKBUF2_SDA")
	)
	(segment
		(start 48.903636 -114.954812)
		(end 48.903636 -119.88673)
		(width 0.127)
		(layer "In5.Cu")
		(net "BMC_I2C9_CLKBUF2_SDA")
	)
	(segment
		(start 43.198034 -183.388)
		(end 42.6974 -182.887366)
		(width 0.127)
		(layer "In5.Cu")
		(net "BMC_I2C9_CLKBUF2_SDA")
	)
	(segment
		(start 43.206416 -185.291984)
		(end 43.206416 -186.640216)
		(width 0.12065)
		(layer "F.Cu")
		(net "BMC_I2C9_CLKBUF2_SCL_R")
	)
	(segment
		(start 43.6118 -184.8866)
		(end 43.206416 -185.291984)
		(width 0.12065)
		(layer "F.Cu")
		(net "BMC_I2C9_CLKBUF2_SCL_R")
	)
	(segment
		(start 43.206416 -186.640216)
		(end 43.79468 -187.22848)
		(width 0.12065)
		(layer "F.Cu")
		(net "BMC_I2C9_CLKBUF2_SCL_R")
	)
	(segment
		(start 43.79468 -187.22848)
		(end 45.0469 -187.22848)
		(width 0.12065)
		(layer "F.Cu")
		(net "BMC_I2C9_CLKBUF2_SCL_R")
	)
	(segment
		(start 43.980608 -183.6801)
		(end 44.57827 -183.082438)
		(width 0.12065)
		(layer "F.Cu")
		(net "BMC_I2C9_CLKBUF2_SCL_R")
	)
	(segment
		(start 43.6118 -183.6801)
		(end 43.6118 -184.8866)
		(width 0.12065)
		(layer "F.Cu")
		(net "BMC_I2C9_CLKBUF2_SCL_R")
	)
	(segment
		(start 43.6118 -183.6801)
		(end 43.980608 -183.6801)
		(width 0.12065)
		(layer "F.Cu")
		(net "BMC_I2C9_CLKBUF2_SCL_R")
	)
	(via
		(at 44.57827 -183.082438)
		(size 0.7112)
		(drill 0.3556)
		(layers "F.Cu" "B.Cu")
		(net "BMC_I2C9_CLKBUF2_SCL_R")
	)
	(segment
		(start 43.6118 -182.7911)
		(end 43.254422 -182.433722)
		(width 0.12065)
		(layer "F.Cu")
		(net "BMC_I2C9_CLKBUF2_SCL")
	)
	(segment
		(start 43.254422 -182.433722)
		(end 43.254422 -182.018178)
		(width 0.12065)
		(layer "F.Cu")
		(net "BMC_I2C9_CLKBUF2_SCL")
	)
	(segment
		(start 43.254422 -182.018178)
		(end 43.434 -181.8386)
		(width 0.12065)
		(layer "F.Cu")
		(net "BMC_I2C9_CLKBUF2_SCL")
	)
	(via
		(at 48.102774 -114.654076)
		(size 0.508)
		(drill 0.254)
		(layers "F.Cu" "B.Cu")
		(net "BMC_I2C9_CLKBUF2_SCL")
	)
	(via
		(at 43.594274 -183.564276)
		(size 0.7112)
		(drill 0.3556)
		(layers "F.Cu" "B.Cu")
		(net "BMC_I2C9_CLKBUF2_SCL")
	)
	(via
		(at 43.434 -181.8386)
		(size 0.508)
		(drill 0.254)
		(layers "F.Cu" "B.Cu")
		(net "BMC_I2C9_CLKBUF2_SCL")
	)
	(segment
		(start 43.245278 -183.564276)
		(end 43.245278 -182.027322)
		(width 0.12065)
		(layer "B.Cu")
		(net "BMC_I2C9_CLKBUF2_SCL")
	)
	(segment
		(start 48.415448 -114.341402)
		(end 48.415448 -113.833148)
		(width 0.12065)
		(layer "B.Cu")
		(net "BMC_I2C9_CLKBUF2_SCL")
	)
	(segment
		(start 43.245278 -183.564276)
		(end 43.594274 -183.564276)
		(width 0.12065)
		(layer "B.Cu")
		(net "BMC_I2C9_CLKBUF2_SCL")
	)
	(segment
		(start 43.5102 -186.9567)
		(end 43.245278 -186.691778)
		(width 0.12065)
		(layer "B.Cu")
		(net "BMC_I2C9_CLKBUF2_SCL")
	)
	(segment
		(start 43.245278 -182.027322)
		(end 43.434 -181.8386)
		(width 0.12065)
		(layer "B.Cu")
		(net "BMC_I2C9_CLKBUF2_SCL")
	)
	(segment
		(start 43.245278 -186.691778)
		(end 43.245278 -183.564276)
		(width 0.12065)
		(layer "B.Cu")
		(net "BMC_I2C9_CLKBUF2_SCL")
	)
	(segment
		(start 48.402748 -115.35664)
		(end 48.1711 -115.588288)
		(width 0.12065)
		(layer "B.Cu")
		(net "BMC_I2C9_CLKBUF2_SCL")
	)
	(segment
		(start 48.102774 -114.654076)
		(end 48.415448 -114.341402)
		(width 0.12065)
		(layer "B.Cu")
		(net "BMC_I2C9_CLKBUF2_SCL")
	)
	(segment
		(start 48.415448 -113.833148)
		(end 48.1584 -113.5761)
		(width 0.12065)
		(layer "B.Cu")
		(net "BMC_I2C9_CLKBUF2_SCL")
	)
	(segment
		(start 48.402748 -114.95405)
		(end 48.402748 -115.35664)
		(width 0.12065)
		(layer "B.Cu")
		(net "BMC_I2C9_CLKBUF2_SCL")
	)
	(segment
		(start 48.102774 -114.654076)
		(end 48.402748 -114.95405)
		(width 0.12065)
		(layer "B.Cu")
		(net "BMC_I2C9_CLKBUF2_SCL")
	)
	(segment
		(start 43.4086 -182.88)
		(end 43.2054 -182.6768)
		(width 0.127)
		(layer "In5.Cu")
		(net "BMC_I2C9_CLKBUF2_SCL")
	)
	(segment
		(start 48.141636 -114.654076)
		(end 48.395636 -114.908076)
		(width 0.127)
		(layer "In5.Cu")
		(net "BMC_I2C9_CLKBUF2_SCL")
	)
	(segment
		(start 50.927508 -167.524176)
		(end 44.31919 -174.132494)
		(width 0.127)
		(layer "In5.Cu")
		(net "BMC_I2C9_CLKBUF2_SCL")
	)
	(segment
		(start 50.927508 -143.277844)
		(end 50.927508 -167.524176)
		(width 0.127)
		(layer "In5.Cu")
		(net "BMC_I2C9_CLKBUF2_SCL")
	)
	(segment
		(start 43.942 -182.88)
		(end 43.4086 -182.88)
		(width 0.127)
		(layer "In5.Cu")
		(net "BMC_I2C9_CLKBUF2_SCL")
	)
	(segment
		(start 44.31919 -174.132494)
		(end 44.31919 -182.50281)
		(width 0.127)
		(layer "In5.Cu")
		(net "BMC_I2C9_CLKBUF2_SCL")
	)
	(segment
		(start 49.389792 -121.091452)
		(end 49.389792 -141.740128)
		(width 0.127)
		(layer "In5.Cu")
		(net "BMC_I2C9_CLKBUF2_SCL")
	)
	(segment
		(start 49.389792 -141.740128)
		(end 50.927508 -143.277844)
		(width 0.127)
		(layer "In5.Cu")
		(net "BMC_I2C9_CLKBUF2_SCL")
	)
	(segment
		(start 44.31919 -182.50281)
		(end 43.942 -182.88)
		(width 0.127)
		(layer "In5.Cu")
		(net "BMC_I2C9_CLKBUF2_SCL")
	)
	(segment
		(start 43.2054 -182.6768)
		(end 43.2054 -182.0672)
		(width 0.127)
		(layer "In5.Cu")
		(net "BMC_I2C9_CLKBUF2_SCL")
	)
	(segment
		(start 48.102774 -114.654076)
		(end 48.141636 -114.654076)
		(width 0.127)
		(layer "In5.Cu")
		(net "BMC_I2C9_CLKBUF2_SCL")
	)
	(segment
		(start 43.2054 -182.0672)
		(end 43.434 -181.8386)
		(width 0.127)
		(layer "In5.Cu")
		(net "BMC_I2C9_CLKBUF2_SCL")
	)
	(segment
		(start 48.395636 -114.908076)
		(end 48.395636 -120.097296)
		(width 0.127)
		(layer "In5.Cu")
		(net "BMC_I2C9_CLKBUF2_SCL")
	)
	(segment
		(start 48.395636 -120.097296)
		(end 49.389792 -121.091452)
		(width 0.127)
		(layer "In5.Cu")
		(net "BMC_I2C9_CLKBUF2_SCL")
	)
	(segment
		(start 50.988468 -179.131468)
		(end 50.988468 -180.532532)
		(width 0.12065)
		(layer "F.Cu")
		(net "BMC_I2C8_CLKBUF1_SDA_R")
	)
	(segment
		(start 50.310542 -177.6095)
		(end 49.730152 -177.02911)
		(width 0.12065)
		(layer "F.Cu")
		(net "BMC_I2C8_CLKBUF1_SDA_R")
	)
	(segment
		(start 50.673 -178.816)
		(end 50.988468 -179.131468)
		(width 0.12065)
		(layer "F.Cu")
		(net "BMC_I2C8_CLKBUF1_SDA_R")
	)
	(segment
		(start 50.673 -177.6095)
		(end 50.310542 -177.6095)
		(width 0.12065)
		(layer "F.Cu")
		(net "BMC_I2C8_CLKBUF1_SDA_R")
	)
	(segment
		(start 50.673 -177.6095)
		(end 50.673 -178.816)
		(width 0.12065)
		(layer "F.Cu")
		(net "BMC_I2C8_CLKBUF1_SDA_R")
	)
	(segment
		(start 50.36312 -181.15788)
		(end 49.1109 -181.15788)
		(width 0.12065)
		(layer "F.Cu")
		(net "BMC_I2C8_CLKBUF1_SDA_R")
	)
	(segment
		(start 50.988468 -180.532532)
		(end 50.36312 -181.15788)
		(width 0.12065)
		(layer "F.Cu")
		(net "BMC_I2C8_CLKBUF1_SDA_R")
	)
	(via
		(at 49.730152 -177.02911)
		(size 0.7112)
		(drill 0.3556)
		(layers "F.Cu" "B.Cu")
		(net "BMC_I2C8_CLKBUF1_SDA_R")
	)
	(segment
		(start 206.517748 -24.800052)
		(end 206.248 -25.0698)
		(width 0.12065)
		(layer "F.Cu")
		(net "BMC_I2C8_CLKBUF1_SDA")
	)
	(segment
		(start 206.848202 -24.800052)
		(end 206.517748 -24.800052)
		(width 0.12065)
		(layer "F.Cu")
		(net "BMC_I2C8_CLKBUF1_SDA")
	)
	(segment
		(start 50.673 -176.7205)
		(end 50.974244 -176.419256)
		(width 0.12065)
		(layer "F.Cu")
		(net "BMC_I2C8_CLKBUF1_SDA")
	)
	(segment
		(start 207.274922 -25.226772)
		(end 206.848202 -24.800052)
		(width 0.12065)
		(layer "F.Cu")
		(net "BMC_I2C8_CLKBUF1_SDA")
	)
	(segment
		(start 206.248 -25.0698)
		(end 205.8289 -25.0698)
		(width 0.12065)
		(layer "F.Cu")
		(net "BMC_I2C8_CLKBUF1_SDA")
	)
	(segment
		(start 50.974244 -175.967644)
		(end 50.7746 -175.768)
		(width 0.12065)
		(layer "F.Cu")
		(net "BMC_I2C8_CLKBUF1_SDA")
	)
	(segment
		(start 50.974244 -176.419256)
		(end 50.974244 -175.967644)
		(width 0.12065)
		(layer "F.Cu")
		(net "BMC_I2C8_CLKBUF1_SDA")
	)
	(via
		(at 137.0076 -96.718374)
		(size 0.508)
		(drill 0.254)
		(layers "F.Cu" "B.Cu")
		(net "BMC_I2C8_CLKBUF1_SDA")
	)
	(via
		(at 138.677396 -66.86296)
		(size 0.508)
		(drill 0.254)
		(layers "F.Cu" "B.Cu")
		(net "BMC_I2C8_CLKBUF1_SDA")
	)
	(via
		(at 58.000138 -123.1138)
		(size 0.508)
		(drill 0.254)
		(layers "F.Cu" "B.Cu")
		(net "BMC_I2C8_CLKBUF1_SDA")
	)
	(via
		(at 50.642266 -177.469292)
		(size 0.7112)
		(drill 0.3556)
		(layers "F.Cu" "B.Cu")
		(net "BMC_I2C8_CLKBUF1_SDA")
	)
	(via
		(at 194.457066 -42.987468)
		(size 0.508)
		(drill 0.254)
		(layers "F.Cu" "B.Cu")
		(net "BMC_I2C8_CLKBUF1_SDA")
	)
	(via
		(at 207.274922 -25.226772)
		(size 0.508)
		(drill 0.254)
		(layers "F.Cu" "B.Cu")
		(net "BMC_I2C8_CLKBUF1_SDA")
	)
	(via
		(at 61.976 -97.023428)
		(size 0.508)
		(drill 0.254)
		(layers "F.Cu" "B.Cu")
		(net "BMC_I2C8_CLKBUF1_SDA")
	)
	(via
		(at 50.7746 -175.768)
		(size 0.508)
		(drill 0.254)
		(layers "F.Cu" "B.Cu")
		(net "BMC_I2C8_CLKBUF1_SDA")
	)
	(segment
		(start 54.719474 -123.104148)
		(end 54.476142 -122.860816)
		(width 0.12065)
		(layer "B.Cu")
		(net "BMC_I2C8_CLKBUF1_SDA")
	)
	(segment
		(start 50.961036 -177.469292)
		(end 50.961036 -175.99787)
		(width 0.12065)
		(layer "B.Cu")
		(net "BMC_I2C8_CLKBUF1_SDA")
	)
	(segment
		(start 57.708292 -123.405646)
		(end 55.409846 -123.405646)
		(width 0.12065)
		(layer "B.Cu")
		(net "BMC_I2C8_CLKBUF1_SDA")
	)
	(segment
		(start 137.307574 -96.4184)
		(end 137.0076 -96.718374)
		(width 0.12065)
		(layer "B.Cu")
		(net "BMC_I2C8_CLKBUF1_SDA")
	)
	(segment
		(start 138.377422 -68.353432)
		(end 139.431776 -69.407786)
		(width 0.12065)
		(layer "B.Cu")
		(net "BMC_I2C8_CLKBUF1_SDA")
	)
	(segment
		(start 58.000138 -123.1138)
		(end 58.312304 -123.425966)
		(width 0.12065)
		(layer "B.Cu")
		(net "BMC_I2C8_CLKBUF1_SDA")
	)
	(segment
		(start 206.974948 -24.926798)
		(end 207.274922 -25.226772)
		(width 0.12065)
		(layer "B.Cu")
		(net "BMC_I2C8_CLKBUF1_SDA")
	)
	(segment
		(start 55.108348 -123.104148)
		(end 54.719474 -123.104148)
		(width 0.12065)
		(layer "B.Cu")
		(net "BMC_I2C8_CLKBUF1_SDA")
	)
	(segment
		(start 50.961036 -177.469292)
		(end 50.642266 -177.469292)
		(width 0.12065)
		(layer "B.Cu")
		(net "BMC_I2C8_CLKBUF1_SDA")
	)
	(segment
		(start 50.961036 -180.750464)
		(end 50.961036 -177.469292)
		(width 0.12065)
		(layer "B.Cu")
		(net "BMC_I2C8_CLKBUF1_SDA")
	)
	(segment
		(start 58.312304 -123.425966)
		(end 58.773822 -123.425966)
		(width 0.12065)
		(layer "B.Cu")
		(net "BMC_I2C8_CLKBUF1_SDA")
	)
	(segment
		(start 50.673 -181.0385)
		(end 50.961036 -180.750464)
		(width 0.12065)
		(layer "B.Cu")
		(net "BMC_I2C8_CLKBUF1_SDA")
	)
	(segment
		(start 138.377422 -67.162934)
		(end 138.377422 -68.353432)
		(width 0.12065)
		(layer "B.Cu")
		(net "BMC_I2C8_CLKBUF1_SDA")
	)
	(segment
		(start 194.136772 -42.667174)
		(end 194.136772 -33.345628)
		(width 0.12065)
		(layer "B.Cu")
		(net "BMC_I2C8_CLKBUF1_SDA")
	)
	(segment
		(start 138.677396 -66.86296)
		(end 138.377422 -67.162934)
		(width 0.12065)
		(layer "B.Cu")
		(net "BMC_I2C8_CLKBUF1_SDA")
	)
	(segment
		(start 139.431776 -75.4761)
		(end 138.1252 -76.782676)
		(width 0.12065)
		(layer "B.Cu")
		(net "BMC_I2C8_CLKBUF1_SDA")
	)
	(segment
		(start 139.431776 -69.407786)
		(end 139.431776 -75.4761)
		(width 0.12065)
		(layer "B.Cu")
		(net "BMC_I2C8_CLKBUF1_SDA")
	)
	(segment
		(start 55.409846 -123.405646)
		(end 55.108348 -123.104148)
		(width 0.12065)
		(layer "B.Cu")
		(net "BMC_I2C8_CLKBUF1_SDA")
	)
	(segment
		(start 194.457066 -42.987468)
		(end 194.136772 -42.667174)
		(width 0.12065)
		(layer "B.Cu")
		(net "BMC_I2C8_CLKBUF1_SDA")
	)
	(segment
		(start 138.1252 -95.208852)
		(end 137.307574 -96.026478)
		(width 0.12065)
		(layer "B.Cu")
		(net "BMC_I2C8_CLKBUF1_SDA")
	)
	(segment
		(start 58.000138 -123.1138)
		(end 57.708292 -123.405646)
		(width 0.12065)
		(layer "B.Cu")
		(net "BMC_I2C8_CLKBUF1_SDA")
	)
	(segment
		(start 202.555602 -24.926798)
		(end 206.974948 -24.926798)
		(width 0.12065)
		(layer "B.Cu")
		(net "BMC_I2C8_CLKBUF1_SDA")
	)
	(segment
		(start 138.1252 -76.782676)
		(end 138.1252 -95.208852)
		(width 0.12065)
		(layer "B.Cu")
		(net "BMC_I2C8_CLKBUF1_SDA")
	)
	(segment
		(start 137.307574 -96.026478)
		(end 137.307574 -96.4184)
		(width 0.12065)
		(layer "B.Cu")
		(net "BMC_I2C8_CLKBUF1_SDA")
	)
	(segment
		(start 194.136772 -33.345628)
		(end 202.555602 -24.926798)
		(width 0.12065)
		(layer "B.Cu")
		(net "BMC_I2C8_CLKBUF1_SDA")
	)
	(segment
		(start 50.7746 -175.811434)
		(end 50.7746 -175.768)
		(width 0.12065)
		(layer "B.Cu")
		(net "BMC_I2C8_CLKBUF1_SDA")
	)
	(segment
		(start 50.961036 -175.99787)
		(end 50.7746 -175.811434)
		(width 0.12065)
		(layer "B.Cu")
		(net "BMC_I2C8_CLKBUF1_SDA")
	)
	(segment
		(start 77.645006 -98.7806)
		(end 75.587352 -96.722946)
		(width 0.127)
		(layer "In2.Cu")
		(net "BMC_I2C8_CLKBUF1_SDA")
	)
	(segment
		(start 128.1176 -104.1908)
		(end 116.4844 -104.1908)
		(width 0.127)
		(layer "In2.Cu")
		(net "BMC_I2C8_CLKBUF1_SDA")
	)
	(segment
		(start 111.0742 -98.7806)
		(end 77.645006 -98.7806)
		(width 0.127)
		(layer "In2.Cu")
		(net "BMC_I2C8_CLKBUF1_SDA")
	)
	(segment
		(start 116.4844 -104.1908)
		(end 111.0742 -98.7806)
		(width 0.127)
		(layer "In2.Cu")
		(net "BMC_I2C8_CLKBUF1_SDA")
	)
	(segment
		(start 75.587352 -96.722946)
		(end 62.276482 -96.722946)
		(width 0.127)
		(layer "In2.Cu")
		(net "BMC_I2C8_CLKBUF1_SDA")
	)
	(segment
		(start 136.783826 -96.4946)
		(end 135.8138 -96.4946)
		(width 0.127)
		(layer "In2.Cu")
		(net "BMC_I2C8_CLKBUF1_SDA")
	)
	(segment
		(start 135.8138 -96.4946)
		(end 128.1176 -104.1908)
		(width 0.127)
		(layer "In2.Cu")
		(net "BMC_I2C8_CLKBUF1_SDA")
	)
	(segment
		(start 62.276482 -96.722946)
		(end 61.976 -97.023428)
		(width 0.127)
		(layer "In2.Cu")
		(net "BMC_I2C8_CLKBUF1_SDA")
	)
	(segment
		(start 137.0076 -96.718374)
		(end 136.783826 -96.4946)
		(width 0.127)
		(layer "In2.Cu")
		(net "BMC_I2C8_CLKBUF1_SDA")
	)
	(segment
		(start 58.590688 -123.2408)
		(end 58.8264 -123.005088)
		(width 0.127)
		(layer "In5.Cu")
		(net "BMC_I2C8_CLKBUF1_SDA")
	)
	(segment
		(start 58.000138 -123.1138)
		(end 57.796938 -123.317)
		(width 0.127)
		(layer "In5.Cu")
		(net "BMC_I2C8_CLKBUF1_SDA")
	)
	(segment
		(start 56.4388 -129.281428)
		(end 56.0832 -129.637028)
		(width 0.127)
		(layer "In5.Cu")
		(net "BMC_I2C8_CLKBUF1_SDA")
	)
	(segment
		(start 56.642 -124.097034)
		(end 56.642 -126.30658)
		(width 0.127)
		(layer "In5.Cu")
		(net "BMC_I2C8_CLKBUF1_SDA")
	)
	(segment
		(start 58.495946 -122.047)
		(end 57.302146 -122.047)
		(width 0.127)
		(layer "In5.Cu")
		(net "BMC_I2C8_CLKBUF1_SDA")
	)
	(segment
		(start 55.37454 -144.329404)
		(end 55.37454 -170.245278)
		(width 0.127)
		(layer "In5.Cu")
		(net "BMC_I2C8_CLKBUF1_SDA")
	)
	(segment
		(start 56.5912 -112.743234)
		(end 62.530482 -106.803952)
		(width 0.127)
		(layer "In5.Cu")
		(net "BMC_I2C8_CLKBUF1_SDA")
	)
	(segment
		(start 58.000138 -123.1138)
		(end 58.127138 -123.2408)
		(width 0.127)
		(layer "In5.Cu")
		(net "BMC_I2C8_CLKBUF1_SDA")
	)
	(segment
		(start 62.530482 -106.803952)
		(end 62.530482 -97.230946)
		(width 0.127)
		(layer "In5.Cu")
		(net "BMC_I2C8_CLKBUF1_SDA")
	)
	(segment
		(start 62.530482 -97.230946)
		(end 62.322964 -97.023428)
		(width 0.127)
		(layer "In5.Cu")
		(net "BMC_I2C8_CLKBUF1_SDA")
	)
	(segment
		(start 55.072534 -137.979912)
		(end 56.2737 -139.181078)
		(width 0.127)
		(layer "In5.Cu")
		(net "BMC_I2C8_CLKBUF1_SDA")
	)
	(segment
		(start 56.0832 -135.721598)
		(end 55.072534 -136.732264)
		(width 0.127)
		(layer "In5.Cu")
		(net "BMC_I2C8_CLKBUF1_SDA")
	)
	(segment
		(start 139.128246 -64.319404)
		(end 139.128246 -59.484514)
		(width 0.127)
		(layer "In5.Cu")
		(net "BMC_I2C8_CLKBUF1_SDA")
	)
	(segment
		(start 164.366702 -52.723034)
		(end 164.366702 -51.10734)
		(width 0.127)
		(layer "In5.Cu")
		(net "BMC_I2C8_CLKBUF1_SDA")
	)
	(segment
		(start 56.4388 -126.50978)
		(end 56.4388 -129.281428)
		(width 0.127)
		(layer "In5.Cu")
		(net "BMC_I2C8_CLKBUF1_SDA")
	)
	(segment
		(start 163.204652 -53.885084)
		(end 164.366702 -52.723034)
		(width 0.127)
		(layer "In5.Cu")
		(net "BMC_I2C8_CLKBUF1_SDA")
	)
	(segment
		(start 50.9524 -175.5902)
		(end 50.7746 -175.768)
		(width 0.127)
		(layer "In5.Cu")
		(net "BMC_I2C8_CLKBUF1_SDA")
	)
	(segment
		(start 155.562554 -52.047648)
		(end 157.39999 -53.885084)
		(width 0.127)
		(layer "In5.Cu")
		(net "BMC_I2C8_CLKBUF1_SDA")
	)
	(segment
		(start 57.796938 -123.317)
		(end 57.422034 -123.317)
		(width 0.127)
		(layer "In5.Cu")
		(net "BMC_I2C8_CLKBUF1_SDA")
	)
	(segment
		(start 50.9524 -174.667418)
		(end 50.9524 -175.5902)
		(width 0.127)
		(layer "In5.Cu")
		(net "BMC_I2C8_CLKBUF1_SDA")
	)
	(segment
		(start 57.302146 -122.047)
		(end 56.5912 -121.336054)
		(width 0.127)
		(layer "In5.Cu")
		(net "BMC_I2C8_CLKBUF1_SDA")
	)
	(segment
		(start 56.5912 -121.336054)
		(end 56.5912 -112.743234)
		(width 0.127)
		(layer "In5.Cu")
		(net "BMC_I2C8_CLKBUF1_SDA")
	)
	(segment
		(start 146.565112 -52.047648)
		(end 155.562554 -52.047648)
		(width 0.127)
		(layer "In5.Cu")
		(net "BMC_I2C8_CLKBUF1_SDA")
	)
	(segment
		(start 58.8264 -122.377454)
		(end 58.495946 -122.047)
		(width 0.127)
		(layer "In5.Cu")
		(net "BMC_I2C8_CLKBUF1_SDA")
	)
	(segment
		(start 58.127138 -123.2408)
		(end 58.590688 -123.2408)
		(width 0.127)
		(layer "In5.Cu")
		(net "BMC_I2C8_CLKBUF1_SDA")
	)
	(segment
		(start 58.8264 -123.005088)
		(end 58.8264 -122.377454)
		(width 0.127)
		(layer "In5.Cu")
		(net "BMC_I2C8_CLKBUF1_SDA")
	)
	(segment
		(start 57.422034 -123.317)
		(end 56.642 -124.097034)
		(width 0.127)
		(layer "In5.Cu")
		(net "BMC_I2C8_CLKBUF1_SDA")
	)
	(segment
		(start 194.107308 -43.942508)
		(end 194.107308 -43.337226)
		(width 0.127)
		(layer "In5.Cu")
		(net "BMC_I2C8_CLKBUF1_SDA")
	)
	(segment
		(start 192.616836 -45.43298)
		(end 194.107308 -43.942508)
		(width 0.127)
		(layer "In5.Cu")
		(net "BMC_I2C8_CLKBUF1_SDA")
	)
	(segment
		(start 56.0832 -129.637028)
		(end 56.0832 -135.721598)
		(width 0.127)
		(layer "In5.Cu")
		(net "BMC_I2C8_CLKBUF1_SDA")
	)
	(segment
		(start 55.072534 -136.732264)
		(end 55.072534 -137.979912)
		(width 0.127)
		(layer "In5.Cu")
		(net "BMC_I2C8_CLKBUF1_SDA")
	)
	(segment
		(start 139.128246 -59.484514)
		(end 146.565112 -52.047648)
		(width 0.127)
		(layer "In5.Cu")
		(net "BMC_I2C8_CLKBUF1_SDA")
	)
	(segment
		(start 170.366944 -49.986438)
		(end 175.344836 -45.008546)
		(width 0.127)
		(layer "In5.Cu")
		(net "BMC_I2C8_CLKBUF1_SDA")
	)
	(segment
		(start 138.38047 -66.566034)
		(end 138.38047 -65.06718)
		(width 0.127)
		(layer "In5.Cu")
		(net "BMC_I2C8_CLKBUF1_SDA")
	)
	(segment
		(start 164.366702 -51.10734)
		(end 165.487604 -49.986438)
		(width 0.127)
		(layer "In5.Cu")
		(net "BMC_I2C8_CLKBUF1_SDA")
	)
	(segment
		(start 56.2737 -143.430244)
		(end 55.37454 -144.329404)
		(width 0.127)
		(layer "In5.Cu")
		(net "BMC_I2C8_CLKBUF1_SDA")
	)
	(segment
		(start 194.107308 -43.337226)
		(end 194.457066 -42.987468)
		(width 0.127)
		(layer "In5.Cu")
		(net "BMC_I2C8_CLKBUF1_SDA")
	)
	(segment
		(start 56.2737 -139.181078)
		(end 56.2737 -143.430244)
		(width 0.127)
		(layer "In5.Cu")
		(net "BMC_I2C8_CLKBUF1_SDA")
	)
	(segment
		(start 178.166014 -45.008546)
		(end 178.590448 -45.43298)
		(width 0.127)
		(layer "In5.Cu")
		(net "BMC_I2C8_CLKBUF1_SDA")
	)
	(segment
		(start 55.37454 -170.245278)
		(end 50.9524 -174.667418)
		(width 0.127)
		(layer "In5.Cu")
		(net "BMC_I2C8_CLKBUF1_SDA")
	)
	(segment
		(start 178.590448 -45.43298)
		(end 192.616836 -45.43298)
		(width 0.127)
		(layer "In5.Cu")
		(net "BMC_I2C8_CLKBUF1_SDA")
	)
	(segment
		(start 138.677396 -66.86296)
		(end 138.38047 -66.566034)
		(width 0.127)
		(layer "In5.Cu")
		(net "BMC_I2C8_CLKBUF1_SDA")
	)
	(segment
		(start 62.322964 -97.023428)
		(end 61.976 -97.023428)
		(width 0.127)
		(layer "In5.Cu")
		(net "BMC_I2C8_CLKBUF1_SDA")
	)
	(segment
		(start 157.39999 -53.885084)
		(end 163.204652 -53.885084)
		(width 0.127)
		(layer "In5.Cu")
		(net "BMC_I2C8_CLKBUF1_SDA")
	)
	(segment
		(start 138.38047 -65.06718)
		(end 139.128246 -64.319404)
		(width 0.127)
		(layer "In5.Cu")
		(net "BMC_I2C8_CLKBUF1_SDA")
	)
	(segment
		(start 56.642 -126.30658)
		(end 56.4388 -126.50978)
		(width 0.127)
		(layer "In5.Cu")
		(net "BMC_I2C8_CLKBUF1_SDA")
	)
	(segment
		(start 175.344836 -45.008546)
		(end 178.166014 -45.008546)
		(width 0.127)
		(layer "In5.Cu")
		(net "BMC_I2C8_CLKBUF1_SDA")
	)
	(segment
		(start 165.487604 -49.986438)
		(end 170.366944 -49.986438)
		(width 0.127)
		(layer "In5.Cu")
		(net "BMC_I2C8_CLKBUF1_SDA")
	)
	(segment
		(start 51.816 -177.6095)
		(end 51.816 -178.816)
		(width 0.12065)
		(layer "F.Cu")
		(net "BMC_I2C8_CLKBUF1_SCL_R")
	)
	(segment
		(start 51.816 -178.816)
		(end 51.490118 -179.141882)
		(width 0.12065)
		(layer "F.Cu")
		(net "BMC_I2C8_CLKBUF1_SCL_R")
	)
	(segment
		(start 51.490118 -180.649118)
		(end 51.99888 -181.15788)
		(width 0.12065)
		(layer "F.Cu")
		(net "BMC_I2C8_CLKBUF1_SCL_R")
	)
	(segment
		(start 51.490118 -179.141882)
		(end 51.490118 -180.649118)
		(width 0.12065)
		(layer "F.Cu")
		(net "BMC_I2C8_CLKBUF1_SCL_R")
	)
	(segment
		(start 51.816 -177.6095)
		(end 52.18049 -177.6095)
		(width 0.12065)
		(layer "F.Cu")
		(net "BMC_I2C8_CLKBUF1_SCL_R")
	)
	(segment
		(start 52.18049 -177.6095)
		(end 52.826158 -176.963832)
		(width 0.12065)
		(layer "F.Cu")
		(net "BMC_I2C8_CLKBUF1_SCL_R")
	)
	(segment
		(start 51.99888 -181.15788)
		(end 53.2511 -181.15788)
		(width 0.12065)
		(layer "F.Cu")
		(net "BMC_I2C8_CLKBUF1_SCL_R")
	)
	(via
		(at 52.826158 -176.963832)
		(size 0.7112)
		(drill 0.3556)
		(layers "F.Cu" "B.Cu")
		(net "BMC_I2C8_CLKBUF1_SCL_R")
	)
	(segment
		(start 207.101694 -24.298402)
		(end 206.517748 -24.298402)
		(width 0.12065)
		(layer "F.Cu")
		(net "BMC_I2C8_CLKBUF1_SCL")
	)
	(segment
		(start 207.274922 -24.125174)
		(end 207.101694 -24.298402)
		(width 0.12065)
		(layer "F.Cu")
		(net "BMC_I2C8_CLKBUF1_SCL")
	)
	(segment
		(start 51.475894 -175.930306)
		(end 51.6382 -175.768)
		(width 0.12065)
		(layer "F.Cu")
		(net "BMC_I2C8_CLKBUF1_SCL")
	)
	(segment
		(start 206.247746 -24.0284)
		(end 205.8289 -24.0284)
		(width 0.12065)
		(layer "F.Cu")
		(net "BMC_I2C8_CLKBUF1_SCL")
	)
	(segment
		(start 51.816 -176.7205)
		(end 51.475894 -176.380394)
		(width 0.12065)
		(layer "F.Cu")
		(net "BMC_I2C8_CLKBUF1_SCL")
	)
	(segment
		(start 51.475894 -176.380394)
		(end 51.475894 -175.930306)
		(width 0.12065)
		(layer "F.Cu")
		(net "BMC_I2C8_CLKBUF1_SCL")
	)
	(segment
		(start 206.517748 -24.298402)
		(end 206.247746 -24.0284)
		(width 0.12065)
		(layer "F.Cu")
		(net "BMC_I2C8_CLKBUF1_SCL")
	)
	(via
		(at 193.355468 -42.987468)
		(size 0.508)
		(drill 0.254)
		(layers "F.Cu" "B.Cu")
		(net "BMC_I2C8_CLKBUF1_SCL")
	)
	(via
		(at 137.575798 -66.86296)
		(size 0.508)
		(drill 0.254)
		(layers "F.Cu" "B.Cu")
		(net "BMC_I2C8_CLKBUF1_SCL")
	)
	(via
		(at 137.0076 -95.616776)
		(size 0.508)
		(drill 0.254)
		(layers "F.Cu" "B.Cu")
		(net "BMC_I2C8_CLKBUF1_SCL")
	)
	(via
		(at 51.6382 -175.768)
		(size 0.508)
		(drill 0.254)
		(layers "F.Cu" "B.Cu")
		(net "BMC_I2C8_CLKBUF1_SCL")
	)
	(via
		(at 61.976 -95.914718)
		(size 0.508)
		(drill 0.254)
		(layers "F.Cu" "B.Cu")
		(net "BMC_I2C8_CLKBUF1_SCL")
	)
	(via
		(at 51.811682 -179.451508)
		(size 0.7112)
		(drill 0.3556)
		(layers "F.Cu" "B.Cu")
		(net "BMC_I2C8_CLKBUF1_SCL")
	)
	(via
		(at 207.274922 -24.125174)
		(size 0.508)
		(drill 0.254)
		(layers "F.Cu" "B.Cu")
		(net "BMC_I2C8_CLKBUF1_SCL")
	)
	(via
		(at 57.987692 -123.9774)
		(size 0.508)
		(drill 0.254)
		(layers "F.Cu" "B.Cu")
		(net "BMC_I2C8_CLKBUF1_SCL")
	)
	(segment
		(start 51.462686 -175.935894)
		(end 51.63058 -175.768)
		(width 0.12065)
		(layer "B.Cu")
		(net "BMC_I2C8_CLKBUF1_SCL")
	)
	(segment
		(start 58.452258 -124.441966)
		(end 58.773822 -124.441966)
		(width 0.12065)
		(layer "B.Cu")
		(net "BMC_I2C8_CLKBUF1_SCL")
	)
	(segment
		(start 138.930126 -69.615812)
		(end 138.930126 -75.268074)
		(width 0.12065)
		(layer "B.Cu")
		(net "BMC_I2C8_CLKBUF1_SCL")
	)
	(segment
		(start 193.635122 -42.707814)
		(end 193.355468 -42.987468)
		(width 0.12065)
		(layer "B.Cu")
		(net "BMC_I2C8_CLKBUF1_SCL")
	)
	(segment
		(start 137.62355 -76.57465)
		(end 137.62355 -95.000826)
		(width 0.12065)
		(layer "B.Cu")
		(net "BMC_I2C8_CLKBUF1_SCL")
	)
	(segment
		(start 57.917588 -123.907296)
		(end 55.20182 -123.907296)
		(width 0.12065)
		(layer "B.Cu")
		(net "BMC_I2C8_CLKBUF1_SCL")
	)
	(segment
		(start 137.875772 -68.561458)
		(end 138.930126 -69.615812)
		(width 0.12065)
		(layer "B.Cu")
		(net "BMC_I2C8_CLKBUF1_SCL")
	)
	(segment
		(start 51.63058 -175.768)
		(end 51.6382 -175.768)
		(width 0.12065)
		(layer "B.Cu")
		(net "BMC_I2C8_CLKBUF1_SCL")
	)
	(segment
		(start 206.974948 -24.425148)
		(end 202.347576 -24.425148)
		(width 0.12065)
		(layer "B.Cu")
		(net "BMC_I2C8_CLKBUF1_SCL")
	)
	(segment
		(start 193.635122 -33.137602)
		(end 193.635122 -42.707814)
		(width 0.12065)
		(layer "B.Cu")
		(net "BMC_I2C8_CLKBUF1_SCL")
	)
	(segment
		(start 207.274922 -24.125174)
		(end 206.974948 -24.425148)
		(width 0.12065)
		(layer "B.Cu")
		(net "BMC_I2C8_CLKBUF1_SCL")
	)
	(segment
		(start 54.74716 -123.605798)
		(end 54.476142 -123.876816)
		(width 0.12065)
		(layer "B.Cu")
		(net "BMC_I2C8_CLKBUF1_SCL")
	)
	(segment
		(start 57.987692 -123.9774)
		(end 57.917588 -123.907296)
		(width 0.12065)
		(layer "B.Cu")
		(net "BMC_I2C8_CLKBUF1_SCL")
	)
	(segment
		(start 137.875772 -67.162934)
		(end 137.875772 -68.561458)
		(width 0.12065)
		(layer "B.Cu")
		(net "BMC_I2C8_CLKBUF1_SCL")
	)
	(segment
		(start 57.987692 -123.9774)
		(end 58.452258 -124.441966)
		(width 0.12065)
		(layer "B.Cu")
		(net "BMC_I2C8_CLKBUF1_SCL")
	)
	(segment
		(start 137.62355 -95.000826)
		(end 137.0076 -95.616776)
		(width 0.12065)
		(layer "B.Cu")
		(net "BMC_I2C8_CLKBUF1_SCL")
	)
	(segment
		(start 138.930126 -75.268074)
		(end 137.62355 -76.57465)
		(width 0.12065)
		(layer "B.Cu")
		(net "BMC_I2C8_CLKBUF1_SCL")
	)
	(segment
		(start 137.575798 -66.86296)
		(end 137.875772 -67.162934)
		(width 0.12065)
		(layer "B.Cu")
		(net "BMC_I2C8_CLKBUF1_SCL")
	)
	(segment
		(start 55.20182 -123.907296)
		(end 54.900322 -123.605798)
		(width 0.12065)
		(layer "B.Cu")
		(net "BMC_I2C8_CLKBUF1_SCL")
	)
	(segment
		(start 51.462686 -180.812186)
		(end 51.462686 -179.451508)
		(width 0.12065)
		(layer "B.Cu")
		(net "BMC_I2C8_CLKBUF1_SCL")
	)
	(segment
		(start 51.462686 -179.451508)
		(end 51.811682 -179.451508)
		(width 0.12065)
		(layer "B.Cu")
		(net "BMC_I2C8_CLKBUF1_SCL")
	)
	(segment
		(start 51.462686 -179.451508)
		(end 51.462686 -175.935894)
		(width 0.12065)
		(layer "B.Cu")
		(net "BMC_I2C8_CLKBUF1_SCL")
	)
	(segment
		(start 51.689 -181.0385)
		(end 51.462686 -180.812186)
		(width 0.12065)
		(layer "B.Cu")
		(net "BMC_I2C8_CLKBUF1_SCL")
	)
	(segment
		(start 54.900322 -123.605798)
		(end 54.74716 -123.605798)
		(width 0.12065)
		(layer "B.Cu")
		(net "BMC_I2C8_CLKBUF1_SCL")
	)
	(segment
		(start 202.347576 -24.425148)
		(end 193.635122 -33.137602)
		(width 0.12065)
		(layer "B.Cu")
		(net "BMC_I2C8_CLKBUF1_SCL")
	)
	(segment
		(start 111.284766 -98.2726)
		(end 77.855572 -98.2726)
		(width 0.127)
		(layer "In2.Cu")
		(net "BMC_I2C8_CLKBUF1_SCL")
	)
	(segment
		(start 116.694966 -103.6828)
		(end 111.284766 -98.2726)
		(width 0.127)
		(layer "In2.Cu")
		(net "BMC_I2C8_CLKBUF1_SCL")
	)
	(segment
		(start 75.797918 -96.214946)
		(end 62.276228 -96.214946)
		(width 0.127)
		(layer "In2.Cu")
		(net "BMC_I2C8_CLKBUF1_SCL")
	)
	(segment
		(start 137.0076 -95.616776)
		(end 136.637776 -95.9866)
		(width 0.127)
		(layer "In2.Cu")
		(net "BMC_I2C8_CLKBUF1_SCL")
	)
	(segment
		(start 62.276228 -96.214946)
		(end 61.976 -95.914718)
		(width 0.127)
		(layer "In2.Cu")
		(net "BMC_I2C8_CLKBUF1_SCL")
	)
	(segment
		(start 135.603234 -95.9866)
		(end 127.907034 -103.6828)
		(width 0.127)
		(layer "In2.Cu")
		(net "BMC_I2C8_CLKBUF1_SCL")
	)
	(segment
		(start 127.907034 -103.6828)
		(end 116.694966 -103.6828)
		(width 0.127)
		(layer "In2.Cu")
		(net "BMC_I2C8_CLKBUF1_SCL")
	)
	(segment
		(start 77.855572 -98.2726)
		(end 75.797918 -96.214946)
		(width 0.127)
		(layer "In2.Cu")
		(net "BMC_I2C8_CLKBUF1_SCL")
	)
	(segment
		(start 136.637776 -95.9866)
		(end 135.603234 -95.9866)
		(width 0.127)
		(layer "In2.Cu")
		(net "BMC_I2C8_CLKBUF1_SCL")
	)
	(segment
		(start 57.6326 -123.825)
		(end 57.15 -124.3076)
		(width 0.127)
		(layer "In5.Cu")
		(net "BMC_I2C8_CLKBUF1_SCL")
	)
	(segment
		(start 57.15 -124.3076)
		(end 57.15 -126.517146)
		(width 0.127)
		(layer "In5.Cu")
		(net "BMC_I2C8_CLKBUF1_SCL")
	)
	(segment
		(start 58.801254 -123.7488)
		(end 59.3344 -123.215654)
		(width 0.127)
		(layer "In5.Cu")
		(net "BMC_I2C8_CLKBUF1_SCL")
	)
	(segment
		(start 56.5912 -129.847594)
		(end 56.5912 -135.932164)
		(width 0.127)
		(layer "In5.Cu")
		(net "BMC_I2C8_CLKBUF1_SCL")
	)
	(segment
		(start 57.0992 -121.125488)
		(end 57.0992 -112.9538)
		(width 0.127)
		(layer "In5.Cu")
		(net "BMC_I2C8_CLKBUF1_SCL")
	)
	(segment
		(start 63.038482 -107.014518)
		(end 63.038482 -97.02038)
		(width 0.127)
		(layer "In5.Cu")
		(net "BMC_I2C8_CLKBUF1_SCL")
	)
	(segment
		(start 157.610556 -53.377084)
		(end 162.994086 -53.377084)
		(width 0.127)
		(layer "In5.Cu")
		(net "BMC_I2C8_CLKBUF1_SCL")
	)
	(segment
		(start 170.156378 -49.478438)
		(end 175.13427 -44.500546)
		(width 0.127)
		(layer "In5.Cu")
		(net "BMC_I2C8_CLKBUF1_SCL")
	)
	(segment
		(start 178.37658 -44.500546)
		(end 178.801014 -44.92498)
		(width 0.127)
		(layer "In5.Cu")
		(net "BMC_I2C8_CLKBUF1_SCL")
	)
	(segment
		(start 57.15 -126.517146)
		(end 56.9468 -126.720346)
		(width 0.127)
		(layer "In5.Cu")
		(net "BMC_I2C8_CLKBUF1_SCL")
	)
	(segment
		(start 62.359794 -96.298512)
		(end 61.976 -95.914718)
		(width 0.127)
		(layer "In5.Cu")
		(net "BMC_I2C8_CLKBUF1_SCL")
	)
	(segment
		(start 163.858702 -50.896774)
		(end 165.277038 -49.478438)
		(width 0.127)
		(layer "In5.Cu")
		(net "BMC_I2C8_CLKBUF1_SCL")
	)
	(segment
		(start 51.4604 -175.5902)
		(end 51.6382 -175.768)
		(width 0.127)
		(layer "In5.Cu")
		(net "BMC_I2C8_CLKBUF1_SCL")
	)
	(segment
		(start 178.801014 -44.92498)
		(end 192.40627 -44.92498)
		(width 0.127)
		(layer "In5.Cu")
		(net "BMC_I2C8_CLKBUF1_SCL")
	)
	(segment
		(start 55.580534 -136.94283)
		(end 55.580534 -137.769346)
		(width 0.127)
		(layer "In5.Cu")
		(net "BMC_I2C8_CLKBUF1_SCL")
	)
	(segment
		(start 175.13427 -44.500546)
		(end 178.37658 -44.500546)
		(width 0.127)
		(layer "In5.Cu")
		(net "BMC_I2C8_CLKBUF1_SCL")
	)
	(segment
		(start 55.88254 -144.53997)
		(end 55.88254 -170.455844)
		(width 0.127)
		(layer "In5.Cu")
		(net "BMC_I2C8_CLKBUF1_SCL")
	)
	(segment
		(start 137.87247 -66.566288)
		(end 137.87247 -64.856614)
		(width 0.127)
		(layer "In5.Cu")
		(net "BMC_I2C8_CLKBUF1_SCL")
	)
	(segment
		(start 137.87247 -64.856614)
		(end 138.620246 -64.108838)
		(width 0.127)
		(layer "In5.Cu")
		(net "BMC_I2C8_CLKBUF1_SCL")
	)
	(segment
		(start 55.88254 -170.455844)
		(end 51.4604 -174.877984)
		(width 0.127)
		(layer "In5.Cu")
		(net "BMC_I2C8_CLKBUF1_SCL")
	)
	(segment
		(start 56.7817 -138.970512)
		(end 56.7817 -143.64081)
		(width 0.127)
		(layer "In5.Cu")
		(net "BMC_I2C8_CLKBUF1_SCL")
	)
	(segment
		(start 146.354546 -51.539648)
		(end 155.77312 -51.539648)
		(width 0.127)
		(layer "In5.Cu")
		(net "BMC_I2C8_CLKBUF1_SCL")
	)
	(segment
		(start 58.216292 -123.7488)
		(end 58.801254 -123.7488)
		(width 0.127)
		(layer "In5.Cu")
		(net "BMC_I2C8_CLKBUF1_SCL")
	)
	(segment
		(start 56.7817 -143.64081)
		(end 55.88254 -144.53997)
		(width 0.127)
		(layer "In5.Cu")
		(net "BMC_I2C8_CLKBUF1_SCL")
	)
	(segment
		(start 63.038482 -97.02038)
		(end 62.359794 -96.341692)
		(width 0.127)
		(layer "In5.Cu")
		(net "BMC_I2C8_CLKBUF1_SCL")
	)
	(segment
		(start 58.706512 -121.539)
		(end 57.512712 -121.539)
		(width 0.127)
		(layer "In5.Cu")
		(net "BMC_I2C8_CLKBUF1_SCL")
	)
	(segment
		(start 165.277038 -49.478438)
		(end 170.156378 -49.478438)
		(width 0.127)
		(layer "In5.Cu")
		(net "BMC_I2C8_CLKBUF1_SCL")
	)
	(segment
		(start 57.835292 -123.825)
		(end 57.6326 -123.825)
		(width 0.127)
		(layer "In5.Cu")
		(net "BMC_I2C8_CLKBUF1_SCL")
	)
	(segment
		(start 59.3344 -123.215654)
		(end 59.3344 -122.166888)
		(width 0.127)
		(layer "In5.Cu")
		(net "BMC_I2C8_CLKBUF1_SCL")
	)
	(segment
		(start 59.3344 -122.166888)
		(end 58.706512 -121.539)
		(width 0.127)
		(layer "In5.Cu")
		(net "BMC_I2C8_CLKBUF1_SCL")
	)
	(segment
		(start 51.4604 -174.877984)
		(end 51.4604 -175.5902)
		(width 0.127)
		(layer "In5.Cu")
		(net "BMC_I2C8_CLKBUF1_SCL")
	)
	(segment
		(start 138.620246 -59.273948)
		(end 146.354546 -51.539648)
		(width 0.127)
		(layer "In5.Cu")
		(net "BMC_I2C8_CLKBUF1_SCL")
	)
	(segment
		(start 56.5912 -135.932164)
		(end 55.580534 -136.94283)
		(width 0.127)
		(layer "In5.Cu")
		(net "BMC_I2C8_CLKBUF1_SCL")
	)
	(segment
		(start 162.994086 -53.377084)
		(end 163.858702 -52.512468)
		(width 0.127)
		(layer "In5.Cu")
		(net "BMC_I2C8_CLKBUF1_SCL")
	)
	(segment
		(start 155.77312 -51.539648)
		(end 157.610556 -53.377084)
		(width 0.127)
		(layer "In5.Cu")
		(net "BMC_I2C8_CLKBUF1_SCL")
	)
	(segment
		(start 57.987692 -123.9774)
		(end 58.216292 -123.7488)
		(width 0.127)
		(layer "In5.Cu")
		(net "BMC_I2C8_CLKBUF1_SCL")
	)
	(segment
		(start 62.359794 -96.341692)
		(end 62.359794 -96.298512)
		(width 0.127)
		(layer "In5.Cu")
		(net "BMC_I2C8_CLKBUF1_SCL")
	)
	(segment
		(start 56.9468 -129.491994)
		(end 56.5912 -129.847594)
		(width 0.127)
		(layer "In5.Cu")
		(net "BMC_I2C8_CLKBUF1_SCL")
	)
	(segment
		(start 192.40627 -44.92498)
		(end 193.599308 -43.731942)
		(width 0.127)
		(layer "In5.Cu")
		(net "BMC_I2C8_CLKBUF1_SCL")
	)
	(segment
		(start 55.580534 -137.769346)
		(end 56.7817 -138.970512)
		(width 0.127)
		(layer "In5.Cu")
		(net "BMC_I2C8_CLKBUF1_SCL")
	)
	(segment
		(start 193.599308 -43.231308)
		(end 193.355468 -42.987468)
		(width 0.127)
		(layer "In5.Cu")
		(net "BMC_I2C8_CLKBUF1_SCL")
	)
	(segment
		(start 163.858702 -52.512468)
		(end 163.858702 -50.896774)
		(width 0.127)
		(layer "In5.Cu")
		(net "BMC_I2C8_CLKBUF1_SCL")
	)
	(segment
		(start 57.0992 -112.9538)
		(end 63.038482 -107.014518)
		(width 0.127)
		(layer "In5.Cu")
		(net "BMC_I2C8_CLKBUF1_SCL")
	)
	(segment
		(start 193.599308 -43.731942)
		(end 193.599308 -43.231308)
		(width 0.127)
		(layer "In5.Cu")
		(net "BMC_I2C8_CLKBUF1_SCL")
	)
	(segment
		(start 56.9468 -126.720346)
		(end 56.9468 -129.491994)
		(width 0.127)
		(layer "In5.Cu")
		(net "BMC_I2C8_CLKBUF1_SCL")
	)
	(segment
		(start 138.620246 -64.108838)
		(end 138.620246 -59.273948)
		(width 0.127)
		(layer "In5.Cu")
		(net "BMC_I2C8_CLKBUF1_SCL")
	)
	(segment
		(start 57.512712 -121.539)
		(end 57.0992 -121.125488)
		(width 0.127)
		(layer "In5.Cu")
		(net "BMC_I2C8_CLKBUF1_SCL")
	)
	(segment
		(start 137.575798 -66.86296)
		(end 137.87247 -66.566288)
		(width 0.127)
		(layer "In5.Cu")
		(net "BMC_I2C8_CLKBUF1_SCL")
	)
	(segment
		(start 57.987692 -123.9774)
		(end 57.835292 -123.825)
		(width 0.127)
		(layer "In5.Cu")
		(net "BMC_I2C8_CLKBUF1_SCL")
	)
	(segment
		(start 50.673 -192.913)
		(end 50.964592 -193.204592)
		(width 0.12065)
		(layer "F.Cu")
		(net "BMC_I2C7_B_DPB_SDA_R")
	)
	(segment
		(start 50.36312 -195.25488)
		(end 49.1109 -195.25488)
		(width 0.12065)
		(layer "F.Cu")
		(net "BMC_I2C7_B_DPB_SDA_R")
	)
	(segment
		(start 50.286412 -191.7065)
		(end 49.654206 -191.074294)
		(width 0.12065)
		(layer "F.Cu")
		(net "BMC_I2C7_B_DPB_SDA_R")
	)
	(segment
		(start 50.964592 -193.204592)
		(end 50.964592 -194.653408)
		(width 0.12065)
		(layer "F.Cu")
		(net "BMC_I2C7_B_DPB_SDA_R")
	)
	(segment
		(start 50.673 -191.7065)
		(end 50.673 -192.913)
		(width 0.12065)
		(layer "F.Cu")
		(net "BMC_I2C7_B_DPB_SDA_R")
	)
	(segment
		(start 50.673 -191.7065)
		(end 50.286412 -191.7065)
		(width 0.12065)
		(layer "F.Cu")
		(net "BMC_I2C7_B_DPB_SDA_R")
	)
	(segment
		(start 50.964592 -194.653408)
		(end 50.36312 -195.25488)
		(width 0.12065)
		(layer "F.Cu")
		(net "BMC_I2C7_B_DPB_SDA_R")
	)
	(via
		(at 49.654206 -191.074294)
		(size 0.7112)
		(drill 0.3556)
		(layers "F.Cu" "B.Cu")
		(net "BMC_I2C7_B_DPB_SDA_R")
	)
	(segment
		(start 54.1655 -118.11)
		(end 54.50078 -118.11)
		(width 0.12065)
		(layer "F.Cu")
		(net "BMC_I2C7_B_DPB_SDA")
	)
	(segment
		(start 50.958496 -190.048896)
		(end 50.7746 -189.865)
		(width 0.12065)
		(layer "F.Cu")
		(net "BMC_I2C7_B_DPB_SDA")
	)
	(segment
		(start 55.370476 -118.11)
		(end 54.935628 -117.675152)
		(width 0.12065)
		(layer "F.Cu")
		(net "BMC_I2C7_B_DPB_SDA")
	)
	(segment
		(start 50.673 -190.8175)
		(end 50.958496 -190.532004)
		(width 0.12065)
		(layer "F.Cu")
		(net "BMC_I2C7_B_DPB_SDA")
	)
	(segment
		(start 55.8165 -118.11)
		(end 55.370476 -118.11)
		(width 0.12065)
		(layer "F.Cu")
		(net "BMC_I2C7_B_DPB_SDA")
	)
	(segment
		(start 54.50078 -118.11)
		(end 54.935628 -117.675152)
		(width 0.12065)
		(layer "F.Cu")
		(net "BMC_I2C7_B_DPB_SDA")
	)
	(segment
		(start 50.958496 -190.532004)
		(end 50.958496 -190.048896)
		(width 0.12065)
		(layer "F.Cu")
		(net "BMC_I2C7_B_DPB_SDA")
	)
	(via
		(at 50.642012 -191.164718)
		(size 0.7112)
		(drill 0.3556)
		(layers "F.Cu" "B.Cu")
		(net "BMC_I2C7_B_DPB_SDA")
	)
	(via
		(at 54.935628 -117.675152)
		(size 0.508)
		(drill 0.254)
		(layers "F.Cu" "B.Cu")
		(net "BMC_I2C7_B_DPB_SDA")
	)
	(via
		(at 50.7746 -189.865)
		(size 0.508)
		(drill 0.254)
		(layers "F.Cu" "B.Cu")
		(net "BMC_I2C7_B_DPB_SDA")
	)
	(segment
		(start 50.673 -195.1355)
		(end 50.960782 -194.847718)
		(width 0.12065)
		(layer "B.Cu")
		(net "BMC_I2C7_B_DPB_SDA")
	)
	(segment
		(start 50.7746 -189.908434)
		(end 50.7746 -189.865)
		(width 0.12065)
		(layer "B.Cu")
		(net "BMC_I2C7_B_DPB_SDA")
	)
	(segment
		(start 50.960782 -194.847718)
		(end 50.960782 -191.164718)
		(width 0.12065)
		(layer "B.Cu")
		(net "BMC_I2C7_B_DPB_SDA")
	)
	(segment
		(start 50.960782 -190.094616)
		(end 50.7746 -189.908434)
		(width 0.12065)
		(layer "B.Cu")
		(net "BMC_I2C7_B_DPB_SDA")
	)
	(segment
		(start 50.960782 -191.164718)
		(end 50.960782 -190.094616)
		(width 0.12065)
		(layer "B.Cu")
		(net "BMC_I2C7_B_DPB_SDA")
	)
	(segment
		(start 50.960782 -191.164718)
		(end 50.642012 -191.164718)
		(width 0.12065)
		(layer "B.Cu")
		(net "BMC_I2C7_B_DPB_SDA")
	)
	(segment
		(start 50.783236 -189.1919)
		(end 50.982626 -189.39129)
		(width 0.127)
		(layer "In5.Cu")
		(net "BMC_I2C7_B_DPB_SDA")
	)
	(segment
		(start 50.369216 -189.1919)
		(end 50.783236 -189.1919)
		(width 0.127)
		(layer "In5.Cu")
		(net "BMC_I2C7_B_DPB_SDA")
	)
	(segment
		(start 50.982626 -189.39129)
		(end 50.982626 -189.656974)
		(width 0.127)
		(layer "In5.Cu")
		(net "BMC_I2C7_B_DPB_SDA")
	)
	(segment
		(start 53.90896 -139.522454)
		(end 53.90896 -170.102022)
		(width 0.127)
		(layer "In5.Cu")
		(net "BMC_I2C7_B_DPB_SDA")
	)
	(segment
		(start 54.935882 -118.012718)
		(end 54.5846 -118.364)
		(width 0.127)
		(layer "In5.Cu")
		(net "BMC_I2C7_B_DPB_SDA")
	)
	(segment
		(start 54.935628 -117.675152)
		(end 54.935882 -117.675152)
		(width 0.127)
		(layer "In5.Cu")
		(net "BMC_I2C7_B_DPB_SDA")
	)
	(segment
		(start 54.5846 -118.364)
		(end 54.120034 -118.364)
		(width 0.127)
		(layer "In5.Cu")
		(net "BMC_I2C7_B_DPB_SDA")
	)
	(segment
		(start 53.37175 -138.985244)
		(end 53.90896 -139.522454)
		(width 0.127)
		(layer "In5.Cu")
		(net "BMC_I2C7_B_DPB_SDA")
	)
	(segment
		(start 54.935882 -117.675152)
		(end 54.935882 -118.012718)
		(width 0.127)
		(layer "In5.Cu")
		(net "BMC_I2C7_B_DPB_SDA")
	)
	(segment
		(start 54.120034 -118.364)
		(end 53.37175 -119.112284)
		(width 0.127)
		(layer "In5.Cu")
		(net "BMC_I2C7_B_DPB_SDA")
	)
	(segment
		(start 53.90896 -170.102022)
		(end 49.6189 -174.392082)
		(width 0.127)
		(layer "In5.Cu")
		(net "BMC_I2C7_B_DPB_SDA")
	)
	(segment
		(start 49.6189 -174.392082)
		(end 49.6189 -188.441584)
		(width 0.127)
		(layer "In5.Cu")
		(net "BMC_I2C7_B_DPB_SDA")
	)
	(segment
		(start 53.37175 -119.112284)
		(end 53.37175 -138.985244)
		(width 0.127)
		(layer "In5.Cu")
		(net "BMC_I2C7_B_DPB_SDA")
	)
	(segment
		(start 49.6189 -188.441584)
		(end 50.369216 -189.1919)
		(width 0.127)
		(layer "In5.Cu")
		(net "BMC_I2C7_B_DPB_SDA")
	)
	(segment
		(start 50.982626 -189.656974)
		(end 50.7746 -189.865)
		(width 0.127)
		(layer "In5.Cu")
		(net "BMC_I2C7_B_DPB_SDA")
	)
	(segment
		(start 51.816 -191.7065)
		(end 52.195222 -191.7065)
		(width 0.12065)
		(layer "F.Cu")
		(net "BMC_I2C7_B_DBP_SCL_R")
	)
	(segment
		(start 51.816 -192.913)
		(end 51.466242 -193.262758)
		(width 0.12065)
		(layer "F.Cu")
		(net "BMC_I2C7_B_DBP_SCL_R")
	)
	(segment
		(start 52.195222 -191.7065)
		(end 52.814474 -191.087248)
		(width 0.12065)
		(layer "F.Cu")
		(net "BMC_I2C7_B_DBP_SCL_R")
	)
	(segment
		(start 51.466242 -193.262758)
		(end 51.466242 -194.722242)
		(width 0.12065)
		(layer "F.Cu")
		(net "BMC_I2C7_B_DBP_SCL_R")
	)
	(segment
		(start 51.466242 -194.722242)
		(end 51.99888 -195.25488)
		(width 0.12065)
		(layer "F.Cu")
		(net "BMC_I2C7_B_DBP_SCL_R")
	)
	(segment
		(start 51.99888 -195.25488)
		(end 53.2511 -195.25488)
		(width 0.12065)
		(layer "F.Cu")
		(net "BMC_I2C7_B_DBP_SCL_R")
	)
	(segment
		(start 51.816 -191.7065)
		(end 51.816 -192.913)
		(width 0.12065)
		(layer "F.Cu")
		(net "BMC_I2C7_B_DBP_SCL_R")
	)
	(via
		(at 52.814474 -191.087248)
		(size 0.7112)
		(drill 0.3556)
		(layers "F.Cu" "B.Cu")
		(net "BMC_I2C7_B_DBP_SCL_R")
	)
	(segment
		(start 54.775862 -119.126)
		(end 54.966616 -119.316754)
		(width 0.12065)
		(layer "F.Cu")
		(net "BMC_I2C7_B_DBP_SCL")
	)
	(segment
		(start 55.15737 -119.126)
		(end 55.8165 -119.126)
		(width 0.12065)
		(layer "F.Cu")
		(net "BMC_I2C7_B_DBP_SCL")
	)
	(segment
		(start 54.1655 -119.126)
		(end 54.775862 -119.126)
		(width 0.12065)
		(layer "F.Cu")
		(net "BMC_I2C7_B_DBP_SCL")
	)
	(segment
		(start 54.966616 -119.316754)
		(end 55.15737 -119.126)
		(width 0.12065)
		(layer "F.Cu")
		(net "BMC_I2C7_B_DBP_SCL")
	)
	(segment
		(start 51.460146 -190.043054)
		(end 51.6382 -189.865)
		(width 0.12065)
		(layer "F.Cu")
		(net "BMC_I2C7_B_DBP_SCL")
	)
	(segment
		(start 51.816 -190.8175)
		(end 51.460146 -190.461646)
		(width 0.12065)
		(layer "F.Cu")
		(net "BMC_I2C7_B_DBP_SCL")
	)
	(segment
		(start 51.460146 -190.461646)
		(end 51.460146 -190.043054)
		(width 0.12065)
		(layer "F.Cu")
		(net "BMC_I2C7_B_DBP_SCL")
	)
	(via
		(at 51.863244 -193.647568)
		(size 0.7112)
		(drill 0.3556)
		(layers "F.Cu" "B.Cu")
		(net "BMC_I2C7_B_DBP_SCL")
	)
	(via
		(at 51.6382 -189.865)
		(size 0.508)
		(drill 0.254)
		(layers "F.Cu" "B.Cu")
		(net "BMC_I2C7_B_DBP_SCL")
	)
	(via
		(at 54.966616 -119.316754)
		(size 0.508)
		(drill 0.254)
		(layers "F.Cu" "B.Cu")
		(net "BMC_I2C7_B_DBP_SCL")
	)
	(segment
		(start 51.689 -195.1355)
		(end 51.462432 -194.908932)
		(width 0.12065)
		(layer "B.Cu")
		(net "BMC_I2C7_B_DBP_SCL")
	)
	(segment
		(start 51.63058 -189.865)
		(end 51.6382 -189.865)
		(width 0.12065)
		(layer "B.Cu")
		(net "BMC_I2C7_B_DBP_SCL")
	)
	(segment
		(start 51.462432 -190.033148)
		(end 51.63058 -189.865)
		(width 0.12065)
		(layer "B.Cu")
		(net "BMC_I2C7_B_DBP_SCL")
	)
	(segment
		(start 51.462432 -193.647568)
		(end 51.462432 -190.033148)
		(width 0.12065)
		(layer "B.Cu")
		(net "BMC_I2C7_B_DBP_SCL")
	)
	(segment
		(start 51.462432 -193.647568)
		(end 51.863244 -193.647568)
		(width 0.12065)
		(layer "B.Cu")
		(net "BMC_I2C7_B_DBP_SCL")
	)
	(segment
		(start 51.462432 -194.908932)
		(end 51.462432 -193.647568)
		(width 0.12065)
		(layer "B.Cu")
		(net "BMC_I2C7_B_DBP_SCL")
	)
	(segment
		(start 50.1269 -174.602648)
		(end 50.1269 -188.231018)
		(width 0.127)
		(layer "In5.Cu")
		(net "BMC_I2C7_B_DBP_SCL")
	)
	(segment
		(start 54.521862 -118.872)
		(end 54.3306 -118.872)
		(width 0.127)
		(layer "In5.Cu")
		(net "BMC_I2C7_B_DBP_SCL")
	)
	(segment
		(start 50.993802 -188.6839)
		(end 51.490626 -189.180724)
		(width 0.127)
		(layer "In5.Cu")
		(net "BMC_I2C7_B_DBP_SCL")
	)
	(segment
		(start 54.966616 -119.316754)
		(end 54.521862 -118.872)
		(width 0.127)
		(layer "In5.Cu")
		(net "BMC_I2C7_B_DBP_SCL")
	)
	(segment
		(start 53.87975 -138.774678)
		(end 54.41696 -139.311888)
		(width 0.127)
		(layer "In5.Cu")
		(net "BMC_I2C7_B_DBP_SCL")
	)
	(segment
		(start 54.41696 -170.312588)
		(end 50.1269 -174.602648)
		(width 0.127)
		(layer "In5.Cu")
		(net "BMC_I2C7_B_DBP_SCL")
	)
	(segment
		(start 51.490626 -189.717426)
		(end 51.6382 -189.865)
		(width 0.127)
		(layer "In5.Cu")
		(net "BMC_I2C7_B_DBP_SCL")
	)
	(segment
		(start 51.490626 -189.180724)
		(end 51.490626 -189.717426)
		(width 0.127)
		(layer "In5.Cu")
		(net "BMC_I2C7_B_DBP_SCL")
	)
	(segment
		(start 53.87975 -119.32285)
		(end 53.87975 -138.774678)
		(width 0.127)
		(layer "In5.Cu")
		(net "BMC_I2C7_B_DBP_SCL")
	)
	(segment
		(start 50.1269 -188.231018)
		(end 50.579782 -188.6839)
		(width 0.127)
		(layer "In5.Cu")
		(net "BMC_I2C7_B_DBP_SCL")
	)
	(segment
		(start 54.3306 -118.872)
		(end 53.87975 -119.32285)
		(width 0.127)
		(layer "In5.Cu")
		(net "BMC_I2C7_B_DBP_SCL")
	)
	(segment
		(start 50.579782 -188.6839)
		(end 50.993802 -188.6839)
		(width 0.127)
		(layer "In5.Cu")
		(net "BMC_I2C7_B_DBP_SCL")
	)
	(segment
		(start 54.41696 -139.311888)
		(end 54.41696 -170.312588)
		(width 0.127)
		(layer "In5.Cu")
		(net "BMC_I2C7_B_DBP_SCL")
	)
	(segment
		(start 40.930576 -199.172576)
		(end 40.64 -198.882)
		(width 0.12065)
		(layer "F.Cu")
		(net "BMC_I2C6_C_FCB_SDA_R")
	)
	(segment
		(start 40.930576 -200.703942)
		(end 40.930576 -199.172576)
		(width 0.12065)
		(layer "F.Cu")
		(net "BMC_I2C6_C_FCB_SDA_R")
	)
	(segment
		(start 39.0779 -201.22388)
		(end 40.410638 -201.22388)
		(width 0.12065)
		(layer "F.Cu")
		(net "BMC_I2C6_C_FCB_SDA_R")
	)
	(segment
		(start 40.64 -197.6755)
		(end 40.64 -198.882)
		(width 0.12065)
		(layer "F.Cu")
		(net "BMC_I2C6_C_FCB_SDA_R")
	)
	(segment
		(start 40.282622 -197.6755)
		(end 39.656004 -197.048882)
		(width 0.12065)
		(layer "F.Cu")
		(net "BMC_I2C6_C_FCB_SDA_R")
	)
	(segment
		(start 40.410638 -201.22388)
		(end 40.930576 -200.703942)
		(width 0.12065)
		(layer "F.Cu")
		(net "BMC_I2C6_C_FCB_SDA_R")
	)
	(segment
		(start 40.64 -197.6755)
		(end 40.282622 -197.6755)
		(width 0.12065)
		(layer "F.Cu")
		(net "BMC_I2C6_C_FCB_SDA_R")
	)
	(via
		(at 39.656004 -197.048882)
		(size 0.7112)
		(drill 0.3556)
		(layers "F.Cu" "B.Cu")
		(net "BMC_I2C6_C_FCB_SDA_R")
	)
	(segment
		(start 40.64 -196.7865)
		(end 40.937942 -196.488558)
		(width 0.12065)
		(layer "F.Cu")
		(net "BMC_I2C6_C_FCB_SDA")
	)
	(segment
		(start 40.937942 -196.030342)
		(end 40.7416 -195.834)
		(width 0.12065)
		(layer "F.Cu")
		(net "BMC_I2C6_C_FCB_SDA")
	)
	(segment
		(start 40.937942 -196.488558)
		(end 40.937942 -196.030342)
		(width 0.12065)
		(layer "F.Cu")
		(net "BMC_I2C6_C_FCB_SDA")
	)
	(via
		(at 40.7416 -195.834)
		(size 0.508)
		(drill 0.254)
		(layers "F.Cu" "B.Cu")
		(net "BMC_I2C6_C_FCB_SDA")
	)
	(via
		(at 40.582596 -199.587358)
		(size 0.7112)
		(drill 0.3556)
		(layers "F.Cu" "B.Cu")
		(net "BMC_I2C6_C_FCB_SDA")
	)
	(via
		(at 62.587378 -124.154946)
		(size 0.508)
		(drill 0.254)
		(layers "F.Cu" "B.Cu")
		(net "BMC_I2C6_C_FCB_SDA")
	)
	(segment
		(start 63.4365 -124.46)
		(end 63.131446 -124.154946)
		(width 0.12065)
		(layer "B.Cu")
		(net "BMC_I2C6_C_FCB_SDA")
	)
	(segment
		(start 40.901366 -200.843134)
		(end 40.901366 -199.587358)
		(width 0.12065)
		(layer "B.Cu")
		(net "BMC_I2C6_C_FCB_SDA")
	)
	(segment
		(start 40.64 -201.1045)
		(end 40.901366 -200.843134)
		(width 0.12065)
		(layer "B.Cu")
		(net "BMC_I2C6_C_FCB_SDA")
	)
	(segment
		(start 62.090554 -124.154946)
		(end 61.7855 -124.46)
		(width 0.12065)
		(layer "B.Cu")
		(net "BMC_I2C6_C_FCB_SDA")
	)
	(segment
		(start 40.901366 -199.587358)
		(end 40.582596 -199.587358)
		(width 0.12065)
		(layer "B.Cu")
		(net "BMC_I2C6_C_FCB_SDA")
	)
	(segment
		(start 40.901366 -199.587358)
		(end 40.901366 -195.993766)
		(width 0.12065)
		(layer "B.Cu")
		(net "BMC_I2C6_C_FCB_SDA")
	)
	(segment
		(start 63.131446 -124.154946)
		(end 62.587378 -124.154946)
		(width 0.12065)
		(layer "B.Cu")
		(net "BMC_I2C6_C_FCB_SDA")
	)
	(segment
		(start 62.587378 -124.154946)
		(end 62.090554 -124.154946)
		(width 0.12065)
		(layer "B.Cu")
		(net "BMC_I2C6_C_FCB_SDA")
	)
	(segment
		(start 40.901366 -195.993766)
		(end 40.7416 -195.834)
		(width 0.12065)
		(layer "B.Cu")
		(net "BMC_I2C6_C_FCB_SDA")
	)
	(segment
		(start 62.296548 -123.864116)
		(end 61.958474 -123.864116)
		(width 0.127)
		(layer "In5.Cu")
		(net "BMC_I2C6_C_FCB_SDA")
	)
	(segment
		(start 62.027054 -132.110226)
		(end 62.0268 -132.11048)
		(width 0.127)
		(layer "In5.Cu")
		(net "BMC_I2C6_C_FCB_SDA")
	)
	(segment
		(start 62.0268 -145.976086)
		(end 59.067446 -148.93544)
		(width 0.127)
		(layer "In5.Cu")
		(net "BMC_I2C6_C_FCB_SDA")
	)
	(segment
		(start 60.2996 -129.962148)
		(end 62.027054 -131.689602)
		(width 0.127)
		(layer "In5.Cu")
		(net "BMC_I2C6_C_FCB_SDA")
	)
	(segment
		(start 62.0268 -132.11048)
		(end 62.0268 -145.976086)
		(width 0.127)
		(layer "In5.Cu")
		(net "BMC_I2C6_C_FCB_SDA")
	)
	(segment
		(start 43.709336 -197.285864)
		(end 41.495472 -197.285864)
		(width 0.127)
		(layer "In5.Cu")
		(net "BMC_I2C6_C_FCB_SDA")
	)
	(segment
		(start 50.350674 -196.3928)
		(end 44.6024 -196.3928)
		(width 0.127)
		(layer "In5.Cu")
		(net "BMC_I2C6_C_FCB_SDA")
	)
	(segment
		(start 61.1886 -124.63399)
		(end 61.1886 -125.915166)
		(width 0.127)
		(layer "In5.Cu")
		(net "BMC_I2C6_C_FCB_SDA")
	)
	(segment
		(start 62.027054 -131.689602)
		(end 62.027054 -132.110226)
		(width 0.127)
		(layer "In5.Cu")
		(net "BMC_I2C6_C_FCB_SDA")
	)
	(segment
		(start 61.1886 -125.915166)
		(end 60.2996 -126.804166)
		(width 0.127)
		(layer "In5.Cu")
		(net "BMC_I2C6_C_FCB_SDA")
	)
	(segment
		(start 60.2996 -126.804166)
		(end 60.2996 -129.962148)
		(width 0.127)
		(layer "In5.Cu")
		(net "BMC_I2C6_C_FCB_SDA")
	)
	(segment
		(start 59.067446 -171.451016)
		(end 57.531 -172.987462)
		(width 0.127)
		(layer "In5.Cu")
		(net "BMC_I2C6_C_FCB_SDA")
	)
	(segment
		(start 57.531 -189.212474)
		(end 50.350674 -196.3928)
		(width 0.127)
		(layer "In5.Cu")
		(net "BMC_I2C6_C_FCB_SDA")
	)
	(segment
		(start 59.067446 -148.93544)
		(end 59.067446 -171.451016)
		(width 0.127)
		(layer "In5.Cu")
		(net "BMC_I2C6_C_FCB_SDA")
	)
	(segment
		(start 44.6024 -196.3928)
		(end 43.709336 -197.285864)
		(width 0.127)
		(layer "In5.Cu")
		(net "BMC_I2C6_C_FCB_SDA")
	)
	(segment
		(start 40.8686 -195.961)
		(end 40.7416 -195.834)
		(width 0.127)
		(layer "In5.Cu")
		(net "BMC_I2C6_C_FCB_SDA")
	)
	(segment
		(start 40.8686 -196.658992)
		(end 40.8686 -195.961)
		(width 0.127)
		(layer "In5.Cu")
		(net "BMC_I2C6_C_FCB_SDA")
	)
	(segment
		(start 41.495472 -197.285864)
		(end 40.8686 -196.658992)
		(width 0.127)
		(layer "In5.Cu")
		(net "BMC_I2C6_C_FCB_SDA")
	)
	(segment
		(start 61.958474 -123.864116)
		(end 61.1886 -124.63399)
		(width 0.127)
		(layer "In5.Cu")
		(net "BMC_I2C6_C_FCB_SDA")
	)
	(segment
		(start 62.587378 -124.154946)
		(end 62.296548 -123.864116)
		(width 0.127)
		(layer "In5.Cu")
		(net "BMC_I2C6_C_FCB_SDA")
	)
	(segment
		(start 57.531 -172.987462)
		(end 57.531 -189.212474)
		(width 0.127)
		(layer "In5.Cu")
		(net "BMC_I2C6_C_FCB_SDA")
	)
	(segment
		(start 41.783 -197.6755)
		(end 42.23385 -197.6755)
		(width 0.12065)
		(layer "F.Cu")
		(net "BMC_I2C6_C_FCB_SCL_R")
	)
	(segment
		(start 41.432226 -199.232774)
		(end 41.432226 -200.690226)
		(width 0.12065)
		(layer "F.Cu")
		(net "BMC_I2C6_C_FCB_SCL_R")
	)
	(segment
		(start 42.23385 -197.6755)
		(end 42.933366 -196.975984)
		(width 0.12065)
		(layer "F.Cu")
		(net "BMC_I2C6_C_FCB_SCL_R")
	)
	(segment
		(start 41.783 -198.882)
		(end 41.432226 -199.232774)
		(width 0.12065)
		(layer "F.Cu")
		(net "BMC_I2C6_C_FCB_SCL_R")
	)
	(segment
		(start 41.432226 -200.690226)
		(end 41.96588 -201.22388)
		(width 0.12065)
		(layer "F.Cu")
		(net "BMC_I2C6_C_FCB_SCL_R")
	)
	(segment
		(start 41.96588 -201.22388)
		(end 43.2181 -201.22388)
		(width 0.12065)
		(layer "F.Cu")
		(net "BMC_I2C6_C_FCB_SCL_R")
	)
	(segment
		(start 41.783 -197.6755)
		(end 41.783 -198.882)
		(width 0.12065)
		(layer "F.Cu")
		(net "BMC_I2C6_C_FCB_SCL_R")
	)
	(via
		(at 42.933366 -196.975984)
		(size 0.7112)
		(drill 0.3556)
		(layers "F.Cu" "B.Cu")
		(net "BMC_I2C6_C_FCB_SCL_R")
	)
	(segment
		(start 41.783 -196.7865)
		(end 41.439592 -196.443092)
		(width 0.12065)
		(layer "F.Cu")
		(net "BMC_I2C6_C_FCB_SCL")
	)
	(segment
		(start 41.439592 -195.999608)
		(end 41.6052 -195.834)
		(width 0.12065)
		(layer "F.Cu")
		(net "BMC_I2C6_C_FCB_SCL")
	)
	(segment
		(start 41.439592 -196.443092)
		(end 41.439592 -195.999608)
		(width 0.12065)
		(layer "F.Cu")
		(net "BMC_I2C6_C_FCB_SCL")
	)
	(via
		(at 62.5602 -123.2916)
		(size 0.508)
		(drill 0.254)
		(layers "F.Cu" "B.Cu")
		(net "BMC_I2C6_C_FCB_SCL")
	)
	(via
		(at 41.6052 -195.834)
		(size 0.508)
		(drill 0.254)
		(layers "F.Cu" "B.Cu")
		(net "BMC_I2C6_C_FCB_SCL")
	)
	(via
		(at 41.752012 -197.728586)
		(size 0.7112)
		(drill 0.3556)
		(layers "F.Cu" "B.Cu")
		(net "BMC_I2C6_C_FCB_SCL")
	)
	(segment
		(start 62.5602 -123.2916)
		(end 62.4078 -123.444)
		(width 0.12065)
		(layer "B.Cu")
		(net "BMC_I2C6_C_FCB_SCL")
	)
	(segment
		(start 41.403016 -197.728586)
		(end 41.752012 -197.728586)
		(width 0.12065)
		(layer "B.Cu")
		(net "BMC_I2C6_C_FCB_SCL")
	)
	(segment
		(start 63.4365 -123.444)
		(end 62.7126 -123.444)
		(width 0.12065)
		(layer "B.Cu")
		(net "BMC_I2C6_C_FCB_SCL")
	)
	(segment
		(start 41.403016 -196.036184)
		(end 41.6052 -195.834)
		(width 0.12065)
		(layer "B.Cu")
		(net "BMC_I2C6_C_FCB_SCL")
	)
	(segment
		(start 41.656 -201.1045)
		(end 41.403016 -200.851516)
		(width 0.12065)
		(layer "B.Cu")
		(net "BMC_I2C6_C_FCB_SCL")
	)
	(segment
		(start 62.4078 -123.444)
		(end 61.7855 -123.444)
		(width 0.12065)
		(layer "B.Cu")
		(net "BMC_I2C6_C_FCB_SCL")
	)
	(segment
		(start 41.403016 -200.851516)
		(end 41.403016 -197.728586)
		(width 0.12065)
		(layer "B.Cu")
		(net "BMC_I2C6_C_FCB_SCL")
	)
	(segment
		(start 41.403016 -197.728586)
		(end 41.403016 -196.036184)
		(width 0.12065)
		(layer "B.Cu")
		(net "BMC_I2C6_C_FCB_SCL")
	)
	(segment
		(start 62.7126 -123.444)
		(end 62.5602 -123.2916)
		(width 0.12065)
		(layer "B.Cu")
		(net "BMC_I2C6_C_FCB_SCL")
	)
	(segment
		(start 44.391834 -195.8848)
		(end 43.49877 -196.777864)
		(width 0.127)
		(layer "In5.Cu")
		(net "BMC_I2C6_C_FCB_SCL")
	)
	(segment
		(start 58.559446 -171.24045)
		(end 57.023 -172.776896)
		(width 0.127)
		(layer "In5.Cu")
		(net "BMC_I2C6_C_FCB_SCL")
	)
	(segment
		(start 59.7916 -130.172714)
		(end 61.5188 -131.899914)
		(width 0.127)
		(layer "In5.Cu")
		(net "BMC_I2C6_C_FCB_SCL")
	)
	(segment
		(start 61.5188 -131.899914)
		(end 61.5188 -145.76552)
		(width 0.127)
		(layer "In5.Cu")
		(net "BMC_I2C6_C_FCB_SCL")
	)
	(segment
		(start 60.6806 -124.423424)
		(end 60.6806 -125.7046)
		(width 0.127)
		(layer "In5.Cu")
		(net "BMC_I2C6_C_FCB_SCL")
	)
	(segment
		(start 61.747908 -123.356116)
		(end 60.6806 -124.423424)
		(width 0.127)
		(layer "In5.Cu")
		(net "BMC_I2C6_C_FCB_SCL")
	)
	(segment
		(start 41.3766 -196.448426)
		(end 41.3766 -196.0626)
		(width 0.127)
		(layer "In5.Cu")
		(net "BMC_I2C6_C_FCB_SCL")
	)
	(segment
		(start 41.706038 -196.777864)
		(end 41.3766 -196.448426)
		(width 0.127)
		(layer "In5.Cu")
		(net "BMC_I2C6_C_FCB_SCL")
	)
	(segment
		(start 62.317122 -123.2916)
		(end 62.252606 -123.356116)
		(width 0.127)
		(layer "In5.Cu")
		(net "BMC_I2C6_C_FCB_SCL")
	)
	(segment
		(start 50.140108 -195.8848)
		(end 44.391834 -195.8848)
		(width 0.127)
		(layer "In5.Cu")
		(net "BMC_I2C6_C_FCB_SCL")
	)
	(segment
		(start 41.3766 -196.0626)
		(end 41.6052 -195.834)
		(width 0.127)
		(layer "In5.Cu")
		(net "BMC_I2C6_C_FCB_SCL")
	)
	(segment
		(start 62.5602 -123.2916)
		(end 62.317122 -123.2916)
		(width 0.127)
		(layer "In5.Cu")
		(net "BMC_I2C6_C_FCB_SCL")
	)
	(segment
		(start 59.7916 -126.5936)
		(end 59.7916 -130.172714)
		(width 0.127)
		(layer "In5.Cu")
		(net "BMC_I2C6_C_FCB_SCL")
	)
	(segment
		(start 62.252606 -123.356116)
		(end 61.747908 -123.356116)
		(width 0.127)
		(layer "In5.Cu")
		(net "BMC_I2C6_C_FCB_SCL")
	)
	(segment
		(start 43.49877 -196.777864)
		(end 41.706038 -196.777864)
		(width 0.127)
		(layer "In5.Cu")
		(net "BMC_I2C6_C_FCB_SCL")
	)
	(segment
		(start 57.023 -172.776896)
		(end 57.023 -189.001908)
		(width 0.127)
		(layer "In5.Cu")
		(net "BMC_I2C6_C_FCB_SCL")
	)
	(segment
		(start 58.559446 -148.724874)
		(end 58.559446 -171.24045)
		(width 0.127)
		(layer "In5.Cu")
		(net "BMC_I2C6_C_FCB_SCL")
	)
	(segment
		(start 61.5188 -145.76552)
		(end 58.559446 -148.724874)
		(width 0.127)
		(layer "In5.Cu")
		(net "BMC_I2C6_C_FCB_SCL")
	)
	(segment
		(start 57.023 -189.001908)
		(end 50.140108 -195.8848)
		(width 0.127)
		(layer "In5.Cu")
		(net "BMC_I2C6_C_FCB_SCL")
	)
	(segment
		(start 60.6806 -125.7046)
		(end 59.7916 -126.5936)
		(width 0.127)
		(layer "In5.Cu")
		(net "BMC_I2C6_C_FCB_SCL")
	)
	(segment
		(start 28.512262 -185.077862)
		(end 28.2956 -184.8612)
		(width 0.12065)
		(layer "F.Cu")
		(net "BMC_I2C5_SDA_R")
	)
	(segment
		(start 25.9334 -183.7182)
		(end 26.0731 -183.8579)
		(width 0.12065)
		(layer "F.Cu")
		(net "BMC_I2C5_SDA_R")
	)
	(segment
		(start 30.63748 -183.2991)
		(end 30.63748 -184.64276)
		(width 0.12065)
		(layer "F.Cu")
		(net "BMC_I2C5_SDA_R")
	)
	(segment
		(start 28.515564 -185.07456)
		(end 28.512262 -185.077862)
		(width 0.12065)
		(layer "F.Cu")
		(net "BMC_I2C5_SDA_R")
	)
	(segment
		(start 26.1366 -184.9247)
		(end 27.1526 -184.9247)
		(width 0.12065)
		(layer "F.Cu")
		(net "BMC_I2C5_SDA_R")
	)
	(segment
		(start 26.0731 -183.8579)
		(end 26.0731 -184.8612)
		(width 0.12065)
		(layer "F.Cu")
		(net "BMC_I2C5_SDA_R")
	)
	(segment
		(start 26.0731 -184.8612)
		(end 26.1366 -184.9247)
		(width 0.12065)
		(layer "F.Cu")
		(net "BMC_I2C5_SDA_R")
	)
	(segment
		(start 30.63748 -184.64276)
		(end 30.20568 -185.07456)
		(width 0.12065)
		(layer "F.Cu")
		(net "BMC_I2C5_SDA_R")
	)
	(segment
		(start 27.1526 -184.9247)
		(end 27.2161 -184.8612)
		(width 0.12065)
		(layer "F.Cu")
		(net "BMC_I2C5_SDA_R")
	)
	(segment
		(start 27.2161 -184.8612)
		(end 28.2956 -184.8612)
		(width 0.12065)
		(layer "F.Cu")
		(net "BMC_I2C5_SDA_R")
	)
	(segment
		(start 30.20568 -185.07456)
		(end 28.515564 -185.07456)
		(width 0.12065)
		(layer "F.Cu")
		(net "BMC_I2C5_SDA_R")
	)
	(via
		(at 25.9334 -183.7182)
		(size 0.7112)
		(drill 0.3556)
		(layers "F.Cu" "B.Cu")
		(net "BMC_I2C5_SDA_R")
	)
	(segment
		(start 27.2161 -186.0042)
		(end 27.1526 -185.9407)
		(width 0.12065)
		(layer "F.Cu")
		(net "BMC_I2C5_SCL_R")
	)
	(segment
		(start 30.63748 -186.019186)
		(end 30.63748 -187.4393)
		(width 0.12065)
		(layer "F.Cu")
		(net "BMC_I2C5_SCL_R")
	)
	(segment
		(start 26.0858 -186.0169)
		(end 26.0731 -186.0042)
		(width 0.12065)
		(layer "F.Cu")
		(net "BMC_I2C5_SCL_R")
	)
	(segment
		(start 28.72359 -185.57621)
		(end 30.194504 -185.57621)
		(width 0.12065)
		(layer "F.Cu")
		(net "BMC_I2C5_SCL_R")
	)
	(segment
		(start 26.0858 -187.0202)
		(end 26.0858 -186.0169)
		(width 0.12065)
		(layer "F.Cu")
		(net "BMC_I2C5_SCL_R")
	)
	(segment
		(start 26.0731 -186.0042)
		(end 26.1366 -185.9407)
		(width 0.12065)
		(layer "F.Cu")
		(net "BMC_I2C5_SCL_R")
	)
	(segment
		(start 28.2956 -186.0042)
		(end 27.2161 -186.0042)
		(width 0.12065)
		(layer "F.Cu")
		(net "BMC_I2C5_SCL_R")
	)
	(segment
		(start 25.8572 -187.2488)
		(end 26.0858 -187.0202)
		(width 0.12065)
		(layer "F.Cu")
		(net "BMC_I2C5_SCL_R")
	)
	(segment
		(start 28.2956 -186.0042)
		(end 28.72359 -185.57621)
		(width 0.12065)
		(layer "F.Cu")
		(net "BMC_I2C5_SCL_R")
	)
	(segment
		(start 30.194504 -185.57621)
		(end 30.63748 -186.019186)
		(width 0.12065)
		(layer "F.Cu")
		(net "BMC_I2C5_SCL_R")
	)
	(segment
		(start 26.1366 -185.9407)
		(end 27.1526 -185.9407)
		(width 0.12065)
		(layer "F.Cu")
		(net "BMC_I2C5_SCL_R")
	)
	(via
		(at 25.8572 -187.2488)
		(size 0.7112)
		(drill 0.3556)
		(layers "F.Cu" "B.Cu")
		(net "BMC_I2C5_SCL_R")
	)
	(segment
		(start 159.211772 -84.497672)
		(end 159.211772 -83.967828)
		(width 0.12065)
		(layer "F.Cu")
		(net "BMC_I2C5_D_PEB_SDA")
	)
	(segment
		(start 5.361432 -186.109102)
		(end 5.38353 -186.1312)
		(width 0.12065)
		(layer "F.Cu")
		(net "BMC_I2C5_D_PEB_SDA")
	)
	(segment
		(start 214.58936 -84.39785)
		(end 177.246026 -84.39785)
		(width 0.12065)
		(layer "F.Cu")
		(net "BMC_I2C5_D_PEB_SDA")
	)
	(segment
		(start 159.211772 -83.967828)
		(end 159.385 -83.7946)
		(width 0.12065)
		(layer "F.Cu")
		(net "BMC_I2C5_D_PEB_SDA")
	)
	(segment
		(start 226.314 -77.6859)
		(end 226.67468 -77.32522)
		(width 0.12065)
		(layer "F.Cu")
		(net "BMC_I2C5_D_PEB_SDA")
	)
	(segment
		(start 5.6642 -186.1312)
		(end 5.8166 -186.2836)
		(width 0.12065)
		(layer "F.Cu")
		(net "BMC_I2C5_D_PEB_SDA")
	)
	(segment
		(start 5.38353 -186.1312)
		(end 5.6642 -186.1312)
		(width 0.12065)
		(layer "F.Cu")
		(net "BMC_I2C5_D_PEB_SDA")
	)
	(segment
		(start 250.324874 -5.872734)
		(end 250.292362 -5.840222)
		(width 0.12065)
		(layer "F.Cu")
		(net "BMC_I2C5_D_PEB_SDA")
	)
	(segment
		(start 25.1841 -184.8612)
		(end 24.902922 -185.142378)
		(width 0.12065)
		(layer "F.Cu")
		(net "BMC_I2C5_D_PEB_SDA")
	)
	(segment
		(start 59.3725 -148.844)
		(end 59.64047 -149.11197)
		(width 0.12065)
		(layer "F.Cu")
		(net "BMC_I2C5_D_PEB_SDA")
	)
	(segment
		(start 122.112786 -86.116414)
		(end 121.647966 -86.116414)
		(width 0.12065)
		(layer "F.Cu")
		(net "BMC_I2C5_D_PEB_SDA")
	)
	(segment
		(start 159.19831 -81.388458)
		(end 159.19831 -83.60791)
		(width 0.12065)
		(layer "F.Cu")
		(net "BMC_I2C5_D_PEB_SDA")
	)
	(segment
		(start 160.710118 -79.87665)
		(end 159.19831 -81.388458)
		(width 0.12065)
		(layer "F.Cu")
		(net "BMC_I2C5_D_PEB_SDA")
	)
	(segment
		(start 65.003934 -149.608032)
		(end 65.382902 -149.987)
		(width 0.12065)
		(layer "F.Cu")
		(net "BMC_I2C5_D_PEB_SDA")
	)
	(segment
		(start 64.547242 -148.844)
		(end 65.003934 -149.300692)
		(width 0.12065)
		(layer "F.Cu")
		(net "BMC_I2C5_D_PEB_SDA")
	)
	(segment
		(start 24.902922 -185.142378)
		(end 24.411178 -185.142378)
		(width 0.12065)
		(layer "F.Cu")
		(net "BMC_I2C5_D_PEB_SDA")
	)
	(segment
		(start 5.8166 -186.2836)
		(end 6.3627 -186.2836)
		(width 0.12065)
		(layer "F.Cu")
		(net "BMC_I2C5_D_PEB_SDA")
	)
	(segment
		(start 120.336056 -84.804504)
		(end 120.303798 -84.804504)
		(width 0.12065)
		(layer "F.Cu")
		(net "BMC_I2C5_D_PEB_SDA")
	)
	(segment
		(start 226.685602 -77.314298)
		(end 226.685602 -76.76388)
		(width 0.12065)
		(layer "F.Cu")
		(net "BMC_I2C5_D_PEB_SDA")
	)
	(segment
		(start 121.647966 -86.116414)
		(end 120.336056 -84.804504)
		(width 0.12065)
		(layer "F.Cu")
		(net "BMC_I2C5_D_PEB_SDA")
	)
	(segment
		(start 24.411178 -185.142378)
		(end 24.2316 -184.9628)
		(width 0.12065)
		(layer "F.Cu")
		(net "BMC_I2C5_D_PEB_SDA")
	)
	(segment
		(start 62.624462 -149.11197)
		(end 62.892432 -148.844)
		(width 0.12065)
		(layer "F.Cu")
		(net "BMC_I2C5_D_PEB_SDA")
	)
	(segment
		(start 222.56496 -76.42225)
		(end 214.58936 -84.39785)
		(width 0.12065)
		(layer "F.Cu")
		(net "BMC_I2C5_D_PEB_SDA")
	)
	(segment
		(start 177.246026 -84.39785)
		(end 172.724826 -79.87665)
		(width 0.12065)
		(layer "F.Cu")
		(net "BMC_I2C5_D_PEB_SDA")
	)
	(segment
		(start 226.67468 -77.324966)
		(end 226.685602 -77.314298)
		(width 0.12065)
		(layer "F.Cu")
		(net "BMC_I2C5_D_PEB_SDA")
	)
	(segment
		(start 226.67468 -77.32522)
		(end 226.67468 -77.324966)
		(width 0.12065)
		(layer "F.Cu")
		(net "BMC_I2C5_D_PEB_SDA")
	)
	(segment
		(start 65.003934 -149.300692)
		(end 65.003934 -149.608032)
		(width 0.12065)
		(layer "F.Cu")
		(net "BMC_I2C5_D_PEB_SDA")
	)
	(segment
		(start 159.19831 -83.60791)
		(end 159.385 -83.7946)
		(width 0.12065)
		(layer "F.Cu")
		(net "BMC_I2C5_D_PEB_SDA")
	)
	(segment
		(start 59.64047 -149.11197)
		(end 62.624462 -149.11197)
		(width 0.12065)
		(layer "F.Cu")
		(net "BMC_I2C5_D_PEB_SDA")
	)
	(segment
		(start 226.685602 -76.76388)
		(end 226.343972 -76.42225)
		(width 0.12065)
		(layer "F.Cu")
		(net "BMC_I2C5_D_PEB_SDA")
	)
	(segment
		(start 62.892432 -148.844)
		(end 64.547242 -148.844)
		(width 0.12065)
		(layer "F.Cu")
		(net "BMC_I2C5_D_PEB_SDA")
	)
	(segment
		(start 172.724826 -79.87665)
		(end 160.710118 -79.87665)
		(width 0.12065)
		(layer "F.Cu")
		(net "BMC_I2C5_D_PEB_SDA")
	)
	(segment
		(start 226.343972 -76.42225)
		(end 222.56496 -76.42225)
		(width 0.12065)
		(layer "F.Cu")
		(net "BMC_I2C5_D_PEB_SDA")
	)
	(segment
		(start 251.236226 -5.872734)
		(end 250.324874 -5.872734)
		(width 0.12065)
		(layer "F.Cu")
		(net "BMC_I2C5_D_PEB_SDA")
	)
	(segment
		(start 159.512 -84.7979)
		(end 159.211772 -84.497672)
		(width 0.12065)
		(layer "F.Cu")
		(net "BMC_I2C5_D_PEB_SDA")
	)
	(via
		(at 5.361432 -186.109102)
		(size 0.508)
		(drill 0.254)
		(layers "F.Cu" "B.Cu")
		(net "BMC_I2C5_D_PEB_SDA")
	)
	(via
		(at 65.382902 -149.987)
		(size 0.508)
		(drill 0.254)
		(layers "F.Cu" "B.Cu")
		(net "BMC_I2C5_D_PEB_SDA")
	)
	(via
		(at 120.303798 -84.804504)
		(size 0.508)
		(drill 0.254)
		(layers "F.Cu" "B.Cu")
		(net "BMC_I2C5_D_PEB_SDA")
	)
	(via
		(at 107.410504 -51.86553)
		(size 0.508)
		(drill 0.254)
		(layers "F.Cu" "B.Cu")
		(net "BMC_I2C5_D_PEB_SDA")
	)
	(via
		(at 26.3652 -184.8358)
		(size 0.7112)
		(drill 0.3556)
		(layers "F.Cu" "B.Cu")
		(net "BMC_I2C5_D_PEB_SDA")
	)
	(via
		(at 159.385 -83.7946)
		(size 0.508)
		(drill 0.254)
		(layers "F.Cu" "B.Cu")
		(net "BMC_I2C5_D_PEB_SDA")
	)
	(via
		(at 24.2316 -184.9628)
		(size 0.508)
		(drill 0.254)
		(layers "F.Cu" "B.Cu")
		(net "BMC_I2C5_D_PEB_SDA")
	)
	(via
		(at 250.292362 -5.840222)
		(size 0.508)
		(drill 0.254)
		(layers "F.Cu" "B.Cu")
		(net "BMC_I2C5_D_PEB_SDA")
	)
	(via
		(at 81.534 -133.858)
		(size 0.508)
		(drill 0.254)
		(layers "F.Cu" "B.Cu")
		(net "BMC_I2C5_D_PEB_SDA")
	)
	(via
		(at 79.9846 -139.192)
		(size 0.508)
		(drill 0.254)
		(layers "F.Cu" "B.Cu")
		(net "BMC_I2C5_D_PEB_SDA")
	)
	(segment
		(start 254.81788 -6.239002)
		(end 253.13894 -6.239002)
		(width 0.12065)
		(layer "B.Cu")
		(net "BMC_I2C5_D_PEB_SDA")
	)
	(segment
		(start 252.925072 -6.025134)
		(end 250.477274 -6.025134)
		(width 0.12065)
		(layer "B.Cu")
		(net "BMC_I2C5_D_PEB_SDA")
	)
	(segment
		(start 79.841598 -138.06932)
		(end 79.841598 -139.048998)
		(width 0.12065)
		(layer "B.Cu")
		(net "BMC_I2C5_D_PEB_SDA")
	)
	(segment
		(start 26.3652 -185.181748)
		(end 24.450548 -185.181748)
		(width 0.12065)
		(layer "B.Cu")
		(net "BMC_I2C5_D_PEB_SDA")
	)
	(segment
		(start 81.870042 -134.19455)
		(end 82.12328 -134.19455)
		(width 0.12065)
		(layer "B.Cu")
		(net "BMC_I2C5_D_PEB_SDA")
	)
	(segment
		(start 27.225752 -185.181748)
		(end 26.3652 -185.181748)
		(width 0.12065)
		(layer "B.Cu")
		(net "BMC_I2C5_D_PEB_SDA")
	)
	(segment
		(start 82.118962 -137.805668)
		(end 80.10525 -137.805668)
		(width 0.12065)
		(layer "B.Cu")
		(net "BMC_I2C5_D_PEB_SDA")
	)
	(segment
		(start 66.1035 -150.622)
		(end 65.998852 -150.622)
		(width 0.12065)
		(layer "B.Cu")
		(net "BMC_I2C5_D_PEB_SDA")
	)
	(segment
		(start 250.477274 -6.025134)
		(end 250.292362 -5.840222)
		(width 0.12065)
		(layer "B.Cu")
		(net "BMC_I2C5_D_PEB_SDA")
	)
	(segment
		(start 65.998852 -150.622)
		(end 65.382902 -150.00605)
		(width 0.12065)
		(layer "B.Cu")
		(net "BMC_I2C5_D_PEB_SDA")
	)
	(segment
		(start 81.534 -133.858)
		(end 81.534 -133.858508)
		(width 0.12065)
		(layer "B.Cu")
		(net "BMC_I2C5_D_PEB_SDA")
	)
	(segment
		(start 83.043776 -136.880854)
		(end 82.118962 -137.805668)
		(width 0.12065)
		(layer "B.Cu")
		(net "BMC_I2C5_D_PEB_SDA")
	)
	(segment
		(start 26.3652 -185.181748)
		(end 26.3652 -184.8358)
		(width 0.12065)
		(layer "B.Cu")
		(net "BMC_I2C5_D_PEB_SDA")
	)
	(segment
		(start 253.13894 -6.239002)
		(end 252.925072 -6.025134)
		(width 0.12065)
		(layer "B.Cu")
		(net "BMC_I2C5_D_PEB_SDA")
	)
	(segment
		(start 65.382902 -150.00605)
		(end 65.382902 -149.987)
		(width 0.12065)
		(layer "B.Cu")
		(net "BMC_I2C5_D_PEB_SDA")
	)
	(segment
		(start 79.841598 -139.048998)
		(end 79.9846 -139.192)
		(width 0.12065)
		(layer "B.Cu")
		(net "BMC_I2C5_D_PEB_SDA")
	)
	(segment
		(start 24.450548 -185.181748)
		(end 24.2316 -184.9628)
		(width 0.12065)
		(layer "B.Cu")
		(net "BMC_I2C5_D_PEB_SDA")
	)
	(segment
		(start 83.043776 -135.115046)
		(end 83.043776 -136.880854)
		(width 0.12065)
		(layer "B.Cu")
		(net "BMC_I2C5_D_PEB_SDA")
	)
	(segment
		(start 80.10525 -137.805668)
		(end 79.841598 -138.06932)
		(width 0.12065)
		(layer "B.Cu")
		(net "BMC_I2C5_D_PEB_SDA")
	)
	(segment
		(start 82.12328 -134.19455)
		(end 83.043776 -135.115046)
		(width 0.12065)
		(layer "B.Cu")
		(net "BMC_I2C5_D_PEB_SDA")
	)
	(segment
		(start 81.534 -133.858508)
		(end 81.870042 -134.19455)
		(width 0.12065)
		(layer "B.Cu")
		(net "BMC_I2C5_D_PEB_SDA")
	)
	(segment
		(start 27.5209 -184.8866)
		(end 27.225752 -185.181748)
		(width 0.12065)
		(layer "B.Cu")
		(net "BMC_I2C5_D_PEB_SDA")
	)
	(segment
		(start 255.061212 -5.99567)
		(end 254.81788 -6.239002)
		(width 0.12065)
		(layer "B.Cu")
		(net "BMC_I2C5_D_PEB_SDA")
	)
	(segment
		(start 64.400938 -148.651722)
		(end 63.287148 -148.651722)
		(width 0.127)
		(layer "In2.Cu")
		(net "BMC_I2C5_D_PEB_SDA")
	)
	(segment
		(start 77.7748 -150.669752)
		(end 77.7748 -138.923776)
		(width 0.127)
		(layer "In2.Cu")
		(net "BMC_I2C5_D_PEB_SDA")
	)
	(segment
		(start 37.479224 -170.265598)
		(end 25.32888 -182.415942)
		(width 0.127)
		(layer "In2.Cu")
		(net "BMC_I2C5_D_PEB_SDA")
	)
	(segment
		(start 110.460282 -72.106536)
		(end 120.468136 -82.11439)
		(width 0.127)
		(layer "In2.Cu")
		(net "BMC_I2C5_D_PEB_SDA")
	)
	(segment
		(start 65.382902 -149.987)
		(end 64.980312 -149.58441)
		(width 0.127)
		(layer "In2.Cu")
		(net "BMC_I2C5_D_PEB_SDA")
	)
	(segment
		(start 79.25943 -138.44651)
		(end 79.556864 -138.743944)
		(width 0.127)
		(layer "In2.Cu")
		(net "BMC_I2C5_D_PEB_SDA")
	)
	(segment
		(start 79.556864 -138.764264)
		(end 79.9846 -139.192)
		(width 0.127)
		(layer "In2.Cu")
		(net "BMC_I2C5_D_PEB_SDA")
	)
	(segment
		(start 65.382902 -149.987)
		(end 65.09766 -150.272242)
		(width 0.127)
		(layer "In2.Cu")
		(net "BMC_I2C5_D_PEB_SDA")
	)
	(segment
		(start 79.556864 -138.743944)
		(end 79.556864 -138.764264)
		(width 0.127)
		(layer "In2.Cu")
		(net "BMC_I2C5_D_PEB_SDA")
	)
	(segment
		(start 50.601118 -170.265598)
		(end 37.479224 -170.265598)
		(width 0.127)
		(layer "In2.Cu")
		(net "BMC_I2C5_D_PEB_SDA")
	)
	(segment
		(start 120.468136 -84.640166)
		(end 120.303798 -84.804504)
		(width 0.127)
		(layer "In2.Cu")
		(net "BMC_I2C5_D_PEB_SDA")
	)
	(segment
		(start 65.09766 -150.272242)
		(end 65.09766 -151.61006)
		(width 0.127)
		(layer "In2.Cu")
		(net "BMC_I2C5_D_PEB_SDA")
	)
	(segment
		(start 62.74689 -155.81503)
		(end 61.495178 -157.066742)
		(width 0.127)
		(layer "In2.Cu")
		(net "BMC_I2C5_D_PEB_SDA")
	)
	(segment
		(start 64.980312 -149.231096)
		(end 64.400938 -148.651722)
		(width 0.127)
		(layer "In2.Cu")
		(net "BMC_I2C5_D_PEB_SDA")
	)
	(segment
		(start 24.317706 -185.048906)
		(end 24.2316 -184.9628)
		(width 0.127)
		(layer "In2.Cu")
		(net "BMC_I2C5_D_PEB_SDA")
	)
	(segment
		(start 65.7098 -152.2222)
		(end 76.222352 -152.2222)
		(width 0.127)
		(layer "In2.Cu")
		(net "BMC_I2C5_D_PEB_SDA")
	)
	(segment
		(start 61.495178 -159.371538)
		(end 50.601118 -170.265598)
		(width 0.127)
		(layer "In2.Cu")
		(net "BMC_I2C5_D_PEB_SDA")
	)
	(segment
		(start 110.460282 -53.06822)
		(end 110.460282 -72.106536)
		(width 0.127)
		(layer "In2.Cu")
		(net "BMC_I2C5_D_PEB_SDA")
	)
	(segment
		(start 78.252066 -138.44651)
		(end 79.25943 -138.44651)
		(width 0.127)
		(layer "In2.Cu")
		(net "BMC_I2C5_D_PEB_SDA")
	)
	(segment
		(start 120.468136 -82.11439)
		(end 120.468136 -84.640166)
		(width 0.127)
		(layer "In2.Cu")
		(net "BMC_I2C5_D_PEB_SDA")
	)
	(segment
		(start 24.925528 -185.048906)
		(end 24.317706 -185.048906)
		(width 0.127)
		(layer "In2.Cu")
		(net "BMC_I2C5_D_PEB_SDA")
	)
	(segment
		(start 108.947966 -51.555904)
		(end 110.460282 -53.06822)
		(width 0.127)
		(layer "In2.Cu")
		(net "BMC_I2C5_D_PEB_SDA")
	)
	(segment
		(start 63.287148 -148.651722)
		(end 62.74689 -149.19198)
		(width 0.127)
		(layer "In2.Cu")
		(net "BMC_I2C5_D_PEB_SDA")
	)
	(segment
		(start 77.7748 -138.923776)
		(end 78.252066 -138.44651)
		(width 0.127)
		(layer "In2.Cu")
		(net "BMC_I2C5_D_PEB_SDA")
	)
	(segment
		(start 107.719114 -51.555904)
		(end 108.947966 -51.555904)
		(width 0.127)
		(layer "In2.Cu")
		(net "BMC_I2C5_D_PEB_SDA")
	)
	(segment
		(start 25.32888 -182.415942)
		(end 25.32888 -184.645554)
		(width 0.127)
		(layer "In2.Cu")
		(net "BMC_I2C5_D_PEB_SDA")
	)
	(segment
		(start 65.09766 -151.61006)
		(end 65.7098 -152.2222)
		(width 0.127)
		(layer "In2.Cu")
		(net "BMC_I2C5_D_PEB_SDA")
	)
	(segment
		(start 62.74689 -149.19198)
		(end 62.74689 -155.81503)
		(width 0.127)
		(layer "In2.Cu")
		(net "BMC_I2C5_D_PEB_SDA")
	)
	(segment
		(start 107.410504 -51.86553)
		(end 107.410504 -51.864514)
		(width 0.127)
		(layer "In2.Cu")
		(net "BMC_I2C5_D_PEB_SDA")
	)
	(segment
		(start 107.410504 -51.864514)
		(end 107.719114 -51.555904)
		(width 0.127)
		(layer "In2.Cu")
		(net "BMC_I2C5_D_PEB_SDA")
	)
	(segment
		(start 64.980312 -149.58441)
		(end 64.980312 -149.231096)
		(width 0.127)
		(layer "In2.Cu")
		(net "BMC_I2C5_D_PEB_SDA")
	)
	(segment
		(start 61.495178 -157.066742)
		(end 61.495178 -159.371538)
		(width 0.127)
		(layer "In2.Cu")
		(net "BMC_I2C5_D_PEB_SDA")
	)
	(segment
		(start 76.222352 -152.2222)
		(end 77.7748 -150.669752)
		(width 0.127)
		(layer "In2.Cu")
		(net "BMC_I2C5_D_PEB_SDA")
	)
	(segment
		(start 25.32888 -184.645554)
		(end 24.925528 -185.048906)
		(width 0.127)
		(layer "In2.Cu")
		(net "BMC_I2C5_D_PEB_SDA")
	)
	(segment
		(start 179.222908 -4.27482)
		(end 177.339498 -2.39141)
		(width 0.127)
		(layer "In5.Cu")
		(net "BMC_I2C5_D_PEB_SDA")
	)
	(segment
		(start 207.347312 -5.5626)
		(end 189.375288 -5.5626)
		(width 0.127)
		(layer "In5.Cu")
		(net "BMC_I2C5_D_PEB_SDA")
	)
	(segment
		(start 250.292362 -5.840222)
		(end 250.218448 -5.766308)
		(width 0.127)
		(layer "In5.Cu")
		(net "BMC_I2C5_D_PEB_SDA")
	)
	(segment
		(start 120.485662 -86.345014)
		(end 120.485662 -84.986368)
		(width 0.127)
		(layer "In5.Cu")
		(net "BMC_I2C5_D_PEB_SDA")
	)
	(segment
		(start 133.077966 -2.39141)
		(end 132.26161 -3.207766)
		(width 0.127)
		(layer "In5.Cu")
		(net "BMC_I2C5_D_PEB_SDA")
	)
	(segment
		(start 250.218448 -5.766308)
		(end 249.579892 -5.766308)
		(width 0.127)
		(layer "In5.Cu")
		(net "BMC_I2C5_D_PEB_SDA")
	)
	(segment
		(start 120.895618 -83.265264)
		(end 125.423676 -83.265264)
		(width 0.127)
		(layer "In5.Cu")
		(net "BMC_I2C5_D_PEB_SDA")
	)
	(segment
		(start 246.133112 -5.9944)
		(end 244.971824 -4.833112)
		(width 0.127)
		(layer "In5.Cu")
		(net "BMC_I2C5_D_PEB_SDA")
	)
	(segment
		(start 81.534 -133.858)
		(end 81.808066 -134.132066)
		(width 0.127)
		(layer "In5.Cu")
		(net "BMC_I2C5_D_PEB_SDA")
	)
	(segment
		(start 81.808066 -134.132066)
		(end 85.432392 -134.132066)
		(width 0.127)
		(layer "In5.Cu")
		(net "BMC_I2C5_D_PEB_SDA")
	)
	(segment
		(start 218.534996 -1.9558)
		(end 216.488518 -1.9558)
		(width 0.127)
		(layer "In5.Cu")
		(net "BMC_I2C5_D_PEB_SDA")
	)
	(segment
		(start 120.38076 -84.35086)
		(end 120.377712 -83.785964)
		(width 0.127)
		(layer "In5.Cu")
		(net "BMC_I2C5_D_PEB_SDA")
	)
	(segment
		(start 249.579892 -5.766308)
		(end 249.3518 -5.9944)
		(width 0.127)
		(layer "In5.Cu")
		(net "BMC_I2C5_D_PEB_SDA")
	)
	(segment
		(start 210.220052 -2.769108)
		(end 208.4832 -4.50596)
		(width 0.127)
		(layer "In5.Cu")
		(net "BMC_I2C5_D_PEB_SDA")
	)
	(segment
		(start 159.295592 -83.704938)
		(end 159.385 -83.794346)
		(width 0.127)
		(layer "In5.Cu")
		(net "BMC_I2C5_D_PEB_SDA")
	)
	(segment
		(start 244.971824 -4.833112)
		(end 226.178618 -4.833112)
		(width 0.127)
		(layer "In5.Cu")
		(net "BMC_I2C5_D_PEB_SDA")
	)
	(segment
		(start 210.946746 -1.6256)
		(end 210.220052 -2.352294)
		(width 0.127)
		(layer "In5.Cu")
		(net "BMC_I2C5_D_PEB_SDA")
	)
	(segment
		(start 128.027938 -3.207766)
		(end 110.715298 -20.520406)
		(width 0.127)
		(layer "In5.Cu")
		(net "BMC_I2C5_D_PEB_SDA")
	)
	(segment
		(start 249.3518 -5.9944)
		(end 246.133112 -5.9944)
		(width 0.127)
		(layer "In5.Cu")
		(net "BMC_I2C5_D_PEB_SDA")
	)
	(segment
		(start 126.401068 -92.26042)
		(end 120.485662 -86.345014)
		(width 0.127)
		(layer "In5.Cu")
		(net "BMC_I2C5_D_PEB_SDA")
	)
	(segment
		(start 139.739878 -83.991196)
		(end 154.80411 -83.991196)
		(width 0.127)
		(layer "In5.Cu")
		(net "BMC_I2C5_D_PEB_SDA")
	)
	(segment
		(start 114.256058 -105.3084)
		(end 120.693434 -105.3084)
		(width 0.127)
		(layer "In5.Cu")
		(net "BMC_I2C5_D_PEB_SDA")
	)
	(segment
		(start 154.80411 -83.991196)
		(end 156.22651 -82.568796)
		(width 0.127)
		(layer "In5.Cu")
		(net "BMC_I2C5_D_PEB_SDA")
	)
	(segment
		(start 109.099858 -41.514776)
		(end 109.099858 -50.741834)
		(width 0.127)
		(layer "In5.Cu")
		(net "BMC_I2C5_D_PEB_SDA")
	)
	(segment
		(start 216.488518 -1.9558)
		(end 216.158318 -1.6256)
		(width 0.127)
		(layer "In5.Cu")
		(net "BMC_I2C5_D_PEB_SDA")
	)
	(segment
		(start 120.693434 -105.3084)
		(end 126.401068 -99.600766)
		(width 0.127)
		(layer "In5.Cu")
		(net "BMC_I2C5_D_PEB_SDA")
	)
	(segment
		(start 188.087508 -4.27482)
		(end 179.222908 -4.27482)
		(width 0.127)
		(layer "In5.Cu")
		(net "BMC_I2C5_D_PEB_SDA")
	)
	(segment
		(start 5.361432 -186.109102)
		(end 5.57784 -185.892694)
		(width 0.127)
		(layer "In5.Cu")
		(net "BMC_I2C5_D_PEB_SDA")
	)
	(segment
		(start 24.351234 -185.082434)
		(end 24.2316 -184.9628)
		(width 0.127)
		(layer "In5.Cu")
		(net "BMC_I2C5_D_PEB_SDA")
	)
	(segment
		(start 177.339498 -2.39141)
		(end 133.077966 -2.39141)
		(width 0.127)
		(layer "In5.Cu")
		(net "BMC_I2C5_D_PEB_SDA")
	)
	(segment
		(start 120.303798 -84.804504)
		(end 120.381014 -84.725764)
		(width 0.127)
		(layer "In5.Cu")
		(net "BMC_I2C5_D_PEB_SDA")
	)
	(segment
		(start 208.403952 -4.50596)
		(end 207.347312 -5.5626)
		(width 0.127)
		(layer "In5.Cu")
		(net "BMC_I2C5_D_PEB_SDA")
	)
	(segment
		(start 120.381014 -84.4169)
		(end 120.38076 -84.403692)
		(width 0.127)
		(layer "In5.Cu")
		(net "BMC_I2C5_D_PEB_SDA")
	)
	(segment
		(start 109.099858 -50.741834)
		(end 108.355892 -51.4858)
		(width 0.127)
		(layer "In5.Cu")
		(net "BMC_I2C5_D_PEB_SDA")
	)
	(segment
		(start 25.057608 -185.082434)
		(end 24.351234 -185.082434)
		(width 0.127)
		(layer "In5.Cu")
		(net "BMC_I2C5_D_PEB_SDA")
	)
	(segment
		(start 120.448324 -84.948776)
		(end 120.317768 -84.81822)
		(width 0.127)
		(layer "In5.Cu")
		(net "BMC_I2C5_D_PEB_SDA")
	)
	(segment
		(start 110.715298 -20.520406)
		(end 110.715298 -39.566596)
		(width 0.127)
		(layer "In5.Cu")
		(net "BMC_I2C5_D_PEB_SDA")
	)
	(segment
		(start 120.317768 -84.81822)
		(end 120.303798 -84.804758)
		(width 0.127)
		(layer "In5.Cu")
		(net "BMC_I2C5_D_PEB_SDA")
	)
	(segment
		(start 125.423676 -83.265264)
		(end 130.169412 -88.011)
		(width 0.127)
		(layer "In5.Cu")
		(net "BMC_I2C5_D_PEB_SDA")
	)
	(segment
		(start 85.432392 -134.132066)
		(end 114.256058 -105.3084)
		(width 0.127)
		(layer "In5.Cu")
		(net "BMC_I2C5_D_PEB_SDA")
	)
	(segment
		(start 10.087102 -185.892694)
		(end 15.457424 -180.522372)
		(width 0.127)
		(layer "In5.Cu")
		(net "BMC_I2C5_D_PEB_SDA")
	)
	(segment
		(start 25.294082 -184.84596)
		(end 25.057608 -185.082434)
		(width 0.127)
		(layer "In5.Cu")
		(net "BMC_I2C5_D_PEB_SDA")
	)
	(segment
		(start 21.109686 -181.379114)
		(end 23.521924 -181.379114)
		(width 0.127)
		(layer "In5.Cu")
		(net "BMC_I2C5_D_PEB_SDA")
	)
	(segment
		(start 216.158318 -1.6256)
		(end 210.946746 -1.6256)
		(width 0.127)
		(layer "In5.Cu")
		(net "BMC_I2C5_D_PEB_SDA")
	)
	(segment
		(start 130.169412 -88.011)
		(end 135.720074 -88.011)
		(width 0.127)
		(layer "In5.Cu")
		(net "BMC_I2C5_D_PEB_SDA")
	)
	(segment
		(start 108.355892 -51.4858)
		(end 107.790234 -51.4858)
		(width 0.127)
		(layer "In5.Cu")
		(net "BMC_I2C5_D_PEB_SDA")
	)
	(segment
		(start 5.57784 -185.892694)
		(end 10.087102 -185.892694)
		(width 0.127)
		(layer "In5.Cu")
		(net "BMC_I2C5_D_PEB_SDA")
	)
	(segment
		(start 110.71479 -39.899844)
		(end 109.099858 -41.514776)
		(width 0.127)
		(layer "In5.Cu")
		(net "BMC_I2C5_D_PEB_SDA")
	)
	(segment
		(start 189.375288 -5.5626)
		(end 188.087508 -4.27482)
		(width 0.127)
		(layer "In5.Cu")
		(net "BMC_I2C5_D_PEB_SDA")
	)
	(segment
		(start 107.790234 -51.4858)
		(end 107.410504 -51.86553)
		(width 0.127)
		(layer "In5.Cu")
		(net "BMC_I2C5_D_PEB_SDA")
	)
	(segment
		(start 226.178618 -4.833112)
		(end 224.177606 -2.8321)
		(width 0.127)
		(layer "In5.Cu")
		(net "BMC_I2C5_D_PEB_SDA")
	)
	(segment
		(start 25.294082 -183.151272)
		(end 25.294082 -184.84596)
		(width 0.127)
		(layer "In5.Cu")
		(net "BMC_I2C5_D_PEB_SDA")
	)
	(segment
		(start 20.252944 -180.522372)
		(end 21.109686 -181.379114)
		(width 0.127)
		(layer "In5.Cu")
		(net "BMC_I2C5_D_PEB_SDA")
	)
	(segment
		(start 120.381014 -84.725764)
		(end 120.381014 -84.4169)
		(width 0.127)
		(layer "In5.Cu")
		(net "BMC_I2C5_D_PEB_SDA")
	)
	(segment
		(start 126.401068 -99.600766)
		(end 126.401068 -92.26042)
		(width 0.127)
		(layer "In5.Cu")
		(net "BMC_I2C5_D_PEB_SDA")
	)
	(segment
		(start 135.720074 -88.011)
		(end 139.739878 -83.991196)
		(width 0.127)
		(layer "In5.Cu")
		(net "BMC_I2C5_D_PEB_SDA")
	)
	(segment
		(start 156.22651 -82.568796)
		(end 158.634684 -82.568796)
		(width 0.127)
		(layer "In5.Cu")
		(net "BMC_I2C5_D_PEB_SDA")
	)
	(segment
		(start 219.411296 -2.8321)
		(end 218.534996 -1.9558)
		(width 0.127)
		(layer "In5.Cu")
		(net "BMC_I2C5_D_PEB_SDA")
	)
	(segment
		(start 15.457424 -180.522372)
		(end 20.252944 -180.522372)
		(width 0.127)
		(layer "In5.Cu")
		(net "BMC_I2C5_D_PEB_SDA")
	)
	(segment
		(start 110.715298 -39.566596)
		(end 110.71479 -39.899844)
		(width 0.127)
		(layer "In5.Cu")
		(net "BMC_I2C5_D_PEB_SDA")
	)
	(segment
		(start 132.26161 -3.207766)
		(end 128.027938 -3.207766)
		(width 0.127)
		(layer "In5.Cu")
		(net "BMC_I2C5_D_PEB_SDA")
	)
	(segment
		(start 120.303798 -84.804758)
		(end 120.303798 -84.804504)
		(width 0.127)
		(layer "In5.Cu")
		(net "BMC_I2C5_D_PEB_SDA")
	)
	(segment
		(start 120.448324 -84.94903)
		(end 120.448324 -84.948776)
		(width 0.127)
		(layer "In5.Cu")
		(net "BMC_I2C5_D_PEB_SDA")
	)
	(segment
		(start 210.220052 -2.352294)
		(end 210.220052 -2.769108)
		(width 0.127)
		(layer "In5.Cu")
		(net "BMC_I2C5_D_PEB_SDA")
	)
	(segment
		(start 224.177606 -2.8321)
		(end 219.411296 -2.8321)
		(width 0.127)
		(layer "In5.Cu")
		(net "BMC_I2C5_D_PEB_SDA")
	)
	(segment
		(start 159.295592 -83.229704)
		(end 159.295592 -83.704938)
		(width 0.127)
		(layer "In5.Cu")
		(net "BMC_I2C5_D_PEB_SDA")
	)
	(segment
		(start 120.38076 -84.403692)
		(end 120.38076 -84.35086)
		(width 0.127)
		(layer "In5.Cu")
		(net "BMC_I2C5_D_PEB_SDA")
	)
	(segment
		(start 23.521924 -181.379114)
		(end 25.294082 -183.151272)
		(width 0.127)
		(layer "In5.Cu")
		(net "BMC_I2C5_D_PEB_SDA")
	)
	(segment
		(start 208.4832 -4.50596)
		(end 208.403952 -4.50596)
		(width 0.127)
		(layer "In5.Cu")
		(net "BMC_I2C5_D_PEB_SDA")
	)
	(segment
		(start 159.385 -83.794346)
		(end 159.385 -83.7946)
		(width 0.127)
		(layer "In5.Cu")
		(net "BMC_I2C5_D_PEB_SDA")
	)
	(segment
		(start 158.634684 -82.568796)
		(end 159.295592 -83.229704)
		(width 0.127)
		(layer "In5.Cu")
		(net "BMC_I2C5_D_PEB_SDA")
	)
	(segment
		(start 120.377712 -83.785964)
		(end 120.895618 -83.265264)
		(width 0.127)
		(layer "In5.Cu")
		(net "BMC_I2C5_D_PEB_SDA")
	)
	(segment
		(start 120.485662 -84.986368)
		(end 120.448324 -84.94903)
		(width 0.127)
		(layer "In5.Cu")
		(net "BMC_I2C5_D_PEB_SDA")
	)
	(segment
		(start 177.454052 -83.8962)
		(end 214.381334 -83.8962)
		(width 0.12065)
		(layer "F.Cu")
		(net "BMC_I2C5_D_PEB_SCL")
	)
	(segment
		(start 64.502284 -149.508718)
		(end 64.502284 -149.873716)
		(width 0.12065)
		(layer "F.Cu")
		(net "BMC_I2C5_D_PEB_SCL")
	)
	(segment
		(start 158.710122 -84.583778)
		(end 158.710122 -84.011008)
		(width 0.12065)
		(layer "F.Cu")
		(net "BMC_I2C5_D_PEB_SCL")
	)
	(segment
		(start 250.528582 -6.920992)
		(end 251.236226 -6.920992)
		(width 0.12065)
		(layer "F.Cu")
		(net "BMC_I2C5_D_PEB_SCL")
	)
	(segment
		(start 24.413972 -185.644028)
		(end 24.2316 -185.8264)
		(width 0.12065)
		(layer "F.Cu")
		(net "BMC_I2C5_D_PEB_SCL")
	)
	(segment
		(start 62.832488 -149.61362)
		(end 63.100458 -149.34565)
		(width 0.12065)
		(layer "F.Cu")
		(net "BMC_I2C5_D_PEB_SCL")
	)
	(segment
		(start 226.551998 -75.9206)
		(end 227.187252 -76.555854)
		(width 0.12065)
		(layer "F.Cu")
		(net "BMC_I2C5_D_PEB_SCL")
	)
	(segment
		(start 158.521654 -83.82254)
		(end 158.69666 -83.647534)
		(width 0.12065)
		(layer "F.Cu")
		(net "BMC_I2C5_D_PEB_SCL")
	)
	(segment
		(start 64.339216 -149.34565)
		(end 64.502284 -149.508718)
		(width 0.12065)
		(layer "F.Cu")
		(net "BMC_I2C5_D_PEB_SCL")
	)
	(segment
		(start 250.337066 -6.729476)
		(end 250.528582 -6.920992)
		(width 0.12065)
		(layer "F.Cu")
		(net "BMC_I2C5_D_PEB_SCL")
	)
	(segment
		(start 227.176838 -77.532738)
		(end 227.33 -77.6859)
		(width 0.12065)
		(layer "F.Cu")
		(net "BMC_I2C5_D_PEB_SCL")
	)
	(segment
		(start 5.4102 -185.0136)
		(end 5.6642 -185.2676)
		(width 0.12065)
		(layer "F.Cu")
		(net "BMC_I2C5_D_PEB_SCL")
	)
	(segment
		(start 158.69666 -81.180432)
		(end 160.502092 -79.375)
		(width 0.12065)
		(layer "F.Cu")
		(net "BMC_I2C5_D_PEB_SCL")
	)
	(segment
		(start 59.3725 -149.86)
		(end 59.61888 -149.61362)
		(width 0.12065)
		(layer "F.Cu")
		(net "BMC_I2C5_D_PEB_SCL")
	)
	(segment
		(start 5.6642 -185.2676)
		(end 6.3627 -185.2676)
		(width 0.12065)
		(layer "F.Cu")
		(net "BMC_I2C5_D_PEB_SCL")
	)
	(segment
		(start 158.710122 -84.011008)
		(end 158.521654 -83.82254)
		(width 0.12065)
		(layer "F.Cu")
		(net "BMC_I2C5_D_PEB_SCL")
	)
	(segment
		(start 59.61888 -149.61362)
		(end 62.832488 -149.61362)
		(width 0.12065)
		(layer "F.Cu")
		(net "BMC_I2C5_D_PEB_SCL")
	)
	(segment
		(start 160.502092 -79.375)
		(end 172.932852 -79.375)
		(width 0.12065)
		(layer "F.Cu")
		(net "BMC_I2C5_D_PEB_SCL")
	)
	(segment
		(start 64.502284 -149.873716)
		(end 64.389 -149.987)
		(width 0.12065)
		(layer "F.Cu")
		(net "BMC_I2C5_D_PEB_SCL")
	)
	(segment
		(start 25.1841 -186.0042)
		(end 24.823928 -185.644028)
		(width 0.12065)
		(layer "F.Cu")
		(net "BMC_I2C5_D_PEB_SCL")
	)
	(segment
		(start 121.218198 -84.846414)
		(end 121.167398 -84.795614)
		(width 0.12065)
		(layer "F.Cu")
		(net "BMC_I2C5_D_PEB_SCL")
	)
	(segment
		(start 24.823928 -185.644028)
		(end 24.413972 -185.644028)
		(width 0.12065)
		(layer "F.Cu")
		(net "BMC_I2C5_D_PEB_SCL")
	)
	(segment
		(start 227.187252 -76.555854)
		(end 227.187252 -77.522324)
		(width 0.12065)
		(layer "F.Cu")
		(net "BMC_I2C5_D_PEB_SCL")
	)
	(segment
		(start 172.932852 -79.375)
		(end 177.454052 -83.8962)
		(width 0.12065)
		(layer "F.Cu")
		(net "BMC_I2C5_D_PEB_SCL")
	)
	(segment
		(start 214.381334 -83.8962)
		(end 222.356934 -75.9206)
		(width 0.12065)
		(layer "F.Cu")
		(net "BMC_I2C5_D_PEB_SCL")
	)
	(segment
		(start 158.69666 -83.647534)
		(end 158.69666 -81.180432)
		(width 0.12065)
		(layer "F.Cu")
		(net "BMC_I2C5_D_PEB_SCL")
	)
	(segment
		(start 158.496 -84.7979)
		(end 158.710122 -84.583778)
		(width 0.12065)
		(layer "F.Cu")
		(net "BMC_I2C5_D_PEB_SCL")
	)
	(segment
		(start 227.187252 -77.522324)
		(end 227.176838 -77.532738)
		(width 0.12065)
		(layer "F.Cu")
		(net "BMC_I2C5_D_PEB_SCL")
	)
	(segment
		(start 222.356934 -75.9206)
		(end 226.551998 -75.9206)
		(width 0.12065)
		(layer "F.Cu")
		(net "BMC_I2C5_D_PEB_SCL")
	)
	(segment
		(start 122.112786 -84.846414)
		(end 121.218198 -84.846414)
		(width 0.12065)
		(layer "F.Cu")
		(net "BMC_I2C5_D_PEB_SCL")
	)
	(segment
		(start 63.100458 -149.34565)
		(end 64.339216 -149.34565)
		(width 0.12065)
		(layer "F.Cu")
		(net "BMC_I2C5_D_PEB_SCL")
	)
	(via
		(at 25.3238 -186.0042)
		(size 0.7112)
		(drill 0.3556)
		(layers "F.Cu" "B.Cu")
		(net "BMC_I2C5_D_PEB_SCL")
	)
	(via
		(at 121.167398 -84.795614)
		(size 0.508)
		(drill 0.254)
		(layers "F.Cu" "B.Cu")
		(net "BMC_I2C5_D_PEB_SCL")
	)
	(via
		(at 81.407 -134.874)
		(size 0.508)
		(drill 0.254)
		(layers "F.Cu" "B.Cu")
		(net "BMC_I2C5_D_PEB_SCL")
	)
	(via
		(at 158.521654 -83.82254)
		(size 0.508)
		(drill 0.254)
		(layers "F.Cu" "B.Cu")
		(net "BMC_I2C5_D_PEB_SCL")
	)
	(via
		(at 64.389 -149.987)
		(size 0.508)
		(drill 0.254)
		(layers "F.Cu" "B.Cu")
		(net "BMC_I2C5_D_PEB_SCL")
	)
	(via
		(at 24.2316 -185.8264)
		(size 0.508)
		(drill 0.254)
		(layers "F.Cu" "B.Cu")
		(net "BMC_I2C5_D_PEB_SCL")
	)
	(via
		(at 79.121 -139.192)
		(size 0.508)
		(drill 0.254)
		(layers "F.Cu" "B.Cu")
		(net "BMC_I2C5_D_PEB_SCL")
	)
	(via
		(at 107.410504 -50.75682)
		(size 0.508)
		(drill 0.254)
		(layers "F.Cu" "B.Cu")
		(net "BMC_I2C5_D_PEB_SCL")
	)
	(via
		(at 5.4102 -185.0136)
		(size 0.508)
		(drill 0.254)
		(layers "F.Cu" "B.Cu")
		(net "BMC_I2C5_D_PEB_SCL")
	)
	(via
		(at 250.337066 -6.729476)
		(size 0.508)
		(drill 0.254)
		(layers "F.Cu" "B.Cu")
		(net "BMC_I2C5_D_PEB_SCL")
	)
	(segment
		(start 79.897224 -137.304018)
		(end 79.339948 -137.861294)
		(width 0.12065)
		(layer "B.Cu")
		(net "BMC_I2C5_D_PEB_SCL")
	)
	(segment
		(start 79.339948 -138.973052)
		(end 79.121 -139.192)
		(width 0.12065)
		(layer "B.Cu")
		(net "BMC_I2C5_D_PEB_SCL")
	)
	(segment
		(start 82.542126 -136.672828)
		(end 81.910936 -137.304018)
		(width 0.12065)
		(layer "B.Cu")
		(net "BMC_I2C5_D_PEB_SCL")
	)
	(segment
		(start 24.374602 -185.683398)
		(end 25.3238 -185.683398)
		(width 0.12065)
		(layer "B.Cu")
		(net "BMC_I2C5_D_PEB_SCL")
	)
	(segment
		(start 81.915254 -134.6962)
		(end 82.542126 -135.323072)
		(width 0.12065)
		(layer "B.Cu")
		(net "BMC_I2C5_D_PEB_SCL")
	)
	(segment
		(start 24.2316 -185.8264)
		(end 24.374602 -185.683398)
		(width 0.12065)
		(layer "B.Cu")
		(net "BMC_I2C5_D_PEB_SCL")
	)
	(segment
		(start 252.717046 -6.526784)
		(end 250.539758 -6.526784)
		(width 0.12065)
		(layer "B.Cu")
		(net "BMC_I2C5_D_PEB_SCL")
	)
	(segment
		(start 254.790194 -6.740652)
		(end 252.930914 -6.740652)
		(width 0.12065)
		(layer "B.Cu")
		(net "BMC_I2C5_D_PEB_SCL")
	)
	(segment
		(start 66.1035 -149.479)
		(end 65.1256 -149.479)
		(width 0.12065)
		(layer "B.Cu")
		(net "BMC_I2C5_D_PEB_SCL")
	)
	(segment
		(start 27.301698 -185.683398)
		(end 27.5209 -185.9026)
		(width 0.12065)
		(layer "B.Cu")
		(net "BMC_I2C5_D_PEB_SCL")
	)
	(segment
		(start 65.1256 -149.479)
		(end 64.6176 -149.987)
		(width 0.12065)
		(layer "B.Cu")
		(net "BMC_I2C5_D_PEB_SCL")
	)
	(segment
		(start 82.542126 -135.323072)
		(end 82.542126 -136.672828)
		(width 0.12065)
		(layer "B.Cu")
		(net "BMC_I2C5_D_PEB_SCL")
	)
	(segment
		(start 25.3238 -185.683398)
		(end 25.3238 -186.0042)
		(width 0.12065)
		(layer "B.Cu")
		(net "BMC_I2C5_D_PEB_SCL")
	)
	(segment
		(start 81.5848 -134.6962)
		(end 81.915254 -134.6962)
		(width 0.12065)
		(layer "B.Cu")
		(net "BMC_I2C5_D_PEB_SCL")
	)
	(segment
		(start 81.407 -134.874)
		(end 81.5848 -134.6962)
		(width 0.12065)
		(layer "B.Cu")
		(net "BMC_I2C5_D_PEB_SCL")
	)
	(segment
		(start 79.339948 -137.861294)
		(end 79.339948 -138.973052)
		(width 0.12065)
		(layer "B.Cu")
		(net "BMC_I2C5_D_PEB_SCL")
	)
	(segment
		(start 81.910936 -137.304018)
		(end 79.897224 -137.304018)
		(width 0.12065)
		(layer "B.Cu")
		(net "BMC_I2C5_D_PEB_SCL")
	)
	(segment
		(start 255.061212 -7.01167)
		(end 254.790194 -6.740652)
		(width 0.12065)
		(layer "B.Cu")
		(net "BMC_I2C5_D_PEB_SCL")
	)
	(segment
		(start 252.930914 -6.740652)
		(end 252.717046 -6.526784)
		(width 0.12065)
		(layer "B.Cu")
		(net "BMC_I2C5_D_PEB_SCL")
	)
	(segment
		(start 64.6176 -149.987)
		(end 64.389 -149.987)
		(width 0.12065)
		(layer "B.Cu")
		(net "BMC_I2C5_D_PEB_SCL")
	)
	(segment
		(start 25.3238 -185.683398)
		(end 27.301698 -185.683398)
		(width 0.12065)
		(layer "B.Cu")
		(net "BMC_I2C5_D_PEB_SCL")
	)
	(segment
		(start 250.539758 -6.526784)
		(end 250.337066 -6.729476)
		(width 0.12065)
		(layer "B.Cu")
		(net "BMC_I2C5_D_PEB_SCL")
	)
	(segment
		(start 64.472312 -149.441662)
		(end 64.190372 -149.159722)
		(width 0.127)
		(layer "In2.Cu")
		(net "BMC_I2C5_D_PEB_SCL")
	)
	(segment
		(start 65.499234 -152.7302)
		(end 76.432918 -152.7302)
		(width 0.127)
		(layer "In2.Cu")
		(net "BMC_I2C5_D_PEB_SCL")
	)
	(segment
		(start 109.158532 -51.047904)
		(end 110.968282 -52.857654)
		(width 0.127)
		(layer "In2.Cu")
		(net "BMC_I2C5_D_PEB_SCL")
	)
	(segment
		(start 24.501094 -185.556906)
		(end 24.2316 -185.8264)
		(width 0.127)
		(layer "In2.Cu")
		(net "BMC_I2C5_D_PEB_SCL")
	)
	(segment
		(start 110.968282 -52.857654)
		(end 110.968282 -71.89597)
		(width 0.127)
		(layer "In2.Cu")
		(net "BMC_I2C5_D_PEB_SCL")
	)
	(segment
		(start 64.389 -149.987)
		(end 64.58966 -150.18766)
		(width 0.127)
		(layer "In2.Cu")
		(net "BMC_I2C5_D_PEB_SCL")
	)
	(segment
		(start 64.190372 -149.159722)
		(end 63.497714 -149.159722)
		(width 0.127)
		(layer "In2.Cu")
		(net "BMC_I2C5_D_PEB_SCL")
	)
	(segment
		(start 78.88351 -138.95451)
		(end 79.121 -139.192)
		(width 0.127)
		(layer "In2.Cu")
		(net "BMC_I2C5_D_PEB_SCL")
	)
	(segment
		(start 78.2828 -150.880318)
		(end 78.2828 -139.134342)
		(width 0.127)
		(layer "In2.Cu")
		(net "BMC_I2C5_D_PEB_SCL")
	)
	(segment
		(start 64.58966 -151.820626)
		(end 65.499234 -152.7302)
		(width 0.127)
		(layer "In2.Cu")
		(net "BMC_I2C5_D_PEB_SCL")
	)
	(segment
		(start 107.701588 -51.047904)
		(end 109.158532 -51.047904)
		(width 0.127)
		(layer "In2.Cu")
		(net "BMC_I2C5_D_PEB_SCL")
	)
	(segment
		(start 63.25489 -156.025596)
		(end 62.003178 -157.277308)
		(width 0.127)
		(layer "In2.Cu")
		(net "BMC_I2C5_D_PEB_SCL")
	)
	(segment
		(start 64.58966 -150.18766)
		(end 64.58966 -151.820626)
		(width 0.127)
		(layer "In2.Cu")
		(net "BMC_I2C5_D_PEB_SCL")
	)
	(segment
		(start 78.462632 -138.95451)
		(end 78.88351 -138.95451)
		(width 0.127)
		(layer "In2.Cu")
		(net "BMC_I2C5_D_PEB_SCL")
	)
	(segment
		(start 37.68979 -170.773598)
		(end 25.83688 -182.626508)
		(width 0.127)
		(layer "In2.Cu")
		(net "BMC_I2C5_D_PEB_SCL")
	)
	(segment
		(start 62.003178 -157.277308)
		(end 62.003178 -159.582104)
		(width 0.127)
		(layer "In2.Cu")
		(net "BMC_I2C5_D_PEB_SCL")
	)
	(segment
		(start 110.968282 -71.89597)
		(end 120.976136 -81.903824)
		(width 0.127)
		(layer "In2.Cu")
		(net "BMC_I2C5_D_PEB_SCL")
	)
	(segment
		(start 76.432918 -152.7302)
		(end 78.2828 -150.880318)
		(width 0.127)
		(layer "In2.Cu")
		(net "BMC_I2C5_D_PEB_SCL")
	)
	(segment
		(start 120.976136 -81.903824)
		(end 120.976136 -84.604352)
		(width 0.127)
		(layer "In2.Cu")
		(net "BMC_I2C5_D_PEB_SCL")
	)
	(segment
		(start 50.811684 -170.773598)
		(end 37.68979 -170.773598)
		(width 0.127)
		(layer "In2.Cu")
		(net "BMC_I2C5_D_PEB_SCL")
	)
	(segment
		(start 63.497714 -149.159722)
		(end 63.25489 -149.402546)
		(width 0.127)
		(layer "In2.Cu")
		(net "BMC_I2C5_D_PEB_SCL")
	)
	(segment
		(start 63.25489 -149.402546)
		(end 63.25489 -156.025596)
		(width 0.127)
		(layer "In2.Cu")
		(net "BMC_I2C5_D_PEB_SCL")
	)
	(segment
		(start 107.410504 -50.75682)
		(end 107.701588 -51.047904)
		(width 0.127)
		(layer "In2.Cu")
		(net "BMC_I2C5_D_PEB_SCL")
	)
	(segment
		(start 64.389 -149.987)
		(end 64.472312 -149.903688)
		(width 0.127)
		(layer "In2.Cu")
		(net "BMC_I2C5_D_PEB_SCL")
	)
	(segment
		(start 120.976136 -84.604352)
		(end 121.167398 -84.795614)
		(width 0.127)
		(layer "In2.Cu")
		(net "BMC_I2C5_D_PEB_SCL")
	)
	(segment
		(start 78.2828 -139.134342)
		(end 78.462632 -138.95451)
		(width 0.127)
		(layer "In2.Cu")
		(net "BMC_I2C5_D_PEB_SCL")
	)
	(segment
		(start 25.83688 -184.85612)
		(end 25.136094 -185.556906)
		(width 0.127)
		(layer "In2.Cu")
		(net "BMC_I2C5_D_PEB_SCL")
	)
	(segment
		(start 25.136094 -185.556906)
		(end 24.501094 -185.556906)
		(width 0.127)
		(layer "In2.Cu")
		(net "BMC_I2C5_D_PEB_SCL")
	)
	(segment
		(start 62.003178 -159.582104)
		(end 50.811684 -170.773598)
		(width 0.127)
		(layer "In2.Cu")
		(net "BMC_I2C5_D_PEB_SCL")
	)
	(segment
		(start 64.472312 -149.903688)
		(end 64.472312 -149.441662)
		(width 0.127)
		(layer "In2.Cu")
		(net "BMC_I2C5_D_PEB_SCL")
	)
	(segment
		(start 25.83688 -182.626508)
		(end 25.83688 -184.85612)
		(width 0.127)
		(layer "In2.Cu")
		(net "BMC_I2C5_D_PEB_SCL")
	)
	(segment
		(start 218.745562 -1.4478)
		(end 216.699084 -1.4478)
		(width 0.127)
		(layer "In5.Cu")
		(net "BMC_I2C5_D_PEB_SCL")
	)
	(segment
		(start 177.550064 -1.88341)
		(end 132.8674 -1.88341)
		(width 0.127)
		(layer "In5.Cu")
		(net "BMC_I2C5_D_PEB_SCL")
	)
	(segment
		(start 25.802082 -182.940706)
		(end 25.802082 -185.056526)
		(width 0.127)
		(layer "In5.Cu")
		(net "BMC_I2C5_D_PEB_SCL")
	)
	(segment
		(start 249.141234 -5.4864)
		(end 246.343678 -5.4864)
		(width 0.127)
		(layer "In5.Cu")
		(net "BMC_I2C5_D_PEB_SCL")
	)
	(segment
		(start 249.369326 -5.258308)
		(end 249.141234 -5.4864)
		(width 0.127)
		(layer "In5.Cu")
		(net "BMC_I2C5_D_PEB_SCL")
	)
	(segment
		(start 5.4102 -185.0136)
		(end 5.4102 -185.025538)
		(width 0.127)
		(layer "In5.Cu")
		(net "BMC_I2C5_D_PEB_SCL")
	)
	(segment
		(start 158.787592 -83.556602)
		(end 158.521654 -83.82254)
		(width 0.127)
		(layer "In5.Cu")
		(net "BMC_I2C5_D_PEB_SCL")
	)
	(segment
		(start 135.85444 -88.5952)
		(end 139.950444 -84.499196)
		(width 0.127)
		(layer "In5.Cu")
		(net "BMC_I2C5_D_PEB_SCL")
	)
	(segment
		(start 226.389184 -4.325112)
		(end 224.388172 -2.3241)
		(width 0.127)
		(layer "In5.Cu")
		(net "BMC_I2C5_D_PEB_SCL")
	)
	(segment
		(start 120.904 -105.8164)
		(end 126.909068 -99.811332)
		(width 0.127)
		(layer "In5.Cu")
		(net "BMC_I2C5_D_PEB_SCL")
	)
	(segment
		(start 125.21311 -83.773264)
		(end 130.035046 -88.5952)
		(width 0.127)
		(layer "In5.Cu")
		(net "BMC_I2C5_D_PEB_SCL")
	)
	(segment
		(start 120.889014 -84.6709)
		(end 120.889014 -84.41182)
		(width 0.127)
		(layer "In5.Cu")
		(net "BMC_I2C5_D_PEB_SCL")
	)
	(segment
		(start 120.891808 -84.673694)
		(end 120.889014 -84.6709)
		(width 0.127)
		(layer "In5.Cu")
		(net "BMC_I2C5_D_PEB_SCL")
	)
	(segment
		(start 250.800362 -5.629656)
		(end 250.429014 -5.258308)
		(width 0.127)
		(layer "In5.Cu")
		(net "BMC_I2C5_D_PEB_SCL")
	)
	(segment
		(start 120.886982 -83.994498)
		(end 121.106946 -83.773264)
		(width 0.127)
		(layer "In5.Cu")
		(net "BMC_I2C5_D_PEB_SCL")
	)
	(segment
		(start 130.035046 -88.5952)
		(end 135.85444 -88.5952)
		(width 0.127)
		(layer "In5.Cu")
		(net "BMC_I2C5_D_PEB_SCL")
	)
	(segment
		(start 155.014676 -84.499196)
		(end 156.437076 -83.076796)
		(width 0.127)
		(layer "In5.Cu")
		(net "BMC_I2C5_D_PEB_SCL")
	)
	(segment
		(start 110.207298 -39.566088)
		(end 110.207044 -39.689024)
		(width 0.127)
		(layer "In5.Cu")
		(net "BMC_I2C5_D_PEB_SCL")
	)
	(segment
		(start 24.467566 -185.590434)
		(end 24.2316 -185.8264)
		(width 0.127)
		(layer "In5.Cu")
		(net "BMC_I2C5_D_PEB_SCL")
	)
	(segment
		(start 250.429014 -5.258308)
		(end 249.369326 -5.258308)
		(width 0.127)
		(layer "In5.Cu")
		(net "BMC_I2C5_D_PEB_SCL")
	)
	(segment
		(start 224.388172 -2.3241)
		(end 219.621862 -2.3241)
		(width 0.127)
		(layer "In5.Cu")
		(net "BMC_I2C5_D_PEB_SCL")
	)
	(segment
		(start 110.207044 -39.689024)
		(end 108.591858 -41.30421)
		(width 0.127)
		(layer "In5.Cu")
		(net "BMC_I2C5_D_PEB_SCL")
	)
	(segment
		(start 210.73618 -1.1176)
		(end 209.712052 -2.141728)
		(width 0.127)
		(layer "In5.Cu")
		(net "BMC_I2C5_D_PEB_SCL")
	)
	(segment
		(start 120.88876 -84.398612)
		(end 120.88876 -84.349336)
		(width 0.127)
		(layer "In5.Cu")
		(net "BMC_I2C5_D_PEB_SCL")
	)
	(segment
		(start 208.272634 -3.99796)
		(end 208.193386 -3.99796)
		(width 0.127)
		(layer "In5.Cu")
		(net "BMC_I2C5_D_PEB_SCL")
	)
	(segment
		(start 245.18239 -4.325112)
		(end 226.389184 -4.325112)
		(width 0.127)
		(layer "In5.Cu")
		(net "BMC_I2C5_D_PEB_SCL")
	)
	(segment
		(start 81.640934 -134.640066)
		(end 85.642958 -134.640066)
		(width 0.127)
		(layer "In5.Cu")
		(net "BMC_I2C5_D_PEB_SCL")
	)
	(segment
		(start 216.368884 -1.1176)
		(end 210.73618 -1.1176)
		(width 0.127)
		(layer "In5.Cu")
		(net "BMC_I2C5_D_PEB_SCL")
	)
	(segment
		(start 246.343678 -5.4864)
		(end 245.18239 -4.325112)
		(width 0.127)
		(layer "In5.Cu")
		(net "BMC_I2C5_D_PEB_SCL")
	)
	(segment
		(start 126.909068 -99.811332)
		(end 126.909068 -92.049854)
		(width 0.127)
		(layer "In5.Cu")
		(net "BMC_I2C5_D_PEB_SCL")
	)
	(segment
		(start 132.051044 -2.699766)
		(end 127.817372 -2.699766)
		(width 0.127)
		(layer "In5.Cu")
		(net "BMC_I2C5_D_PEB_SCL")
	)
	(segment
		(start 5.4102 -185.025538)
		(end 5.769356 -185.384694)
		(width 0.127)
		(layer "In5.Cu")
		(net "BMC_I2C5_D_PEB_SCL")
	)
	(segment
		(start 121.106946 -83.773264)
		(end 125.21311 -83.773264)
		(width 0.127)
		(layer "In5.Cu")
		(net "BMC_I2C5_D_PEB_SCL")
	)
	(segment
		(start 216.699084 -1.4478)
		(end 216.368884 -1.1176)
		(width 0.127)
		(layer "In5.Cu")
		(net "BMC_I2C5_D_PEB_SCL")
	)
	(segment
		(start 25.802082 -185.056526)
		(end 25.268174 -185.590434)
		(width 0.127)
		(layer "In5.Cu")
		(net "BMC_I2C5_D_PEB_SCL")
	)
	(segment
		(start 23.73249 -180.871114)
		(end 25.802082 -182.940706)
		(width 0.127)
		(layer "In5.Cu")
		(net "BMC_I2C5_D_PEB_SCL")
	)
	(segment
		(start 208.193386 -3.99796)
		(end 207.136746 -5.0546)
		(width 0.127)
		(layer "In5.Cu")
		(net "BMC_I2C5_D_PEB_SCL")
	)
	(segment
		(start 139.950444 -84.499196)
		(end 155.014676 -84.499196)
		(width 0.127)
		(layer "In5.Cu")
		(net "BMC_I2C5_D_PEB_SCL")
	)
	(segment
		(start 25.268174 -185.590434)
		(end 24.467566 -185.590434)
		(width 0.127)
		(layer "In5.Cu")
		(net "BMC_I2C5_D_PEB_SCL")
	)
	(segment
		(start 158.424118 -83.076796)
		(end 158.787592 -83.44027)
		(width 0.127)
		(layer "In5.Cu")
		(net "BMC_I2C5_D_PEB_SCL")
	)
	(segment
		(start 132.8674 -1.88341)
		(end 132.051044 -2.699766)
		(width 0.127)
		(layer "In5.Cu")
		(net "BMC_I2C5_D_PEB_SCL")
	)
	(segment
		(start 120.993662 -84.96935)
		(end 121.167398 -84.795614)
		(width 0.127)
		(layer "In5.Cu")
		(net "BMC_I2C5_D_PEB_SCL")
	)
	(segment
		(start 108.591858 -41.30421)
		(end 108.591858 -50.531268)
		(width 0.127)
		(layer "In5.Cu")
		(net "BMC_I2C5_D_PEB_SCL")
	)
	(segment
		(start 81.407 -134.874)
		(end 81.640934 -134.640066)
		(width 0.127)
		(layer "In5.Cu")
		(net "BMC_I2C5_D_PEB_SCL")
	)
	(segment
		(start 179.433474 -3.76682)
		(end 177.550064 -1.88341)
		(width 0.127)
		(layer "In5.Cu")
		(net "BMC_I2C5_D_PEB_SCL")
	)
	(segment
		(start 85.642958 -134.640066)
		(end 114.466624 -105.8164)
		(width 0.127)
		(layer "In5.Cu")
		(net "BMC_I2C5_D_PEB_SCL")
	)
	(segment
		(start 219.621862 -2.3241)
		(end 218.745562 -1.4478)
		(width 0.127)
		(layer "In5.Cu")
		(net "BMC_I2C5_D_PEB_SCL")
	)
	(segment
		(start 126.909068 -92.049854)
		(end 120.993662 -86.134448)
		(width 0.127)
		(layer "In5.Cu")
		(net "BMC_I2C5_D_PEB_SCL")
	)
	(segment
		(start 127.817372 -2.699766)
		(end 110.207298 -20.30984)
		(width 0.127)
		(layer "In5.Cu")
		(net "BMC_I2C5_D_PEB_SCL")
	)
	(segment
		(start 20.46351 -180.014372)
		(end 21.320252 -180.871114)
		(width 0.127)
		(layer "In5.Cu")
		(net "BMC_I2C5_D_PEB_SCL")
	)
	(segment
		(start 21.320252 -180.871114)
		(end 23.73249 -180.871114)
		(width 0.127)
		(layer "In5.Cu")
		(net "BMC_I2C5_D_PEB_SCL")
	)
	(segment
		(start 158.787592 -83.44027)
		(end 158.787592 -83.556602)
		(width 0.127)
		(layer "In5.Cu")
		(net "BMC_I2C5_D_PEB_SCL")
	)
	(segment
		(start 188.298074 -3.76682)
		(end 179.433474 -3.76682)
		(width 0.127)
		(layer "In5.Cu")
		(net "BMC_I2C5_D_PEB_SCL")
	)
	(segment
		(start 207.136746 -5.0546)
		(end 189.585854 -5.0546)
		(width 0.127)
		(layer "In5.Cu")
		(net "BMC_I2C5_D_PEB_SCL")
	)
	(segment
		(start 107.631484 -50.9778)
		(end 107.410504 -50.75682)
		(width 0.127)
		(layer "In5.Cu")
		(net "BMC_I2C5_D_PEB_SCL")
	)
	(segment
		(start 108.145326 -50.9778)
		(end 107.631484 -50.9778)
		(width 0.127)
		(layer "In5.Cu")
		(net "BMC_I2C5_D_PEB_SCL")
	)
	(segment
		(start 5.769356 -185.384694)
		(end 9.876536 -185.384694)
		(width 0.127)
		(layer "In5.Cu")
		(net "BMC_I2C5_D_PEB_SCL")
	)
	(segment
		(start 9.876536 -185.384694)
		(end 15.246858 -180.014372)
		(width 0.127)
		(layer "In5.Cu")
		(net "BMC_I2C5_D_PEB_SCL")
	)
	(segment
		(start 250.800362 -6.26618)
		(end 250.800362 -5.629656)
		(width 0.127)
		(layer "In5.Cu")
		(net "BMC_I2C5_D_PEB_SCL")
	)
	(segment
		(start 120.88876 -84.349336)
		(end 120.886982 -83.994498)
		(width 0.127)
		(layer "In5.Cu")
		(net "BMC_I2C5_D_PEB_SCL")
	)
	(segment
		(start 209.712052 -2.558542)
		(end 208.272634 -3.99796)
		(width 0.127)
		(layer "In5.Cu")
		(net "BMC_I2C5_D_PEB_SCL")
	)
	(segment
		(start 209.712052 -2.141728)
		(end 209.712052 -2.558542)
		(width 0.127)
		(layer "In5.Cu")
		(net "BMC_I2C5_D_PEB_SCL")
	)
	(segment
		(start 189.585854 -5.0546)
		(end 188.298074 -3.76682)
		(width 0.127)
		(layer "In5.Cu")
		(net "BMC_I2C5_D_PEB_SCL")
	)
	(segment
		(start 121.013474 -84.795614)
		(end 120.891808 -84.673694)
		(width 0.127)
		(layer "In5.Cu")
		(net "BMC_I2C5_D_PEB_SCL")
	)
	(segment
		(start 121.167398 -84.795614)
		(end 121.013474 -84.795614)
		(width 0.127)
		(layer "In5.Cu")
		(net "BMC_I2C5_D_PEB_SCL")
	)
	(segment
		(start 114.466624 -105.8164)
		(end 120.904 -105.8164)
		(width 0.127)
		(layer "In5.Cu")
		(net "BMC_I2C5_D_PEB_SCL")
	)
	(segment
		(start 15.246858 -180.014372)
		(end 20.46351 -180.014372)
		(width 0.127)
		(layer "In5.Cu")
		(net "BMC_I2C5_D_PEB_SCL")
	)
	(segment
		(start 120.889014 -84.41182)
		(end 120.88876 -84.398612)
		(width 0.127)
		(layer "In5.Cu")
		(net "BMC_I2C5_D_PEB_SCL")
	)
	(segment
		(start 108.591858 -50.531268)
		(end 108.145326 -50.9778)
		(width 0.127)
		(layer "In5.Cu")
		(net "BMC_I2C5_D_PEB_SCL")
	)
	(segment
		(start 110.207298 -20.30984)
		(end 110.207298 -39.566088)
		(width 0.127)
		(layer "In5.Cu")
		(net "BMC_I2C5_D_PEB_SCL")
	)
	(segment
		(start 120.993662 -86.134448)
		(end 120.993662 -84.96935)
		(width 0.127)
		(layer "In5.Cu")
		(net "BMC_I2C5_D_PEB_SCL")
	)
	(segment
		(start 250.337066 -6.729476)
		(end 250.800362 -6.26618)
		(width 0.127)
		(layer "In5.Cu")
		(net "BMC_I2C5_D_PEB_SCL")
	)
	(segment
		(start 156.437076 -83.076796)
		(end 158.424118 -83.076796)
		(width 0.127)
		(layer "In5.Cu")
		(net "BMC_I2C5_D_PEB_SCL")
	)
	(segment
		(start 59.413648 -106.541824)
		(end 59.413648 -109.342428)
		(width 0.12065)
		(layer "F.Cu")
		(net "BMC_I2C5_D_PEB_DEVICE_SDA")
	)
	(segment
		(start 35.7251 -184.8612)
		(end 36.022788 -185.158888)
		(width 0.12065)
		(layer "F.Cu")
		(net "BMC_I2C5_D_PEB_DEVICE_SDA")
	)
	(segment
		(start 57.21985 -116.352574)
		(end 58.10885 -117.241574)
		(width 0.12065)
		(layer "F.Cu")
		(net "BMC_I2C5_D_PEB_DEVICE_SDA")
	)
	(segment
		(start 58.160666 -112.313466)
		(end 57.21985 -113.254282)
		(width 0.12065)
		(layer "F.Cu")
		(net "BMC_I2C5_D_PEB_DEVICE_SDA")
	)
	(segment
		(start 50.995072 -97.707196)
		(end 59.413902 -106.126026)
		(width 0.12065)
		(layer "F.Cu")
		(net "BMC_I2C5_D_PEB_DEVICE_SDA")
	)
	(segment
		(start 30.4292 -59.570874)
		(end 29.303726 -58.4454)
		(width 0.12065)
		(layer "F.Cu")
		(net "BMC_I2C5_D_PEB_DEVICE_SDA")
	)
	(segment
		(start 57.21985 -113.254282)
		(end 57.21985 -116.352574)
		(width 0.12065)
		(layer "F.Cu")
		(net "BMC_I2C5_D_PEB_DEVICE_SDA")
	)
	(segment
		(start 58.10885 -117.241574)
		(end 58.10885 -119.309896)
		(width 0.12065)
		(layer "F.Cu")
		(net "BMC_I2C5_D_PEB_DEVICE_SDA")
	)
	(segment
		(start 50.995072 -81.119472)
		(end 50.995072 -97.707196)
		(width 0.12065)
		(layer "F.Cu")
		(net "BMC_I2C5_D_PEB_DEVICE_SDA")
	)
	(segment
		(start 36.022788 -185.158888)
		(end 36.481512 -185.158888)
		(width 0.12065)
		(layer "F.Cu")
		(net "BMC_I2C5_D_PEB_DEVICE_SDA")
	)
	(segment
		(start 59.413648 -109.342428)
		(end 58.160666 -110.59541)
		(width 0.12065)
		(layer "F.Cu")
		(net "BMC_I2C5_D_PEB_DEVICE_SDA")
	)
	(segment
		(start 42.5958 -74.299318)
		(end 42.89933 -74.602848)
		(width 0.12065)
		(layer "F.Cu")
		(net "BMC_I2C5_D_PEB_DEVICE_SDA")
	)
	(segment
		(start 29.303726 -58.4454)
		(end 27.8257 -58.4454)
		(width 0.12065)
		(layer "F.Cu")
		(net "BMC_I2C5_D_PEB_DEVICE_SDA")
	)
	(segment
		(start 59.413902 -106.126026)
		(end 59.413902 -106.54157)
		(width 0.12065)
		(layer "F.Cu")
		(net "BMC_I2C5_D_PEB_DEVICE_SDA")
	)
	(segment
		(start 59.413902 -106.54157)
		(end 59.413648 -106.541824)
		(width 0.12065)
		(layer "F.Cu")
		(net "BMC_I2C5_D_PEB_DEVICE_SDA")
	)
	(segment
		(start 58.160666 -110.59541)
		(end 58.160666 -112.313466)
		(width 0.12065)
		(layer "F.Cu")
		(net "BMC_I2C5_D_PEB_DEVICE_SDA")
	)
	(segment
		(start 42.89933 -74.602848)
		(end 44.478448 -74.602848)
		(width 0.12065)
		(layer "F.Cu")
		(net "BMC_I2C5_D_PEB_DEVICE_SDA")
	)
	(segment
		(start 57.8358 -119.582946)
		(end 57.8358 -119.9388)
		(width 0.12065)
		(layer "F.Cu")
		(net "BMC_I2C5_D_PEB_DEVICE_SDA")
	)
	(segment
		(start 36.481512 -185.158888)
		(end 36.6776 -184.9628)
		(width 0.12065)
		(layer "F.Cu")
		(net "BMC_I2C5_D_PEB_DEVICE_SDA")
	)
	(segment
		(start 44.478448 -74.602848)
		(end 50.995072 -81.119472)
		(width 0.12065)
		(layer "F.Cu")
		(net "BMC_I2C5_D_PEB_DEVICE_SDA")
	)
	(segment
		(start 58.10885 -119.309896)
		(end 57.8358 -119.582946)
		(width 0.12065)
		(layer "F.Cu")
		(net "BMC_I2C5_D_PEB_DEVICE_SDA")
	)
	(via
		(at 30.4292 -59.570874)
		(size 0.508)
		(drill 0.254)
		(layers "F.Cu" "B.Cu")
		(net "BMC_I2C5_D_PEB_DEVICE_SDA")
	)
	(via
		(at 34.847276 -184.797954)
		(size 0.7112)
		(drill 0.3556)
		(layers "F.Cu" "B.Cu")
		(net "BMC_I2C5_D_PEB_DEVICE_SDA")
	)
	(via
		(at 36.6776 -184.9628)
		(size 0.508)
		(drill 0.254)
		(layers "F.Cu" "B.Cu")
		(net "BMC_I2C5_D_PEB_DEVICE_SDA")
	)
	(via
		(at 42.5958 -74.299318)
		(size 0.508)
		(drill 0.254)
		(layers "F.Cu" "B.Cu")
		(net "BMC_I2C5_D_PEB_DEVICE_SDA")
	)
	(via
		(at 57.8358 -119.9388)
		(size 0.508)
		(drill 0.254)
		(layers "F.Cu" "B.Cu")
		(net "BMC_I2C5_D_PEB_DEVICE_SDA")
	)
	(segment
		(start 34.847276 -185.110882)
		(end 36.529518 -185.110882)
		(width 0.12065)
		(layer "B.Cu")
		(net "BMC_I2C5_D_PEB_DEVICE_SDA")
	)
	(segment
		(start 28.4099 -184.8866)
		(end 28.634182 -185.110882)
		(width 0.12065)
		(layer "B.Cu")
		(net "BMC_I2C5_D_PEB_DEVICE_SDA")
	)
	(segment
		(start 56.667654 -120.2944)
		(end 55.905654 -121.0564)
		(width 0.12065)
		(layer "B.Cu")
		(net "BMC_I2C5_D_PEB_DEVICE_SDA")
	)
	(segment
		(start 57.35955 -120.2944)
		(end 56.667654 -120.2944)
		(width 0.12065)
		(layer "B.Cu")
		(net "BMC_I2C5_D_PEB_DEVICE_SDA")
	)
	(segment
		(start 34.847276 -185.110882)
		(end 34.847276 -184.797954)
		(width 0.12065)
		(layer "B.Cu")
		(net "BMC_I2C5_D_PEB_DEVICE_SDA")
	)
	(segment
		(start 57.71515 -119.9388)
		(end 57.35955 -120.2944)
		(width 0.12065)
		(layer "B.Cu")
		(net "BMC_I2C5_D_PEB_DEVICE_SDA")
	)
	(segment
		(start 55.905654 -121.0564)
		(end 54.669182 -121.0564)
		(width 0.12065)
		(layer "B.Cu")
		(net "BMC_I2C5_D_PEB_DEVICE_SDA")
	)
	(segment
		(start 28.634182 -185.110882)
		(end 34.847276 -185.110882)
		(width 0.12065)
		(layer "B.Cu")
		(net "BMC_I2C5_D_PEB_DEVICE_SDA")
	)
	(segment
		(start 58.249566 -120.352566)
		(end 57.8358 -119.9388)
		(width 0.12065)
		(layer "B.Cu")
		(net "BMC_I2C5_D_PEB_DEVICE_SDA")
	)
	(segment
		(start 57.8358 -119.9388)
		(end 57.71515 -119.9388)
		(width 0.12065)
		(layer "B.Cu")
		(net "BMC_I2C5_D_PEB_DEVICE_SDA")
	)
	(segment
		(start 58.773822 -120.352566)
		(end 58.249566 -120.352566)
		(width 0.12065)
		(layer "B.Cu")
		(net "BMC_I2C5_D_PEB_DEVICE_SDA")
	)
	(segment
		(start 36.529518 -185.110882)
		(end 36.6776 -184.9628)
		(width 0.12065)
		(layer "B.Cu")
		(net "BMC_I2C5_D_PEB_DEVICE_SDA")
	)
	(segment
		(start 54.669182 -121.0564)
		(end 54.420008 -120.807226)
		(width 0.12065)
		(layer "B.Cu")
		(net "BMC_I2C5_D_PEB_DEVICE_SDA")
	)
	(segment
		(start 60.3504 -123.469146)
		(end 58.649362 -125.170184)
		(width 0.127)
		(layer "In5.Cu")
		(net "BMC_I2C5_D_PEB_DEVICE_SDA")
	)
	(segment
		(start 57.9628 -120.2182)
		(end 59.240166 -120.2182)
		(width 0.127)
		(layer "In5.Cu")
		(net "BMC_I2C5_D_PEB_DEVICE_SDA")
	)
	(segment
		(start 56.7944 -171.126912)
		(end 54.6481 -173.273212)
		(width 0.127)
		(layer "In5.Cu")
		(net "BMC_I2C5_D_PEB_DEVICE_SDA")
	)
	(segment
		(start 58.649362 -129.216404)
		(end 57.484772 -130.380994)
		(width 0.127)
		(layer "In5.Cu")
		(net "BMC_I2C5_D_PEB_DEVICE_SDA")
	)
	(segment
		(start 28.3464 -61.653674)
		(end 28.3464 -64.389)
		(width 0.127)
		(layer "In5.Cu")
		(net "BMC_I2C5_D_PEB_DEVICE_SDA")
	)
	(segment
		(start 35.56 -184.126378)
		(end 35.56 -184.792874)
		(width 0.127)
		(layer "In5.Cu")
		(net "BMC_I2C5_D_PEB_DEVICE_SDA")
	)
	(segment
		(start 58.3184 -138.8872)
		(end 57.8358 -139.3698)
		(width 0.127)
		(layer "In5.Cu")
		(net "BMC_I2C5_D_PEB_DEVICE_SDA")
	)
	(segment
		(start 60.3504 -121.328434)
		(end 60.3504 -123.469146)
		(width 0.127)
		(layer "In5.Cu")
		(net "BMC_I2C5_D_PEB_DEVICE_SDA")
	)
	(segment
		(start 57.8358 -119.9388)
		(end 57.8358 -120.0912)
		(width 0.127)
		(layer "In5.Cu")
		(net "BMC_I2C5_D_PEB_DEVICE_SDA")
	)
	(segment
		(start 56.7944 -148.114766)
		(end 56.7944 -171.126912)
		(width 0.127)
		(layer "In5.Cu")
		(net "BMC_I2C5_D_PEB_DEVICE_SDA")
	)
	(segment
		(start 57.484772 -130.380994)
		(end 57.484772 -135.810752)
		(width 0.127)
		(layer "In5.Cu")
		(net "BMC_I2C5_D_PEB_DEVICE_SDA")
	)
	(segment
		(start 28.3464 -64.389)
		(end 29.9974 -66.04)
		(width 0.127)
		(layer "In5.Cu")
		(net "BMC_I2C5_D_PEB_DEVICE_SDA")
	)
	(segment
		(start 35.764978 -183.9214)
		(end 35.56 -184.126378)
		(width 0.127)
		(layer "In5.Cu")
		(net "BMC_I2C5_D_PEB_DEVICE_SDA")
	)
	(segment
		(start 39.827454 -74.5998)
		(end 42.295318 -74.5998)
		(width 0.127)
		(layer "In5.Cu")
		(net "BMC_I2C5_D_PEB_DEVICE_SDA")
	)
	(segment
		(start 57.8358 -139.3698)
		(end 57.8358 -147.073366)
		(width 0.127)
		(layer "In5.Cu")
		(net "BMC_I2C5_D_PEB_DEVICE_SDA")
	)
	(segment
		(start 57.8358 -120.0912)
		(end 57.9628 -120.2182)
		(width 0.127)
		(layer "In5.Cu")
		(net "BMC_I2C5_D_PEB_DEVICE_SDA")
	)
	(segment
		(start 38.911022 -183.9214)
		(end 35.764978 -183.9214)
		(width 0.127)
		(layer "In5.Cu")
		(net "BMC_I2C5_D_PEB_DEVICE_SDA")
	)
	(segment
		(start 54.6481 -179.659534)
		(end 56.1848 -181.196234)
		(width 0.127)
		(layer "In5.Cu")
		(net "BMC_I2C5_D_PEB_DEVICE_SDA")
	)
	(segment
		(start 58.649362 -125.170184)
		(end 58.649362 -129.216404)
		(width 0.127)
		(layer "In5.Cu")
		(net "BMC_I2C5_D_PEB_DEVICE_SDA")
	)
	(segment
		(start 29.9974 -66.04)
		(end 31.267654 -66.04)
		(width 0.127)
		(layer "In5.Cu")
		(net "BMC_I2C5_D_PEB_DEVICE_SDA")
	)
	(segment
		(start 44.087288 -185.3438)
		(end 40.333422 -185.3438)
		(width 0.127)
		(layer "In5.Cu")
		(net "BMC_I2C5_D_PEB_DEVICE_SDA")
	)
	(segment
		(start 56.1848 -187.6552)
		(end 52.578 -191.262)
		(width 0.127)
		(layer "In5.Cu")
		(net "BMC_I2C5_D_PEB_DEVICE_SDA")
	)
	(segment
		(start 31.267654 -66.04)
		(end 39.827454 -74.5998)
		(width 0.127)
		(layer "In5.Cu")
		(net "BMC_I2C5_D_PEB_DEVICE_SDA")
	)
	(segment
		(start 57.8358 -147.073366)
		(end 56.7944 -148.114766)
		(width 0.127)
		(layer "In5.Cu")
		(net "BMC_I2C5_D_PEB_DEVICE_SDA")
	)
	(segment
		(start 58.3184 -136.64438)
		(end 58.3184 -138.8872)
		(width 0.127)
		(layer "In5.Cu")
		(net "BMC_I2C5_D_PEB_DEVICE_SDA")
	)
	(segment
		(start 57.484772 -135.810752)
		(end 58.3184 -136.64438)
		(width 0.127)
		(layer "In5.Cu")
		(net "BMC_I2C5_D_PEB_DEVICE_SDA")
	)
	(segment
		(start 40.333422 -185.3438)
		(end 38.911022 -183.9214)
		(width 0.127)
		(layer "In5.Cu")
		(net "BMC_I2C5_D_PEB_DEVICE_SDA")
	)
	(segment
		(start 35.729926 -184.9628)
		(end 36.6776 -184.9628)
		(width 0.127)
		(layer "In5.Cu")
		(net "BMC_I2C5_D_PEB_DEVICE_SDA")
	)
	(segment
		(start 52.578 -191.262)
		(end 50.005488 -191.262)
		(width 0.127)
		(layer "In5.Cu")
		(net "BMC_I2C5_D_PEB_DEVICE_SDA")
	)
	(segment
		(start 50.005488 -191.262)
		(end 44.087288 -185.3438)
		(width 0.127)
		(layer "In5.Cu")
		(net "BMC_I2C5_D_PEB_DEVICE_SDA")
	)
	(segment
		(start 30.4292 -59.570874)
		(end 28.3464 -61.653674)
		(width 0.127)
		(layer "In5.Cu")
		(net "BMC_I2C5_D_PEB_DEVICE_SDA")
	)
	(segment
		(start 59.240166 -120.2182)
		(end 60.3504 -121.328434)
		(width 0.127)
		(layer "In5.Cu")
		(net "BMC_I2C5_D_PEB_DEVICE_SDA")
	)
	(segment
		(start 35.56 -184.792874)
		(end 35.729926 -184.9628)
		(width 0.127)
		(layer "In5.Cu")
		(net "BMC_I2C5_D_PEB_DEVICE_SDA")
	)
	(segment
		(start 42.295318 -74.5998)
		(end 42.5958 -74.299318)
		(width 0.127)
		(layer "In5.Cu")
		(net "BMC_I2C5_D_PEB_DEVICE_SDA")
	)
	(segment
		(start 56.1848 -181.196234)
		(end 56.1848 -187.6552)
		(width 0.127)
		(layer "In5.Cu")
		(net "BMC_I2C5_D_PEB_DEVICE_SDA")
	)
	(segment
		(start 54.6481 -173.273212)
		(end 54.6481 -179.659534)
		(width 0.127)
		(layer "In5.Cu")
		(net "BMC_I2C5_D_PEB_DEVICE_SDA")
	)
	(segment
		(start 58.911998 -106.333798)
		(end 58.911998 -109.134402)
		(width 0.12065)
		(layer "F.Cu")
		(net "BMC_I2C5_D_PEB_DEVICE_SCL")
	)
	(segment
		(start 42.89933 -75.104498)
		(end 44.270422 -75.104498)
		(width 0.12065)
		(layer "F.Cu")
		(net "BMC_I2C5_D_PEB_DEVICE_SCL")
	)
	(segment
		(start 36.511738 -185.660538)
		(end 36.6776 -185.8264)
		(width 0.12065)
		(layer "F.Cu")
		(net "BMC_I2C5_D_PEB_DEVICE_SCL")
	)
	(segment
		(start 57.565798 -121.040398)
		(end 57.8358 -121.040398)
		(width 0.12065)
		(layer "F.Cu")
		(net "BMC_I2C5_D_PEB_DEVICE_SCL")
	)
	(segment
		(start 42.5958 -75.408028)
		(end 42.89933 -75.104498)
		(width 0.12065)
		(layer "F.Cu")
		(net "BMC_I2C5_D_PEB_DEVICE_SCL")
	)
	(segment
		(start 56.7182 -113.046256)
		(end 56.7182 -116.5606)
		(width 0.12065)
		(layer "F.Cu")
		(net "BMC_I2C5_D_PEB_DEVICE_SCL")
	)
	(segment
		(start 57.659016 -110.387384)
		(end 57.659016 -112.10544)
		(width 0.12065)
		(layer "F.Cu")
		(net "BMC_I2C5_D_PEB_DEVICE_SCL")
	)
	(segment
		(start 57.659016 -112.10544)
		(end 56.7182 -113.046256)
		(width 0.12065)
		(layer "F.Cu")
		(net "BMC_I2C5_D_PEB_DEVICE_SCL")
	)
	(segment
		(start 57.303162 -119.405908)
		(end 57.30113 -120.77573)
		(width 0.12065)
		(layer "F.Cu")
		(net "BMC_I2C5_D_PEB_DEVICE_SCL")
	)
	(segment
		(start 36.068762 -185.660538)
		(end 36.511738 -185.660538)
		(width 0.12065)
		(layer "F.Cu")
		(net "BMC_I2C5_D_PEB_DEVICE_SCL")
	)
	(segment
		(start 24.8539 -67.76466)
		(end 24.75992 -67.67068)
		(width 0.12065)
		(layer "F.Cu")
		(net "BMC_I2C5_D_PEB_DEVICE_SCL")
	)
	(segment
		(start 57.6072 -117.4496)
		(end 57.6072 -119.10187)
		(width 0.12065)
		(layer "F.Cu")
		(net "BMC_I2C5_D_PEB_DEVICE_SCL")
	)
	(segment
		(start 57.6072 -119.10187)
		(end 57.303162 -119.405908)
		(width 0.12065)
		(layer "F.Cu")
		(net "BMC_I2C5_D_PEB_DEVICE_SCL")
	)
	(segment
		(start 44.270422 -75.104498)
		(end 50.493422 -81.327498)
		(width 0.12065)
		(layer "F.Cu")
		(net "BMC_I2C5_D_PEB_DEVICE_SCL")
	)
	(segment
		(start 50.493422 -97.915222)
		(end 58.911998 -106.333798)
		(width 0.12065)
		(layer "F.Cu")
		(net "BMC_I2C5_D_PEB_DEVICE_SCL")
	)
	(segment
		(start 58.911998 -109.134402)
		(end 57.659016 -110.387384)
		(width 0.12065)
		(layer "F.Cu")
		(net "BMC_I2C5_D_PEB_DEVICE_SCL")
	)
	(segment
		(start 56.7182 -116.5606)
		(end 57.6072 -117.4496)
		(width 0.12065)
		(layer "F.Cu")
		(net "BMC_I2C5_D_PEB_DEVICE_SCL")
	)
	(segment
		(start 57.30113 -120.77573)
		(end 57.565798 -121.040398)
		(width 0.12065)
		(layer "F.Cu")
		(net "BMC_I2C5_D_PEB_DEVICE_SCL")
	)
	(segment
		(start 35.7251 -186.0042)
		(end 36.068762 -185.660538)
		(width 0.12065)
		(layer "F.Cu")
		(net "BMC_I2C5_D_PEB_DEVICE_SCL")
	)
	(segment
		(start 50.493422 -81.327498)
		(end 50.493422 -97.915222)
		(width 0.12065)
		(layer "F.Cu")
		(net "BMC_I2C5_D_PEB_DEVICE_SCL")
	)
	(segment
		(start 24.8539 -69.088)
		(end 24.8539 -67.76466)
		(width 0.12065)
		(layer "F.Cu")
		(net "BMC_I2C5_D_PEB_DEVICE_SCL")
	)
	(via
		(at 42.5958 -75.408028)
		(size 0.508)
		(drill 0.254)
		(layers "F.Cu" "B.Cu")
		(net "BMC_I2C5_D_PEB_DEVICE_SCL")
	)
	(via
		(at 31.030418 -185.92546)
		(size 0.7112)
		(drill 0.3556)
		(layers "F.Cu" "B.Cu")
		(net "BMC_I2C5_D_PEB_DEVICE_SCL")
	)
	(via
		(at 57.8358 -121.040398)
		(size 0.508)
		(drill 0.254)
		(layers "F.Cu" "B.Cu")
		(net "BMC_I2C5_D_PEB_DEVICE_SCL")
	)
	(via
		(at 36.6776 -185.8264)
		(size 0.508)
		(drill 0.254)
		(layers "F.Cu" "B.Cu")
		(net "BMC_I2C5_D_PEB_DEVICE_SCL")
	)
	(via
		(at 24.75992 -67.67068)
		(size 0.508)
		(drill 0.254)
		(layers "F.Cu" "B.Cu")
		(net "BMC_I2C5_D_PEB_DEVICE_SCL")
	)
	(segment
		(start 58.697114 -121.291858)
		(end 58.773822 -121.368566)
		(width 0.12065)
		(layer "B.Cu")
		(net "BMC_I2C5_D_PEB_DEVICE_SCL")
	)
	(segment
		(start 56.11368 -121.55805)
		(end 56.87568 -120.79605)
		(width 0.12065)
		(layer "B.Cu")
		(net "BMC_I2C5_D_PEB_DEVICE_SCL")
	)
	(segment
		(start 36.463732 -185.612532)
		(end 36.6776 -185.8264)
		(width 0.12065)
		(layer "B.Cu")
		(net "BMC_I2C5_D_PEB_DEVICE_SCL")
	)
	(segment
		(start 31.030418 -185.612532)
		(end 36.463732 -185.612532)
		(width 0.12065)
		(layer "B.Cu")
		(net "BMC_I2C5_D_PEB_DEVICE_SCL")
	)
	(segment
		(start 54.420008 -121.823226)
		(end 54.685184 -121.55805)
		(width 0.12065)
		(layer "B.Cu")
		(net "BMC_I2C5_D_PEB_DEVICE_SCL")
	)
	(segment
		(start 57.591452 -120.79605)
		(end 57.8358 -121.040398)
		(width 0.12065)
		(layer "B.Cu")
		(net "BMC_I2C5_D_PEB_DEVICE_SCL")
	)
	(segment
		(start 54.685184 -121.55805)
		(end 56.11368 -121.55805)
		(width 0.12065)
		(layer "B.Cu")
		(net "BMC_I2C5_D_PEB_DEVICE_SCL")
	)
	(segment
		(start 58.08726 -121.291858)
		(end 58.697114 -121.291858)
		(width 0.12065)
		(layer "B.Cu")
		(net "BMC_I2C5_D_PEB_DEVICE_SCL")
	)
	(segment
		(start 28.4099 -185.9026)
		(end 28.699968 -185.612532)
		(width 0.12065)
		(layer "B.Cu")
		(net "BMC_I2C5_D_PEB_DEVICE_SCL")
	)
	(segment
		(start 56.87568 -120.79605)
		(end 57.591452 -120.79605)
		(width 0.12065)
		(layer "B.Cu")
		(net "BMC_I2C5_D_PEB_DEVICE_SCL")
	)
	(segment
		(start 28.699968 -185.612532)
		(end 31.030418 -185.612532)
		(width 0.12065)
		(layer "B.Cu")
		(net "BMC_I2C5_D_PEB_DEVICE_SCL")
	)
	(segment
		(start 57.8358 -121.040398)
		(end 58.08726 -121.291858)
		(width 0.12065)
		(layer "B.Cu")
		(net "BMC_I2C5_D_PEB_DEVICE_SCL")
	)
	(segment
		(start 31.030418 -185.612532)
		(end 31.030418 -185.92546)
		(width 0.12065)
		(layer "B.Cu")
		(net "BMC_I2C5_D_PEB_DEVICE_SCL")
	)
	(segment
		(start 44.297854 -184.8358)
		(end 40.543988 -184.8358)
		(width 0.127)
		(layer "In5.Cu")
		(net "BMC_I2C5_D_PEB_DEVICE_SCL")
	)
	(segment
		(start 35.63366 -185.5851)
		(end 36.4363 -185.5851)
		(width 0.127)
		(layer "In5.Cu")
		(net "BMC_I2C5_D_PEB_DEVICE_SCL")
	)
	(segment
		(start 59.0296 -120.7262)
		(end 59.8424 -121.539)
		(width 0.127)
		(layer "In5.Cu")
		(net "BMC_I2C5_D_PEB_DEVICE_SCL")
	)
	(segment
		(start 57.3278 -146.8628)
		(end 56.2864 -147.9042)
		(width 0.127)
		(layer "In5.Cu")
		(net "BMC_I2C5_D_PEB_DEVICE_SCL")
	)
	(segment
		(start 35.052 -183.915812)
		(end 35.052 -185.00344)
		(width 0.127)
		(layer "In5.Cu")
		(net "BMC_I2C5_D_PEB_DEVICE_SCL")
	)
	(segment
		(start 54.1401 -173.062646)
		(end 54.1401 -179.8701)
		(width 0.127)
		(layer "In5.Cu")
		(net "BMC_I2C5_D_PEB_DEVICE_SCL")
	)
	(segment
		(start 55.6768 -181.4068)
		(end 55.6768 -187.444634)
		(width 0.127)
		(layer "In5.Cu")
		(net "BMC_I2C5_D_PEB_DEVICE_SCL")
	)
	(segment
		(start 58.141362 -129.005838)
		(end 56.976772 -130.170428)
		(width 0.127)
		(layer "In5.Cu")
		(net "BMC_I2C5_D_PEB_DEVICE_SCL")
	)
	(segment
		(start 58.141362 -124.959618)
		(end 58.141362 -129.005838)
		(width 0.127)
		(layer "In5.Cu")
		(net "BMC_I2C5_D_PEB_DEVICE_SCL")
	)
	(segment
		(start 59.8424 -121.539)
		(end 59.8424 -123.25858)
		(width 0.127)
		(layer "In5.Cu")
		(net "BMC_I2C5_D_PEB_DEVICE_SCL")
	)
	(segment
		(start 56.976772 -130.170428)
		(end 56.976772 -136.021318)
		(width 0.127)
		(layer "In5.Cu")
		(net "BMC_I2C5_D_PEB_DEVICE_SCL")
	)
	(segment
		(start 57.8104 -138.676634)
		(end 57.3278 -139.159234)
		(width 0.127)
		(layer "In5.Cu")
		(net "BMC_I2C5_D_PEB_DEVICE_SCL")
	)
	(segment
		(start 50.216054 -190.754)
		(end 44.297854 -184.8358)
		(width 0.127)
		(layer "In5.Cu")
		(net "BMC_I2C5_D_PEB_DEVICE_SCL")
	)
	(segment
		(start 58.149998 -120.7262)
		(end 59.0296 -120.7262)
		(width 0.127)
		(layer "In5.Cu")
		(net "BMC_I2C5_D_PEB_DEVICE_SCL")
	)
	(segment
		(start 52.367434 -190.754)
		(end 50.216054 -190.754)
		(width 0.127)
		(layer "In5.Cu")
		(net "BMC_I2C5_D_PEB_DEVICE_SCL")
	)
	(segment
		(start 56.2864 -147.9042)
		(end 56.2864 -170.916346)
		(width 0.127)
		(layer "In5.Cu")
		(net "BMC_I2C5_D_PEB_DEVICE_SCL")
	)
	(segment
		(start 42.295572 -75.1078)
		(end 42.5958 -75.408028)
		(width 0.127)
		(layer "In5.Cu")
		(net "BMC_I2C5_D_PEB_DEVICE_SCL")
	)
	(segment
		(start 59.8424 -123.25858)
		(end 58.141362 -124.959618)
		(width 0.127)
		(layer "In5.Cu")
		(net "BMC_I2C5_D_PEB_DEVICE_SCL")
	)
	(segment
		(start 39.121588 -183.4134)
		(end 35.554412 -183.4134)
		(width 0.127)
		(layer "In5.Cu")
		(net "BMC_I2C5_D_PEB_DEVICE_SCL")
	)
	(segment
		(start 36.4363 -185.5851)
		(end 36.6776 -185.8264)
		(width 0.127)
		(layer "In5.Cu")
		(net "BMC_I2C5_D_PEB_DEVICE_SCL")
	)
	(segment
		(start 57.3278 -139.159234)
		(end 57.3278 -146.8628)
		(width 0.127)
		(layer "In5.Cu")
		(net "BMC_I2C5_D_PEB_DEVICE_SCL")
	)
	(segment
		(start 54.1401 -179.8701)
		(end 55.6768 -181.4068)
		(width 0.127)
		(layer "In5.Cu")
		(net "BMC_I2C5_D_PEB_DEVICE_SCL")
	)
	(segment
		(start 56.976772 -136.021318)
		(end 57.8104 -136.854946)
		(width 0.127)
		(layer "In5.Cu")
		(net "BMC_I2C5_D_PEB_DEVICE_SCL")
	)
	(segment
		(start 57.8358 -121.040398)
		(end 58.149998 -120.7262)
		(width 0.127)
		(layer "In5.Cu")
		(net "BMC_I2C5_D_PEB_DEVICE_SCL")
	)
	(segment
		(start 35.554412 -183.4134)
		(end 35.052 -183.915812)
		(width 0.127)
		(layer "In5.Cu")
		(net "BMC_I2C5_D_PEB_DEVICE_SCL")
	)
	(segment
		(start 57.8104 -136.854946)
		(end 57.8104 -138.676634)
		(width 0.127)
		(layer "In5.Cu")
		(net "BMC_I2C5_D_PEB_DEVICE_SCL")
	)
	(segment
		(start 40.543988 -184.8358)
		(end 39.121588 -183.4134)
		(width 0.127)
		(layer "In5.Cu")
		(net "BMC_I2C5_D_PEB_DEVICE_SCL")
	)
	(segment
		(start 55.6768 -187.444634)
		(end 52.367434 -190.754)
		(width 0.127)
		(layer "In5.Cu")
		(net "BMC_I2C5_D_PEB_DEVICE_SCL")
	)
	(segment
		(start 27.98699 -64.748156)
		(end 29.786834 -66.548)
		(width 0.127)
		(layer "In5.Cu")
		(net "BMC_I2C5_D_PEB_DEVICE_SCL")
	)
	(segment
		(start 27.682444 -64.748156)
		(end 27.98699 -64.748156)
		(width 0.127)
		(layer "In5.Cu")
		(net "BMC_I2C5_D_PEB_DEVICE_SCL")
	)
	(segment
		(start 56.2864 -170.916346)
		(end 54.1401 -173.062646)
		(width 0.127)
		(layer "In5.Cu")
		(net "BMC_I2C5_D_PEB_DEVICE_SCL")
	)
	(segment
		(start 35.052 -185.00344)
		(end 35.63366 -185.5851)
		(width 0.127)
		(layer "In5.Cu")
		(net "BMC_I2C5_D_PEB_DEVICE_SCL")
	)
	(segment
		(start 24.75992 -67.67068)
		(end 27.682444 -64.748156)
		(width 0.127)
		(layer "In5.Cu")
		(net "BMC_I2C5_D_PEB_DEVICE_SCL")
	)
	(segment
		(start 29.786834 -66.548)
		(end 31.057088 -66.548)
		(width 0.127)
		(layer "In5.Cu")
		(net "BMC_I2C5_D_PEB_DEVICE_SCL")
	)
	(segment
		(start 31.057088 -66.548)
		(end 39.616888 -75.1078)
		(width 0.127)
		(layer "In5.Cu")
		(net "BMC_I2C5_D_PEB_DEVICE_SCL")
	)
	(segment
		(start 39.616888 -75.1078)
		(end 42.295572 -75.1078)
		(width 0.127)
		(layer "In5.Cu")
		(net "BMC_I2C5_D_PEB_DEVICE_SCL")
	)
	(segment
		(start 30.3911 -181.4322)
		(end 30.3911 -182.0545)
		(width 0.12065)
		(layer "F.Cu")
		(net "BMC_I2C5_BUF_READY")
	)
	(segment
		(start 30.3911 -179.7812)
		(end 30.3911 -181.4322)
		(width 0.12065)
		(layer "F.Cu")
		(net "BMC_I2C5_BUF_READY")
	)
	(segment
		(start 30.3911 -182.0545)
		(end 29.98724 -182.45836)
		(width 0.12065)
		(layer "F.Cu")
		(net "BMC_I2C5_BUF_READY")
	)
	(segment
		(start 29.98724 -182.45836)
		(end 29.98724 -183.2991)
		(width 0.12065)
		(layer "F.Cu")
		(net "BMC_I2C5_BUF_READY")
	)
	(via
		(at 30.3911 -179.7812)
		(size 0.7112)
		(drill 0.3556)
		(layers "F.Cu" "B.Cu")
		(net "BMC_I2C5_BUF_READY")
	)
	(segment
		(start 69.00164 -120.390158)
		(end 69.540882 -120.9294)
		(width 0.12065)
		(layer "F.Cu")
		(net "BMC_I2C4_MINI4_SDA")
	)
	(segment
		(start 69.540882 -120.9294)
		(end 69.934582 -120.5357)
		(width 0.12065)
		(layer "F.Cu")
		(net "BMC_I2C4_MINI4_SDA")
	)
	(segment
		(start 164.338 -36.322)
		(end 166.243 -36.322)
		(width 0.12065)
		(layer "F.Cu")
		(net "BMC_I2C4_MINI4_SDA")
	)
	(segment
		(start 69.934582 -120.5357)
		(end 70.6374 -120.5357)
		(width 0.12065)
		(layer "F.Cu")
		(net "BMC_I2C4_MINI4_SDA")
	)
	(segment
		(start 69.00164 -120.0404)
		(end 69.00164 -120.390158)
		(width 0.12065)
		(layer "F.Cu")
		(net "BMC_I2C4_MINI4_SDA")
	)
	(via
		(at 166.751 -35.3822)
		(size 0.7112)
		(drill 0.3556)
		(layers "F.Cu" "B.Cu")
		(net "BMC_I2C4_MINI4_SDA")
	)
	(via
		(at 69.540882 -120.9294)
		(size 0.508)
		(drill 0.254)
		(layers "F.Cu" "B.Cu")
		(net "BMC_I2C4_MINI4_SDA")
	)
	(via
		(at 166.243 -36.322)
		(size 0.508)
		(drill 0.254)
		(layers "F.Cu" "B.Cu")
		(net "BMC_I2C4_MINI4_SDA")
	)
	(via
		(at 164.338 -36.322)
		(size 0.508)
		(drill 0.254)
		(layers "F.Cu" "B.Cu")
		(net "BMC_I2C4_MINI4_SDA")
	)
	(via
		(at 77.290422 -118.401084)
		(size 0.508)
		(drill 0.254)
		(layers "F.Cu" "B.Cu")
		(net "BMC_I2C4_MINI4_SDA")
	)
	(segment
		(start 164.084 -33.9725)
		(end 163.98494 -34.07156)
		(width 0.12065)
		(layer "B.Cu")
		(net "BMC_I2C4_MINI4_SDA")
	)
	(segment
		(start 166.243 -35.8902)
		(end 166.751 -35.3822)
		(width 0.12065)
		(layer "B.Cu")
		(net "BMC_I2C4_MINI4_SDA")
	)
	(segment
		(start 86.334346 -97.783396)
		(end 79.0194 -105.098342)
		(width 0.12065)
		(layer "B.Cu")
		(net "BMC_I2C4_MINI4_SDA")
	)
	(segment
		(start 123.655836 -40.16375)
		(end 121.230136 -37.73805)
		(width 0.12065)
		(layer "B.Cu")
		(net "BMC_I2C4_MINI4_SDA")
	)
	(segment
		(start 111.556038 -37.73805)
		(end 103.256588 -46.0375)
		(width 0.12065)
		(layer "B.Cu")
		(net "BMC_I2C4_MINI4_SDA")
	)
	(segment
		(start 166.243 -36.322)
		(end 166.243 -35.8902)
		(width 0.12065)
		(layer "B.Cu")
		(net "BMC_I2C4_MINI4_SDA")
	)
	(segment
		(start 141.54912 -41.0718)
		(end 141.126972 -40.649652)
		(width 0.12065)
		(layer "B.Cu")
		(net "BMC_I2C4_MINI4_SDA")
	)
	(segment
		(start 91.251278 -88.4174)
		(end 86.334346 -93.334332)
		(width 0.12065)
		(layer "B.Cu")
		(net "BMC_I2C4_MINI4_SDA")
	)
	(segment
		(start 79.0194 -105.098342)
		(end 79.0194 -117.294914)
		(width 0.12065)
		(layer "B.Cu")
		(net "BMC_I2C4_MINI4_SDA")
	)
	(segment
		(start 137.280904 -41.3004)
		(end 137.28065 -41.300654)
		(width 0.12065)
		(layer "B.Cu")
		(net "BMC_I2C4_MINI4_SDA")
	)
	(segment
		(start 99.7077 -62.627764)
		(end 99.7077 -84.3915)
		(width 0.12065)
		(layer "B.Cu")
		(net "BMC_I2C4_MINI4_SDA")
	)
	(segment
		(start 96.437704 -51.005994)
		(end 96.437704 -59.357768)
		(width 0.12065)
		(layer "B.Cu")
		(net "BMC_I2C4_MINI4_SDA")
	)
	(segment
		(start 78.06436 -118.249954)
		(end 77.441552 -118.249954)
		(width 0.12065)
		(layer "B.Cu")
		(net "BMC_I2C4_MINI4_SDA")
	)
	(segment
		(start 137.28065 -41.300654)
		(end 134.290054 -41.300654)
		(width 0.12065)
		(layer "B.Cu")
		(net "BMC_I2C4_MINI4_SDA")
	)
	(segment
		(start 163.98494 -34.07156)
		(end 163.98494 -35.96894)
		(width 0.12065)
		(layer "B.Cu")
		(net "BMC_I2C4_MINI4_SDA")
	)
	(segment
		(start 96.437704 -59.357768)
		(end 99.7077 -62.627764)
		(width 0.12065)
		(layer "B.Cu")
		(net "BMC_I2C4_MINI4_SDA")
	)
	(segment
		(start 101.406198 -46.0375)
		(end 96.437704 -51.005994)
		(width 0.12065)
		(layer "B.Cu")
		(net "BMC_I2C4_MINI4_SDA")
	)
	(segment
		(start 77.441552 -118.249954)
		(end 77.290422 -118.401084)
		(width 0.12065)
		(layer "B.Cu")
		(net "BMC_I2C4_MINI4_SDA")
	)
	(segment
		(start 99.7077 -84.3915)
		(end 95.6818 -88.4174)
		(width 0.12065)
		(layer "B.Cu")
		(net "BMC_I2C4_MINI4_SDA")
	)
	(segment
		(start 154.091132 -41.0718)
		(end 141.54912 -41.0718)
		(width 0.12065)
		(layer "B.Cu")
		(net "BMC_I2C4_MINI4_SDA")
	)
	(segment
		(start 163.98494 -35.96894)
		(end 164.338 -36.322)
		(width 0.12065)
		(layer "B.Cu")
		(net "BMC_I2C4_MINI4_SDA")
	)
	(segment
		(start 138.049 -40.649652)
		(end 137.398252 -41.3004)
		(width 0.12065)
		(layer "B.Cu")
		(net "BMC_I2C4_MINI4_SDA")
	)
	(segment
		(start 103.256588 -46.0375)
		(end 101.406198 -46.0375)
		(width 0.12065)
		(layer "B.Cu")
		(net "BMC_I2C4_MINI4_SDA")
	)
	(segment
		(start 161.74593 -41.420542)
		(end 154.439874 -41.420542)
		(width 0.12065)
		(layer "B.Cu")
		(net "BMC_I2C4_MINI4_SDA")
	)
	(segment
		(start 141.126972 -40.649652)
		(end 138.049 -40.649652)
		(width 0.12065)
		(layer "B.Cu")
		(net "BMC_I2C4_MINI4_SDA")
	)
	(segment
		(start 166.751 -35.3822)
		(end 167.513 -34.6202)
		(width 0.12065)
		(layer "B.Cu")
		(net "BMC_I2C4_MINI4_SDA")
	)
	(segment
		(start 167.513 -34.6202)
		(end 167.513 -33.9725)
		(width 0.12065)
		(layer "B.Cu")
		(net "BMC_I2C4_MINI4_SDA")
	)
	(segment
		(start 134.290054 -41.300654)
		(end 133.15315 -40.16375)
		(width 0.12065)
		(layer "B.Cu")
		(net "BMC_I2C4_MINI4_SDA")
	)
	(segment
		(start 121.230136 -37.73805)
		(end 111.556038 -37.73805)
		(width 0.12065)
		(layer "B.Cu")
		(net "BMC_I2C4_MINI4_SDA")
	)
	(segment
		(start 164.338 -36.322)
		(end 164.4904 -36.4744)
		(width 0.12065)
		(layer "B.Cu")
		(net "BMC_I2C4_MINI4_SDA")
	)
	(segment
		(start 164.4904 -36.4744)
		(end 164.4904 -38.676072)
		(width 0.12065)
		(layer "B.Cu")
		(net "BMC_I2C4_MINI4_SDA")
	)
	(segment
		(start 86.334346 -93.334332)
		(end 86.334346 -97.783396)
		(width 0.12065)
		(layer "B.Cu")
		(net "BMC_I2C4_MINI4_SDA")
	)
	(segment
		(start 95.6818 -88.4174)
		(end 91.251278 -88.4174)
		(width 0.12065)
		(layer "B.Cu")
		(net "BMC_I2C4_MINI4_SDA")
	)
	(segment
		(start 154.439874 -41.420542)
		(end 154.091132 -41.0718)
		(width 0.12065)
		(layer "B.Cu")
		(net "BMC_I2C4_MINI4_SDA")
	)
	(segment
		(start 133.15315 -40.16375)
		(end 123.655836 -40.16375)
		(width 0.12065)
		(layer "B.Cu")
		(net "BMC_I2C4_MINI4_SDA")
	)
	(segment
		(start 79.0194 -117.294914)
		(end 78.06436 -118.249954)
		(width 0.12065)
		(layer "B.Cu")
		(net "BMC_I2C4_MINI4_SDA")
	)
	(segment
		(start 164.4904 -38.676072)
		(end 161.74593 -41.420542)
		(width 0.12065)
		(layer "B.Cu")
		(net "BMC_I2C4_MINI4_SDA")
	)
	(segment
		(start 137.398252 -41.3004)
		(end 137.280904 -41.3004)
		(width 0.12065)
		(layer "B.Cu")
		(net "BMC_I2C4_MINI4_SDA")
	)
	(segment
		(start 68.824094 -120.9294)
		(end 68.673726 -120.779032)
		(width 0.127)
		(layer "In2.Cu")
		(net "BMC_I2C4_MINI4_SDA")
	)
	(segment
		(start 73.50633 -120.19407)
		(end 75.17638 -118.52402)
		(width 0.127)
		(layer "In2.Cu")
		(net "BMC_I2C4_MINI4_SDA")
	)
	(segment
		(start 69.540882 -120.9294)
		(end 68.824094 -120.9294)
		(width 0.127)
		(layer "In2.Cu")
		(net "BMC_I2C4_MINI4_SDA")
	)
	(segment
		(start 76.902564 -118.52402)
		(end 77.0255 -118.401084)
		(width 0.127)
		(layer "In2.Cu")
		(net "BMC_I2C4_MINI4_SDA")
	)
	(segment
		(start 68.932298 -120.19407)
		(end 73.50633 -120.19407)
		(width 0.127)
		(layer "In2.Cu")
		(net "BMC_I2C4_MINI4_SDA")
	)
	(segment
		(start 68.673726 -120.452642)
		(end 68.932298 -120.19407)
		(width 0.127)
		(layer "In2.Cu")
		(net "BMC_I2C4_MINI4_SDA")
	)
	(segment
		(start 75.17638 -118.52402)
		(end 76.902564 -118.52402)
		(width 0.127)
		(layer "In2.Cu")
		(net "BMC_I2C4_MINI4_SDA")
	)
	(segment
		(start 68.673726 -120.779032)
		(end 68.673726 -120.452642)
		(width 0.127)
		(layer "In2.Cu")
		(net "BMC_I2C4_MINI4_SDA")
	)
	(segment
		(start 77.0255 -118.401084)
		(end 77.290422 -118.401084)
		(width 0.127)
		(layer "In2.Cu")
		(net "BMC_I2C4_MINI4_SDA")
	)
	(segment
		(start 67.70116 -121.570242)
		(end 67.70116 -121.92)
		(width 0.12065)
		(layer "F.Cu")
		(net "BMC_I2C4_MINI4_SCL")
	)
	(segment
		(start 66.9798 -120.5484)
		(end 66.9798 -120.848882)
		(width 0.12065)
		(layer "F.Cu")
		(net "BMC_I2C4_MINI4_SCL")
	)
	(segment
		(start 66.1924 -121.0437)
		(end 66.4845 -121.0437)
		(width 0.12065)
		(layer "F.Cu")
		(net "BMC_I2C4_MINI4_SCL")
	)
	(segment
		(start 66.4845 -121.0437)
		(end 66.9798 -120.5484)
		(width 0.12065)
		(layer "F.Cu")
		(net "BMC_I2C4_MINI4_SCL")
	)
	(segment
		(start 66.9798 -120.848882)
		(end 67.70116 -121.570242)
		(width 0.12065)
		(layer "F.Cu")
		(net "BMC_I2C4_MINI4_SCL")
	)
	(via
		(at 163.453572 -31.866078)
		(size 0.7112)
		(drill 0.3556)
		(layers "F.Cu" "B.Cu")
		(net "BMC_I2C4_MINI4_SCL")
	)
	(via
		(at 77.856334 -117.748304)
		(size 0.508)
		(drill 0.254)
		(layers "F.Cu" "B.Cu")
		(net "BMC_I2C4_MINI4_SCL")
	)
	(via
		(at 66.9798 -120.5484)
		(size 0.508)
		(drill 0.254)
		(layers "F.Cu" "B.Cu")
		(net "BMC_I2C4_MINI4_SCL")
	)
	(segment
		(start 137.840974 -40.148002)
		(end 141.334998 -40.148002)
		(width 0.12065)
		(layer "B.Cu")
		(net "BMC_I2C4_MINI4_SCL")
	)
	(segment
		(start 141.334998 -40.148002)
		(end 141.757146 -40.57015)
		(width 0.12065)
		(layer "B.Cu")
		(net "BMC_I2C4_MINI4_SCL")
	)
	(segment
		(start 162.80765 -32.512)
		(end 163.453572 -31.866078)
		(width 0.12065)
		(layer "B.Cu")
		(net "BMC_I2C4_MINI4_SCL")
	)
	(segment
		(start 111.348012 -37.2364)
		(end 121.438162 -37.2364)
		(width 0.12065)
		(layer "B.Cu")
		(net "BMC_I2C4_MINI4_SCL")
	)
	(segment
		(start 163.48329 -34.10331)
		(end 162.80765 -33.42767)
		(width 0.12065)
		(layer "B.Cu")
		(net "BMC_I2C4_MINI4_SCL")
	)
	(segment
		(start 163.98875 -38.468046)
		(end 163.98875 -36.682426)
		(width 0.12065)
		(layer "B.Cu")
		(net "BMC_I2C4_MINI4_SCL")
	)
	(segment
		(start 154.299158 -40.57015)
		(end 154.6479 -40.918892)
		(width 0.12065)
		(layer "B.Cu")
		(net "BMC_I2C4_MINI4_SCL")
	)
	(segment
		(start 162.80765 -33.42767)
		(end 162.80765 -32.512)
		(width 0.12065)
		(layer "B.Cu")
		(net "BMC_I2C4_MINI4_SCL")
	)
	(segment
		(start 85.832696 -97.57537)
		(end 85.832696 -93.126306)
		(width 0.12065)
		(layer "B.Cu")
		(net "BMC_I2C4_MINI4_SCL")
	)
	(segment
		(start 164.659818 -23.00478)
		(end 164.659818 -30.659832)
		(width 0.12065)
		(layer "B.Cu")
		(net "BMC_I2C4_MINI4_SCL")
	)
	(segment
		(start 77.856334 -117.748304)
		(end 78.51775 -117.086888)
		(width 0.12065)
		(layer "B.Cu")
		(net "BMC_I2C4_MINI4_SCL")
	)
	(segment
		(start 141.757146 -40.57015)
		(end 154.299158 -40.57015)
		(width 0.12065)
		(layer "B.Cu")
		(net "BMC_I2C4_MINI4_SCL")
	)
	(segment
		(start 137.190226 -40.79875)
		(end 137.840974 -40.148002)
		(width 0.12065)
		(layer "B.Cu")
		(net "BMC_I2C4_MINI4_SCL")
	)
	(segment
		(start 134.497826 -40.79875)
		(end 137.190226 -40.79875)
		(width 0.12065)
		(layer "B.Cu")
		(net "BMC_I2C4_MINI4_SCL")
	)
	(segment
		(start 154.6479 -40.918892)
		(end 161.537904 -40.918892)
		(width 0.12065)
		(layer "B.Cu")
		(net "BMC_I2C4_MINI4_SCL")
	)
	(segment
		(start 95.936054 -50.797968)
		(end 101.198172 -45.53585)
		(width 0.12065)
		(layer "B.Cu")
		(net "BMC_I2C4_MINI4_SCL")
	)
	(segment
		(start 78.51775 -104.890316)
		(end 85.832696 -97.57537)
		(width 0.12065)
		(layer "B.Cu")
		(net "BMC_I2C4_MINI4_SCL")
	)
	(segment
		(start 133.361176 -39.6621)
		(end 134.497826 -40.79875)
		(width 0.12065)
		(layer "B.Cu")
		(net "BMC_I2C4_MINI4_SCL")
	)
	(segment
		(start 91.043252 -87.91575)
		(end 95.473774 -87.91575)
		(width 0.12065)
		(layer "B.Cu")
		(net "BMC_I2C4_MINI4_SCL")
	)
	(segment
		(start 95.936054 -59.565794)
		(end 95.936054 -50.797968)
		(width 0.12065)
		(layer "B.Cu")
		(net "BMC_I2C4_MINI4_SCL")
	)
	(segment
		(start 99.20605 -84.183474)
		(end 99.20605 -62.83579)
		(width 0.12065)
		(layer "B.Cu")
		(net "BMC_I2C4_MINI4_SCL")
	)
	(segment
		(start 164.659818 -30.659832)
		(end 163.453572 -31.866078)
		(width 0.12065)
		(layer "B.Cu")
		(net "BMC_I2C4_MINI4_SCL")
	)
	(segment
		(start 99.20605 -62.83579)
		(end 95.936054 -59.565794)
		(width 0.12065)
		(layer "B.Cu")
		(net "BMC_I2C4_MINI4_SCL")
	)
	(segment
		(start 166.134542 -21.530056)
		(end 164.659818 -23.00478)
		(width 0.12065)
		(layer "B.Cu")
		(net "BMC_I2C4_MINI4_SCL")
	)
	(segment
		(start 78.51775 -117.086888)
		(end 78.51775 -104.890316)
		(width 0.12065)
		(layer "B.Cu")
		(net "BMC_I2C4_MINI4_SCL")
	)
	(segment
		(start 163.98875 -36.682426)
		(end 163.48329 -36.176966)
		(width 0.12065)
		(layer "B.Cu")
		(net "BMC_I2C4_MINI4_SCL")
	)
	(segment
		(start 85.832696 -93.126306)
		(end 91.043252 -87.91575)
		(width 0.12065)
		(layer "B.Cu")
		(net "BMC_I2C4_MINI4_SCL")
	)
	(segment
		(start 95.473774 -87.91575)
		(end 99.20605 -84.183474)
		(width 0.12065)
		(layer "B.Cu")
		(net "BMC_I2C4_MINI4_SCL")
	)
	(segment
		(start 163.48329 -36.176966)
		(end 163.48329 -34.10331)
		(width 0.12065)
		(layer "B.Cu")
		(net "BMC_I2C4_MINI4_SCL")
	)
	(segment
		(start 161.537904 -40.918892)
		(end 163.98875 -38.468046)
		(width 0.12065)
		(layer "B.Cu")
		(net "BMC_I2C4_MINI4_SCL")
	)
	(segment
		(start 101.198172 -45.53585)
		(end 103.048562 -45.53585)
		(width 0.12065)
		(layer "B.Cu")
		(net "BMC_I2C4_MINI4_SCL")
	)
	(segment
		(start 103.048562 -45.53585)
		(end 111.348012 -37.2364)
		(width 0.12065)
		(layer "B.Cu")
		(net "BMC_I2C4_MINI4_SCL")
	)
	(segment
		(start 121.438162 -37.2364)
		(end 123.863862 -39.6621)
		(width 0.12065)
		(layer "B.Cu")
		(net "BMC_I2C4_MINI4_SCL")
	)
	(segment
		(start 123.863862 -39.6621)
		(end 133.361176 -39.6621)
		(width 0.12065)
		(layer "B.Cu")
		(net "BMC_I2C4_MINI4_SCL")
	)
	(segment
		(start 68.034154 -121.031)
		(end 68.165726 -120.899428)
		(width 0.127)
		(layer "In2.Cu")
		(net "BMC_I2C4_MINI4_SCL")
	)
	(segment
		(start 68.165726 -120.242076)
		(end 68.721732 -119.68607)
		(width 0.127)
		(layer "In2.Cu")
		(net "BMC_I2C4_MINI4_SCL")
	)
	(segment
		(start 66.9798 -120.5484)
		(end 67.4624 -121.031)
		(width 0.127)
		(layer "In2.Cu")
		(net "BMC_I2C4_MINI4_SCL")
	)
	(segment
		(start 74.965814 -118.01602)
		(end 76.691998 -118.01602)
		(width 0.127)
		(layer "In2.Cu")
		(net "BMC_I2C4_MINI4_SCL")
	)
	(segment
		(start 77.222096 -117.748304)
		(end 77.856334 -117.748304)
		(width 0.127)
		(layer "In2.Cu")
		(net "BMC_I2C4_MINI4_SCL")
	)
	(segment
		(start 67.4624 -121.031)
		(end 68.034154 -121.031)
		(width 0.127)
		(layer "In2.Cu")
		(net "BMC_I2C4_MINI4_SCL")
	)
	(segment
		(start 68.165726 -120.899428)
		(end 68.165726 -120.242076)
		(width 0.127)
		(layer "In2.Cu")
		(net "BMC_I2C4_MINI4_SCL")
	)
	(segment
		(start 76.814934 -117.893084)
		(end 77.077316 -117.893084)
		(width 0.127)
		(layer "In2.Cu")
		(net "BMC_I2C4_MINI4_SCL")
	)
	(segment
		(start 76.691998 -118.01602)
		(end 76.814934 -117.893084)
		(width 0.127)
		(layer "In2.Cu")
		(net "BMC_I2C4_MINI4_SCL")
	)
	(segment
		(start 77.077316 -117.893084)
		(end 77.222096 -117.748304)
		(width 0.127)
		(layer "In2.Cu")
		(net "BMC_I2C4_MINI4_SCL")
	)
	(segment
		(start 68.721732 -119.68607)
		(end 73.295764 -119.68607)
		(width 0.127)
		(layer "In2.Cu")
		(net "BMC_I2C4_MINI4_SCL")
	)
	(segment
		(start 73.295764 -119.68607)
		(end 74.965814 -118.01602)
		(width 0.127)
		(layer "In2.Cu")
		(net "BMC_I2C4_MINI4_SCL")
	)
	(via
		(at 63.119 -118.11)
		(size 0.508)
		(drill 0.254)
		(layers "F.Cu" "B.Cu")
		(net "BMC_I2C3_MINI3_SDA")
	)
	(via
		(at 155.654248 -37.867336)
		(size 0.7112)
		(drill 0.3556)
		(layers "F.Cu" "B.Cu")
		(net "BMC_I2C3_MINI3_SDA")
	)
	(via
		(at 76.495148 -116.65966)
		(size 0.508)
		(drill 0.254)
		(layers "F.Cu" "B.Cu")
		(net "BMC_I2C3_MINI3_SDA")
	)
	(segment
		(start 157.49016 -34.036508)
		(end 157.492192 -34.034476)
		(width 0.12065)
		(layer "B.Cu")
		(net "BMC_I2C3_MINI3_SDA")
	)
	(segment
		(start 59.7154 -117.5385)
		(end 60.1853 -117.0686)
		(width 0.12065)
		(layer "B.Cu")
		(net "BMC_I2C3_MINI3_SDA")
	)
	(segment
		(start 100.897182 -44.81195)
		(end 102.748334 -44.81195)
		(width 0.12065)
		(layer "B.Cu")
		(net "BMC_I2C3_MINI3_SDA")
	)
	(segment
		(start 140.279374 -38.06825)
		(end 142.057374 -39.84625)
		(width 0.12065)
		(layer "B.Cu")
		(net "BMC_I2C3_MINI3_SDA")
	)
	(segment
		(start 76.339446 -116.81587)
		(end 76.339446 -116.815362)
		(width 0.12065)
		(layer "B.Cu")
		(net "BMC_I2C3_MINI3_SDA")
	)
	(segment
		(start 77.79385 -104.144826)
		(end 85.108288 -96.830388)
		(width 0.12065)
		(layer "B.Cu")
		(net "BMC_I2C3_MINI3_SDA")
	)
	(segment
		(start 61.17336 -117.61216)
		(end 61.17336 -117.0686)
		(width 0.12065)
		(layer "B.Cu")
		(net "BMC_I2C3_MINI3_SDA")
	)
	(segment
		(start 98.318066 -62.971934)
		(end 94.876366 -59.530234)
		(width 0.12065)
		(layer "B.Cu")
		(net "BMC_I2C3_MINI3_SDA")
	)
	(segment
		(start 156.470604 -34.036508)
		(end 156.470604 -34.476436)
		(width 0.12065)
		(layer "B.Cu")
		(net "BMC_I2C3_MINI3_SDA")
	)
	(segment
		(start 156.470604 -34.036508)
		(end 157.49016 -34.036508)
		(width 0.12065)
		(layer "B.Cu")
		(net "BMC_I2C3_MINI3_SDA")
	)
	(segment
		(start 133.15188 -38.9382)
		(end 134.02183 -38.06825)
		(width 0.12065)
		(layer "B.Cu")
		(net "BMC_I2C3_MINI3_SDA")
	)
	(segment
		(start 156.605986 -35.38855)
		(end 155.218638 -36.775898)
		(width 0.12065)
		(layer "B.Cu")
		(net "BMC_I2C3_MINI3_SDA")
	)
	(segment
		(start 155.218638 -36.775898)
		(end 155.218638 -37.431726)
		(width 0.12065)
		(layer "B.Cu")
		(net "BMC_I2C3_MINI3_SDA")
	)
	(segment
		(start 63.119 -118.11)
		(end 62.9412 -117.9322)
		(width 0.12065)
		(layer "B.Cu")
		(net "BMC_I2C3_MINI3_SDA")
	)
	(segment
		(start 111.311182 -36.249102)
		(end 121.520966 -36.249102)
		(width 0.12065)
		(layer "B.Cu")
		(net "BMC_I2C3_MINI3_SDA")
	)
	(segment
		(start 155.278074 -38.267894)
		(end 155.278074 -38.24351)
		(width 0.12065)
		(layer "B.Cu")
		(net "BMC_I2C3_MINI3_SDA")
	)
	(segment
		(start 75.98918 -116.236496)
		(end 77.79385 -114.431826)
		(width 0.12065)
		(layer "B.Cu")
		(net "BMC_I2C3_MINI3_SDA")
	)
	(segment
		(start 85.108288 -92.826332)
		(end 91.622118 -86.312502)
		(width 0.12065)
		(layer "B.Cu")
		(net "BMC_I2C3_MINI3_SDA")
	)
	(segment
		(start 98.318066 -83.469734)
		(end 98.318066 -62.971934)
		(width 0.12065)
		(layer "B.Cu")
		(net "BMC_I2C3_MINI3_SDA")
	)
	(segment
		(start 60.1853 -117.0686)
		(end 61.17336 -117.0686)
		(width 0.12065)
		(layer "B.Cu")
		(net "BMC_I2C3_MINI3_SDA")
	)
	(segment
		(start 124.210064 -38.9382)
		(end 133.15188 -38.9382)
		(width 0.12065)
		(layer "B.Cu")
		(net "BMC_I2C3_MINI3_SDA")
	)
	(segment
		(start 61.4934 -117.9322)
		(end 61.17336 -117.61216)
		(width 0.12065)
		(layer "B.Cu")
		(net "BMC_I2C3_MINI3_SDA")
	)
	(segment
		(start 155.277566 -38.268402)
		(end 155.278074 -38.267894)
		(width 0.12065)
		(layer "B.Cu")
		(net "BMC_I2C3_MINI3_SDA")
	)
	(segment
		(start 155.278074 -38.24351)
		(end 155.654248 -37.867336)
		(width 0.12065)
		(layer "B.Cu")
		(net "BMC_I2C3_MINI3_SDA")
	)
	(segment
		(start 85.108288 -96.830388)
		(end 85.108288 -92.826332)
		(width 0.12065)
		(layer "B.Cu")
		(net "BMC_I2C3_MINI3_SDA")
	)
	(segment
		(start 76.339446 -116.815362)
		(end 76.339192 -116.81587)
		(width 0.12065)
		(layer "B.Cu")
		(net "BMC_I2C3_MINI3_SDA")
	)
	(segment
		(start 76.279248 -116.815362)
		(end 76.218796 -116.815362)
		(width 0.12065)
		(layer "B.Cu")
		(net "BMC_I2C3_MINI3_SDA")
	)
	(segment
		(start 134.02183 -38.06825)
		(end 140.279374 -38.06825)
		(width 0.12065)
		(layer "B.Cu")
		(net "BMC_I2C3_MINI3_SDA")
	)
	(segment
		(start 75.98918 -116.585746)
		(end 75.98918 -116.236496)
		(width 0.12065)
		(layer "B.Cu")
		(net "BMC_I2C3_MINI3_SDA")
	)
	(segment
		(start 155.277566 -38.929818)
		(end 155.277566 -38.268402)
		(width 0.12065)
		(layer "B.Cu")
		(net "BMC_I2C3_MINI3_SDA")
	)
	(segment
		(start 155.218638 -37.431726)
		(end 155.654248 -37.867336)
		(width 0.12065)
		(layer "B.Cu")
		(net "BMC_I2C3_MINI3_SDA")
	)
	(segment
		(start 95.475298 -86.312502)
		(end 98.318066 -83.469734)
		(width 0.12065)
		(layer "B.Cu")
		(net "BMC_I2C3_MINI3_SDA")
	)
	(segment
		(start 77.79385 -114.431826)
		(end 77.79385 -104.144826)
		(width 0.12065)
		(layer "B.Cu")
		(net "BMC_I2C3_MINI3_SDA")
	)
	(segment
		(start 142.057374 -39.84625)
		(end 154.361134 -39.84625)
		(width 0.12065)
		(layer "B.Cu")
		(net "BMC_I2C3_MINI3_SDA")
	)
	(segment
		(start 121.520966 -36.249102)
		(end 124.210064 -38.9382)
		(width 0.12065)
		(layer "B.Cu")
		(net "BMC_I2C3_MINI3_SDA")
	)
	(segment
		(start 62.9412 -117.9322)
		(end 61.4934 -117.9322)
		(width 0.12065)
		(layer "B.Cu")
		(net "BMC_I2C3_MINI3_SDA")
	)
	(segment
		(start 94.876366 -59.530234)
		(end 94.876366 -50.832766)
		(width 0.12065)
		(layer "B.Cu")
		(net "BMC_I2C3_MINI3_SDA")
	)
	(segment
		(start 76.495148 -116.65966)
		(end 76.339446 -116.81587)
		(width 0.12065)
		(layer "B.Cu")
		(net "BMC_I2C3_MINI3_SDA")
	)
	(segment
		(start 94.876366 -50.832766)
		(end 100.897182 -44.81195)
		(width 0.12065)
		(layer "B.Cu")
		(net "BMC_I2C3_MINI3_SDA")
	)
	(segment
		(start 154.361134 -39.84625)
		(end 155.277566 -38.929818)
		(width 0.12065)
		(layer "B.Cu")
		(net "BMC_I2C3_MINI3_SDA")
	)
	(segment
		(start 91.622118 -86.312502)
		(end 95.475298 -86.312502)
		(width 0.12065)
		(layer "B.Cu")
		(net "BMC_I2C3_MINI3_SDA")
	)
	(segment
		(start 156.470604 -34.476436)
		(end 156.605986 -34.611818)
		(width 0.12065)
		(layer "B.Cu")
		(net "BMC_I2C3_MINI3_SDA")
	)
	(segment
		(start 102.748334 -44.81195)
		(end 111.311182 -36.249102)
		(width 0.12065)
		(layer "B.Cu")
		(net "BMC_I2C3_MINI3_SDA")
	)
	(segment
		(start 76.218796 -116.815362)
		(end 75.98918 -116.585746)
		(width 0.12065)
		(layer "B.Cu")
		(net "BMC_I2C3_MINI3_SDA")
	)
	(segment
		(start 156.605986 -34.611818)
		(end 156.605986 -35.38855)
		(width 0.12065)
		(layer "B.Cu")
		(net "BMC_I2C3_MINI3_SDA")
	)
	(segment
		(start 76.339192 -116.81587)
		(end 76.279248 -116.815362)
		(width 0.12065)
		(layer "B.Cu")
		(net "BMC_I2C3_MINI3_SDA")
	)
	(segment
		(start 63.940944 -118.19382)
		(end 63.941198 -118.194074)
		(width 0.127)
		(layer "In2.Cu")
		(net "BMC_I2C3_MINI3_SDA")
	)
	(segment
		(start 64.655446 -117.5258)
		(end 70.6374 -117.5258)
		(width 0.127)
		(layer "In2.Cu")
		(net "BMC_I2C3_MINI3_SDA")
	)
	(segment
		(start 70.6374 -117.5258)
		(end 72.3392 -115.824)
		(width 0.127)
		(layer "In2.Cu")
		(net "BMC_I2C3_MINI3_SDA")
	)
	(segment
		(start 63.509906 -118.19382)
		(end 63.940944 -118.19382)
		(width 0.127)
		(layer "In2.Cu")
		(net "BMC_I2C3_MINI3_SDA")
	)
	(segment
		(start 72.3392 -115.824)
		(end 74.7268 -115.824)
		(width 0.127)
		(layer "In2.Cu")
		(net "BMC_I2C3_MINI3_SDA")
	)
	(segment
		(start 74.7268 -115.824)
		(end 75.7047 -116.8019)
		(width 0.127)
		(layer "In2.Cu")
		(net "BMC_I2C3_MINI3_SDA")
	)
	(segment
		(start 75.7047 -116.8019)
		(end 76.352908 -116.8019)
		(width 0.127)
		(layer "In2.Cu")
		(net "BMC_I2C3_MINI3_SDA")
	)
	(segment
		(start 76.352908 -116.8019)
		(end 76.495148 -116.65966)
		(width 0.127)
		(layer "In2.Cu")
		(net "BMC_I2C3_MINI3_SDA")
	)
	(segment
		(start 63.987172 -118.194074)
		(end 64.655446 -117.5258)
		(width 0.127)
		(layer "In2.Cu")
		(net "BMC_I2C3_MINI3_SDA")
	)
	(segment
		(start 63.941198 -118.194074)
		(end 63.987172 -118.194074)
		(width 0.127)
		(layer "In2.Cu")
		(net "BMC_I2C3_MINI3_SDA")
	)
	(segment
		(start 63.119 -118.11)
		(end 63.509906 -118.19382)
		(width 0.127)
		(layer "In2.Cu")
		(net "BMC_I2C3_MINI3_SDA")
	)
	(via
		(at 76.49718 -117.54612)
		(size 0.508)
		(drill 0.254)
		(layers "F.Cu" "B.Cu")
		(net "BMC_I2C3_MINI3_SCL")
	)
	(via
		(at 63.9572 -119.4054)
		(size 0.508)
		(drill 0.254)
		(layers "F.Cu" "B.Cu")
		(net "BMC_I2C3_MINI3_SCL")
	)
	(via
		(at 154.384248 -37.876734)
		(size 0.7112)
		(drill 0.3556)
		(layers "F.Cu" "B.Cu")
		(net "BMC_I2C3_MINI3_SCL")
	)
	(segment
		(start 76.49718 -117.54612)
		(end 76.26858 -117.31752)
		(width 0.12065)
		(layer "B.Cu")
		(net "BMC_I2C3_MINI3_SCL")
	)
	(segment
		(start 154.775916 -38.721792)
		(end 154.775916 -38.268402)
		(width 0.12065)
		(layer "B.Cu")
		(net "BMC_I2C3_MINI3_SCL")
	)
	(segment
		(start 75.48753 -116.793772)
		(end 75.48753 -116.02847)
		(width 0.12065)
		(layer "B.Cu")
		(net "BMC_I2C3_MINI3_SCL")
	)
	(segment
		(start 95.267272 -85.810852)
		(end 97.816416 -83.261708)
		(width 0.12065)
		(layer "B.Cu")
		(net "BMC_I2C3_MINI3_SCL")
	)
	(segment
		(start 111.103156 -35.747452)
		(end 121.728992 -35.747452)
		(width 0.12065)
		(layer "B.Cu")
		(net "BMC_I2C3_MINI3_SCL")
	)
	(segment
		(start 155.134564 -22.360636)
		(end 153.4922 -24.003)
		(width 0.12065)
		(layer "B.Cu")
		(net "BMC_I2C3_MINI3_SCL")
	)
	(segment
		(start 97.816416 -83.261708)
		(end 97.816416 -63.17996)
		(width 0.12065)
		(layer "B.Cu")
		(net "BMC_I2C3_MINI3_SCL")
	)
	(segment
		(start 62.47384 -118.9482)
		(end 63.4873 -118.9482)
		(width 0.12065)
		(layer "B.Cu")
		(net "BMC_I2C3_MINI3_SCL")
	)
	(segment
		(start 154.716988 -36.494212)
		(end 154.716988 -37.543994)
		(width 0.12065)
		(layer "B.Cu")
		(net "BMC_I2C3_MINI3_SCL")
	)
	(segment
		(start 94.374716 -59.73826)
		(end 94.374716 -50.62474)
		(width 0.12065)
		(layer "B.Cu")
		(net "BMC_I2C3_MINI3_SCL")
	)
	(segment
		(start 133.813804 -37.5666)
		(end 140.4874 -37.5666)
		(width 0.12065)
		(layer "B.Cu")
		(net "BMC_I2C3_MINI3_SCL")
	)
	(segment
		(start 153.4922 -24.003)
		(end 153.4922 -27.72156)
		(width 0.12065)
		(layer "B.Cu")
		(net "BMC_I2C3_MINI3_SCL")
	)
	(segment
		(start 154.776932 -32.130238)
		(end 154.958542 -32.311848)
		(width 0.12065)
		(layer "B.Cu")
		(net "BMC_I2C3_MINI3_SCL")
	)
	(segment
		(start 84.606638 -96.622362)
		(end 84.606638 -92.618306)
		(width 0.12065)
		(layer "B.Cu")
		(net "BMC_I2C3_MINI3_SCL")
	)
	(segment
		(start 154.153108 -39.3446)
		(end 154.775916 -38.721792)
		(width 0.12065)
		(layer "B.Cu")
		(net "BMC_I2C3_MINI3_SCL")
	)
	(segment
		(start 140.4874 -37.5666)
		(end 142.2654 -39.3446)
		(width 0.12065)
		(layer "B.Cu")
		(net "BMC_I2C3_MINI3_SCL")
	)
	(segment
		(start 155.134564 -21.530056)
		(end 155.134564 -22.360636)
		(width 0.12065)
		(layer "B.Cu")
		(net "BMC_I2C3_MINI3_SCL")
	)
	(segment
		(start 121.728992 -35.747452)
		(end 124.41809 -38.43655)
		(width 0.12065)
		(layer "B.Cu")
		(net "BMC_I2C3_MINI3_SCL")
	)
	(segment
		(start 84.606638 -92.618306)
		(end 91.414092 -85.810852)
		(width 0.12065)
		(layer "B.Cu")
		(net "BMC_I2C3_MINI3_SCL")
	)
	(segment
		(start 77.2922 -114.2238)
		(end 77.2922 -103.9368)
		(width 0.12065)
		(layer "B.Cu")
		(net "BMC_I2C3_MINI3_SCL")
	)
	(segment
		(start 76.26858 -117.31752)
		(end 76.011278 -117.31752)
		(width 0.12065)
		(layer "B.Cu")
		(net "BMC_I2C3_MINI3_SCL")
	)
	(segment
		(start 63.9572 -118.4783)
		(end 63.9572 -119.4054)
		(width 0.12065)
		(layer "B.Cu")
		(net "BMC_I2C3_MINI3_SCL")
	)
	(segment
		(start 77.2922 -103.9368)
		(end 84.606638 -96.622362)
		(width 0.12065)
		(layer "B.Cu")
		(net "BMC_I2C3_MINI3_SCL")
	)
	(segment
		(start 91.414092 -85.810852)
		(end 95.267272 -85.810852)
		(width 0.12065)
		(layer "B.Cu")
		(net "BMC_I2C3_MINI3_SCL")
	)
	(segment
		(start 124.41809 -38.43655)
		(end 132.943854 -38.43655)
		(width 0.12065)
		(layer "B.Cu")
		(net "BMC_I2C3_MINI3_SCL")
	)
	(segment
		(start 75.48753 -116.02847)
		(end 77.2922 -114.2238)
		(width 0.12065)
		(layer "B.Cu")
		(net "BMC_I2C3_MINI3_SCL")
	)
	(segment
		(start 76.011278 -117.31752)
		(end 75.48753 -116.793772)
		(width 0.12065)
		(layer "B.Cu")
		(net "BMC_I2C3_MINI3_SCL")
	)
	(segment
		(start 154.775916 -38.268402)
		(end 154.384248 -37.876734)
		(width 0.12065)
		(layer "B.Cu")
		(net "BMC_I2C3_MINI3_SCL")
	)
	(segment
		(start 154.776932 -29.006292)
		(end 154.776932 -32.130238)
		(width 0.12065)
		(layer "B.Cu")
		(net "BMC_I2C3_MINI3_SCL")
	)
	(segment
		(start 94.374716 -50.62474)
		(end 100.689156 -44.3103)
		(width 0.12065)
		(layer "B.Cu")
		(net "BMC_I2C3_MINI3_SCL")
	)
	(segment
		(start 100.689156 -44.3103)
		(end 102.540308 -44.3103)
		(width 0.12065)
		(layer "B.Cu")
		(net "BMC_I2C3_MINI3_SCL")
	)
	(segment
		(start 102.540308 -44.3103)
		(end 111.103156 -35.747452)
		(width 0.12065)
		(layer "B.Cu")
		(net "BMC_I2C3_MINI3_SCL")
	)
	(segment
		(start 142.2654 -39.3446)
		(end 154.153108 -39.3446)
		(width 0.12065)
		(layer "B.Cu")
		(net "BMC_I2C3_MINI3_SCL")
	)
	(segment
		(start 132.943854 -38.43655)
		(end 133.813804 -37.5666)
		(width 0.12065)
		(layer "B.Cu")
		(net "BMC_I2C3_MINI3_SCL")
	)
	(segment
		(start 154.716988 -37.543994)
		(end 154.384248 -37.876734)
		(width 0.12065)
		(layer "B.Cu")
		(net "BMC_I2C3_MINI3_SCL")
	)
	(segment
		(start 154.958542 -32.311848)
		(end 154.958542 -36.252658)
		(width 0.12065)
		(layer "B.Cu")
		(net "BMC_I2C3_MINI3_SCL")
	)
	(segment
		(start 97.816416 -63.17996)
		(end 94.374716 -59.73826)
		(width 0.12065)
		(layer "B.Cu")
		(net "BMC_I2C3_MINI3_SCL")
	)
	(segment
		(start 153.4922 -27.72156)
		(end 154.776932 -29.006292)
		(width 0.12065)
		(layer "B.Cu")
		(net "BMC_I2C3_MINI3_SCL")
	)
	(segment
		(start 154.958542 -36.252658)
		(end 154.716988 -36.494212)
		(width 0.12065)
		(layer "B.Cu")
		(net "BMC_I2C3_MINI3_SCL")
	)
	(segment
		(start 63.4873 -118.9482)
		(end 63.9572 -118.4783)
		(width 0.12065)
		(layer "B.Cu")
		(net "BMC_I2C3_MINI3_SCL")
	)
	(segment
		(start 72.549766 -116.332)
		(end 74.516234 -116.332)
		(width 0.127)
		(layer "In2.Cu")
		(net "BMC_I2C3_MINI3_SCL")
	)
	(segment
		(start 64.083184 -118.816628)
		(end 64.866012 -118.0338)
		(width 0.127)
		(layer "In2.Cu")
		(net "BMC_I2C3_MINI3_SCL")
	)
	(segment
		(start 70.847966 -118.0338)
		(end 72.549766 -116.332)
		(width 0.127)
		(layer "In2.Cu")
		(net "BMC_I2C3_MINI3_SCL")
	)
	(segment
		(start 64.866012 -118.0338)
		(end 70.847966 -118.0338)
		(width 0.127)
		(layer "In2.Cu")
		(net "BMC_I2C3_MINI3_SCL")
	)
	(segment
		(start 76.26096 -117.3099)
		(end 76.49718 -117.54612)
		(width 0.127)
		(layer "In2.Cu")
		(net "BMC_I2C3_MINI3_SCL")
	)
	(segment
		(start 75.494134 -117.3099)
		(end 76.26096 -117.3099)
		(width 0.127)
		(layer "In2.Cu")
		(net "BMC_I2C3_MINI3_SCL")
	)
	(segment
		(start 74.516234 -116.332)
		(end 75.494134 -117.3099)
		(width 0.127)
		(layer "In2.Cu")
		(net "BMC_I2C3_MINI3_SCL")
	)
	(segment
		(start 63.9572 -119.4054)
		(end 64.083184 -118.816628)
		(width 0.127)
		(layer "In2.Cu")
		(net "BMC_I2C3_MINI3_SCL")
	)
	(segment
		(start 15.878556 -124.6505)
		(end 15.490698 -124.262642)
		(width 0.12065)
		(layer "F.Cu")
		(net "BMC_I2C2_MINI2_SDA")
	)
	(segment
		(start 15.38224 -124.1552)
		(end 15.489682 -124.262642)
		(width 0.12065)
		(layer "F.Cu")
		(net "BMC_I2C2_MINI2_SDA")
	)
	(segment
		(start 15.489682 -124.262642)
		(end 15.490698 -124.262642)
		(width 0.12065)
		(layer "F.Cu")
		(net "BMC_I2C2_MINI2_SDA")
	)
	(segment
		(start 14.74724 -124.1552)
		(end 15.38224 -124.1552)
		(width 0.12065)
		(layer "F.Cu")
		(net "BMC_I2C2_MINI2_SDA")
	)
	(segment
		(start 16.256 -124.6505)
		(end 15.878556 -124.6505)
		(width 0.12065)
		(layer "F.Cu")
		(net "BMC_I2C2_MINI2_SDA")
	)
	(via
		(at 79.5274 -95.107252)
		(size 0.508)
		(drill 0.254)
		(layers "F.Cu" "B.Cu")
		(net "BMC_I2C2_MINI2_SDA")
	)
	(via
		(at 15.490698 -124.262642)
		(size 0.508)
		(drill 0.254)
		(layers "F.Cu" "B.Cu")
		(net "BMC_I2C2_MINI2_SDA")
	)
	(via
		(at 81.713832 -94.405958)
		(size 0.7112)
		(drill 0.3556)
		(layers "F.Cu" "B.Cu")
		(net "BMC_I2C2_MINI2_SDA")
	)
	(segment
		(start 144.365726 -36.660074)
		(end 144.205706 -36.820094)
		(width 0.12065)
		(layer "B.Cu")
		(net "BMC_I2C2_MINI2_SDA")
	)
	(segment
		(start 100.332794 -43.5864)
		(end 93.533468 -50.385726)
		(width 0.12065)
		(layer "B.Cu")
		(net "BMC_I2C2_MINI2_SDA")
	)
	(segment
		(start 142.336774 -37.15385)
		(end 142.00378 -36.820856)
		(width 0.12065)
		(layer "B.Cu")
		(net "BMC_I2C2_MINI2_SDA")
	)
	(segment
		(start 133.53542 -36.820856)
		(end 132.643626 -37.71265)
		(width 0.12065)
		(layer "B.Cu")
		(net "BMC_I2C2_MINI2_SDA")
	)
	(segment
		(start 93.533468 -50.385726)
		(end 93.533468 -60.462668)
		(width 0.12065)
		(layer "B.Cu")
		(net "BMC_I2C2_MINI2_SDA")
	)
	(segment
		(start 94.6912 -81.0514)
		(end 91.5416 -84.201)
		(width 0.12065)
		(layer "B.Cu")
		(net "BMC_I2C2_MINI2_SDA")
	)
	(segment
		(start 80.707484 -94.958154)
		(end 79.676498 -94.958154)
		(width 0.12065)
		(layer "B.Cu")
		(net "BMC_I2C2_MINI2_SDA")
	)
	(segment
		(start 145.30197 -35.16757)
		(end 144.365726 -36.103814)
		(width 0.12065)
		(layer "B.Cu")
		(net "BMC_I2C2_MINI2_SDA")
	)
	(segment
		(start 117.593872 -35.013392)
		(end 116.97208 -34.3916)
		(width 0.12065)
		(layer "B.Cu")
		(net "BMC_I2C2_MINI2_SDA")
	)
	(segment
		(start 132.643626 -37.71265)
		(end 124.718318 -37.71265)
		(width 0.12065)
		(layer "B.Cu")
		(net "BMC_I2C2_MINI2_SDA")
	)
	(segment
		(start 81.486756 -94.178882)
		(end 80.707484 -94.958154)
		(width 0.12065)
		(layer "B.Cu")
		(net "BMC_I2C2_MINI2_SDA")
	)
	(segment
		(start 145.88363 -33.98012)
		(end 145.30197 -34.56178)
		(width 0.12065)
		(layer "B.Cu")
		(net "BMC_I2C2_MINI2_SDA")
	)
	(segment
		(start 144.365726 -36.103814)
		(end 144.365726 -36.660074)
		(width 0.12065)
		(layer "B.Cu")
		(net "BMC_I2C2_MINI2_SDA")
	)
	(segment
		(start 102.24008 -43.5864)
		(end 100.332794 -43.5864)
		(width 0.12065)
		(layer "B.Cu")
		(net "BMC_I2C2_MINI2_SDA")
	)
	(segment
		(start 93.533468 -60.462668)
		(end 94.6912 -61.6204)
		(width 0.12065)
		(layer "B.Cu")
		(net "BMC_I2C2_MINI2_SDA")
	)
	(segment
		(start 90.463116 -84.201)
		(end 82.054954 -92.609162)
		(width 0.12065)
		(layer "B.Cu")
		(net "BMC_I2C2_MINI2_SDA")
	)
	(segment
		(start 79.676498 -94.958154)
		(end 79.5274 -95.107252)
		(width 0.12065)
		(layer "B.Cu")
		(net "BMC_I2C2_MINI2_SDA")
	)
	(segment
		(start 81.713832 -94.405958)
		(end 81.486756 -94.178882)
		(width 0.12065)
		(layer "B.Cu")
		(net "BMC_I2C2_MINI2_SDA")
	)
	(segment
		(start 124.718318 -37.71265)
		(end 122.01906 -35.013392)
		(width 0.12065)
		(layer "B.Cu")
		(net "BMC_I2C2_MINI2_SDA")
	)
	(segment
		(start 94.6912 -61.6204)
		(end 94.6912 -81.0514)
		(width 0.12065)
		(layer "B.Cu")
		(net "BMC_I2C2_MINI2_SDA")
	)
	(segment
		(start 145.30197 -34.56178)
		(end 145.30197 -35.16757)
		(width 0.12065)
		(layer "B.Cu")
		(net "BMC_I2C2_MINI2_SDA")
	)
	(segment
		(start 122.01906 -35.013392)
		(end 117.593872 -35.013392)
		(width 0.12065)
		(layer "B.Cu")
		(net "BMC_I2C2_MINI2_SDA")
	)
	(segment
		(start 91.5416 -84.201)
		(end 90.463116 -84.201)
		(width 0.12065)
		(layer "B.Cu")
		(net "BMC_I2C2_MINI2_SDA")
	)
	(segment
		(start 116.97208 -34.3916)
		(end 111.43488 -34.3916)
		(width 0.12065)
		(layer "B.Cu")
		(net "BMC_I2C2_MINI2_SDA")
	)
	(segment
		(start 144.205706 -36.820094)
		(end 143.853154 -36.820094)
		(width 0.12065)
		(layer "B.Cu")
		(net "BMC_I2C2_MINI2_SDA")
	)
	(segment
		(start 111.43488 -34.3916)
		(end 102.24008 -43.5864)
		(width 0.12065)
		(layer "B.Cu")
		(net "BMC_I2C2_MINI2_SDA")
	)
	(segment
		(start 143.853154 -36.820094)
		(end 143.519398 -37.15385)
		(width 0.12065)
		(layer "B.Cu")
		(net "BMC_I2C2_MINI2_SDA")
	)
	(segment
		(start 82.054954 -92.609162)
		(end 82.054954 -93.610684)
		(width 0.12065)
		(layer "B.Cu")
		(net "BMC_I2C2_MINI2_SDA")
	)
	(segment
		(start 143.519398 -37.15385)
		(end 142.336774 -37.15385)
		(width 0.12065)
		(layer "B.Cu")
		(net "BMC_I2C2_MINI2_SDA")
	)
	(segment
		(start 82.054954 -93.610684)
		(end 81.486756 -94.178882)
		(width 0.12065)
		(layer "B.Cu")
		(net "BMC_I2C2_MINI2_SDA")
	)
	(segment
		(start 142.00378 -36.820856)
		(end 133.53542 -36.820856)
		(width 0.12065)
		(layer "B.Cu")
		(net "BMC_I2C2_MINI2_SDA")
	)
	(segment
		(start 145.88363 -33.98012)
		(end 146.930618 -33.98012)
		(width 0.12065)
		(layer "B.Cu")
		(net "BMC_I2C2_MINI2_SDA")
	)
	(segment
		(start 17.458182 -113.660428)
		(end 17.78 -113.983008)
		(width 0.127)
		(layer "In2.Cu")
		(net "BMC_I2C2_MINI2_SDA")
	)
	(segment
		(start 30.429708 -97.118678)
		(end 30.429962 -97.165668)
		(width 0.127)
		(layer "In2.Cu")
		(net "BMC_I2C2_MINI2_SDA")
	)
	(segment
		(start 17.2974 -118.53164)
		(end 17.2974 -120.321578)
		(width 0.127)
		(layer "In2.Cu")
		(net "BMC_I2C2_MINI2_SDA")
	)
	(segment
		(start 21.824442 -104.681528)
		(end 17.45742 -109.04855)
		(width 0.127)
		(layer "In2.Cu")
		(net "BMC_I2C2_MINI2_SDA")
	)
	(segment
		(start 77.38491 -93.9673)
		(end 72.578214 -93.9673)
		(width 0.127)
		(layer "In2.Cu")
		(net "BMC_I2C2_MINI2_SDA")
	)
	(segment
		(start 15.2146 -122.404632)
		(end 15.2146 -122.968512)
		(width 0.127)
		(layer "In2.Cu")
		(net "BMC_I2C2_MINI2_SDA")
	)
	(segment
		(start 72.578214 -93.9673)
		(end 72.306434 -93.69552)
		(width 0.127)
		(layer "In2.Cu")
		(net "BMC_I2C2_MINI2_SDA")
	)
	(segment
		(start 31.421578 -96.126808)
		(end 30.429708 -97.118678)
		(width 0.127)
		(layer "In2.Cu")
		(net "BMC_I2C2_MINI2_SDA")
	)
	(segment
		(start 79.1718 -94.751652)
		(end 78.169262 -94.751652)
		(width 0.127)
		(layer "In2.Cu")
		(net "BMC_I2C2_MINI2_SDA")
	)
	(segment
		(start 14.56563 -124.39523)
		(end 15.35811 -124.39523)
		(width 0.127)
		(layer "In2.Cu")
		(net "BMC_I2C2_MINI2_SDA")
	)
	(segment
		(start 53.572918 -93.9673)
		(end 52.125372 -95.414846)
		(width 0.127)
		(layer "In2.Cu")
		(net "BMC_I2C2_MINI2_SDA")
	)
	(segment
		(start 15.35811 -124.39523)
		(end 15.490698 -124.262642)
		(width 0.127)
		(layer "In2.Cu")
		(net "BMC_I2C2_MINI2_SDA")
	)
	(segment
		(start 78.169262 -94.751652)
		(end 77.38491 -93.9673)
		(width 0.127)
		(layer "In2.Cu")
		(net "BMC_I2C2_MINI2_SDA")
	)
	(segment
		(start 21.824442 -104.169718)
		(end 21.824442 -104.681528)
		(width 0.127)
		(layer "In2.Cu")
		(net "BMC_I2C2_MINI2_SDA")
	)
	(segment
		(start 17.78 -118.04904)
		(end 17.2974 -118.53164)
		(width 0.127)
		(layer "In2.Cu")
		(net "BMC_I2C2_MINI2_SDA")
	)
	(segment
		(start 25.003506 -101.628194)
		(end 24.364696 -101.62794)
		(width 0.127)
		(layer "In2.Cu")
		(net "BMC_I2C2_MINI2_SDA")
	)
	(segment
		(start 17.2974 -120.321578)
		(end 15.2146 -122.404632)
		(width 0.127)
		(layer "In2.Cu")
		(net "BMC_I2C2_MINI2_SDA")
	)
	(segment
		(start 59.182 -93.69552)
		(end 58.91022 -93.9673)
		(width 0.127)
		(layer "In2.Cu")
		(net "BMC_I2C2_MINI2_SDA")
	)
	(segment
		(start 30.429962 -97.165668)
		(end 30.429962 -97.975928)
		(width 0.127)
		(layer "In2.Cu")
		(net "BMC_I2C2_MINI2_SDA")
	)
	(segment
		(start 14.3256 -123.857512)
		(end 14.3256 -124.1552)
		(width 0.127)
		(layer "In2.Cu")
		(net "BMC_I2C2_MINI2_SDA")
	)
	(segment
		(start 36.455858 -95.414846)
		(end 35.743896 -96.126808)
		(width 0.127)
		(layer "In2.Cu")
		(net "BMC_I2C2_MINI2_SDA")
	)
	(segment
		(start 25.30983 -101.628194)
		(end 25.003506 -101.628194)
		(width 0.127)
		(layer "In2.Cu")
		(net "BMC_I2C2_MINI2_SDA")
	)
	(segment
		(start 26.774648 -100.163376)
		(end 25.30983 -101.628194)
		(width 0.127)
		(layer "In2.Cu")
		(net "BMC_I2C2_MINI2_SDA")
	)
	(segment
		(start 17.78 -113.983008)
		(end 17.78 -118.04904)
		(width 0.127)
		(layer "In2.Cu")
		(net "BMC_I2C2_MINI2_SDA")
	)
	(segment
		(start 28.367482 -98.9838)
		(end 27.187906 -100.163376)
		(width 0.127)
		(layer "In2.Cu")
		(net "BMC_I2C2_MINI2_SDA")
	)
	(segment
		(start 17.45742 -109.151166)
		(end 17.458182 -113.660428)
		(width 0.127)
		(layer "In2.Cu")
		(net "BMC_I2C2_MINI2_SDA")
	)
	(segment
		(start 72.306434 -93.69552)
		(end 59.182 -93.69552)
		(width 0.127)
		(layer "In2.Cu")
		(net "BMC_I2C2_MINI2_SDA")
	)
	(segment
		(start 24.364696 -101.62794)
		(end 21.824442 -104.169718)
		(width 0.127)
		(layer "In2.Cu")
		(net "BMC_I2C2_MINI2_SDA")
	)
	(segment
		(start 30.429962 -97.975928)
		(end 29.42209 -98.9838)
		(width 0.127)
		(layer "In2.Cu")
		(net "BMC_I2C2_MINI2_SDA")
	)
	(segment
		(start 27.187906 -100.163376)
		(end 26.774648 -100.163376)
		(width 0.127)
		(layer "In2.Cu")
		(net "BMC_I2C2_MINI2_SDA")
	)
	(segment
		(start 17.45742 -109.04855)
		(end 17.45742 -109.151166)
		(width 0.127)
		(layer "In2.Cu")
		(net "BMC_I2C2_MINI2_SDA")
	)
	(segment
		(start 14.3256 -124.1552)
		(end 14.56563 -124.39523)
		(width 0.127)
		(layer "In2.Cu")
		(net "BMC_I2C2_MINI2_SDA")
	)
	(segment
		(start 52.125372 -95.414846)
		(end 36.455858 -95.414846)
		(width 0.127)
		(layer "In2.Cu")
		(net "BMC_I2C2_MINI2_SDA")
	)
	(segment
		(start 15.2146 -122.968512)
		(end 14.3256 -123.857512)
		(width 0.127)
		(layer "In2.Cu")
		(net "BMC_I2C2_MINI2_SDA")
	)
	(segment
		(start 35.743896 -96.126808)
		(end 31.421578 -96.126808)
		(width 0.127)
		(layer "In2.Cu")
		(net "BMC_I2C2_MINI2_SDA")
	)
	(segment
		(start 29.42209 -98.9838)
		(end 28.367482 -98.9838)
		(width 0.127)
		(layer "In2.Cu")
		(net "BMC_I2C2_MINI2_SDA")
	)
	(segment
		(start 79.5274 -95.107252)
		(end 79.1718 -94.751652)
		(width 0.127)
		(layer "In2.Cu")
		(net "BMC_I2C2_MINI2_SDA")
	)
	(segment
		(start 58.91022 -93.9673)
		(end 53.572918 -93.9673)
		(width 0.127)
		(layer "In2.Cu")
		(net "BMC_I2C2_MINI2_SDA")
	)
	(segment
		(start 13.44676 -126.0348)
		(end 13.009372 -126.0348)
		(width 0.12065)
		(layer "F.Cu")
		(net "BMC_I2C2_MINI2_SCL")
	)
	(segment
		(start 12.767818 -125.650244)
		(end 12.73556 -125.617986)
		(width 0.12065)
		(layer "F.Cu")
		(net "BMC_I2C2_MINI2_SCL")
	)
	(segment
		(start 12.73556 -125.617986)
		(end 12.73556 -125.581156)
		(width 0.12065)
		(layer "F.Cu")
		(net "BMC_I2C2_MINI2_SCL")
	)
	(segment
		(start 11.826494 -125.4633)
		(end 10.933684 -126.35611)
		(width 0.12065)
		(layer "F.Cu")
		(net "BMC_I2C2_MINI2_SCL")
	)
	(segment
		(start 12.767818 -125.793246)
		(end 12.767818 -125.650244)
		(width 0.12065)
		(layer "F.Cu")
		(net "BMC_I2C2_MINI2_SCL")
	)
	(segment
		(start 13.009372 -126.0348)
		(end 12.767818 -125.793246)
		(width 0.12065)
		(layer "F.Cu")
		(net "BMC_I2C2_MINI2_SCL")
	)
	(segment
		(start 12.617704 -125.4633)
		(end 11.9126 -125.4633)
		(width 0.12065)
		(layer "F.Cu")
		(net "BMC_I2C2_MINI2_SCL")
	)
	(segment
		(start 12.73556 -125.581156)
		(end 12.617704 -125.4633)
		(width 0.12065)
		(layer "F.Cu")
		(net "BMC_I2C2_MINI2_SCL")
	)
	(segment
		(start 11.9126 -125.4633)
		(end 11.826494 -125.4633)
		(width 0.12065)
		(layer "F.Cu")
		(net "BMC_I2C2_MINI2_SCL")
	)
	(via
		(at 12.73556 -125.617986)
		(size 0.508)
		(drill 0.254)
		(layers "F.Cu" "B.Cu")
		(net "BMC_I2C2_MINI2_SCL")
	)
	(via
		(at 10.933684 -126.35611)
		(size 0.7112)
		(drill 0.3556)
		(layers "F.Cu" "B.Cu")
		(net "BMC_I2C2_MINI2_SCL")
	)
	(via
		(at 79.5274 -94.243652)
		(size 0.508)
		(drill 0.254)
		(layers "F.Cu" "B.Cu")
		(net "BMC_I2C2_MINI2_SCL")
	)
	(segment
		(start 93.031818 -50.1777)
		(end 93.031818 -60.670694)
		(width 0.12065)
		(layer "B.Cu")
		(net "BMC_I2C2_MINI2_SCL")
	)
	(segment
		(start 81.553304 -93.402658)
		(end 80.499458 -94.456504)
		(width 0.12065)
		(layer "B.Cu")
		(net "BMC_I2C2_MINI2_SCL")
	)
	(segment
		(start 144.134332 -21.530056)
		(end 144.134332 -22.231604)
		(width 0.12065)
		(layer "B.Cu")
		(net "BMC_I2C2_MINI2_SCL")
	)
	(segment
		(start 143.55826 -35.66668)
		(end 143.55826 -35.912806)
		(width 0.12065)
		(layer "B.Cu")
		(net "BMC_I2C2_MINI2_SCL")
	)
	(segment
		(start 144.22501 -34.99993)
		(end 143.55826 -35.66668)
		(width 0.12065)
		(layer "B.Cu")
		(net "BMC_I2C2_MINI2_SCL")
	)
	(segment
		(start 122.227086 -34.511742)
		(end 117.801898 -34.511742)
		(width 0.12065)
		(layer "B.Cu")
		(net "BMC_I2C2_MINI2_SCL")
	)
	(segment
		(start 142.211806 -36.319206)
		(end 133.327394 -36.319206)
		(width 0.12065)
		(layer "B.Cu")
		(net "BMC_I2C2_MINI2_SCL")
	)
	(segment
		(start 143.55826 -35.912806)
		(end 143.432022 -36.039044)
		(width 0.12065)
		(layer "B.Cu")
		(net "BMC_I2C2_MINI2_SCL")
	)
	(segment
		(start 124.926344 -37.211)
		(end 122.227086 -34.511742)
		(width 0.12065)
		(layer "B.Cu")
		(net "BMC_I2C2_MINI2_SCL")
	)
	(segment
		(start 117.180106 -33.88995)
		(end 111.226854 -33.88995)
		(width 0.12065)
		(layer "B.Cu")
		(net "BMC_I2C2_MINI2_SCL")
	)
	(segment
		(start 144.22501 -29.097478)
		(end 144.22501 -34.99993)
		(width 0.12065)
		(layer "B.Cu")
		(net "BMC_I2C2_MINI2_SCL")
	)
	(segment
		(start 91.333574 -83.69935)
		(end 90.25509 -83.69935)
		(width 0.12065)
		(layer "B.Cu")
		(net "BMC_I2C2_MINI2_SCL")
	)
	(segment
		(start 143.432022 -36.039044)
		(end 143.432022 -36.53155)
		(width 0.12065)
		(layer "B.Cu")
		(net "BMC_I2C2_MINI2_SCL")
	)
	(segment
		(start 143.311372 -36.6522)
		(end 142.5448 -36.6522)
		(width 0.12065)
		(layer "B.Cu")
		(net "BMC_I2C2_MINI2_SCL")
	)
	(segment
		(start 143.432022 -36.53155)
		(end 143.311372 -36.6522)
		(width 0.12065)
		(layer "B.Cu")
		(net "BMC_I2C2_MINI2_SCL")
	)
	(segment
		(start 142.5448 -36.6522)
		(end 142.211806 -36.319206)
		(width 0.12065)
		(layer "B.Cu")
		(net "BMC_I2C2_MINI2_SCL")
	)
	(segment
		(start 143.736822 -22.62505)
		(end 142.113 -24.248872)
		(width 0.12065)
		(layer "B.Cu")
		(net "BMC_I2C2_MINI2_SCL")
	)
	(segment
		(start 80.499458 -94.456504)
		(end 79.740252 -94.456504)
		(width 0.12065)
		(layer "B.Cu")
		(net "BMC_I2C2_MINI2_SCL")
	)
	(segment
		(start 90.25509 -83.69935)
		(end 81.553304 -92.401136)
		(width 0.12065)
		(layer "B.Cu")
		(net "BMC_I2C2_MINI2_SCL")
	)
	(segment
		(start 111.226854 -33.88995)
		(end 102.032054 -43.08475)
		(width 0.12065)
		(layer "B.Cu")
		(net "BMC_I2C2_MINI2_SCL")
	)
	(segment
		(start 102.032054 -43.08475)
		(end 100.124768 -43.08475)
		(width 0.12065)
		(layer "B.Cu")
		(net "BMC_I2C2_MINI2_SCL")
	)
	(segment
		(start 94.18955 -80.843374)
		(end 91.333574 -83.69935)
		(width 0.12065)
		(layer "B.Cu")
		(net "BMC_I2C2_MINI2_SCL")
	)
	(segment
		(start 94.18955 -61.828426)
		(end 94.18955 -80.843374)
		(width 0.12065)
		(layer "B.Cu")
		(net "BMC_I2C2_MINI2_SCL")
	)
	(segment
		(start 144.134332 -22.231604)
		(end 143.740886 -22.62505)
		(width 0.12065)
		(layer "B.Cu")
		(net "BMC_I2C2_MINI2_SCL")
	)
	(segment
		(start 143.740886 -22.62505)
		(end 143.736822 -22.62505)
		(width 0.12065)
		(layer "B.Cu")
		(net "BMC_I2C2_MINI2_SCL")
	)
	(segment
		(start 132.4356 -37.211)
		(end 124.926344 -37.211)
		(width 0.12065)
		(layer "B.Cu")
		(net "BMC_I2C2_MINI2_SCL")
	)
	(segment
		(start 81.553304 -92.401136)
		(end 81.553304 -93.402658)
		(width 0.12065)
		(layer "B.Cu")
		(net "BMC_I2C2_MINI2_SCL")
	)
	(segment
		(start 100.124768 -43.08475)
		(end 93.031818 -50.1777)
		(width 0.12065)
		(layer "B.Cu")
		(net "BMC_I2C2_MINI2_SCL")
	)
	(segment
		(start 142.113 -24.248872)
		(end 142.113 -26.985468)
		(width 0.12065)
		(layer "B.Cu")
		(net "BMC_I2C2_MINI2_SCL")
	)
	(segment
		(start 142.113 -26.985468)
		(end 144.22501 -29.097478)
		(width 0.12065)
		(layer "B.Cu")
		(net "BMC_I2C2_MINI2_SCL")
	)
	(segment
		(start 93.031818 -60.670694)
		(end 94.18955 -61.828426)
		(width 0.12065)
		(layer "B.Cu")
		(net "BMC_I2C2_MINI2_SCL")
	)
	(segment
		(start 117.801898 -34.511742)
		(end 117.180106 -33.88995)
		(width 0.12065)
		(layer "B.Cu")
		(net "BMC_I2C2_MINI2_SCL")
	)
	(segment
		(start 133.327394 -36.319206)
		(end 132.4356 -37.211)
		(width 0.12065)
		(layer "B.Cu")
		(net "BMC_I2C2_MINI2_SCL")
	)
	(segment
		(start 79.740252 -94.456504)
		(end 79.5274 -94.243652)
		(width 0.12065)
		(layer "B.Cu")
		(net "BMC_I2C2_MINI2_SCL")
	)
	(segment
		(start 58.971434 -93.18752)
		(end 58.699654 -93.4593)
		(width 0.127)
		(layer "In2.Cu")
		(net "BMC_I2C2_MINI2_SCL")
	)
	(segment
		(start 21.316442 -104.470962)
		(end 16.94942 -108.837984)
		(width 0.127)
		(layer "In2.Cu")
		(net "BMC_I2C2_MINI2_SCL")
	)
	(segment
		(start 24.762968 -101.11994)
		(end 24.153876 -101.11994)
		(width 0.127)
		(layer "In2.Cu")
		(net "BMC_I2C2_MINI2_SCL")
	)
	(segment
		(start 23.848568 -101.425248)
		(end 21.316442 -103.959152)
		(width 0.127)
		(layer "In2.Cu")
		(net "BMC_I2C2_MINI2_SCL")
	)
	(segment
		(start 14.7066 -122.757946)
		(end 13.8176 -123.646946)
		(width 0.127)
		(layer "In2.Cu")
		(net "BMC_I2C2_MINI2_SCL")
	)
	(segment
		(start 13.193014 -125.617986)
		(end 12.73556 -125.617986)
		(width 0.127)
		(layer "In2.Cu")
		(net "BMC_I2C2_MINI2_SCL")
	)
	(segment
		(start 13.8176 -124.9934)
		(end 13.193014 -125.617986)
		(width 0.127)
		(layer "In2.Cu")
		(net "BMC_I2C2_MINI2_SCL")
	)
	(segment
		(start 16.950182 -113.870486)
		(end 17.272 -114.19332)
		(width 0.127)
		(layer "In2.Cu")
		(net "BMC_I2C2_MINI2_SCL")
	)
	(segment
		(start 77.595476 -93.4593)
		(end 72.78878 -93.4593)
		(width 0.127)
		(layer "In2.Cu")
		(net "BMC_I2C2_MINI2_SCL")
	)
	(segment
		(start 17.272 -117.838474)
		(end 16.7894 -118.321074)
		(width 0.127)
		(layer "In2.Cu")
		(net "BMC_I2C2_MINI2_SCL")
	)
	(segment
		(start 58.699654 -93.4593)
		(end 53.362352 -93.4593)
		(width 0.127)
		(layer "In2.Cu")
		(net "BMC_I2C2_MINI2_SCL")
	)
	(segment
		(start 28.156916 -98.4758)
		(end 26.97734 -99.655376)
		(width 0.127)
		(layer "In2.Cu")
		(net "BMC_I2C2_MINI2_SCL")
	)
	(segment
		(start 35.53333 -95.618808)
		(end 31.211012 -95.618808)
		(width 0.127)
		(layer "In2.Cu")
		(net "BMC_I2C2_MINI2_SCL")
	)
	(segment
		(start 78.379828 -94.243652)
		(end 77.595476 -93.4593)
		(width 0.127)
		(layer "In2.Cu")
		(net "BMC_I2C2_MINI2_SCL")
	)
	(segment
		(start 25.00376 -101.120194)
		(end 24.762968 -101.11994)
		(width 0.127)
		(layer "In2.Cu")
		(net "BMC_I2C2_MINI2_SCL")
	)
	(segment
		(start 14.7066 -122.194066)
		(end 14.7066 -122.757946)
		(width 0.127)
		(layer "In2.Cu")
		(net "BMC_I2C2_MINI2_SCL")
	)
	(segment
		(start 29.921962 -97.765362)
		(end 29.211524 -98.4758)
		(width 0.127)
		(layer "In2.Cu")
		(net "BMC_I2C2_MINI2_SCL")
	)
	(segment
		(start 16.94942 -109.15142)
		(end 16.950182 -113.870486)
		(width 0.127)
		(layer "In2.Cu")
		(net "BMC_I2C2_MINI2_SCL")
	)
	(segment
		(start 16.7894 -118.321074)
		(end 16.7894 -120.111012)
		(width 0.127)
		(layer "In2.Cu")
		(net "BMC_I2C2_MINI2_SCL")
	)
	(segment
		(start 72.517 -93.18752)
		(end 58.971434 -93.18752)
		(width 0.127)
		(layer "In2.Cu")
		(net "BMC_I2C2_MINI2_SCL")
	)
	(segment
		(start 25.099264 -101.120194)
		(end 25.00376 -101.120194)
		(width 0.127)
		(layer "In2.Cu")
		(net "BMC_I2C2_MINI2_SCL")
	)
	(segment
		(start 31.211012 -95.618808)
		(end 29.920438 -96.909382)
		(width 0.127)
		(layer "In2.Cu")
		(net "BMC_I2C2_MINI2_SCL")
	)
	(segment
		(start 72.78878 -93.4593)
		(end 72.517 -93.18752)
		(width 0.127)
		(layer "In2.Cu")
		(net "BMC_I2C2_MINI2_SCL")
	)
	(segment
		(start 79.5274 -94.243652)
		(end 78.379828 -94.243652)
		(width 0.127)
		(layer "In2.Cu")
		(net "BMC_I2C2_MINI2_SCL")
	)
	(segment
		(start 24.153876 -101.11994)
		(end 23.848568 -101.425248)
		(width 0.127)
		(layer "In2.Cu")
		(net "BMC_I2C2_MINI2_SCL")
	)
	(segment
		(start 36.245292 -94.906846)
		(end 35.53333 -95.618808)
		(width 0.127)
		(layer "In2.Cu")
		(net "BMC_I2C2_MINI2_SCL")
	)
	(segment
		(start 53.362352 -93.4593)
		(end 51.914806 -94.906846)
		(width 0.127)
		(layer "In2.Cu")
		(net "BMC_I2C2_MINI2_SCL")
	)
	(segment
		(start 29.921962 -97.167192)
		(end 29.921962 -97.765362)
		(width 0.127)
		(layer "In2.Cu")
		(net "BMC_I2C2_MINI2_SCL")
	)
	(segment
		(start 17.272 -114.19332)
		(end 17.272 -117.838474)
		(width 0.127)
		(layer "In2.Cu")
		(net "BMC_I2C2_MINI2_SCL")
	)
	(segment
		(start 51.914806 -94.906846)
		(end 36.245292 -94.906846)
		(width 0.127)
		(layer "In2.Cu")
		(net "BMC_I2C2_MINI2_SCL")
	)
	(segment
		(start 16.94942 -108.837984)
		(end 16.94942 -109.15142)
		(width 0.127)
		(layer "In2.Cu")
		(net "BMC_I2C2_MINI2_SCL")
	)
	(segment
		(start 21.316442 -103.959152)
		(end 21.316442 -104.470962)
		(width 0.127)
		(layer "In2.Cu")
		(net "BMC_I2C2_MINI2_SCL")
	)
	(segment
		(start 13.8176 -123.646946)
		(end 13.8176 -124.9934)
		(width 0.127)
		(layer "In2.Cu")
		(net "BMC_I2C2_MINI2_SCL")
	)
	(segment
		(start 26.97734 -99.655376)
		(end 26.564082 -99.655376)
		(width 0.127)
		(layer "In2.Cu")
		(net "BMC_I2C2_MINI2_SCL")
	)
	(segment
		(start 14.85519 -122.045476)
		(end 14.7066 -122.194066)
		(width 0.127)
		(layer "In2.Cu")
		(net "BMC_I2C2_MINI2_SCL")
	)
	(segment
		(start 16.7894 -120.111012)
		(end 14.85519 -122.045476)
		(width 0.127)
		(layer "In2.Cu")
		(net "BMC_I2C2_MINI2_SCL")
	)
	(segment
		(start 29.920438 -96.909382)
		(end 29.921962 -97.167192)
		(width 0.127)
		(layer "In2.Cu")
		(net "BMC_I2C2_MINI2_SCL")
	)
	(segment
		(start 26.564082 -99.655376)
		(end 25.099264 -101.120194)
		(width 0.127)
		(layer "In2.Cu")
		(net "BMC_I2C2_MINI2_SCL")
	)
	(segment
		(start 29.211524 -98.4758)
		(end 28.156916 -98.4758)
		(width 0.127)
		(layer "In2.Cu")
		(net "BMC_I2C2_MINI2_SCL")
	)
	(via
		(at 270.833088 -0.495046)
		(size 0.7112)
		(drill 0.3556)
		(layers "F.Cu" "B.Cu")
		(net "BMC_I2C14_MINI8_SDA")
	)
	(via
		(at 50.038 -102.616)
		(size 0.508)
		(drill 0.254)
		(layers "F.Cu" "B.Cu")
		(net "BMC_I2C14_MINI8_SDA")
	)
	(via
		(at 270.66748 1.10109)
		(size 0.508)
		(drill 0.254)
		(layers "F.Cu" "B.Cu")
		(net "BMC_I2C14_MINI8_SDA")
	)
	(segment
		(start 49.8602 -102.4382)
		(end 50.038 -102.616)
		(width 0.12065)
		(layer "B.Cu")
		(net "BMC_I2C14_MINI8_SDA")
	)
	(segment
		(start 270.519906 -0.495046)
		(end 270.519906 -1.02743)
		(width 0.12065)
		(layer "B.Cu")
		(net "BMC_I2C14_MINI8_SDA")
	)
	(segment
		(start 271.957546 -2.466848)
		(end 272.63979 -3.1496)
		(width 0.12065)
		(layer "B.Cu")
		(net "BMC_I2C14_MINI8_SDA")
	)
	(segment
		(start 49.30775 -103.15575)
		(end 49.53 -103.378)
		(width 0.12065)
		(layer "B.Cu")
		(net "BMC_I2C14_MINI8_SDA")
	)
	(segment
		(start 271.7038 -2.0447)
		(end 271.7038 -2.21234)
		(width 0.12065)
		(layer "B.Cu")
		(net "BMC_I2C14_MINI8_SDA")
	)
	(segment
		(start 49.53 -103.378)
		(end 49.53 -103.89616)
		(width 0.12065)
		(layer "B.Cu")
		(net "BMC_I2C14_MINI8_SDA")
	)
	(segment
		(start 49.30775 -103.02494)
		(end 49.30775 -103.15575)
		(width 0.12065)
		(layer "B.Cu")
		(net "BMC_I2C14_MINI8_SDA")
	)
	(segment
		(start 49.0093 -102.4382)
		(end 49.8602 -102.4382)
		(width 0.12065)
		(layer "B.Cu")
		(net "BMC_I2C14_MINI8_SDA")
	)
	(segment
		(start 271.128744 -1.636268)
		(end 271.275302 -1.78308)
		(width 0.12065)
		(layer "B.Cu")
		(net "BMC_I2C14_MINI8_SDA")
	)
	(segment
		(start 270.519906 -1.02743)
		(end 271.128744 -1.636268)
		(width 0.12065)
		(layer "B.Cu")
		(net "BMC_I2C14_MINI8_SDA")
	)
	(segment
		(start 271.7038 -2.21234)
		(end 271.957546 -2.466848)
		(width 0.12065)
		(layer "B.Cu")
		(net "BMC_I2C14_MINI8_SDA")
	)
	(segment
		(start 270.519906 0.953516)
		(end 270.519906 -0.495046)
		(width 0.12065)
		(layer "B.Cu")
		(net "BMC_I2C14_MINI8_SDA")
	)
	(segment
		(start 49.0093 -102.4382)
		(end 49.0093 -102.72649)
		(width 0.12065)
		(layer "B.Cu")
		(net "BMC_I2C14_MINI8_SDA")
	)
	(segment
		(start 270.519906 -0.495046)
		(end 270.833088 -0.495046)
		(width 0.12065)
		(layer "B.Cu")
		(net "BMC_I2C14_MINI8_SDA")
	)
	(segment
		(start 272.63979 -3.1496)
		(end 272.8341 -3.1496)
		(width 0.12065)
		(layer "B.Cu")
		(net "BMC_I2C14_MINI8_SDA")
	)
	(segment
		(start 49.0093 -102.72649)
		(end 49.30775 -103.02494)
		(width 0.12065)
		(layer "B.Cu")
		(net "BMC_I2C14_MINI8_SDA")
	)
	(segment
		(start 271.275302 -1.78308)
		(end 271.536414 -2.0447)
		(width 0.12065)
		(layer "B.Cu")
		(net "BMC_I2C14_MINI8_SDA")
	)
	(segment
		(start 270.66748 1.10109)
		(end 270.519906 0.953516)
		(width 0.12065)
		(layer "B.Cu")
		(net "BMC_I2C14_MINI8_SDA")
	)
	(segment
		(start 271.536414 -2.0447)
		(end 271.7038 -2.0447)
		(width 0.12065)
		(layer "B.Cu")
		(net "BMC_I2C14_MINI8_SDA")
	)
	(segment
		(start 92.244164 -58.9026)
		(end 72.691498 -58.9026)
		(width 0.127)
		(layer "In5.Cu")
		(net "BMC_I2C14_MINI8_SDA")
	)
	(segment
		(start 245.313454 3.28549)
		(end 128.413002 3.28549)
		(width 0.127)
		(layer "In5.Cu")
		(net "BMC_I2C14_MINI8_SDA")
	)
	(segment
		(start 104.009444 -47.13732)
		(end 92.244164 -58.9026)
		(width 0.127)
		(layer "In5.Cu")
		(net "BMC_I2C14_MINI8_SDA")
	)
	(segment
		(start 270.66748 1.10109)
		(end 270.66748 0.93853)
		(width 0.127)
		(layer "In5.Cu")
		(net "BMC_I2C14_MINI8_SDA")
	)
	(segment
		(start 264.903966 0.137414)
		(end 259.060696 0.137414)
		(width 0.127)
		(layer "In5.Cu")
		(net "BMC_I2C14_MINI8_SDA")
	)
	(segment
		(start 106.057192 -19.07032)
		(end 106.057192 -38.44925)
		(width 0.127)
		(layer "In5.Cu")
		(net "BMC_I2C14_MINI8_SDA")
	)
	(segment
		(start 104.009444 -40.496998)
		(end 104.009444 -47.13732)
		(width 0.127)
		(layer "In5.Cu")
		(net "BMC_I2C14_MINI8_SDA")
	)
	(segment
		(start 264.92454 0.157988)
		(end 264.903966 0.137414)
		(width 0.127)
		(layer "In5.Cu")
		(net "BMC_I2C14_MINI8_SDA")
	)
	(segment
		(start 59.21756 -76.00188)
		(end 59.21756 -90.663522)
		(width 0.127)
		(layer "In5.Cu")
		(net "BMC_I2C14_MINI8_SDA")
	)
	(segment
		(start 49.7586 -102.616)
		(end 50.038 -102.616)
		(width 0.127)
		(layer "In5.Cu")
		(net "BMC_I2C14_MINI8_SDA")
	)
	(segment
		(start 257.597402 1.600708)
		(end 246.998236 1.600708)
		(width 0.127)
		(layer "In5.Cu")
		(net "BMC_I2C14_MINI8_SDA")
	)
	(segment
		(start 49.276 -100.605082)
		(end 49.276 -102.1334)
		(width 0.127)
		(layer "In5.Cu")
		(net "BMC_I2C14_MINI8_SDA")
	)
	(segment
		(start 62.796928 -72.422512)
		(end 59.21756 -76.00188)
		(width 0.127)
		(layer "In5.Cu")
		(net "BMC_I2C14_MINI8_SDA")
	)
	(segment
		(start 59.21756 -90.663522)
		(end 49.276 -100.605082)
		(width 0.127)
		(layer "In5.Cu")
		(net "BMC_I2C14_MINI8_SDA")
	)
	(segment
		(start 266.387834 0.137414)
		(end 266.36726 0.157988)
		(width 0.127)
		(layer "In5.Cu")
		(net "BMC_I2C14_MINI8_SDA")
	)
	(segment
		(start 106.057192 -38.44925)
		(end 104.009444 -40.496998)
		(width 0.127)
		(layer "In5.Cu")
		(net "BMC_I2C14_MINI8_SDA")
	)
	(segment
		(start 62.796928 -68.79717)
		(end 62.796928 -72.422512)
		(width 0.127)
		(layer "In5.Cu")
		(net "BMC_I2C14_MINI8_SDA")
	)
	(segment
		(start 270.66748 0.93853)
		(end 269.866364 0.137414)
		(width 0.127)
		(layer "In5.Cu")
		(net "BMC_I2C14_MINI8_SDA")
	)
	(segment
		(start 259.060696 0.137414)
		(end 257.597402 1.600708)
		(width 0.127)
		(layer "In5.Cu")
		(net "BMC_I2C14_MINI8_SDA")
	)
	(segment
		(start 246.998236 1.600708)
		(end 245.313454 3.28549)
		(width 0.127)
		(layer "In5.Cu")
		(net "BMC_I2C14_MINI8_SDA")
	)
	(segment
		(start 49.276 -102.1334)
		(end 49.7586 -102.616)
		(width 0.127)
		(layer "In5.Cu")
		(net "BMC_I2C14_MINI8_SDA")
	)
	(segment
		(start 269.866364 0.137414)
		(end 266.387834 0.137414)
		(width 0.127)
		(layer "In5.Cu")
		(net "BMC_I2C14_MINI8_SDA")
	)
	(segment
		(start 128.413002 3.28549)
		(end 106.057192 -19.07032)
		(width 0.127)
		(layer "In5.Cu")
		(net "BMC_I2C14_MINI8_SDA")
	)
	(segment
		(start 72.691498 -58.9026)
		(end 62.796928 -68.79717)
		(width 0.127)
		(layer "In5.Cu")
		(net "BMC_I2C14_MINI8_SDA")
	)
	(segment
		(start 266.36726 0.157988)
		(end 264.92454 0.157988)
		(width 0.127)
		(layer "In5.Cu")
		(net "BMC_I2C14_MINI8_SDA")
	)
	(via
		(at 48.8061 -103.232966)
		(size 0.508)
		(drill 0.254)
		(layers "F.Cu" "B.Cu")
		(net "BMC_I2C14_MINI8_SCL")
	)
	(via
		(at 269.759176 1.059942)
		(size 0.508)
		(drill 0.254)
		(layers "F.Cu" "B.Cu")
		(net "BMC_I2C14_MINI8_SCL")
	)
	(via
		(at 271.626076 -3.306572)
		(size 0.7112)
		(drill 0.3556)
		(layers "F.Cu" "B.Cu")
		(net "BMC_I2C14_MINI8_SCL")
	)
	(segment
		(start 270.018256 0.800862)
		(end 270.018256 -1.235456)
		(width 0.12065)
		(layer "B.Cu")
		(net "BMC_I2C14_MINI8_SCL")
	)
	(segment
		(start 317.4492 -18.1102)
		(end 319.13449 -19.79549)
		(width 0.12065)
		(layer "B.Cu")
		(net "BMC_I2C14_MINI8_SCL")
	)
	(segment
		(start 312.1152 -4.0132)
		(end 317.4492 -9.3472)
		(width 0.12065)
		(layer "B.Cu")
		(net "BMC_I2C14_MINI8_SCL")
	)
	(segment
		(start 271.856708 -3.07594)
		(end 272.431256 -3.65125)
		(width 0.12065)
		(layer "B.Cu")
		(net "BMC_I2C14_MINI8_SCL")
	)
	(segment
		(start 317.4492 -9.3472)
		(end 317.4492 -18.1102)
		(width 0.12065)
		(layer "B.Cu")
		(net "BMC_I2C14_MINI8_SCL")
	)
	(segment
		(start 48.1711 -106.6292)
		(end 47.6504 -106.1085)
		(width 0.12065)
		(layer "B.Cu")
		(net "BMC_I2C14_MINI8_SCL")
	)
	(segment
		(start 270.773652 -1.990852)
		(end 271.328134 -2.546604)
		(width 0.12065)
		(layer "B.Cu")
		(net "BMC_I2C14_MINI8_SCL")
	)
	(segment
		(start 274.85721 -3.108706)
		(end 280.273506 -3.108706)
		(width 0.12065)
		(layer "B.Cu")
		(net "BMC_I2C14_MINI8_SCL")
	)
	(segment
		(start 48.8061 -103.232966)
		(end 48.8061 -103.3526)
		(width 0.12065)
		(layer "B.Cu")
		(net "BMC_I2C14_MINI8_SCL")
	)
	(segment
		(start 48.8061 -103.3526)
		(end 48.50765 -103.65105)
		(width 0.12065)
		(layer "B.Cu")
		(net "BMC_I2C14_MINI8_SCL")
	)
	(segment
		(start 271.348454 -2.566924)
		(end 271.856708 -3.07594)
		(width 0.12065)
		(layer "B.Cu")
		(net "BMC_I2C14_MINI8_SCL")
	)
	(segment
		(start 271.328134 -2.546604)
		(end 271.348454 -2.566924)
		(width 0.12065)
		(layer "B.Cu")
		(net "BMC_I2C14_MINI8_SCL")
	)
	(segment
		(start 281.178 -4.0132)
		(end 312.1152 -4.0132)
		(width 0.12065)
		(layer "B.Cu")
		(net "BMC_I2C14_MINI8_SCL")
	)
	(segment
		(start 274.314666 -3.65125)
		(end 274.85721 -3.108706)
		(width 0.12065)
		(layer "B.Cu")
		(net "BMC_I2C14_MINI8_SCL")
	)
	(segment
		(start 269.759176 1.059942)
		(end 270.018256 0.800862)
		(width 0.12065)
		(layer "B.Cu")
		(net "BMC_I2C14_MINI8_SCL")
	)
	(segment
		(start 48.50765 -105.77195)
		(end 48.1711 -106.1085)
		(width 0.12065)
		(layer "B.Cu")
		(net "BMC_I2C14_MINI8_SCL")
	)
	(segment
		(start 270.018256 -1.235456)
		(end 270.773652 -1.990852)
		(width 0.12065)
		(layer "B.Cu")
		(net "BMC_I2C14_MINI8_SCL")
	)
	(segment
		(start 319.13449 -19.79549)
		(end 319.13449 -21.530056)
		(width 0.12065)
		(layer "B.Cu")
		(net "BMC_I2C14_MINI8_SCL")
	)
	(segment
		(start 271.626076 -3.306572)
		(end 271.856708 -3.07594)
		(width 0.12065)
		(layer "B.Cu")
		(net "BMC_I2C14_MINI8_SCL")
	)
	(segment
		(start 47.6504 -106.1085)
		(end 47.6504 -105.19664)
		(width 0.12065)
		(layer "B.Cu")
		(net "BMC_I2C14_MINI8_SCL")
	)
	(segment
		(start 48.1711 -106.1085)
		(end 48.1711 -106.6292)
		(width 0.12065)
		(layer "B.Cu")
		(net "BMC_I2C14_MINI8_SCL")
	)
	(segment
		(start 272.431256 -3.65125)
		(end 274.314666 -3.65125)
		(width 0.12065)
		(layer "B.Cu")
		(net "BMC_I2C14_MINI8_SCL")
	)
	(segment
		(start 280.273506 -3.108706)
		(end 281.178 -4.0132)
		(width 0.12065)
		(layer "B.Cu")
		(net "BMC_I2C14_MINI8_SCL")
	)
	(segment
		(start 48.50765 -103.65105)
		(end 48.50765 -105.77195)
		(width 0.12065)
		(layer "B.Cu")
		(net "BMC_I2C14_MINI8_SCL")
	)
	(segment
		(start 269.759176 1.059942)
		(end 269.344648 0.645414)
		(width 0.127)
		(layer "In5.Cu")
		(net "BMC_I2C14_MINI8_SCL")
	)
	(segment
		(start 72.480932 -58.3946)
		(end 62.288928 -68.586604)
		(width 0.127)
		(layer "In5.Cu")
		(net "BMC_I2C14_MINI8_SCL")
	)
	(segment
		(start 103.50119 -40.286686)
		(end 103.501444 -40.887142)
		(width 0.127)
		(layer "In5.Cu")
		(net "BMC_I2C14_MINI8_SCL")
	)
	(segment
		(start 48.768 -100.394516)
		(end 48.768 -102.343966)
		(width 0.127)
		(layer "In5.Cu")
		(net "BMC_I2C14_MINI8_SCL")
	)
	(segment
		(start 269.344648 0.645414)
		(end 266.5984 0.645414)
		(width 0.127)
		(layer "In5.Cu")
		(net "BMC_I2C14_MINI8_SCL")
	)
	(segment
		(start 266.577826 0.665988)
		(end 264.713974 0.665988)
		(width 0.127)
		(layer "In5.Cu")
		(net "BMC_I2C14_MINI8_SCL")
	)
	(segment
		(start 62.288928 -68.586604)
		(end 62.288928 -72.211946)
		(width 0.127)
		(layer "In5.Cu")
		(net "BMC_I2C14_MINI8_SCL")
	)
	(segment
		(start 49.0982 -102.674166)
		(end 49.0982 -102.940866)
		(width 0.127)
		(layer "In5.Cu")
		(net "BMC_I2C14_MINI8_SCL")
	)
	(segment
		(start 48.768 -102.343966)
		(end 49.0982 -102.674166)
		(width 0.127)
		(layer "In5.Cu")
		(net "BMC_I2C14_MINI8_SCL")
	)
	(segment
		(start 58.70956 -90.452956)
		(end 48.768 -100.394516)
		(width 0.127)
		(layer "In5.Cu")
		(net "BMC_I2C14_MINI8_SCL")
	)
	(segment
		(start 103.501444 -46.926754)
		(end 92.033598 -58.3946)
		(width 0.127)
		(layer "In5.Cu")
		(net "BMC_I2C14_MINI8_SCL")
	)
	(segment
		(start 128.202436 3.79349)
		(end 105.549192 -18.859754)
		(width 0.127)
		(layer "In5.Cu")
		(net "BMC_I2C14_MINI8_SCL")
	)
	(segment
		(start 103.501444 -40.887142)
		(end 103.501444 -46.926754)
		(width 0.127)
		(layer "In5.Cu")
		(net "BMC_I2C14_MINI8_SCL")
	)
	(segment
		(start 49.0982 -102.940866)
		(end 48.8061 -103.232966)
		(width 0.127)
		(layer "In5.Cu")
		(net "BMC_I2C14_MINI8_SCL")
	)
	(segment
		(start 58.70956 -75.791314)
		(end 58.70956 -90.452956)
		(width 0.127)
		(layer "In5.Cu")
		(net "BMC_I2C14_MINI8_SCL")
	)
	(segment
		(start 266.5984 0.645414)
		(end 266.577826 0.665988)
		(width 0.127)
		(layer "In5.Cu")
		(net "BMC_I2C14_MINI8_SCL")
	)
	(segment
		(start 247.208802 2.108708)
		(end 245.52402 3.79349)
		(width 0.127)
		(layer "In5.Cu")
		(net "BMC_I2C14_MINI8_SCL")
	)
	(segment
		(start 105.549192 -18.859754)
		(end 105.549192 -38.238684)
		(width 0.127)
		(layer "In5.Cu")
		(net "BMC_I2C14_MINI8_SCL")
	)
	(segment
		(start 264.713974 0.665988)
		(end 264.6934 0.645414)
		(width 0.127)
		(layer "In5.Cu")
		(net "BMC_I2C14_MINI8_SCL")
	)
	(segment
		(start 62.288928 -72.211946)
		(end 58.70956 -75.791314)
		(width 0.127)
		(layer "In5.Cu")
		(net "BMC_I2C14_MINI8_SCL")
	)
	(segment
		(start 264.6934 0.645414)
		(end 259.271262 0.645414)
		(width 0.127)
		(layer "In5.Cu")
		(net "BMC_I2C14_MINI8_SCL")
	)
	(segment
		(start 245.52402 3.79349)
		(end 128.202436 3.79349)
		(width 0.127)
		(layer "In5.Cu")
		(net "BMC_I2C14_MINI8_SCL")
	)
	(segment
		(start 92.033598 -58.3946)
		(end 72.480932 -58.3946)
		(width 0.127)
		(layer "In5.Cu")
		(net "BMC_I2C14_MINI8_SCL")
	)
	(segment
		(start 259.271262 0.645414)
		(end 257.807968 2.108708)
		(width 0.127)
		(layer "In5.Cu")
		(net "BMC_I2C14_MINI8_SCL")
	)
	(segment
		(start 257.807968 2.108708)
		(end 247.208802 2.108708)
		(width 0.127)
		(layer "In5.Cu")
		(net "BMC_I2C14_MINI8_SCL")
	)
	(segment
		(start 105.549192 -38.238684)
		(end 103.50119 -40.286686)
		(width 0.127)
		(layer "In5.Cu")
		(net "BMC_I2C14_MINI8_SCL")
	)
	(segment
		(start 274.271486 -1.27)
		(end 275.14169 -1.27)
		(width 0.12065)
		(layer "F.Cu")
		(net "BMC_I2C13_MINI7_SDA")
	)
	(segment
		(start 54.175152 -112.25403)
		(end 55.233062 -112.25403)
		(width 0.12065)
		(layer "F.Cu")
		(net "BMC_I2C13_MINI7_SDA")
	)
	(segment
		(start 275.14169 -1.27)
		(end 276.1615 -1.27)
		(width 0.12065)
		(layer "F.Cu")
		(net "BMC_I2C13_MINI7_SDA")
	)
	(segment
		(start 54.695852 -111.445548)
		(end 54.175152 -111.966248)
		(width 0.12065)
		(layer "F.Cu")
		(net "BMC_I2C13_MINI7_SDA")
	)
	(segment
		(start 274.144486 -1.397)
		(end 274.271486 -1.27)
		(width 0.12065)
		(layer "F.Cu")
		(net "BMC_I2C13_MINI7_SDA")
	)
	(segment
		(start 54.695852 -110.84687)
		(end 54.695852 -111.445548)
		(width 0.12065)
		(layer "F.Cu")
		(net "BMC_I2C13_MINI7_SDA")
	)
	(segment
		(start 276.1615 -1.7653)
		(end 275.5392 -2.3876)
		(width 0.12065)
		(layer "F.Cu")
		(net "BMC_I2C13_MINI7_SDA")
	)
	(segment
		(start 54.175152 -111.966248)
		(end 54.175152 -112.25403)
		(width 0.12065)
		(layer "F.Cu")
		(net "BMC_I2C13_MINI7_SDA")
	)
	(segment
		(start 55.233062 -112.25403)
		(end 55.245 -112.265968)
		(width 0.12065)
		(layer "F.Cu")
		(net "BMC_I2C13_MINI7_SDA")
	)
	(segment
		(start 276.1615 -1.27)
		(end 276.1615 -1.7653)
		(width 0.12065)
		(layer "F.Cu")
		(net "BMC_I2C13_MINI7_SDA")
	)
	(via
		(at 55.245 -112.265968)
		(size 0.508)
		(drill 0.254)
		(layers "F.Cu" "B.Cu")
		(net "BMC_I2C13_MINI7_SDA")
	)
	(via
		(at 275.14169 -1.27)
		(size 0.7112)
		(drill 0.3556)
		(layers "F.Cu" "B.Cu")
		(net "BMC_I2C13_MINI7_SDA")
	)
	(via
		(at 275.5392 -2.3876)
		(size 0.508)
		(drill 0.254)
		(layers "F.Cu" "B.Cu")
		(net "BMC_I2C13_MINI7_SDA")
	)
	(segment
		(start 61.8236 -98.424746)
		(end 61.4426 -98.043746)
		(width 0.127)
		(layer "In5.Cu")
		(net "BMC_I2C13_MINI7_SDA")
	)
	(segment
		(start 275.178012 -2.907284)
		(end 275.178012 -2.774188)
		(width 0.127)
		(layer "In5.Cu")
		(net "BMC_I2C13_MINI7_SDA")
	)
	(segment
		(start 202.895454 -1.778)
		(end 205.774798 1.101344)
		(width 0.127)
		(layer "In5.Cu")
		(net "BMC_I2C13_MINI7_SDA")
	)
	(segment
		(start 75.870054 -61.6204)
		(end 92.666566 -61.6204)
		(width 0.127)
		(layer "In5.Cu")
		(net "BMC_I2C13_MINI7_SDA")
	)
	(segment
		(start 205.774798 1.101344)
		(end 244.303804 1.101344)
		(width 0.127)
		(layer "In5.Cu")
		(net "BMC_I2C13_MINI7_SDA")
	)
	(segment
		(start 251.589286 -2.643886)
		(end 253.17704 -4.23164)
		(width 0.127)
		(layer "In5.Cu")
		(net "BMC_I2C13_MINI7_SDA")
	)
	(segment
		(start 267.672566 -2.04978)
		(end 271.917414 -2.04978)
		(width 0.127)
		(layer "In5.Cu")
		(net "BMC_I2C13_MINI7_SDA")
	)
	(segment
		(start 259.673852 -4.904232)
		(end 261.036562 -3.541522)
		(width 0.127)
		(layer "In5.Cu")
		(net "BMC_I2C13_MINI7_SDA")
	)
	(segment
		(start 65.511426 -71.979028)
		(end 75.870054 -61.6204)
		(width 0.127)
		(layer "In5.Cu")
		(net "BMC_I2C13_MINI7_SDA")
	)
	(segment
		(start 179.500276 1.038352)
		(end 180.924962 -0.386334)
		(width 0.127)
		(layer "In5.Cu")
		(net "BMC_I2C13_MINI7_SDA")
	)
	(segment
		(start 55.0164 -111.66602)
		(end 56.49722 -110.1852)
		(width 0.127)
		(layer "In5.Cu")
		(net "BMC_I2C13_MINI7_SDA")
	)
	(segment
		(start 244.303804 1.101344)
		(end 248.049034 -2.643886)
		(width 0.127)
		(layer "In5.Cu")
		(net "BMC_I2C13_MINI7_SDA")
	)
	(segment
		(start 275.5392 -2.413)
		(end 275.5392 -2.3876)
		(width 0.127)
		(layer "In5.Cu")
		(net "BMC_I2C13_MINI7_SDA")
	)
	(segment
		(start 261.036562 -3.541522)
		(end 261.036562 -3.271266)
		(width 0.127)
		(layer "In5.Cu")
		(net "BMC_I2C13_MINI7_SDA")
	)
	(segment
		(start 248.049034 -2.643886)
		(end 251.589286 -2.643886)
		(width 0.127)
		(layer "In5.Cu")
		(net "BMC_I2C13_MINI7_SDA")
	)
	(segment
		(start 61.8236 -105.993184)
		(end 61.8236 -98.424746)
		(width 0.127)
		(layer "In5.Cu")
		(net "BMC_I2C13_MINI7_SDA")
	)
	(segment
		(start 61.4426 -77.583284)
		(end 65.511426 -73.514458)
		(width 0.127)
		(layer "In5.Cu")
		(net "BMC_I2C13_MINI7_SDA")
	)
	(segment
		(start 257.335528 -4.904232)
		(end 259.673852 -4.904232)
		(width 0.127)
		(layer "In5.Cu")
		(net "BMC_I2C13_MINI7_SDA")
	)
	(segment
		(start 61.4426 -98.043746)
		(end 61.4426 -77.583284)
		(width 0.127)
		(layer "In5.Cu")
		(net "BMC_I2C13_MINI7_SDA")
	)
	(segment
		(start 253.17704 -4.23164)
		(end 256.662936 -4.23164)
		(width 0.127)
		(layer "In5.Cu")
		(net "BMC_I2C13_MINI7_SDA")
	)
	(segment
		(start 273.423634 -3.556)
		(end 274.529296 -3.556)
		(width 0.127)
		(layer "In5.Cu")
		(net "BMC_I2C13_MINI7_SDA")
	)
	(segment
		(start 65.511426 -73.514458)
		(end 65.511426 -71.979028)
		(width 0.127)
		(layer "In5.Cu")
		(net "BMC_I2C13_MINI7_SDA")
	)
	(segment
		(start 274.529296 -3.556)
		(end 275.178012 -2.907284)
		(width 0.127)
		(layer "In5.Cu")
		(net "BMC_I2C13_MINI7_SDA")
	)
	(segment
		(start 197.5866 -1.778)
		(end 202.895454 -1.778)
		(width 0.127)
		(layer "In5.Cu")
		(net "BMC_I2C13_MINI7_SDA")
	)
	(segment
		(start 129.21996 1.038352)
		(end 179.500276 1.038352)
		(width 0.127)
		(layer "In5.Cu")
		(net "BMC_I2C13_MINI7_SDA")
	)
	(segment
		(start 271.917414 -2.04978)
		(end 273.423634 -3.556)
		(width 0.127)
		(layer "In5.Cu")
		(net "BMC_I2C13_MINI7_SDA")
	)
	(segment
		(start 261.036562 -3.271266)
		(end 261.623302 -2.684526)
		(width 0.127)
		(layer "In5.Cu")
		(net "BMC_I2C13_MINI7_SDA")
	)
	(segment
		(start 106.628184 -47.658782)
		(end 106.628184 -40.932354)
		(width 0.127)
		(layer "In5.Cu")
		(net "BMC_I2C13_MINI7_SDA")
	)
	(segment
		(start 275.178012 -2.774188)
		(end 275.5392 -2.413)
		(width 0.127)
		(layer "In5.Cu")
		(net "BMC_I2C13_MINI7_SDA")
	)
	(segment
		(start 256.662936 -4.23164)
		(end 257.335528 -4.904232)
		(width 0.127)
		(layer "In5.Cu")
		(net "BMC_I2C13_MINI7_SDA")
	)
	(segment
		(start 56.49722 -110.1852)
		(end 57.631584 -110.1852)
		(width 0.127)
		(layer "In5.Cu")
		(net "BMC_I2C13_MINI7_SDA")
	)
	(segment
		(start 55.245 -112.265968)
		(end 55.0164 -112.037368)
		(width 0.127)
		(layer "In5.Cu")
		(net "BMC_I2C13_MINI7_SDA")
	)
	(segment
		(start 92.666566 -61.6204)
		(end 106.628184 -47.658782)
		(width 0.127)
		(layer "In5.Cu")
		(net "BMC_I2C13_MINI7_SDA")
	)
	(segment
		(start 196.194934 -0.386334)
		(end 197.5866 -1.778)
		(width 0.127)
		(layer "In5.Cu")
		(net "BMC_I2C13_MINI7_SDA")
	)
	(segment
		(start 55.0164 -112.037368)
		(end 55.0164 -111.66602)
		(width 0.127)
		(layer "In5.Cu")
		(net "BMC_I2C13_MINI7_SDA")
	)
	(segment
		(start 108.536232 -19.645376)
		(end 129.21996 1.038352)
		(width 0.127)
		(layer "In5.Cu")
		(net "BMC_I2C13_MINI7_SDA")
	)
	(segment
		(start 106.628184 -40.932354)
		(end 108.536232 -39.024306)
		(width 0.127)
		(layer "In5.Cu")
		(net "BMC_I2C13_MINI7_SDA")
	)
	(segment
		(start 57.631584 -110.1852)
		(end 61.8236 -105.993184)
		(width 0.127)
		(layer "In5.Cu")
		(net "BMC_I2C13_MINI7_SDA")
	)
	(segment
		(start 267.03782 -2.684526)
		(end 267.672566 -2.04978)
		(width 0.127)
		(layer "In5.Cu")
		(net "BMC_I2C13_MINI7_SDA")
	)
	(segment
		(start 261.623302 -2.684526)
		(end 267.03782 -2.684526)
		(width 0.127)
		(layer "In5.Cu")
		(net "BMC_I2C13_MINI7_SDA")
	)
	(segment
		(start 180.924962 -0.386334)
		(end 196.194934 -0.386334)
		(width 0.127)
		(layer "In5.Cu")
		(net "BMC_I2C13_MINI7_SDA")
	)
	(segment
		(start 108.536232 -39.024306)
		(end 108.536232 -19.645376)
		(width 0.127)
		(layer "In5.Cu")
		(net "BMC_I2C13_MINI7_SDA")
	)
	(segment
		(start 52.222654 -108.952792)
		(end 52.222654 -108.257848)
		(width 0.12065)
		(layer "F.Cu")
		(net "BMC_I2C13_MINI7_SCL")
	)
	(segment
		(start 52.225194 -108.004102)
		(end 52.345844 -107.883452)
		(width 0.12065)
		(layer "F.Cu")
		(net "BMC_I2C13_MINI7_SCL")
	)
	(segment
		(start 274.5486 -2.413)
		(end 274.490688 -2.413)
		(width 0.12065)
		(layer "F.Cu")
		(net "BMC_I2C13_MINI7_SCL")
	)
	(segment
		(start 52.225194 -108.255308)
		(end 52.225194 -108.004102)
		(width 0.12065)
		(layer "F.Cu")
		(net "BMC_I2C13_MINI7_SCL")
	)
	(segment
		(start 306.279042 -14.483842)
		(end 306.279042 -9.61517)
		(width 0.12065)
		(layer "F.Cu")
		(net "BMC_I2C13_MINI7_SCL")
	)
	(segment
		(start 53.673502 -109.350302)
		(end 53.673502 -111.258604)
		(width 0.12065)
		(layer "F.Cu")
		(net "BMC_I2C13_MINI7_SCL")
	)
	(segment
		(start 53.381148 -108.158026)
		(end 53.381148 -109.057948)
		(width 0.12065)
		(layer "F.Cu")
		(net "BMC_I2C13_MINI7_SCL")
	)
	(segment
		(start 306.279042 -9.61517)
		(end 299.809916 -3.146044)
		(width 0.12065)
		(layer "F.Cu")
		(net "BMC_I2C13_MINI7_SCL")
	)
	(segment
		(start 278.487124 -3.146044)
		(end 278.255984 -2.914904)
		(width 0.12065)
		(layer "F.Cu")
		(net "BMC_I2C13_MINI7_SCL")
	)
	(segment
		(start 52.816252 -109.54639)
		(end 52.222654 -108.952792)
		(width 0.12065)
		(layer "F.Cu")
		(net "BMC_I2C13_MINI7_SCL")
	)
	(segment
		(start 52.222654 -108.257848)
		(end 52.225194 -108.255308)
		(width 0.12065)
		(layer "F.Cu")
		(net "BMC_I2C13_MINI7_SCL")
	)
	(segment
		(start 52.345844 -107.883452)
		(end 53.106574 -107.883452)
		(width 0.12065)
		(layer "F.Cu")
		(net "BMC_I2C13_MINI7_SCL")
	)
	(segment
		(start 53.106574 -107.883452)
		(end 53.336952 -108.11383)
		(width 0.12065)
		(layer "F.Cu")
		(net "BMC_I2C13_MINI7_SCL")
	)
	(segment
		(start 306.959 -15.1638)
		(end 306.279042 -14.483842)
		(width 0.12065)
		(layer "F.Cu")
		(net "BMC_I2C13_MINI7_SCL")
	)
	(segment
		(start 308.134512 -19.717512)
		(end 306.959 -18.542)
		(width 0.12065)
		(layer "F.Cu")
		(net "BMC_I2C13_MINI7_SCL")
	)
	(segment
		(start 275.050504 -2.914904)
		(end 274.5486 -2.413)
		(width 0.12065)
		(layer "F.Cu")
		(net "BMC_I2C13_MINI7_SCL")
	)
	(segment
		(start 53.381148 -109.057948)
		(end 53.673502 -109.350302)
		(width 0.12065)
		(layer "F.Cu")
		(net "BMC_I2C13_MINI7_SCL")
	)
	(segment
		(start 53.336952 -108.11383)
		(end 53.381148 -108.158026)
		(width 0.12065)
		(layer "F.Cu")
		(net "BMC_I2C13_MINI7_SCL")
	)
	(segment
		(start 278.255984 -2.914904)
		(end 275.050504 -2.914904)
		(width 0.12065)
		(layer "F.Cu")
		(net "BMC_I2C13_MINI7_SCL")
	)
	(segment
		(start 53.673502 -111.258604)
		(end 53.848 -111.433102)
		(width 0.12065)
		(layer "F.Cu")
		(net "BMC_I2C13_MINI7_SCL")
	)
	(segment
		(start 299.809916 -3.146044)
		(end 278.487124 -3.146044)
		(width 0.12065)
		(layer "F.Cu")
		(net "BMC_I2C13_MINI7_SCL")
	)
	(segment
		(start 308.134512 -21.530056)
		(end 308.134512 -19.717512)
		(width 0.12065)
		(layer "F.Cu")
		(net "BMC_I2C13_MINI7_SCL")
	)
	(segment
		(start 306.959 -18.542)
		(end 306.959 -15.1638)
		(width 0.12065)
		(layer "F.Cu")
		(net "BMC_I2C13_MINI7_SCL")
	)
	(via
		(at 53.848 -111.433102)
		(size 0.508)
		(drill 0.254)
		(layers "F.Cu" "B.Cu")
		(net "BMC_I2C13_MINI7_SCL")
	)
	(via
		(at 274.490688 -2.413)
		(size 0.508)
		(drill 0.254)
		(layers "F.Cu" "B.Cu")
		(net "BMC_I2C13_MINI7_SCL")
	)
	(via
		(at 52.222654 -108.257848)
		(size 0.7112)
		(drill 0.3556)
		(layers "F.Cu" "B.Cu")
		(net "BMC_I2C13_MINI7_SCL")
	)
	(segment
		(start 244.51437 1.609344)
		(end 248.2596 -2.135886)
		(width 0.127)
		(layer "In5.Cu")
		(net "BMC_I2C13_MINI7_SCL")
	)
	(segment
		(start 267.462 -1.54178)
		(end 272.12798 -1.54178)
		(width 0.127)
		(layer "In5.Cu")
		(net "BMC_I2C13_MINI7_SCL")
	)
	(segment
		(start 256.873502 -3.72364)
		(end 257.546094 -4.396232)
		(width 0.127)
		(layer "In5.Cu")
		(net "BMC_I2C13_MINI7_SCL")
	)
	(segment
		(start 257.546094 -4.396232)
		(end 259.463286 -4.396232)
		(width 0.127)
		(layer "In5.Cu")
		(net "BMC_I2C13_MINI7_SCL")
	)
	(segment
		(start 60.9346 -98.254312)
		(end 60.9346 -77.372718)
		(width 0.127)
		(layer "In5.Cu")
		(net "BMC_I2C13_MINI7_SCL")
	)
	(segment
		(start 274.521168 -2.845562)
		(end 274.521168 -2.44348)
		(width 0.127)
		(layer "In5.Cu")
		(net "BMC_I2C13_MINI7_SCL")
	)
	(segment
		(start 272.12798 -1.54178)
		(end 273.6342 -3.048)
		(width 0.127)
		(layer "In5.Cu")
		(net "BMC_I2C13_MINI7_SCL")
	)
	(segment
		(start 106.120184 -47.448216)
		(end 106.120184 -40.721788)
		(width 0.127)
		(layer "In5.Cu")
		(net "BMC_I2C13_MINI7_SCL")
	)
	(segment
		(start 129.009394 1.546352)
		(end 179.710842 1.546352)
		(width 0.127)
		(layer "In5.Cu")
		(net "BMC_I2C13_MINI7_SCL")
	)
	(segment
		(start 57.421018 -109.6772)
		(end 61.3156 -105.782618)
		(width 0.127)
		(layer "In5.Cu")
		(net "BMC_I2C13_MINI7_SCL")
	)
	(segment
		(start 251.799852 -2.135886)
		(end 253.387606 -3.72364)
		(width 0.127)
		(layer "In5.Cu")
		(net "BMC_I2C13_MINI7_SCL")
	)
	(segment
		(start 197.797166 -1.27)
		(end 202.684888 -1.27)
		(width 0.127)
		(layer "In5.Cu")
		(net "BMC_I2C13_MINI7_SCL")
	)
	(segment
		(start 181.135528 0.121666)
		(end 196.4055 0.121666)
		(width 0.127)
		(layer "In5.Cu")
		(net "BMC_I2C13_MINI7_SCL")
	)
	(segment
		(start 253.387606 -3.72364)
		(end 256.873502 -3.72364)
		(width 0.127)
		(layer "In5.Cu")
		(net "BMC_I2C13_MINI7_SCL")
	)
	(segment
		(start 61.3156 -105.782618)
		(end 61.3156 -98.635312)
		(width 0.127)
		(layer "In5.Cu")
		(net "BMC_I2C13_MINI7_SCL")
	)
	(segment
		(start 56.286654 -109.6772)
		(end 57.421018 -109.6772)
		(width 0.127)
		(layer "In5.Cu")
		(net "BMC_I2C13_MINI7_SCL")
	)
	(segment
		(start 54.530752 -111.433102)
		(end 56.286654 -109.6772)
		(width 0.127)
		(layer "In5.Cu")
		(net "BMC_I2C13_MINI7_SCL")
	)
	(segment
		(start 261.412736 -2.176526)
		(end 266.827254 -2.176526)
		(width 0.127)
		(layer "In5.Cu")
		(net "BMC_I2C13_MINI7_SCL")
	)
	(segment
		(start 108.028232 -19.43481)
		(end 129.009394 1.546352)
		(width 0.127)
		(layer "In5.Cu")
		(net "BMC_I2C13_MINI7_SCL")
	)
	(segment
		(start 108.028232 -38.81374)
		(end 108.028232 -19.43481)
		(width 0.127)
		(layer "In5.Cu")
		(net "BMC_I2C13_MINI7_SCL")
	)
	(segment
		(start 202.684888 -1.27)
		(end 205.564232 1.609344)
		(width 0.127)
		(layer "In5.Cu")
		(net "BMC_I2C13_MINI7_SCL")
	)
	(segment
		(start 248.2596 -2.135886)
		(end 251.799852 -2.135886)
		(width 0.127)
		(layer "In5.Cu")
		(net "BMC_I2C13_MINI7_SCL")
	)
	(segment
		(start 75.659488 -61.1124)
		(end 92.456 -61.1124)
		(width 0.127)
		(layer "In5.Cu")
		(net "BMC_I2C13_MINI7_SCL")
	)
	(segment
		(start 259.463286 -4.396232)
		(end 260.528562 -3.330956)
		(width 0.127)
		(layer "In5.Cu")
		(net "BMC_I2C13_MINI7_SCL")
	)
	(segment
		(start 273.6342 -3.048)
		(end 274.31873 -3.048)
		(width 0.127)
		(layer "In5.Cu")
		(net "BMC_I2C13_MINI7_SCL")
	)
	(segment
		(start 53.848 -111.433102)
		(end 54.530752 -111.433102)
		(width 0.127)
		(layer "In5.Cu")
		(net "BMC_I2C13_MINI7_SCL")
	)
	(segment
		(start 196.4055 0.121666)
		(end 197.797166 -1.27)
		(width 0.127)
		(layer "In5.Cu")
		(net "BMC_I2C13_MINI7_SCL")
	)
	(segment
		(start 260.528562 -3.330956)
		(end 260.528562 -3.0607)
		(width 0.127)
		(layer "In5.Cu")
		(net "BMC_I2C13_MINI7_SCL")
	)
	(segment
		(start 274.521168 -2.44348)
		(end 274.490688 -2.413)
		(width 0.127)
		(layer "In5.Cu")
		(net "BMC_I2C13_MINI7_SCL")
	)
	(segment
		(start 274.31873 -3.048)
		(end 274.521168 -2.845562)
		(width 0.127)
		(layer "In5.Cu")
		(net "BMC_I2C13_MINI7_SCL")
	)
	(segment
		(start 106.120184 -40.721788)
		(end 108.028232 -38.81374)
		(width 0.127)
		(layer "In5.Cu")
		(net "BMC_I2C13_MINI7_SCL")
	)
	(segment
		(start 60.9346 -77.372718)
		(end 65.003426 -73.303892)
		(width 0.127)
		(layer "In5.Cu")
		(net "BMC_I2C13_MINI7_SCL")
	)
	(segment
		(start 65.003426 -71.768462)
		(end 75.659488 -61.1124)
		(width 0.127)
		(layer "In5.Cu")
		(net "BMC_I2C13_MINI7_SCL")
	)
	(segment
		(start 61.3156 -98.635312)
		(end 60.9346 -98.254312)
		(width 0.127)
		(layer "In5.Cu")
		(net "BMC_I2C13_MINI7_SCL")
	)
	(segment
		(start 266.827254 -2.176526)
		(end 267.462 -1.54178)
		(width 0.127)
		(layer "In5.Cu")
		(net "BMC_I2C13_MINI7_SCL")
	)
	(segment
		(start 179.710842 1.546352)
		(end 181.135528 0.121666)
		(width 0.127)
		(layer "In5.Cu")
		(net "BMC_I2C13_MINI7_SCL")
	)
	(segment
		(start 260.528562 -3.0607)
		(end 261.412736 -2.176526)
		(width 0.127)
		(layer "In5.Cu")
		(net "BMC_I2C13_MINI7_SCL")
	)
	(segment
		(start 92.456 -61.1124)
		(end 106.120184 -47.448216)
		(width 0.127)
		(layer "In5.Cu")
		(net "BMC_I2C13_MINI7_SCL")
	)
	(segment
		(start 205.564232 1.609344)
		(end 244.51437 1.609344)
		(width 0.127)
		(layer "In5.Cu")
		(net "BMC_I2C13_MINI7_SCL")
	)
	(segment
		(start 65.003426 -73.303892)
		(end 65.003426 -71.768462)
		(width 0.127)
		(layer "In5.Cu")
		(net "BMC_I2C13_MINI7_SCL")
	)
	(segment
		(start 275.385022 -6.943852)
		(end 274.245578 -6.943852)
		(width 0.12065)
		(layer "F.Cu")
		(net "BMC_I2C12_MINI6_SDA")
	)
	(segment
		(start 276.06498 -6.96976)
		(end 275.41093 -6.96976)
		(width 0.12065)
		(layer "F.Cu")
		(net "BMC_I2C12_MINI6_SDA")
	)
	(segment
		(start 274.245578 -6.943852)
		(end 274.147026 -6.8453)
		(width 0.12065)
		(layer "F.Cu")
		(net "BMC_I2C12_MINI6_SDA")
	)
	(segment
		(start 276.807168 -7.711948)
		(end 276.06498 -6.96976)
		(width 0.12065)
		(layer "F.Cu")
		(net "BMC_I2C12_MINI6_SDA")
	)
	(segment
		(start 275.41093 -6.96976)
		(end 275.385022 -6.943852)
		(width 0.12065)
		(layer "F.Cu")
		(net "BMC_I2C12_MINI6_SDA")
	)
	(segment
		(start 277.391876 -7.711948)
		(end 276.807168 -7.711948)
		(width 0.12065)
		(layer "F.Cu")
		(net "BMC_I2C12_MINI6_SDA")
	)
	(via
		(at 276.02561 -7.032244)
		(size 0.7112)
		(drill 0.3556)
		(layers "F.Cu" "B.Cu")
		(net "BMC_I2C12_MINI6_SDA")
	)
	(via
		(at 277.391876 -7.711948)
		(size 0.508)
		(drill 0.254)
		(layers "F.Cu" "B.Cu")
		(net "BMC_I2C12_MINI6_SDA")
	)
	(via
		(at 53.8988 -108.9152)
		(size 0.508)
		(drill 0.254)
		(layers "F.Cu" "B.Cu")
		(net "BMC_I2C12_MINI6_SDA")
	)
	(segment
		(start 53.866796 -108.947204)
		(end 53.852826 -108.947204)
		(width 0.12065)
		(layer "B.Cu")
		(net "BMC_I2C12_MINI6_SDA")
	)
	(segment
		(start 53.37048 -111.401098)
		(end 52.816252 -110.84687)
		(width 0.12065)
		(layer "B.Cu")
		(net "BMC_I2C12_MINI6_SDA")
	)
	(segment
		(start 276.859746 -7.711948)
		(end 277.391876 -7.711948)
		(width 0.12065)
		(layer "B.Cu")
		(net "BMC_I2C12_MINI6_SDA")
	)
	(segment
		(start 53.565552 -111.985298)
		(end 53.36921 -111.788956)
		(width 0.12065)
		(layer "B.Cu")
		(net "BMC_I2C12_MINI6_SDA")
	)
	(segment
		(start 53.36921 -111.402368)
		(end 53.37048 -111.401098)
		(width 0.12065)
		(layer "B.Cu")
		(net "BMC_I2C12_MINI6_SDA")
	)
	(segment
		(start 53.594 -110.617)
		(end 53.36413 -110.84687)
		(width 0.12065)
		(layer "B.Cu")
		(net "BMC_I2C12_MINI6_SDA")
	)
	(segment
		(start 53.852826 -108.947204)
		(end 53.594 -109.20603)
		(width 0.12065)
		(layer "B.Cu")
		(net "BMC_I2C12_MINI6_SDA")
	)
	(segment
		(start 53.36921 -111.788956)
		(end 53.36921 -111.402368)
		(width 0.12065)
		(layer "B.Cu")
		(net "BMC_I2C12_MINI6_SDA")
	)
	(segment
		(start 276.02561 -7.032244)
		(end 276.180042 -7.032244)
		(width 0.12065)
		(layer "B.Cu")
		(net "BMC_I2C12_MINI6_SDA")
	)
	(segment
		(start 53.594 -109.20603)
		(end 53.594 -110.617)
		(width 0.12065)
		(layer "B.Cu")
		(net "BMC_I2C12_MINI6_SDA")
	)
	(segment
		(start 53.36413 -110.84687)
		(end 52.816252 -110.84687)
		(width 0.12065)
		(layer "B.Cu")
		(net "BMC_I2C12_MINI6_SDA")
	)
	(segment
		(start 53.565552 -112.22863)
		(end 53.565552 -111.985298)
		(width 0.12065)
		(layer "B.Cu")
		(net "BMC_I2C12_MINI6_SDA")
	)
	(segment
		(start 276.180042 -7.032244)
		(end 276.859746 -7.711948)
		(width 0.12065)
		(layer "B.Cu")
		(net "BMC_I2C12_MINI6_SDA")
	)
	(segment
		(start 53.8988 -108.9152)
		(end 53.866796 -108.947204)
		(width 0.12065)
		(layer "B.Cu")
		(net "BMC_I2C12_MINI6_SDA")
	)
	(segment
		(start 252.828044 0.771652)
		(end 255.902206 -2.30251)
		(width 0.127)
		(layer "In5.Cu")
		(net "BMC_I2C12_MINI6_SDA")
	)
	(segment
		(start 276.5552 -1.6764)
		(end 276.5552 -6.875272)
		(width 0.127)
		(layer "In5.Cu")
		(net "BMC_I2C12_MINI6_SDA")
	)
	(segment
		(start 266.051284 -0.604012)
		(end 266.094972 -0.6477)
		(width 0.127)
		(layer "In5.Cu")
		(net "BMC_I2C12_MINI6_SDA")
	)
	(segment
		(start 54.253892 -108.560108)
		(end 54.253892 -108.101638)
		(width 0.127)
		(layer "In5.Cu")
		(net "BMC_I2C12_MINI6_SDA")
	)
	(segment
		(start 258.23164 -2.30251)
		(end 259.88645 -0.6477)
		(width 0.127)
		(layer "In5.Cu")
		(net "BMC_I2C12_MINI6_SDA")
	)
	(segment
		(start 128.707388 2.5019)
		(end 183.208676 2.5019)
		(width 0.127)
		(layer "In5.Cu")
		(net "BMC_I2C12_MINI6_SDA")
	)
	(segment
		(start 190.983108 1.038098)
		(end 192.20561 2.2606)
		(width 0.127)
		(layer "In5.Cu")
		(net "BMC_I2C12_MINI6_SDA")
	)
	(segment
		(start 255.902206 -2.30251)
		(end 258.23164 -2.30251)
		(width 0.127)
		(layer "In5.Cu")
		(net "BMC_I2C12_MINI6_SDA")
	)
	(segment
		(start 53.8988 -108.9152)
		(end 54.253892 -108.560108)
		(width 0.127)
		(layer "In5.Cu")
		(net "BMC_I2C12_MINI6_SDA")
	)
	(segment
		(start 72.773286 -59.3598)
		(end 92.728034 -59.3598)
		(width 0.127)
		(layer "In5.Cu")
		(net "BMC_I2C12_MINI6_SDA")
	)
	(segment
		(start 59.6646 -102.69093)
		(end 59.6646 -76.558394)
		(width 0.127)
		(layer "In5.Cu")
		(net "BMC_I2C12_MINI6_SDA")
	)
	(segment
		(start 63.273686 -72.949308)
		(end 63.273686 -68.8594)
		(width 0.127)
		(layer "In5.Cu")
		(net "BMC_I2C12_MINI6_SDA")
	)
	(segment
		(start 259.88645 -0.6477)
		(end 265.196828 -0.6477)
		(width 0.127)
		(layer "In5.Cu")
		(net "BMC_I2C12_MINI6_SDA")
	)
	(segment
		(start 265.196828 -0.6477)
		(end 265.240516 -0.604012)
		(width 0.127)
		(layer "In5.Cu")
		(net "BMC_I2C12_MINI6_SDA")
	)
	(segment
		(start 246.68861 0.771652)
		(end 252.828044 0.771652)
		(width 0.127)
		(layer "In5.Cu")
		(net "BMC_I2C12_MINI6_SDA")
	)
	(segment
		(start 106.874818 -38.7096)
		(end 106.874818 -19.33067)
		(width 0.127)
		(layer "In5.Cu")
		(net "BMC_I2C12_MINI6_SDA")
	)
	(segment
		(start 59.6646 -76.558394)
		(end 63.273686 -72.949308)
		(width 0.127)
		(layer "In5.Cu")
		(net "BMC_I2C12_MINI6_SDA")
	)
	(segment
		(start 192.20561 2.2606)
		(end 200.8886 2.2606)
		(width 0.127)
		(layer "In5.Cu")
		(net "BMC_I2C12_MINI6_SDA")
	)
	(segment
		(start 266.094972 -0.6477)
		(end 275.5265 -0.6477)
		(width 0.127)
		(layer "In5.Cu")
		(net "BMC_I2C12_MINI6_SDA")
	)
	(segment
		(start 276.5552 -6.875272)
		(end 277.391876 -7.711948)
		(width 0.127)
		(layer "In5.Cu")
		(net "BMC_I2C12_MINI6_SDA")
	)
	(segment
		(start 203.5683 1.010666)
		(end 205.081124 2.52349)
		(width 0.127)
		(layer "In5.Cu")
		(net "BMC_I2C12_MINI6_SDA")
	)
	(segment
		(start 275.5265 -0.6477)
		(end 276.5552 -1.6764)
		(width 0.127)
		(layer "In5.Cu")
		(net "BMC_I2C12_MINI6_SDA")
	)
	(segment
		(start 184.672478 1.038098)
		(end 190.983108 1.038098)
		(width 0.127)
		(layer "In5.Cu")
		(net "BMC_I2C12_MINI6_SDA")
	)
	(segment
		(start 105.1306 -40.453818)
		(end 106.874818 -38.7096)
		(width 0.127)
		(layer "In5.Cu")
		(net "BMC_I2C12_MINI6_SDA")
	)
	(segment
		(start 54.253892 -108.101638)
		(end 59.6646 -102.69093)
		(width 0.127)
		(layer "In5.Cu")
		(net "BMC_I2C12_MINI6_SDA")
	)
	(segment
		(start 183.208676 2.5019)
		(end 184.672478 1.038098)
		(width 0.127)
		(layer "In5.Cu")
		(net "BMC_I2C12_MINI6_SDA")
	)
	(segment
		(start 244.936772 2.52349)
		(end 246.68861 0.771652)
		(width 0.127)
		(layer "In5.Cu")
		(net "BMC_I2C12_MINI6_SDA")
	)
	(segment
		(start 205.081124 2.52349)
		(end 244.936772 2.52349)
		(width 0.127)
		(layer "In5.Cu")
		(net "BMC_I2C12_MINI6_SDA")
	)
	(segment
		(start 63.273686 -68.8594)
		(end 72.773286 -59.3598)
		(width 0.127)
		(layer "In5.Cu")
		(net "BMC_I2C12_MINI6_SDA")
	)
	(segment
		(start 106.874818 -19.33067)
		(end 128.707388 2.5019)
		(width 0.127)
		(layer "In5.Cu")
		(net "BMC_I2C12_MINI6_SDA")
	)
	(segment
		(start 202.138534 1.010666)
		(end 203.5683 1.010666)
		(width 0.127)
		(layer "In5.Cu")
		(net "BMC_I2C12_MINI6_SDA")
	)
	(segment
		(start 92.728034 -59.3598)
		(end 105.1306 -46.957234)
		(width 0.127)
		(layer "In5.Cu")
		(net "BMC_I2C12_MINI6_SDA")
	)
	(segment
		(start 265.240516 -0.604012)
		(end 266.051284 -0.604012)
		(width 0.127)
		(layer "In5.Cu")
		(net "BMC_I2C12_MINI6_SDA")
	)
	(segment
		(start 105.1306 -46.957234)
		(end 105.1306 -40.453818)
		(width 0.127)
		(layer "In5.Cu")
		(net "BMC_I2C12_MINI6_SDA")
	)
	(segment
		(start 200.8886 2.2606)
		(end 202.138534 1.010666)
		(width 0.127)
		(layer "In5.Cu")
		(net "BMC_I2C12_MINI6_SDA")
	)
	(segment
		(start 275.470112 -8.639048)
		(end 275.033232 -8.202168)
		(width 0.12065)
		(layer "F.Cu")
		(net "BMC_I2C12_MINI6_SCL")
	)
	(segment
		(start 292.053772 -6.1087)
		(end 283.106114 -6.1087)
		(width 0.12065)
		(layer "F.Cu")
		(net "BMC_I2C12_MINI6_SCL")
	)
	(segment
		(start 293.2049 -7.259828)
		(end 292.053772 -6.1087)
		(width 0.12065)
		(layer "F.Cu")
		(net "BMC_I2C12_MINI6_SCL")
	)
	(segment
		(start 283.106114 -6.1087)
		(end 280.575766 -8.639048)
		(width 0.12065)
		(layer "F.Cu")
		(net "BMC_I2C12_MINI6_SCL")
	)
	(segment
		(start 280.575766 -8.639048)
		(end 275.470112 -8.639048)
		(width 0.12065)
		(layer "F.Cu")
		(net "BMC_I2C12_MINI6_SCL")
	)
	(segment
		(start 275.033232 -8.202168)
		(end 275.033232 -7.772654)
		(width 0.12065)
		(layer "F.Cu")
		(net "BMC_I2C12_MINI6_SCL")
	)
	(segment
		(start 293.2049 -14.5923)
		(end 293.2049 -7.259828)
		(width 0.12065)
		(layer "F.Cu")
		(net "BMC_I2C12_MINI6_SCL")
	)
	(segment
		(start 297.13428 -18.52168)
		(end 293.2049 -14.5923)
		(width 0.12065)
		(layer "F.Cu")
		(net "BMC_I2C12_MINI6_SCL")
	)
	(segment
		(start 297.13428 -21.530056)
		(end 297.13428 -18.52168)
		(width 0.12065)
		(layer "F.Cu")
		(net "BMC_I2C12_MINI6_SCL")
	)
	(via
		(at 55.16626 -108.83519)
		(size 0.508)
		(drill 0.254)
		(layers "F.Cu" "B.Cu")
		(net "BMC_I2C12_MINI6_SCL")
	)
	(via
		(at 54.581552 -108.06303)
		(size 0.7112)
		(drill 0.3556)
		(layers "F.Cu" "B.Cu")
		(net "BMC_I2C12_MINI6_SCL")
	)
	(via
		(at 275.033232 -7.772654)
		(size 0.508)
		(drill 0.254)
		(layers "F.Cu" "B.Cu")
		(net "BMC_I2C12_MINI6_SCL")
	)
	(segment
		(start 54.581552 -108.06303)
		(end 53.667152 -108.06303)
		(width 0.12065)
		(layer "B.Cu")
		(net "BMC_I2C12_MINI6_SCL")
	)
	(segment
		(start 55.16626 -108.83519)
		(end 54.695852 -109.305598)
		(width 0.12065)
		(layer "B.Cu")
		(net "BMC_I2C12_MINI6_SCL")
	)
	(segment
		(start 55.038752 -108.06303)
		(end 54.581552 -108.06303)
		(width 0.12065)
		(layer "B.Cu")
		(net "BMC_I2C12_MINI6_SCL")
	)
	(segment
		(start 55.16626 -108.83519)
		(end 55.16626 -108.190538)
		(width 0.12065)
		(layer "B.Cu")
		(net "BMC_I2C12_MINI6_SCL")
	)
	(segment
		(start 55.16626 -108.190538)
		(end 55.038752 -108.06303)
		(width 0.12065)
		(layer "B.Cu")
		(net "BMC_I2C12_MINI6_SCL")
	)
	(segment
		(start 54.695852 -109.305598)
		(end 54.695852 -109.54639)
		(width 0.12065)
		(layer "B.Cu")
		(net "BMC_I2C12_MINI6_SCL")
	)
	(segment
		(start 275.360384 -7.772654)
		(end 275.033232 -7.772654)
		(width 0.127)
		(layer "In5.Cu")
		(net "BMC_I2C12_MINI6_SCL")
	)
	(segment
		(start 184.461912 0.530098)
		(end 191.193674 0.530098)
		(width 0.127)
		(layer "In5.Cu")
		(net "BMC_I2C12_MINI6_SCL")
	)
	(segment
		(start 244.726206 2.01549)
		(end 246.478044 0.263652)
		(width 0.127)
		(layer "In5.Cu")
		(net "BMC_I2C12_MINI6_SCL")
	)
	(segment
		(start 265.451082 -1.112012)
		(end 265.840718 -1.112012)
		(width 0.127)
		(layer "In5.Cu")
		(net "BMC_I2C12_MINI6_SCL")
	)
	(segment
		(start 191.193674 0.530098)
		(end 192.416176 1.7526)
		(width 0.127)
		(layer "In5.Cu")
		(net "BMC_I2C12_MINI6_SCL")
	)
	(segment
		(start 72.983852 -59.8678)
		(end 92.9386 -59.8678)
		(width 0.127)
		(layer "In5.Cu")
		(net "BMC_I2C12_MINI6_SCL")
	)
	(segment
		(start 252.617478 0.263652)
		(end 255.69164 -2.81051)
		(width 0.127)
		(layer "In5.Cu")
		(net "BMC_I2C12_MINI6_SCL")
	)
	(segment
		(start 255.69164 -2.81051)
		(end 258.442206 -2.81051)
		(width 0.127)
		(layer "In5.Cu")
		(net "BMC_I2C12_MINI6_SCL")
	)
	(segment
		(start 260.097016 -1.1557)
		(end 265.407394 -1.1557)
		(width 0.127)
		(layer "In5.Cu")
		(net "BMC_I2C12_MINI6_SCL")
	)
	(segment
		(start 182.99811 1.9939)
		(end 184.461912 0.530098)
		(width 0.127)
		(layer "In5.Cu")
		(net "BMC_I2C12_MINI6_SCL")
	)
	(segment
		(start 92.9386 -59.8678)
		(end 105.6386 -47.1678)
		(width 0.127)
		(layer "In5.Cu")
		(net "BMC_I2C12_MINI6_SCL")
	)
	(segment
		(start 107.382818 -38.920166)
		(end 107.382818 -19.541236)
		(width 0.127)
		(layer "In5.Cu")
		(net "BMC_I2C12_MINI6_SCL")
	)
	(segment
		(start 200.678034 1.7526)
		(end 201.927968 0.502666)
		(width 0.127)
		(layer "In5.Cu")
		(net "BMC_I2C12_MINI6_SCL")
	)
	(segment
		(start 63.781686 -69.069966)
		(end 72.983852 -59.8678)
		(width 0.127)
		(layer "In5.Cu")
		(net "BMC_I2C12_MINI6_SCL")
	)
	(segment
		(start 128.917954 1.9939)
		(end 182.99811 1.9939)
		(width 0.127)
		(layer "In5.Cu")
		(net "BMC_I2C12_MINI6_SCL")
	)
	(segment
		(start 275.315934 -1.1557)
		(end 276.0472 -1.886966)
		(width 0.127)
		(layer "In5.Cu")
		(net "BMC_I2C12_MINI6_SCL")
	)
	(segment
		(start 107.382818 -19.541236)
		(end 128.917954 1.9939)
		(width 0.127)
		(layer "In5.Cu")
		(net "BMC_I2C12_MINI6_SCL")
	)
	(segment
		(start 60.1726 -102.901496)
		(end 60.1726 -76.76896)
		(width 0.127)
		(layer "In5.Cu")
		(net "BMC_I2C12_MINI6_SCL")
	)
	(segment
		(start 54.761892 -108.312204)
		(end 60.1726 -102.901496)
		(width 0.127)
		(layer "In5.Cu")
		(net "BMC_I2C12_MINI6_SCL")
	)
	(segment
		(start 192.416176 1.7526)
		(end 200.678034 1.7526)
		(width 0.127)
		(layer "In5.Cu")
		(net "BMC_I2C12_MINI6_SCL")
	)
	(segment
		(start 265.840718 -1.112012)
		(end 265.884406 -1.1557)
		(width 0.127)
		(layer "In5.Cu")
		(net "BMC_I2C12_MINI6_SCL")
	)
	(segment
		(start 276.0472 -1.886966)
		(end 276.0472 -7.085838)
		(width 0.127)
		(layer "In5.Cu")
		(net "BMC_I2C12_MINI6_SCL")
	)
	(segment
		(start 201.927968 0.502666)
		(end 203.778866 0.502666)
		(width 0.127)
		(layer "In5.Cu")
		(net "BMC_I2C12_MINI6_SCL")
	)
	(segment
		(start 105.6386 -47.1678)
		(end 105.6386 -40.664384)
		(width 0.127)
		(layer "In5.Cu")
		(net "BMC_I2C12_MINI6_SCL")
	)
	(segment
		(start 276.0472 -7.085838)
		(end 275.360384 -7.772654)
		(width 0.127)
		(layer "In5.Cu")
		(net "BMC_I2C12_MINI6_SCL")
	)
	(segment
		(start 105.6386 -40.664384)
		(end 107.382818 -38.920166)
		(width 0.127)
		(layer "In5.Cu")
		(net "BMC_I2C12_MINI6_SCL")
	)
	(segment
		(start 205.29169 2.01549)
		(end 244.726206 2.01549)
		(width 0.127)
		(layer "In5.Cu")
		(net "BMC_I2C12_MINI6_SCL")
	)
	(segment
		(start 258.442206 -2.81051)
		(end 260.097016 -1.1557)
		(width 0.127)
		(layer "In5.Cu")
		(net "BMC_I2C12_MINI6_SCL")
	)
	(segment
		(start 246.478044 0.263652)
		(end 252.617478 0.263652)
		(width 0.127)
		(layer "In5.Cu")
		(net "BMC_I2C12_MINI6_SCL")
	)
	(segment
		(start 54.761892 -108.430822)
		(end 54.761892 -108.312204)
		(width 0.127)
		(layer "In5.Cu")
		(net "BMC_I2C12_MINI6_SCL")
	)
	(segment
		(start 203.778866 0.502666)
		(end 205.29169 2.01549)
		(width 0.127)
		(layer "In5.Cu")
		(net "BMC_I2C12_MINI6_SCL")
	)
	(segment
		(start 265.884406 -1.1557)
		(end 275.315934 -1.1557)
		(width 0.127)
		(layer "In5.Cu")
		(net "BMC_I2C12_MINI6_SCL")
	)
	(segment
		(start 55.16626 -108.83519)
		(end 54.761892 -108.430822)
		(width 0.127)
		(layer "In5.Cu")
		(net "BMC_I2C12_MINI6_SCL")
	)
	(segment
		(start 60.1726 -76.76896)
		(end 63.781686 -73.159874)
		(width 0.127)
		(layer "In5.Cu")
		(net "BMC_I2C12_MINI6_SCL")
	)
	(segment
		(start 63.781686 -73.159874)
		(end 63.781686 -69.069966)
		(width 0.127)
		(layer "In5.Cu")
		(net "BMC_I2C12_MINI6_SCL")
	)
	(segment
		(start 265.407394 -1.1557)
		(end 265.451082 -1.112012)
		(width 0.127)
		(layer "In5.Cu")
		(net "BMC_I2C12_MINI6_SCL")
	)
	(segment
		(start 274.75561 -8.903716)
		(end 275.16201 -9.310116)
		(width 0.12065)
		(layer "F.Cu")
		(net "BMC_I2C11_MINI5_SDA")
	)
	(segment
		(start 65.4304 -111.1631)
		(end 65.4304 -110.02264)
		(width 0.12065)
		(layer "F.Cu")
		(net "BMC_I2C11_MINI5_SDA")
	)
	(segment
		(start 64.66205 -110.91545)
		(end 65.151 -111.4044)
		(width 0.12065)
		(layer "F.Cu")
		(net "BMC_I2C11_MINI5_SDA")
	)
	(segment
		(start 274.287996 -8.903716)
		(end 274.75561 -8.903716)
		(width 0.12065)
		(layer "F.Cu")
		(net "BMC_I2C11_MINI5_SDA")
	)
	(segment
		(start 63.9318 -108.0008)
		(end 64.66205 -108.73105)
		(width 0.12065)
		(layer "F.Cu")
		(net "BMC_I2C11_MINI5_SDA")
	)
	(segment
		(start 65.1891 -111.4044)
		(end 65.4304 -111.1631)
		(width 0.12065)
		(layer "F.Cu")
		(net "BMC_I2C11_MINI5_SDA")
	)
	(segment
		(start 64.66205 -108.73105)
		(end 64.66205 -110.91545)
		(width 0.12065)
		(layer "F.Cu")
		(net "BMC_I2C11_MINI5_SDA")
	)
	(segment
		(start 275.230844 -9.241282)
		(end 275.16201 -9.310116)
		(width 0.12065)
		(layer "F.Cu")
		(net "BMC_I2C11_MINI5_SDA")
	)
	(segment
		(start 276.162516 -9.241282)
		(end 275.230844 -9.241282)
		(width 0.12065)
		(layer "F.Cu")
		(net "BMC_I2C11_MINI5_SDA")
	)
	(segment
		(start 65.151 -111.4044)
		(end 65.1891 -111.4044)
		(width 0.12065)
		(layer "F.Cu")
		(net "BMC_I2C11_MINI5_SDA")
	)
	(via
		(at 63.9318 -108.0008)
		(size 0.508)
		(drill 0.254)
		(layers "F.Cu" "B.Cu")
		(net "BMC_I2C11_MINI5_SDA")
	)
	(via
		(at 275.16201 -9.310116)
		(size 0.508)
		(drill 0.254)
		(layers "F.Cu" "B.Cu")
		(net "BMC_I2C11_MINI5_SDA")
	)
	(via
		(at 63.9318 -109.0168)
		(size 0.7112)
		(drill 0.3556)
		(layers "F.Cu" "B.Cu")
		(net "BMC_I2C11_MINI5_SDA")
	)
	(segment
		(start 63.9318 -108.0008)
		(end 63.9318 -109.0168)
		(width 0.12065)
		(layer "B.Cu")
		(net "BMC_I2C11_MINI5_SDA")
	)
	(segment
		(start 262.443976 -5.086858)
		(end 266.141454 -5.086858)
		(width 0.127)
		(layer "In5.Cu")
		(net "BMC_I2C11_MINI5_SDA")
	)
	(segment
		(start 274.439126 -10.033)
		(end 275.16201 -9.310116)
		(width 0.127)
		(layer "In5.Cu")
		(net "BMC_I2C11_MINI5_SDA")
	)
	(segment
		(start 253.09068 -6.188202)
		(end 261.342632 -6.188202)
		(width 0.127)
		(layer "In5.Cu")
		(net "BMC_I2C11_MINI5_SDA")
	)
	(segment
		(start 269.296388 -10.80897)
		(end 272.05686 -10.80897)
		(width 0.127)
		(layer "In5.Cu")
		(net "BMC_I2C11_MINI5_SDA")
	)
	(segment
		(start 207.874362 -0.78232)
		(end 208.539842 -1.4478)
		(width 0.127)
		(layer "In5.Cu")
		(net "BMC_I2C11_MINI5_SDA")
	)
	(segment
		(start 65.892934 -73.037954)
		(end 76.929488 -62.0014)
		(width 0.127)
		(layer "In5.Cu")
		(net "BMC_I2C11_MINI5_SDA")
	)
	(segment
		(start 272.05686 -10.80897)
		(end 272.83283 -10.033)
		(width 0.127)
		(layer "In5.Cu")
		(net "BMC_I2C11_MINI5_SDA")
	)
	(segment
		(start 208.539842 -1.4478)
		(end 209.148426 -1.4478)
		(width 0.127)
		(layer "In5.Cu")
		(net "BMC_I2C11_MINI5_SDA")
	)
	(segment
		(start 267.081 -6.026404)
		(end 267.081 -7.700264)
		(width 0.127)
		(layer "In5.Cu")
		(net "BMC_I2C11_MINI5_SDA")
	)
	(segment
		(start 217.067638 -0.5588)
		(end 219.114116 -0.5588)
		(width 0.127)
		(layer "In5.Cu")
		(net "BMC_I2C11_MINI5_SDA")
	)
	(segment
		(start 210.367626 -0.2286)
		(end 216.737438 -0.2286)
		(width 0.127)
		(layer "In5.Cu")
		(net "BMC_I2C11_MINI5_SDA")
	)
	(segment
		(start 204.340206 -2.611374)
		(end 206.16926 -0.78232)
		(width 0.127)
		(layer "In5.Cu")
		(net "BMC_I2C11_MINI5_SDA")
	)
	(segment
		(start 63.4238 -95.63862)
		(end 62.05474 -94.26956)
		(width 0.127)
		(layer "In5.Cu")
		(net "BMC_I2C11_MINI5_SDA")
	)
	(segment
		(start 206.16926 -0.78232)
		(end 207.874362 -0.78232)
		(width 0.127)
		(layer "In5.Cu")
		(net "BMC_I2C11_MINI5_SDA")
	)
	(segment
		(start 109.318044 -39.32047)
		(end 109.318044 -19.94154)
		(width 0.127)
		(layer "In5.Cu")
		(net "BMC_I2C11_MINI5_SDA")
	)
	(segment
		(start 62.05474 -94.26956)
		(end 62.05474 -77.570584)
		(width 0.127)
		(layer "In5.Cu")
		(net "BMC_I2C11_MINI5_SDA")
	)
	(segment
		(start 226.286568 0.339344)
		(end 243.741702 0.339344)
		(width 0.127)
		(layer "In5.Cu")
		(net "BMC_I2C11_MINI5_SDA")
	)
	(segment
		(start 63.737744 -108.0008)
		(end 63.4238 -107.686856)
		(width 0.127)
		(layer "In5.Cu")
		(net "BMC_I2C11_MINI5_SDA")
	)
	(segment
		(start 268.90599 -10.418572)
		(end 269.296388 -10.80897)
		(width 0.127)
		(layer "In5.Cu")
		(net "BMC_I2C11_MINI5_SDA")
	)
	(segment
		(start 267.081 -7.700264)
		(end 268.90599 -9.525254)
		(width 0.127)
		(layer "In5.Cu")
		(net "BMC_I2C11_MINI5_SDA")
	)
	(segment
		(start 224.728024 -1.2192)
		(end 226.286568 0.339344)
		(width 0.127)
		(layer "In5.Cu")
		(net "BMC_I2C11_MINI5_SDA")
	)
	(segment
		(start 62.05474 -77.570584)
		(end 65.892934 -73.73239)
		(width 0.127)
		(layer "In5.Cu")
		(net "BMC_I2C11_MINI5_SDA")
	)
	(segment
		(start 63.9318 -108.0008)
		(end 63.737744 -108.0008)
		(width 0.127)
		(layer "In5.Cu")
		(net "BMC_I2C11_MINI5_SDA")
	)
	(segment
		(start 216.737438 -0.2286)
		(end 217.067638 -0.5588)
		(width 0.127)
		(layer "In5.Cu")
		(net "BMC_I2C11_MINI5_SDA")
	)
	(segment
		(start 261.342632 -6.188202)
		(end 262.443976 -5.086858)
		(width 0.127)
		(layer "In5.Cu")
		(net "BMC_I2C11_MINI5_SDA")
	)
	(segment
		(start 65.892934 -73.73239)
		(end 65.892934 -73.037954)
		(width 0.127)
		(layer "In5.Cu")
		(net "BMC_I2C11_MINI5_SDA")
	)
	(segment
		(start 109.318044 -19.94154)
		(end 127.448818 -1.810766)
		(width 0.127)
		(layer "In5.Cu")
		(net "BMC_I2C11_MINI5_SDA")
	)
	(segment
		(start 93.262704 -62.0014)
		(end 107.65536 -47.608744)
		(width 0.127)
		(layer "In5.Cu")
		(net "BMC_I2C11_MINI5_SDA")
	)
	(segment
		(start 251.172726 -4.270248)
		(end 253.09068 -6.188202)
		(width 0.127)
		(layer "In5.Cu")
		(net "BMC_I2C11_MINI5_SDA")
	)
	(segment
		(start 219.774516 -1.2192)
		(end 224.728024 -1.2192)
		(width 0.127)
		(layer "In5.Cu")
		(net "BMC_I2C11_MINI5_SDA")
	)
	(segment
		(start 63.4238 -107.686856)
		(end 63.4238 -95.63862)
		(width 0.127)
		(layer "In5.Cu")
		(net "BMC_I2C11_MINI5_SDA")
	)
	(segment
		(start 266.141454 -5.086858)
		(end 267.081 -6.026404)
		(width 0.127)
		(layer "In5.Cu")
		(net "BMC_I2C11_MINI5_SDA")
	)
	(segment
		(start 243.741702 0.339344)
		(end 248.351294 -4.270248)
		(width 0.127)
		(layer "In5.Cu")
		(net "BMC_I2C11_MINI5_SDA")
	)
	(segment
		(start 107.65536 -40.983154)
		(end 109.318044 -39.32047)
		(width 0.127)
		(layer "In5.Cu")
		(net "BMC_I2C11_MINI5_SDA")
	)
	(segment
		(start 76.929488 -62.0014)
		(end 93.262704 -62.0014)
		(width 0.127)
		(layer "In5.Cu")
		(net "BMC_I2C11_MINI5_SDA")
	)
	(segment
		(start 248.351294 -4.270248)
		(end 251.172726 -4.270248)
		(width 0.127)
		(layer "In5.Cu")
		(net "BMC_I2C11_MINI5_SDA")
	)
	(segment
		(start 272.83283 -10.033)
		(end 274.439126 -10.033)
		(width 0.127)
		(layer "In5.Cu")
		(net "BMC_I2C11_MINI5_SDA")
	)
	(segment
		(start 132.498846 -0.99441)
		(end 179.30495 -0.99441)
		(width 0.127)
		(layer "In5.Cu")
		(net "BMC_I2C11_MINI5_SDA")
	)
	(segment
		(start 219.114116 -0.5588)
		(end 219.774516 -1.2192)
		(width 0.127)
		(layer "In5.Cu")
		(net "BMC_I2C11_MINI5_SDA")
	)
	(segment
		(start 179.30495 -0.99441)
		(end 180.921914 -2.611374)
		(width 0.127)
		(layer "In5.Cu")
		(net "BMC_I2C11_MINI5_SDA")
	)
	(segment
		(start 180.921914 -2.611374)
		(end 204.340206 -2.611374)
		(width 0.127)
		(layer "In5.Cu")
		(net "BMC_I2C11_MINI5_SDA")
	)
	(segment
		(start 131.68249 -1.810766)
		(end 132.498846 -0.99441)
		(width 0.127)
		(layer "In5.Cu")
		(net "BMC_I2C11_MINI5_SDA")
	)
	(segment
		(start 209.148426 -1.4478)
		(end 210.367626 -0.2286)
		(width 0.127)
		(layer "In5.Cu")
		(net "BMC_I2C11_MINI5_SDA")
	)
	(segment
		(start 268.90599 -9.525254)
		(end 268.90599 -10.418572)
		(width 0.127)
		(layer "In5.Cu")
		(net "BMC_I2C11_MINI5_SDA")
	)
	(segment
		(start 107.65536 -47.608744)
		(end 107.65536 -40.983154)
		(width 0.127)
		(layer "In5.Cu")
		(net "BMC_I2C11_MINI5_SDA")
	)
	(segment
		(start 127.448818 -1.810766)
		(end 131.68249 -1.810766)
		(width 0.127)
		(layer "In5.Cu")
		(net "BMC_I2C11_MINI5_SDA")
	)
	(segment
		(start 64.7573 -107.0864)
		(end 63.9318 -107.0864)
		(width 0.12065)
		(layer "F.Cu")
		(net "BMC_I2C11_MINI5_SCL")
	)
	(segment
		(start 279.651968 -13.270484)
		(end 279.651968 -13.302996)
		(width 0.12065)
		(layer "F.Cu")
		(net "BMC_I2C11_MINI5_SCL")
	)
	(segment
		(start 62.966854 -108.138214)
		(end 62.966854 -107.286806)
		(width 0.12065)
		(layer "F.Cu")
		(net "BMC_I2C11_MINI5_SCL")
	)
	(segment
		(start 63.5508 -108.72216)
		(end 62.966854 -108.138214)
		(width 0.12065)
		(layer "F.Cu")
		(net "BMC_I2C11_MINI5_SCL")
	)
	(segment
		(start 273.988276 -11.043412)
		(end 274.48637 -11.043412)
		(width 0.12065)
		(layer "F.Cu")
		(net "BMC_I2C11_MINI5_SCL")
	)
	(segment
		(start 274.79752 -11.354562)
		(end 277.736046 -11.354562)
		(width 0.12065)
		(layer "F.Cu")
		(net "BMC_I2C11_MINI5_SCL")
	)
	(segment
		(start 63.16726 -107.0864)
		(end 63.9318 -107.0864)
		(width 0.12065)
		(layer "F.Cu")
		(net "BMC_I2C11_MINI5_SCL")
	)
	(segment
		(start 64.9859 -107.315)
		(end 64.7573 -107.0864)
		(width 0.12065)
		(layer "F.Cu")
		(net "BMC_I2C11_MINI5_SCL")
	)
	(segment
		(start 277.736046 -11.354562)
		(end 279.651968 -13.270484)
		(width 0.12065)
		(layer "F.Cu")
		(net "BMC_I2C11_MINI5_SCL")
	)
	(segment
		(start 62.966854 -107.286806)
		(end 63.16726 -107.0864)
		(width 0.12065)
		(layer "F.Cu")
		(net "BMC_I2C11_MINI5_SCL")
	)
	(segment
		(start 274.48637 -11.043412)
		(end 274.79752 -11.354562)
		(width 0.12065)
		(layer "F.Cu")
		(net "BMC_I2C11_MINI5_SCL")
	)
	(via
		(at 273.988276 -11.043412)
		(size 0.508)
		(drill 0.254)
		(layers "F.Cu" "B.Cu")
		(net "BMC_I2C11_MINI5_SCL")
	)
	(via
		(at 63.9318 -107.0864)
		(size 0.508)
		(drill 0.254)
		(layers "F.Cu" "B.Cu")
		(net "BMC_I2C11_MINI5_SCL")
	)
	(via
		(at 62.966854 -107.286806)
		(size 0.7112)
		(drill 0.3556)
		(layers "F.Cu" "B.Cu")
		(net "BMC_I2C11_MINI5_SCL")
	)
	(via
		(at 279.651968 -13.302996)
		(size 0.508)
		(drill 0.254)
		(layers "F.Cu" "B.Cu")
		(net "BMC_I2C11_MINI5_SCL")
	)
	(segment
		(start 180.711348 -3.119374)
		(end 204.550772 -3.119374)
		(width 0.127)
		(layer "In5.Cu")
		(net "BMC_I2C11_MINI5_SCL")
	)
	(segment
		(start 262.654542 -5.594858)
		(end 265.930888 -5.594858)
		(width 0.127)
		(layer "In5.Cu")
		(net "BMC_I2C11_MINI5_SCL")
	)
	(segment
		(start 179.094384 -1.50241)
		(end 180.711348 -3.119374)
		(width 0.127)
		(layer "In5.Cu")
		(net "BMC_I2C11_MINI5_SCL")
	)
	(segment
		(start 207.663796 -1.29032)
		(end 208.329276 -1.9558)
		(width 0.127)
		(layer "In5.Cu")
		(net "BMC_I2C11_MINI5_SCL")
	)
	(segment
		(start 204.550772 -3.119374)
		(end 206.379826 -1.29032)
		(width 0.127)
		(layer "In5.Cu")
		(net "BMC_I2C11_MINI5_SCL")
	)
	(segment
		(start 108.16336 -47.81931)
		(end 108.16336 -41.19372)
		(width 0.127)
		(layer "In5.Cu")
		(net "BMC_I2C11_MINI5_SCL")
	)
	(segment
		(start 93.47327 -62.5094)
		(end 108.16336 -47.81931)
		(width 0.127)
		(layer "In5.Cu")
		(net "BMC_I2C11_MINI5_SCL")
	)
	(segment
		(start 109.826044 -39.531036)
		(end 109.826044 -20.152106)
		(width 0.127)
		(layer "In5.Cu")
		(net "BMC_I2C11_MINI5_SCL")
	)
	(segment
		(start 266.573 -7.91083)
		(end 268.39799 -9.73582)
		(width 0.127)
		(layer "In5.Cu")
		(net "BMC_I2C11_MINI5_SCL")
	)
	(segment
		(start 132.709412 -1.50241)
		(end 179.094384 -1.50241)
		(width 0.127)
		(layer "In5.Cu")
		(net "BMC_I2C11_MINI5_SCL")
	)
	(segment
		(start 77.140054 -62.5094)
		(end 93.47327 -62.5094)
		(width 0.127)
		(layer "In5.Cu")
		(net "BMC_I2C11_MINI5_SCL")
	)
	(segment
		(start 269.085822 -11.31697)
		(end 272.267426 -11.31697)
		(width 0.127)
		(layer "In5.Cu")
		(net "BMC_I2C11_MINI5_SCL")
	)
	(segment
		(start 209.358992 -1.9558)
		(end 210.578192 -0.7366)
		(width 0.127)
		(layer "In5.Cu")
		(net "BMC_I2C11_MINI5_SCL")
	)
	(segment
		(start 63.9318 -107.0864)
		(end 63.9318 -95.428054)
		(width 0.127)
		(layer "In5.Cu")
		(net "BMC_I2C11_MINI5_SCL")
	)
	(segment
		(start 261.553198 -6.696202)
		(end 262.654542 -5.594858)
		(width 0.127)
		(layer "In5.Cu")
		(net "BMC_I2C11_MINI5_SCL")
	)
	(segment
		(start 216.857072 -1.0668)
		(end 218.90355 -1.0668)
		(width 0.127)
		(layer "In5.Cu")
		(net "BMC_I2C11_MINI5_SCL")
	)
	(segment
		(start 266.573 -6.23697)
		(end 266.573 -7.91083)
		(width 0.127)
		(layer "In5.Cu")
		(net "BMC_I2C11_MINI5_SCL")
	)
	(segment
		(start 109.826044 -20.152106)
		(end 127.659384 -2.318766)
		(width 0.127)
		(layer "In5.Cu")
		(net "BMC_I2C11_MINI5_SCL")
	)
	(segment
		(start 216.526872 -0.7366)
		(end 216.857072 -1.0668)
		(width 0.127)
		(layer "In5.Cu")
		(net "BMC_I2C11_MINI5_SCL")
	)
	(segment
		(start 250.96216 -4.778248)
		(end 252.880114 -6.696202)
		(width 0.127)
		(layer "In5.Cu")
		(net "BMC_I2C11_MINI5_SCL")
	)
	(segment
		(start 273.043396 -10.541)
		(end 273.485864 -10.541)
		(width 0.127)
		(layer "In5.Cu")
		(net "BMC_I2C11_MINI5_SCL")
	)
	(segment
		(start 206.379826 -1.29032)
		(end 207.663796 -1.29032)
		(width 0.127)
		(layer "In5.Cu")
		(net "BMC_I2C11_MINI5_SCL")
	)
	(segment
		(start 243.531136 -0.168656)
		(end 248.140728 -4.778248)
		(width 0.127)
		(layer "In5.Cu")
		(net "BMC_I2C11_MINI5_SCL")
	)
	(segment
		(start 62.56274 -77.78115)
		(end 66.400934 -73.942956)
		(width 0.127)
		(layer "In5.Cu")
		(net "BMC_I2C11_MINI5_SCL")
	)
	(segment
		(start 226.497134 -0.168656)
		(end 243.531136 -0.168656)
		(width 0.127)
		(layer "In5.Cu")
		(net "BMC_I2C11_MINI5_SCL")
	)
	(segment
		(start 268.39799 -9.73582)
		(end 268.39799 -10.629138)
		(width 0.127)
		(layer "In5.Cu")
		(net "BMC_I2C11_MINI5_SCL")
	)
	(segment
		(start 208.329276 -1.9558)
		(end 209.358992 -1.9558)
		(width 0.127)
		(layer "In5.Cu")
		(net "BMC_I2C11_MINI5_SCL")
	)
	(segment
		(start 210.578192 -0.7366)
		(end 216.526872 -0.7366)
		(width 0.127)
		(layer "In5.Cu")
		(net "BMC_I2C11_MINI5_SCL")
	)
	(segment
		(start 272.267426 -11.31697)
		(end 273.043396 -10.541)
		(width 0.127)
		(layer "In5.Cu")
		(net "BMC_I2C11_MINI5_SCL")
	)
	(segment
		(start 248.140728 -4.778248)
		(end 250.96216 -4.778248)
		(width 0.127)
		(layer "In5.Cu")
		(net "BMC_I2C11_MINI5_SCL")
	)
	(segment
		(start 218.90355 -1.0668)
		(end 219.56395 -1.7272)
		(width 0.127)
		(layer "In5.Cu")
		(net "BMC_I2C11_MINI5_SCL")
	)
	(segment
		(start 66.400934 -73.942956)
		(end 66.400934 -73.24852)
		(width 0.127)
		(layer "In5.Cu")
		(net "BMC_I2C11_MINI5_SCL")
	)
	(segment
		(start 131.893056 -2.318766)
		(end 132.709412 -1.50241)
		(width 0.127)
		(layer "In5.Cu")
		(net "BMC_I2C11_MINI5_SCL")
	)
	(segment
		(start 62.56274 -94.058994)
		(end 62.56274 -77.78115)
		(width 0.127)
		(layer "In5.Cu")
		(net "BMC_I2C11_MINI5_SCL")
	)
	(segment
		(start 127.659384 -2.318766)
		(end 131.893056 -2.318766)
		(width 0.127)
		(layer "In5.Cu")
		(net "BMC_I2C11_MINI5_SCL")
	)
	(segment
		(start 279.62225 -14.147038)
		(end 286.134302 -20.65909)
		(width 0.127)
		(layer "In5.Cu")
		(net "BMC_I2C11_MINI5_SCL")
	)
	(segment
		(start 224.93859 -1.7272)
		(end 226.497134 -0.168656)
		(width 0.127)
		(layer "In5.Cu")
		(net "BMC_I2C11_MINI5_SCL")
	)
	(segment
		(start 279.651968 -13.302996)
		(end 279.62225 -13.332714)
		(width 0.127)
		(layer "In5.Cu")
		(net "BMC_I2C11_MINI5_SCL")
	)
	(segment
		(start 268.39799 -10.629138)
		(end 269.085822 -11.31697)
		(width 0.127)
		(layer "In5.Cu")
		(net "BMC_I2C11_MINI5_SCL")
	)
	(segment
		(start 219.56395 -1.7272)
		(end 224.93859 -1.7272)
		(width 0.127)
		(layer "In5.Cu")
		(net "BMC_I2C11_MINI5_SCL")
	)
	(segment
		(start 265.930888 -5.594858)
		(end 266.573 -6.23697)
		(width 0.127)
		(layer "In5.Cu")
		(net "BMC_I2C11_MINI5_SCL")
	)
	(segment
		(start 66.400934 -73.24852)
		(end 77.140054 -62.5094)
		(width 0.127)
		(layer "In5.Cu")
		(net "BMC_I2C11_MINI5_SCL")
	)
	(segment
		(start 279.62225 -13.332714)
		(end 279.62225 -14.147038)
		(width 0.127)
		(layer "In5.Cu")
		(net "BMC_I2C11_MINI5_SCL")
	)
	(segment
		(start 252.880114 -6.696202)
		(end 261.553198 -6.696202)
		(width 0.127)
		(layer "In5.Cu")
		(net "BMC_I2C11_MINI5_SCL")
	)
	(segment
		(start 286.134302 -20.65909)
		(end 286.134302 -21.530056)
		(width 0.127)
		(layer "In5.Cu")
		(net "BMC_I2C11_MINI5_SCL")
	)
	(segment
		(start 108.16336 -41.19372)
		(end 109.826044 -39.531036)
		(width 0.127)
		(layer "In5.Cu")
		(net "BMC_I2C11_MINI5_SCL")
	)
	(segment
		(start 63.9318 -95.428054)
		(end 62.56274 -94.058994)
		(width 0.127)
		(layer "In5.Cu")
		(net "BMC_I2C11_MINI5_SCL")
	)
	(segment
		(start 273.485864 -10.541)
		(end 273.988276 -11.043412)
		(width 0.127)
		(layer "In5.Cu")
		(net "BMC_I2C11_MINI5_SCL")
	)
	(segment
		(start 120.52935 -92.2147)
		(end 119.850408 -91.535758)
		(width 0.12065)
		(layer "F.Cu")
		(net "BMC_I2C10_8536_SDA_R")
	)
	(segment
		(start 120.9548 -92.2147)
		(end 120.52935 -92.2147)
		(width 0.12065)
		(layer "F.Cu")
		(net "BMC_I2C10_8536_SDA_R")
	)
	(segment
		(start 121.277126 -93.743526)
		(end 121.277126 -95.130874)
		(width 0.12065)
		(layer "F.Cu")
		(net "BMC_I2C10_8536_SDA_R")
	)
	(segment
		(start 121.277126 -95.130874)
		(end 120.64492 -95.76308)
		(width 0.12065)
		(layer "F.Cu")
		(net "BMC_I2C10_8536_SDA_R")
	)
	(segment
		(start 120.9548 -93.4212)
		(end 120.9548 -92.2147)
		(width 0.12065)
		(layer "F.Cu")
		(net "BMC_I2C10_8536_SDA_R")
	)
	(segment
		(start 120.64492 -95.76308)
		(end 119.3927 -95.76308)
		(width 0.12065)
		(layer "F.Cu")
		(net "BMC_I2C10_8536_SDA_R")
	)
	(segment
		(start 120.9548 -93.4212)
		(end 121.277126 -93.743526)
		(width 0.12065)
		(layer "F.Cu")
		(net "BMC_I2C10_8536_SDA_R")
	)
	(via
		(at 119.850408 -91.535758)
		(size 0.7112)
		(drill 0.3556)
		(layers "F.Cu" "B.Cu")
		(net "BMC_I2C10_8536_SDA_R")
	)
	(segment
		(start 121.239788 -90.556588)
		(end 121.0564 -90.3732)
		(width 0.12065)
		(layer "F.Cu")
		(net "BMC_I2C10_8536_SDA")
	)
	(segment
		(start 121.239788 -91.040712)
		(end 121.239788 -90.556588)
		(width 0.12065)
		(layer "F.Cu")
		(net "BMC_I2C10_8536_SDA")
	)
	(segment
		(start 120.9548 -91.3257)
		(end 121.239788 -91.040712)
		(width 0.12065)
		(layer "F.Cu")
		(net "BMC_I2C10_8536_SDA")
	)
	(via
		(at 121.0564 -90.3732)
		(size 0.508)
		(drill 0.254)
		(layers "F.Cu" "B.Cu")
		(net "BMC_I2C10_8536_SDA")
	)
	(via
		(at 56.739282 -96.012)
		(size 0.508)
		(drill 0.254)
		(layers "F.Cu" "B.Cu")
		(net "BMC_I2C10_8536_SDA")
	)
	(via
		(at 120.848628 -94.346268)
		(size 0.7112)
		(drill 0.3556)
		(layers "F.Cu" "B.Cu")
		(net "BMC_I2C10_8536_SDA")
	)
	(via
		(at 51.274472 -114.601498)
		(size 0.508)
		(drill 0.254)
		(layers "F.Cu" "B.Cu")
		(net "BMC_I2C10_8536_SDA")
	)
	(segment
		(start 121.233692 -95.466408)
		(end 121.233692 -94.346268)
		(width 0.12065)
		(layer "B.Cu")
		(net "BMC_I2C10_8536_SDA")
	)
	(segment
		(start 50.974498 -114.901472)
		(end 51.274472 -114.601498)
		(width 0.12065)
		(layer "B.Cu")
		(net "BMC_I2C10_8536_SDA")
	)
	(segment
		(start 120.9548 -95.7453)
		(end 121.233692 -95.466408)
		(width 0.12065)
		(layer "B.Cu")
		(net "BMC_I2C10_8536_SDA")
	)
	(segment
		(start 51.274472 -114.601498)
		(end 50.9778 -114.304826)
		(width 0.12065)
		(layer "B.Cu")
		(net "BMC_I2C10_8536_SDA")
	)
	(segment
		(start 51.2318 -115.46459)
		(end 50.974498 -115.207288)
		(width 0.12065)
		(layer "B.Cu")
		(net "BMC_I2C10_8536_SDA")
	)
	(segment
		(start 121.233692 -94.346268)
		(end 121.233692 -90.550492)
		(width 0.12065)
		(layer "B.Cu")
		(net "BMC_I2C10_8536_SDA")
	)
	(segment
		(start 50.9778 -113.8809)
		(end 51.2572 -113.6015)
		(width 0.12065)
		(layer "B.Cu")
		(net "BMC_I2C10_8536_SDA")
	)
	(segment
		(start 121.233692 -94.346268)
		(end 120.848628 -94.346268)
		(width 0.12065)
		(layer "B.Cu")
		(net "BMC_I2C10_8536_SDA")
	)
	(segment
		(start 121.233692 -90.550492)
		(end 121.0564 -90.3732)
		(width 0.12065)
		(layer "B.Cu")
		(net "BMC_I2C10_8536_SDA")
	)
	(segment
		(start 50.974498 -115.207288)
		(end 50.974498 -114.901472)
		(width 0.12065)
		(layer "B.Cu")
		(net "BMC_I2C10_8536_SDA")
	)
	(segment
		(start 50.9778 -114.304826)
		(end 50.9778 -113.8809)
		(width 0.12065)
		(layer "B.Cu")
		(net "BMC_I2C10_8536_SDA")
	)
	(segment
		(start 78.538578 -96.991424)
		(end 78.549754 -97.0026)
		(width 0.127)
		(layer "In2.Cu")
		(net "BMC_I2C10_8536_SDA")
	)
	(segment
		(start 78.549754 -97.0026)
		(end 110.1344 -97.0026)
		(width 0.127)
		(layer "In2.Cu")
		(net "BMC_I2C10_8536_SDA")
	)
	(segment
		(start 121.2342 -89.465912)
		(end 121.2342 -90.1954)
		(width 0.127)
		(layer "In2.Cu")
		(net "BMC_I2C10_8536_SDA")
	)
	(segment
		(start 121.2342 -90.1954)
		(end 121.0564 -90.3732)
		(width 0.127)
		(layer "In2.Cu")
		(net "BMC_I2C10_8536_SDA")
	)
	(segment
		(start 78.359 -96.991424)
		(end 78.538578 -96.991424)
		(width 0.127)
		(layer "In2.Cu")
		(net "BMC_I2C10_8536_SDA")
	)
	(segment
		(start 71.31558 -95.177864)
		(end 71.69785 -95.560134)
		(width 0.127)
		(layer "In2.Cu")
		(net "BMC_I2C10_8536_SDA")
	)
	(segment
		(start 56.667908 -95.444818)
		(end 60.81776 -95.444818)
		(width 0.127)
		(layer "In2.Cu")
		(net "BMC_I2C10_8536_SDA")
	)
	(segment
		(start 120.998488 -89.2302)
		(end 121.2342 -89.465912)
		(width 0.127)
		(layer "In2.Cu")
		(net "BMC_I2C10_8536_SDA")
	)
	(segment
		(start 71.69785 -95.560134)
		(end 76.92771 -95.560134)
		(width 0.127)
		(layer "In2.Cu")
		(net "BMC_I2C10_8536_SDA")
	)
	(segment
		(start 56.739282 -96.012)
		(end 56.508396 -95.78086)
		(width 0.127)
		(layer "In2.Cu")
		(net "BMC_I2C10_8536_SDA")
	)
	(segment
		(start 56.508396 -95.78086)
		(end 56.508396 -95.60433)
		(width 0.127)
		(layer "In2.Cu")
		(net "BMC_I2C10_8536_SDA")
	)
	(segment
		(start 110.1344 -97.0026)
		(end 117.9068 -89.2302)
		(width 0.127)
		(layer "In2.Cu")
		(net "BMC_I2C10_8536_SDA")
	)
	(segment
		(start 117.9068 -89.2302)
		(end 120.998488 -89.2302)
		(width 0.127)
		(layer "In2.Cu")
		(net "BMC_I2C10_8536_SDA")
	)
	(segment
		(start 76.92771 -95.560134)
		(end 78.359 -96.991424)
		(width 0.127)
		(layer "In2.Cu")
		(net "BMC_I2C10_8536_SDA")
	)
	(segment
		(start 60.81776 -95.444818)
		(end 61.084714 -95.177864)
		(width 0.127)
		(layer "In2.Cu")
		(net "BMC_I2C10_8536_SDA")
	)
	(segment
		(start 61.084714 -95.177864)
		(end 71.31558 -95.177864)
		(width 0.127)
		(layer "In2.Cu")
		(net "BMC_I2C10_8536_SDA")
	)
	(segment
		(start 56.508396 -95.60433)
		(end 56.667908 -95.444818)
		(width 0.127)
		(layer "In2.Cu")
		(net "BMC_I2C10_8536_SDA")
	)
	(segment
		(start 51.2445 -112.7125)
		(end 51.2445 -106.921554)
		(width 0.127)
		(layer "In5.Cu")
		(net "BMC_I2C10_8536_SDA")
	)
	(segment
		(start 51.274472 -114.601498)
		(end 50.9524 -114.279426)
		(width 0.127)
		(layer "In5.Cu")
		(net "BMC_I2C10_8536_SDA")
	)
	(segment
		(start 56.4388 -101.727254)
		(end 56.4388 -96.312482)
		(width 0.127)
		(layer "In5.Cu")
		(net "BMC_I2C10_8536_SDA")
	)
	(segment
		(start 50.9524 -114.279426)
		(end 50.9524 -113.0046)
		(width 0.127)
		(layer "In5.Cu")
		(net "BMC_I2C10_8536_SDA")
	)
	(segment
		(start 51.2445 -106.921554)
		(end 56.4388 -101.727254)
		(width 0.127)
		(layer "In5.Cu")
		(net "BMC_I2C10_8536_SDA")
	)
	(segment
		(start 50.9524 -113.0046)
		(end 51.2445 -112.7125)
		(width 0.127)
		(layer "In5.Cu")
		(net "BMC_I2C10_8536_SDA")
	)
	(segment
		(start 56.4388 -96.312482)
		(end 56.739282 -96.012)
		(width 0.127)
		(layer "In5.Cu")
		(net "BMC_I2C10_8536_SDA")
	)
	(segment
		(start 122.0978 -93.4212)
		(end 121.778776 -93.740224)
		(width 0.12065)
		(layer "F.Cu")
		(net "BMC_I2C10_8536_SCL_R")
	)
	(segment
		(start 121.778776 -93.740224)
		(end 121.778776 -95.261176)
		(width 0.12065)
		(layer "F.Cu")
		(net "BMC_I2C10_8536_SCL_R")
	)
	(segment
		(start 122.28068 -95.76308)
		(end 123.5329 -95.76308)
		(width 0.12065)
		(layer "F.Cu")
		(net "BMC_I2C10_8536_SCL_R")
	)
	(segment
		(start 122.0978 -92.2147)
		(end 122.482864 -92.2147)
		(width 0.12065)
		(layer "F.Cu")
		(net "BMC_I2C10_8536_SCL_R")
	)
	(segment
		(start 121.778776 -95.261176)
		(end 122.28068 -95.76308)
		(width 0.12065)
		(layer "F.Cu")
		(net "BMC_I2C10_8536_SCL_R")
	)
	(segment
		(start 122.0978 -93.4212)
		(end 122.0978 -92.2147)
		(width 0.12065)
		(layer "F.Cu")
		(net "BMC_I2C10_8536_SCL_R")
	)
	(segment
		(start 122.482864 -92.2147)
		(end 123.11253 -91.585034)
		(width 0.12065)
		(layer "F.Cu")
		(net "BMC_I2C10_8536_SCL_R")
	)
	(via
		(at 123.11253 -91.585034)
		(size 0.7112)
		(drill 0.3556)
		(layers "F.Cu" "B.Cu")
		(net "BMC_I2C10_8536_SCL_R")
	)
	(segment
		(start 121.741438 -90.551762)
		(end 121.92 -90.3732)
		(width 0.12065)
		(layer "F.Cu")
		(net "BMC_I2C10_8536_SCL")
	)
	(segment
		(start 122.0978 -91.3257)
		(end 121.741438 -90.969338)
		(width 0.12065)
		(layer "F.Cu")
		(net "BMC_I2C10_8536_SCL")
	)
	(segment
		(start 121.741438 -90.969338)
		(end 121.741438 -90.551762)
		(width 0.12065)
		(layer "F.Cu")
		(net "BMC_I2C10_8536_SCL")
	)
	(via
		(at 122.055382 -92.422726)
		(size 0.7112)
		(drill 0.3556)
		(layers "F.Cu" "B.Cu")
		(net "BMC_I2C10_8536_SCL")
	)
	(via
		(at 55.630572 -96.012)
		(size 0.508)
		(drill 0.254)
		(layers "F.Cu" "B.Cu")
		(net "BMC_I2C10_8536_SCL")
	)
	(via
		(at 121.92 -90.3732)
		(size 0.508)
		(drill 0.254)
		(layers "F.Cu" "B.Cu")
		(net "BMC_I2C10_8536_SCL")
	)
	(via
		(at 50.172874 -114.601498)
		(size 0.508)
		(drill 0.254)
		(layers "F.Cu" "B.Cu")
		(net "BMC_I2C10_8536_SCL")
	)
	(segment
		(start 50.472848 -114.901472)
		(end 50.172874 -114.601498)
		(width 0.12065)
		(layer "B.Cu")
		(net "BMC_I2C10_8536_SCL")
	)
	(segment
		(start 121.735342 -95.509842)
		(end 121.735342 -92.422726)
		(width 0.12065)
		(layer "B.Cu")
		(net "BMC_I2C10_8536_SCL")
	)
	(segment
		(start 50.47615 -114.298222)
		(end 50.47615 -113.83645)
		(width 0.12065)
		(layer "B.Cu")
		(net "BMC_I2C10_8536_SCL")
	)
	(segment
		(start 121.9708 -95.7453)
		(end 121.735342 -95.509842)
		(width 0.12065)
		(layer "B.Cu")
		(net "BMC_I2C10_8536_SCL")
	)
	(segment
		(start 121.735342 -92.422726)
		(end 121.735342 -90.557858)
		(width 0.12065)
		(layer "B.Cu")
		(net "BMC_I2C10_8536_SCL")
	)
	(segment
		(start 50.47615 -113.83645)
		(end 50.2412 -113.6015)
		(width 0.12065)
		(layer "B.Cu")
		(net "BMC_I2C10_8536_SCL")
	)
	(segment
		(start 50.472848 -115.207542)
		(end 50.472848 -114.901472)
		(width 0.12065)
		(layer "B.Cu")
		(net "BMC_I2C10_8536_SCL")
	)
	(segment
		(start 121.735342 -90.557858)
		(end 121.92 -90.3732)
		(width 0.12065)
		(layer "B.Cu")
		(net "BMC_I2C10_8536_SCL")
	)
	(segment
		(start 50.172874 -114.601498)
		(end 50.47615 -114.298222)
		(width 0.12065)
		(layer "B.Cu")
		(net "BMC_I2C10_8536_SCL")
	)
	(segment
		(start 50.2158 -115.46459)
		(end 50.472848 -115.207542)
		(width 0.12065)
		(layer "B.Cu")
		(net "BMC_I2C10_8536_SCL")
	)
	(segment
		(start 121.735342 -92.422726)
		(end 122.055382 -92.422726)
		(width 0.12065)
		(layer "B.Cu")
		(net "BMC_I2C10_8536_SCL")
	)
	(segment
		(start 110.62589 -95.792544)
		(end 117.696234 -88.7222)
		(width 0.127)
		(layer "In2.Cu")
		(net "BMC_I2C10_8536_SCL")
	)
	(segment
		(start 60.607194 -94.936818)
		(end 60.874148 -94.669864)
		(width 0.127)
		(layer "In2.Cu")
		(net "BMC_I2C10_8536_SCL")
	)
	(segment
		(start 78.569566 -96.483424)
		(end 78.749144 -96.483424)
		(width 0.127)
		(layer "In2.Cu")
		(net "BMC_I2C10_8536_SCL")
	)
	(segment
		(start 117.696234 -88.7222)
		(end 121.209054 -88.7222)
		(width 0.127)
		(layer "In2.Cu")
		(net "BMC_I2C10_8536_SCL")
	)
	(segment
		(start 121.209054 -88.7222)
		(end 121.7422 -89.255346)
		(width 0.127)
		(layer "In2.Cu")
		(net "BMC_I2C10_8536_SCL")
	)
	(segment
		(start 60.874148 -94.669864)
		(end 71.526146 -94.669864)
		(width 0.127)
		(layer "In2.Cu")
		(net "BMC_I2C10_8536_SCL")
	)
	(segment
		(start 71.526146 -94.669864)
		(end 71.908416 -95.052134)
		(width 0.127)
		(layer "In2.Cu")
		(net "BMC_I2C10_8536_SCL")
	)
	(segment
		(start 109.923834 -96.4946)
		(end 110.62589 -95.79229)
		(width 0.127)
		(layer "In2.Cu")
		(net "BMC_I2C10_8536_SCL")
	)
	(segment
		(start 77.138276 -95.052134)
		(end 78.569566 -96.483424)
		(width 0.127)
		(layer "In2.Cu")
		(net "BMC_I2C10_8536_SCL")
	)
	(segment
		(start 56.000396 -95.642176)
		(end 56.000396 -95.393764)
		(width 0.127)
		(layer "In2.Cu")
		(net "BMC_I2C10_8536_SCL")
	)
	(segment
		(start 56.000396 -95.393764)
		(end 56.457342 -94.936818)
		(width 0.127)
		(layer "In2.Cu")
		(net "BMC_I2C10_8536_SCL")
	)
	(segment
		(start 121.7422 -89.255346)
		(end 121.7422 -90.1954)
		(width 0.127)
		(layer "In2.Cu")
		(net "BMC_I2C10_8536_SCL")
	)
	(segment
		(start 78.749144 -96.483424)
		(end 78.76032 -96.4946)
		(width 0.127)
		(layer "In2.Cu")
		(net "BMC_I2C10_8536_SCL")
	)
	(segment
		(start 121.7422 -90.1954)
		(end 121.92 -90.3732)
		(width 0.127)
		(layer "In2.Cu")
		(net "BMC_I2C10_8536_SCL")
	)
	(segment
		(start 71.908416 -95.052134)
		(end 77.138276 -95.052134)
		(width 0.127)
		(layer "In2.Cu")
		(net "BMC_I2C10_8536_SCL")
	)
	(segment
		(start 110.62589 -95.79229)
		(end 110.62589 -95.792544)
		(width 0.127)
		(layer "In2.Cu")
		(net "BMC_I2C10_8536_SCL")
	)
	(segment
		(start 55.630572 -96.012)
		(end 56.000396 -95.642176)
		(width 0.127)
		(layer "In2.Cu")
		(net "BMC_I2C10_8536_SCL")
	)
	(segment
		(start 56.457342 -94.936818)
		(end 60.607194 -94.936818)
		(width 0.127)
		(layer "In2.Cu")
		(net "BMC_I2C10_8536_SCL")
	)
	(segment
		(start 78.76032 -96.4946)
		(end 109.923834 -96.4946)
		(width 0.127)
		(layer "In2.Cu")
		(net "BMC_I2C10_8536_SCL")
	)
	(segment
		(start 55.9308 -101.516688)
		(end 55.9308 -96.312228)
		(width 0.127)
		(layer "In5.Cu")
		(net "BMC_I2C10_8536_SCL")
	)
	(segment
		(start 50.4444 -114.329972)
		(end 50.4444 -112.794034)
		(width 0.127)
		(layer "In5.Cu")
		(net "BMC_I2C10_8536_SCL")
	)
	(segment
		(start 50.4444 -112.794034)
		(end 50.7365 -112.501934)
		(width 0.127)
		(layer "In5.Cu")
		(net "BMC_I2C10_8536_SCL")
	)
	(segment
		(start 50.7365 -106.710988)
		(end 55.9308 -101.516688)
		(width 0.127)
		(layer "In5.Cu")
		(net "BMC_I2C10_8536_SCL")
	)
	(segment
		(start 55.9308 -96.312228)
		(end 55.630572 -96.012)
		(width 0.127)
		(layer "In5.Cu")
		(net "BMC_I2C10_8536_SCL")
	)
	(segment
		(start 50.172874 -114.601498)
		(end 50.4444 -114.329972)
		(width 0.127)
		(layer "In5.Cu")
		(net "BMC_I2C10_8536_SCL")
	)
	(segment
		(start 50.7365 -112.501934)
		(end 50.7365 -106.710988)
		(width 0.127)
		(layer "In5.Cu")
		(net "BMC_I2C10_8536_SCL")
	)
	(segment
		(start 9.398 -121.5898)
		(end 9.63676 -121.5898)
		(width 0.12065)
		(layer "F.Cu")
		(net "BMC_I2C1_MINI1_SDA")
	)
	(segment
		(start 9.453372 -120.405652)
		(end 11.472926 -120.405652)
		(width 0.12065)
		(layer "F.Cu")
		(net "BMC_I2C1_MINI1_SDA")
	)
	(segment
		(start 8.65505 -120.56745)
		(end 9.291574 -120.56745)
		(width 0.12065)
		(layer "F.Cu")
		(net "BMC_I2C1_MINI1_SDA")
	)
	(segment
		(start 8.6106 -122.3772)
		(end 9.398 -121.5898)
		(width 0.12065)
		(layer "F.Cu")
		(net "BMC_I2C1_MINI1_SDA")
	)
	(segment
		(start 8.2296 -122.3772)
		(end 8.6106 -122.3772)
		(width 0.12065)
		(layer "F.Cu")
		(net "BMC_I2C1_MINI1_SDA")
	)
	(segment
		(start 11.472926 -120.405652)
		(end 11.564874 -120.4976)
		(width 0.12065)
		(layer "F.Cu")
		(net "BMC_I2C1_MINI1_SDA")
	)
	(segment
		(start 8.0518 -121.1707)
		(end 8.0518 -122.1994)
		(width 0.12065)
		(layer "F.Cu")
		(net "BMC_I2C1_MINI1_SDA")
	)
	(segment
		(start 8.0518 -122.1994)
		(end 8.2296 -122.3772)
		(width 0.12065)
		(layer "F.Cu")
		(net "BMC_I2C1_MINI1_SDA")
	)
	(segment
		(start 8.128 -121.0945)
		(end 8.65505 -120.56745)
		(width 0.12065)
		(layer "F.Cu")
		(net "BMC_I2C1_MINI1_SDA")
	)
	(segment
		(start 9.291574 -120.56745)
		(end 9.453372 -120.405652)
		(width 0.12065)
		(layer "F.Cu")
		(net "BMC_I2C1_MINI1_SDA")
	)
	(segment
		(start 8.128 -121.0945)
		(end 8.0518 -121.1707)
		(width 0.12065)
		(layer "F.Cu")
		(net "BMC_I2C1_MINI1_SDA")
	)
	(via
		(at 53.384958 -82.646774)
		(size 0.508)
		(drill 0.254)
		(layers "F.Cu" "B.Cu")
		(net "BMC_I2C1_MINI1_SDA")
	)
	(via
		(at 8.0518 -122.1994)
		(size 0.7112)
		(drill 0.3556)
		(layers "F.Cu" "B.Cu")
		(net "BMC_I2C1_MINI1_SDA")
	)
	(via
		(at 11.564874 -120.4976)
		(size 0.508)
		(drill 0.254)
		(layers "F.Cu" "B.Cu")
		(net "BMC_I2C1_MINI1_SDA")
	)
	(via
		(at 8.674862 -95.736664)
		(size 0.508)
		(drill 0.254)
		(layers "F.Cu" "B.Cu")
		(net "BMC_I2C1_MINI1_SDA")
	)
	(segment
		(start 131.492244 -33.99028)
		(end 131.52628 -33.99028)
		(width 0.12065)
		(layer "B.Cu")
		(net "BMC_I2C1_MINI1_SDA")
	)
	(segment
		(start 128.80594 -36.4871)
		(end 129.717546 -36.4871)
		(width 0.12065)
		(layer "B.Cu")
		(net "BMC_I2C1_MINI1_SDA")
	)
	(segment
		(start 69.424804 -74.796396)
		(end 82.169 -62.0522)
		(width 0.12065)
		(layer "B.Cu")
		(net "BMC_I2C1_MINI1_SDA")
	)
	(segment
		(start 91.839796 -59.417204)
		(end 91.839796 -50.32375)
		(width 0.12065)
		(layer "B.Cu")
		(net "BMC_I2C1_MINI1_SDA")
	)
	(segment
		(start 111.148876 -32.9438)
		(end 118.12397 -32.9438)
		(width 0.12065)
		(layer "B.Cu")
		(net "BMC_I2C1_MINI1_SDA")
	)
	(segment
		(start 125.080776 -36.34105)
		(end 128.65989 -36.34105)
		(width 0.12065)
		(layer "B.Cu")
		(net "BMC_I2C1_MINI1_SDA")
	)
	(segment
		(start 128.65989 -36.34105)
		(end 128.80594 -36.4871)
		(width 0.12065)
		(layer "B.Cu")
		(net "BMC_I2C1_MINI1_SDA")
	)
	(segment
		(start 53.384958 -82.646774)
		(end 53.07965 -82.341466)
		(width 0.12065)
		(layer "B.Cu")
		(net "BMC_I2C1_MINI1_SDA")
	)
	(segment
		(start 125.080268 -36.340542)
		(end 125.080776 -36.34105)
		(width 0.12065)
		(layer "B.Cu")
		(net "BMC_I2C1_MINI1_SDA")
	)
	(segment
		(start 129.8956 -35.586416)
		(end 131.492244 -33.99028)
		(width 0.12065)
		(layer "B.Cu")
		(net "BMC_I2C1_MINI1_SDA")
	)
	(segment
		(start 89.2048 -62.0522)
		(end 91.839796 -59.417204)
		(width 0.12065)
		(layer "B.Cu")
		(net "BMC_I2C1_MINI1_SDA")
	)
	(segment
		(start 91.839796 -50.32375)
		(end 99.802696 -42.36085)
		(width 0.12065)
		(layer "B.Cu")
		(net "BMC_I2C1_MINI1_SDA")
	)
	(segment
		(start 125.080014 -36.340542)
		(end 125.080268 -36.340542)
		(width 0.12065)
		(layer "B.Cu")
		(net "BMC_I2C1_MINI1_SDA")
	)
	(segment
		(start 129.717546 -36.4871)
		(end 129.8956 -36.309046)
		(width 0.12065)
		(layer "B.Cu")
		(net "BMC_I2C1_MINI1_SDA")
	)
	(segment
		(start 99.802696 -42.36085)
		(end 101.731826 -42.36085)
		(width 0.12065)
		(layer "B.Cu")
		(net "BMC_I2C1_MINI1_SDA")
	)
	(segment
		(start 129.8956 -36.309046)
		(end 129.8956 -35.586416)
		(width 0.12065)
		(layer "B.Cu")
		(net "BMC_I2C1_MINI1_SDA")
	)
	(segment
		(start 65.194942 -76.75245)
		(end 67.150996 -74.796396)
		(width 0.12065)
		(layer "B.Cu")
		(net "BMC_I2C1_MINI1_SDA")
	)
	(segment
		(start 118.967758 -33.787588)
		(end 122.52706 -33.787588)
		(width 0.12065)
		(layer "B.Cu")
		(net "BMC_I2C1_MINI1_SDA")
	)
	(segment
		(start 132.54228 -33.99028)
		(end 131.52628 -33.99028)
		(width 0.12065)
		(layer "B.Cu")
		(net "BMC_I2C1_MINI1_SDA")
	)
	(segment
		(start 57.86755 -76.75245)
		(end 65.194942 -76.75245)
		(width 0.12065)
		(layer "B.Cu")
		(net "BMC_I2C1_MINI1_SDA")
	)
	(segment
		(start 82.169 -62.0522)
		(end 89.2048 -62.0522)
		(width 0.12065)
		(layer "B.Cu")
		(net "BMC_I2C1_MINI1_SDA")
	)
	(segment
		(start 122.52706 -33.787588)
		(end 125.080014 -36.340542)
		(width 0.12065)
		(layer "B.Cu")
		(net "BMC_I2C1_MINI1_SDA")
	)
	(segment
		(start 53.07965 -82.341466)
		(end 53.07965 -81.54035)
		(width 0.12065)
		(layer "B.Cu")
		(net "BMC_I2C1_MINI1_SDA")
	)
	(segment
		(start 53.07965 -81.54035)
		(end 57.86755 -76.75245)
		(width 0.12065)
		(layer "B.Cu")
		(net "BMC_I2C1_MINI1_SDA")
	)
	(segment
		(start 118.12397 -32.9438)
		(end 118.967758 -33.787588)
		(width 0.12065)
		(layer "B.Cu")
		(net "BMC_I2C1_MINI1_SDA")
	)
	(segment
		(start 67.150996 -74.796396)
		(end 69.424804 -74.796396)
		(width 0.12065)
		(layer "B.Cu")
		(net "BMC_I2C1_MINI1_SDA")
	)
	(segment
		(start 101.731826 -42.36085)
		(end 111.148876 -32.9438)
		(width 0.12065)
		(layer "B.Cu")
		(net "BMC_I2C1_MINI1_SDA")
	)
	(segment
		(start 41.47185 -83.4136)
		(end 42.187114 -82.698336)
		(width 0.127)
		(layer "In2.Cu")
		(net "BMC_I2C1_MINI1_SDA")
	)
	(segment
		(start 50.164238 -80.316578)
		(end 50.83048 -80.98282)
		(width 0.127)
		(layer "In2.Cu")
		(net "BMC_I2C1_MINI1_SDA")
	)
	(segment
		(start 50.83048 -80.98282)
		(end 52.258722 -80.98282)
		(width 0.127)
		(layer "In2.Cu")
		(net "BMC_I2C1_MINI1_SDA")
	)
	(segment
		(start 52.258722 -80.98282)
		(end 53.0606 -81.784698)
		(width 0.127)
		(layer "In2.Cu")
		(net "BMC_I2C1_MINI1_SDA")
	)
	(segment
		(start 12.403582 -92.263976)
		(end 14.464284 -90.203274)
		(width 0.127)
		(layer "In2.Cu")
		(net "BMC_I2C1_MINI1_SDA")
	)
	(segment
		(start 23.6347 -84.4423)
		(end 25.3492 -82.7278)
		(width 0.127)
		(layer "In2.Cu")
		(net "BMC_I2C1_MINI1_SDA")
	)
	(segment
		(start 34.882074 -82.7278)
		(end 35.567874 -83.4136)
		(width 0.127)
		(layer "In2.Cu")
		(net "BMC_I2C1_MINI1_SDA")
	)
	(segment
		(start 8.9408 -95.079312)
		(end 8.5344 -94.672912)
		(width 0.127)
		(layer "In2.Cu")
		(net "BMC_I2C1_MINI1_SDA")
	)
	(segment
		(start 45.456094 -81.2292)
		(end 46.682152 -81.2292)
		(width 0.127)
		(layer "In2.Cu")
		(net "BMC_I2C1_MINI1_SDA")
	)
	(segment
		(start 16.808196 -88.7222)
		(end 17.925796 -87.6046)
		(width 0.127)
		(layer "In2.Cu")
		(net "BMC_I2C1_MINI1_SDA")
	)
	(segment
		(start 18.005044 -87.6046)
		(end 19.427444 -86.1822)
		(width 0.127)
		(layer "In2.Cu")
		(net "BMC_I2C1_MINI1_SDA")
	)
	(segment
		(start 19.427444 -86.1822)
		(end 22.35327 -86.1822)
		(width 0.127)
		(layer "In2.Cu")
		(net "BMC_I2C1_MINI1_SDA")
	)
	(segment
		(start 53.086 -82.347816)
		(end 53.384958 -82.646774)
		(width 0.127)
		(layer "In2.Cu")
		(net "BMC_I2C1_MINI1_SDA")
	)
	(segment
		(start 22.35327 -86.1822)
		(end 23.6347 -84.90077)
		(width 0.127)
		(layer "In2.Cu")
		(net "BMC_I2C1_MINI1_SDA")
	)
	(segment
		(start 8.5344 -94.672912)
		(end 8.5344 -93.591888)
		(width 0.127)
		(layer "In2.Cu")
		(net "BMC_I2C1_MINI1_SDA")
	)
	(segment
		(start 15.929356 -88.7222)
		(end 16.808196 -88.7222)
		(width 0.127)
		(layer "In2.Cu")
		(net "BMC_I2C1_MINI1_SDA")
	)
	(segment
		(start 43.986958 -82.698336)
		(end 45.456094 -81.2292)
		(width 0.127)
		(layer "In2.Cu")
		(net "BMC_I2C1_MINI1_SDA")
	)
	(segment
		(start 9.861804 -92.263976)
		(end 12.403582 -92.263976)
		(width 0.127)
		(layer "In2.Cu")
		(net "BMC_I2C1_MINI1_SDA")
	)
	(segment
		(start 53.0606 -81.784698)
		(end 53.0606 -82.347816)
		(width 0.127)
		(layer "In2.Cu")
		(net "BMC_I2C1_MINI1_SDA")
	)
	(segment
		(start 8.9408 -95.470726)
		(end 8.9408 -95.079312)
		(width 0.127)
		(layer "In2.Cu")
		(net "BMC_I2C1_MINI1_SDA")
	)
	(segment
		(start 17.925796 -87.6046)
		(end 18.005044 -87.6046)
		(width 0.127)
		(layer "In2.Cu")
		(net "BMC_I2C1_MINI1_SDA")
	)
	(segment
		(start 46.682152 -81.2292)
		(end 47.594774 -80.316578)
		(width 0.127)
		(layer "In2.Cu")
		(net "BMC_I2C1_MINI1_SDA")
	)
	(segment
		(start 14.464284 -90.187272)
		(end 15.929356 -88.7222)
		(width 0.127)
		(layer "In2.Cu")
		(net "BMC_I2C1_MINI1_SDA")
	)
	(segment
		(start 14.464284 -90.203274)
		(end 14.464284 -90.187272)
		(width 0.127)
		(layer "In2.Cu")
		(net "BMC_I2C1_MINI1_SDA")
	)
	(segment
		(start 8.674862 -95.736664)
		(end 8.9408 -95.470726)
		(width 0.127)
		(layer "In2.Cu")
		(net "BMC_I2C1_MINI1_SDA")
	)
	(segment
		(start 35.567874 -83.4136)
		(end 41.47185 -83.4136)
		(width 0.127)
		(layer "In2.Cu")
		(net "BMC_I2C1_MINI1_SDA")
	)
	(segment
		(start 47.594774 -80.316578)
		(end 50.164238 -80.316578)
		(width 0.127)
		(layer "In2.Cu")
		(net "BMC_I2C1_MINI1_SDA")
	)
	(segment
		(start 53.0606 -82.347816)
		(end 53.086 -82.347816)
		(width 0.127)
		(layer "In2.Cu")
		(net "BMC_I2C1_MINI1_SDA")
	)
	(segment
		(start 25.3492 -82.7278)
		(end 34.882074 -82.7278)
		(width 0.127)
		(layer "In2.Cu")
		(net "BMC_I2C1_MINI1_SDA")
	)
	(segment
		(start 8.5344 -93.591888)
		(end 9.861804 -92.263976)
		(width 0.127)
		(layer "In2.Cu")
		(net "BMC_I2C1_MINI1_SDA")
	)
	(segment
		(start 42.187114 -82.698336)
		(end 43.986958 -82.698336)
		(width 0.127)
		(layer "In2.Cu")
		(net "BMC_I2C1_MINI1_SDA")
	)
	(segment
		(start 23.6347 -84.90077)
		(end 23.6347 -84.4423)
		(width 0.127)
		(layer "In2.Cu")
		(net "BMC_I2C1_MINI1_SDA")
	)
	(segment
		(start 11.535664 -119.587264)
		(end 11.6586 -119.61876)
		(width 0.127)
		(layer "In5.Cu")
		(net "BMC_I2C1_MINI1_SDA")
	)
	(segment
		(start 11.324844 -119.587264)
		(end 11.535664 -119.587264)
		(width 0.127)
		(layer "In5.Cu")
		(net "BMC_I2C1_MINI1_SDA")
	)
	(segment
		(start 9.0043 -106.709464)
		(end 10.2616 -107.966764)
		(width 0.127)
		(layer "In5.Cu")
		(net "BMC_I2C1_MINI1_SDA")
	)
	(segment
		(start 8.674862 -95.736664)
		(end 9.0043 -96.066102)
		(width 0.127)
		(layer "In5.Cu")
		(net "BMC_I2C1_MINI1_SDA")
	)
	(segment
		(start 9.0043 -96.066102)
		(end 9.0043 -106.709464)
		(width 0.127)
		(layer "In5.Cu")
		(net "BMC_I2C1_MINI1_SDA")
	)
	(segment
		(start 10.2616 -107.966764)
		(end 10.2616 -118.52402)
		(width 0.127)
		(layer "In5.Cu")
		(net "BMC_I2C1_MINI1_SDA")
	)
	(segment
		(start 10.2616 -118.52402)
		(end 10.970768 -119.233442)
		(width 0.127)
		(layer "In5.Cu")
		(net "BMC_I2C1_MINI1_SDA")
	)
	(segment
		(start 11.750548 -119.773192)
		(end 11.564874 -120.4976)
		(width 0.127)
		(layer "In5.Cu")
		(net "BMC_I2C1_MINI1_SDA")
	)
	(segment
		(start 10.970768 -119.233442)
		(end 11.324844 -119.587264)
		(width 0.127)
		(layer "In5.Cu")
		(net "BMC_I2C1_MINI1_SDA")
	)
	(segment
		(start 11.6586 -119.61876)
		(end 11.750548 -119.773192)
		(width 0.127)
		(layer "In5.Cu")
		(net "BMC_I2C1_MINI1_SDA")
	)
	(segment
		(start 12.124436 -118.392448)
		(end 12.446 -118.714012)
		(width 0.12065)
		(layer "F.Cu")
		(net "BMC_I2C1_MINI1_SCL")
	)
	(segment
		(start 12.1539 -120.2055)
		(end 11.6586 -119.7102)
		(width 0.12065)
		(layer "F.Cu")
		(net "BMC_I2C1_MINI1_SCL")
	)
	(segment
		(start 12.446 -118.714012)
		(end 12.446 -119.2276)
		(width 0.12065)
		(layer "F.Cu")
		(net "BMC_I2C1_MINI1_SCL")
	)
	(segment
		(start 12.446 -120.2055)
		(end 12.1539 -120.2055)
		(width 0.12065)
		(layer "F.Cu")
		(net "BMC_I2C1_MINI1_SCL")
	)
	(segment
		(start 12.446 -119.2276)
		(end 12.446 -120.2055)
		(width 0.12065)
		(layer "F.Cu")
		(net "BMC_I2C1_MINI1_SCL")
	)
	(segment
		(start 12.124436 -118.311168)
		(end 12.124436 -118.392448)
		(width 0.12065)
		(layer "F.Cu")
		(net "BMC_I2C1_MINI1_SCL")
	)
	(segment
		(start 11.6586 -119.7102)
		(end 10.93724 -119.7102)
		(width 0.12065)
		(layer "F.Cu")
		(net "BMC_I2C1_MINI1_SCL")
	)
	(via
		(at 12.446 -119.2276)
		(size 0.7112)
		(drill 0.3556)
		(layers "F.Cu" "B.Cu")
		(net "BMC_I2C1_MINI1_SCL")
	)
	(via
		(at 12.124436 -118.311168)
		(size 0.508)
		(drill 0.254)
		(layers "F.Cu" "B.Cu")
		(net "BMC_I2C1_MINI1_SCL")
	)
	(via
		(at 52.28336 -82.646774)
		(size 0.508)
		(drill 0.254)
		(layers "F.Cu" "B.Cu")
		(net "BMC_I2C1_MINI1_SCL")
	)
	(via
		(at 9.783572 -95.736664)
		(size 0.508)
		(drill 0.254)
		(layers "F.Cu" "B.Cu")
		(net "BMC_I2C1_MINI1_SCL")
	)
	(segment
		(start 129.783332 -31.740348)
		(end 130.50393 -31.01975)
		(width 0.12065)
		(layer "B.Cu")
		(net "BMC_I2C1_MINI1_SCL")
	)
	(segment
		(start 133.134354 -21.928582)
		(end 133.134354 -21.530056)
		(width 0.12065)
		(layer "B.Cu")
		(net "BMC_I2C1_MINI1_SCL")
	)
	(segment
		(start 69.216778 -74.294746)
		(end 81.960974 -61.55055)
		(width 0.12065)
		(layer "B.Cu")
		(net "BMC_I2C1_MINI1_SCL")
	)
	(segment
		(start 119.175784 -33.285938)
		(end 122.735086 -33.285938)
		(width 0.12065)
		(layer "B.Cu")
		(net "BMC_I2C1_MINI1_SCL")
	)
	(segment
		(start 91.338146 -59.209178)
		(end 91.338146 -50.115724)
		(width 0.12065)
		(layer "B.Cu")
		(net "BMC_I2C1_MINI1_SCL")
	)
	(segment
		(start 118.331996 -32.44215)
		(end 119.175784 -33.285938)
		(width 0.12065)
		(layer "B.Cu")
		(net "BMC_I2C1_MINI1_SCL")
	)
	(segment
		(start 64.986916 -76.2508)
		(end 66.94297 -74.294746)
		(width 0.12065)
		(layer "B.Cu")
		(net "BMC_I2C1_MINI1_SCL")
	)
	(segment
		(start 130.50393 -31.01975)
		(end 130.50393 -29.715206)
		(width 0.12065)
		(layer "B.Cu")
		(net "BMC_I2C1_MINI1_SCL")
	)
	(segment
		(start 57.659524 -76.2508)
		(end 64.986916 -76.2508)
		(width 0.12065)
		(layer "B.Cu")
		(net "BMC_I2C1_MINI1_SCL")
	)
	(segment
		(start 125.28804 -35.838892)
		(end 125.288294 -35.838892)
		(width 0.12065)
		(layer "B.Cu")
		(net "BMC_I2C1_MINI1_SCL")
	)
	(segment
		(start 88.996774 -61.55055)
		(end 91.338146 -59.209178)
		(width 0.12065)
		(layer "B.Cu")
		(net "BMC_I2C1_MINI1_SCL")
	)
	(segment
		(start 99.59467 -41.8592)
		(end 101.5238 -41.8592)
		(width 0.12065)
		(layer "B.Cu")
		(net "BMC_I2C1_MINI1_SCL")
	)
	(segment
		(start 130.50393 -29.715206)
		(end 130.9751 -29.244036)
		(width 0.12065)
		(layer "B.Cu")
		(net "BMC_I2C1_MINI1_SCL")
	)
	(segment
		(start 81.960974 -61.55055)
		(end 88.996774 -61.55055)
		(width 0.12065)
		(layer "B.Cu")
		(net "BMC_I2C1_MINI1_SCL")
	)
	(segment
		(start 130.9751 -29.244036)
		(end 130.9751 -24.087836)
		(width 0.12065)
		(layer "B.Cu")
		(net "BMC_I2C1_MINI1_SCL")
	)
	(segment
		(start 128.451864 -35.8394)
		(end 129.783332 -34.507932)
		(width 0.12065)
		(layer "B.Cu")
		(net "BMC_I2C1_MINI1_SCL")
	)
	(segment
		(start 66.94297 -74.294746)
		(end 69.216778 -74.294746)
		(width 0.12065)
		(layer "B.Cu")
		(net "BMC_I2C1_MINI1_SCL")
	)
	(segment
		(start 110.94085 -32.44215)
		(end 118.331996 -32.44215)
		(width 0.12065)
		(layer "B.Cu")
		(net "BMC_I2C1_MINI1_SCL")
	)
	(segment
		(start 125.288802 -35.8394)
		(end 128.451864 -35.8394)
		(width 0.12065)
		(layer "B.Cu")
		(net "BMC_I2C1_MINI1_SCL")
	)
	(segment
		(start 52.28336 -82.646774)
		(end 52.578 -82.352134)
		(width 0.12065)
		(layer "B.Cu")
		(net "BMC_I2C1_MINI1_SCL")
	)
	(segment
		(start 91.338146 -50.115724)
		(end 99.59467 -41.8592)
		(width 0.12065)
		(layer "B.Cu")
		(net "BMC_I2C1_MINI1_SCL")
	)
	(segment
		(start 52.578 -82.352134)
		(end 52.578 -81.332324)
		(width 0.12065)
		(layer "B.Cu")
		(net "BMC_I2C1_MINI1_SCL")
	)
	(segment
		(start 129.783332 -34.507932)
		(end 129.783332 -31.740348)
		(width 0.12065)
		(layer "B.Cu")
		(net "BMC_I2C1_MINI1_SCL")
	)
	(segment
		(start 101.5238 -41.8592)
		(end 110.94085 -32.44215)
		(width 0.12065)
		(layer "B.Cu")
		(net "BMC_I2C1_MINI1_SCL")
	)
	(segment
		(start 122.735086 -33.285938)
		(end 125.28804 -35.838892)
		(width 0.12065)
		(layer "B.Cu")
		(net "BMC_I2C1_MINI1_SCL")
	)
	(segment
		(start 130.9751 -24.087836)
		(end 133.134354 -21.928582)
		(width 0.12065)
		(layer "B.Cu")
		(net "BMC_I2C1_MINI1_SCL")
	)
	(segment
		(start 52.578 -81.332324)
		(end 57.659524 -76.2508)
		(width 0.12065)
		(layer "B.Cu")
		(net "BMC_I2C1_MINI1_SCL")
	)
	(segment
		(start 125.288294 -35.838892)
		(end 125.288802 -35.8394)
		(width 0.12065)
		(layer "B.Cu")
		(net "BMC_I2C1_MINI1_SCL")
	)
	(segment
		(start 41.682416 -83.9216)
		(end 42.39768 -83.206336)
		(width 0.127)
		(layer "In2.Cu")
		(net "BMC_I2C1_MINI1_SCL")
	)
	(segment
		(start 42.39768 -83.206336)
		(end 44.197524 -83.206336)
		(width 0.127)
		(layer "In2.Cu")
		(net "BMC_I2C1_MINI1_SCL")
	)
	(segment
		(start 19.63801 -86.6902)
		(end 22.563836 -86.6902)
		(width 0.127)
		(layer "In2.Cu")
		(net "BMC_I2C1_MINI1_SCL")
	)
	(segment
		(start 44.197524 -83.206336)
		(end 45.66666 -81.7372)
		(width 0.127)
		(layer "In2.Cu")
		(net "BMC_I2C1_MINI1_SCL")
	)
	(segment
		(start 9.0424 -94.462346)
		(end 9.0424 -93.802454)
		(width 0.127)
		(layer "In2.Cu")
		(net "BMC_I2C1_MINI1_SCL")
	)
	(segment
		(start 50.619914 -81.49082)
		(end 52.048156 -81.49082)
		(width 0.127)
		(layer "In2.Cu")
		(net "BMC_I2C1_MINI1_SCL")
	)
	(segment
		(start 24.1427 -85.111336)
		(end 24.1427 -84.652866)
		(width 0.127)
		(layer "In2.Cu")
		(net "BMC_I2C1_MINI1_SCL")
	)
	(segment
		(start 22.563836 -86.6902)
		(end 24.1427 -85.111336)
		(width 0.127)
		(layer "In2.Cu")
		(net "BMC_I2C1_MINI1_SCL")
	)
	(segment
		(start 10.07237 -92.771976)
		(end 12.614148 -92.771976)
		(width 0.127)
		(layer "In2.Cu")
		(net "BMC_I2C1_MINI1_SCL")
	)
	(segment
		(start 16.139922 -89.2302)
		(end 17.018762 -89.2302)
		(width 0.127)
		(layer "In2.Cu")
		(net "BMC_I2C1_MINI1_SCL")
	)
	(segment
		(start 18.136362 -88.1126)
		(end 18.21561 -88.1126)
		(width 0.127)
		(layer "In2.Cu")
		(net "BMC_I2C1_MINI1_SCL")
	)
	(segment
		(start 52.048156 -81.49082)
		(end 52.5526 -81.995264)
		(width 0.127)
		(layer "In2.Cu")
		(net "BMC_I2C1_MINI1_SCL")
	)
	(segment
		(start 52.5526 -82.377534)
		(end 52.28336 -82.646774)
		(width 0.127)
		(layer "In2.Cu")
		(net "BMC_I2C1_MINI1_SCL")
	)
	(segment
		(start 24.1427 -84.652866)
		(end 25.559766 -83.2358)
		(width 0.127)
		(layer "In2.Cu")
		(net "BMC_I2C1_MINI1_SCL")
	)
	(segment
		(start 9.783572 -95.736664)
		(end 9.4488 -95.401892)
		(width 0.127)
		(layer "In2.Cu")
		(net "BMC_I2C1_MINI1_SCL")
	)
	(segment
		(start 35.357308 -83.9216)
		(end 41.682416 -83.9216)
		(width 0.127)
		(layer "In2.Cu")
		(net "BMC_I2C1_MINI1_SCL")
	)
	(segment
		(start 49.953672 -80.824578)
		(end 50.619914 -81.49082)
		(width 0.127)
		(layer "In2.Cu")
		(net "BMC_I2C1_MINI1_SCL")
	)
	(segment
		(start 52.5526 -81.995264)
		(end 52.5526 -82.377534)
		(width 0.127)
		(layer "In2.Cu")
		(net "BMC_I2C1_MINI1_SCL")
	)
	(segment
		(start 47.80534 -80.824578)
		(end 49.953672 -80.824578)
		(width 0.127)
		(layer "In2.Cu")
		(net "BMC_I2C1_MINI1_SCL")
	)
	(segment
		(start 17.018762 -89.2302)
		(end 18.136362 -88.1126)
		(width 0.127)
		(layer "In2.Cu")
		(net "BMC_I2C1_MINI1_SCL")
	)
	(segment
		(start 9.4488 -95.401892)
		(end 9.4488 -94.868746)
		(width 0.127)
		(layer "In2.Cu")
		(net "BMC_I2C1_MINI1_SCL")
	)
	(segment
		(start 14.972284 -90.41384)
		(end 14.972284 -90.397838)
		(width 0.127)
		(layer "In2.Cu")
		(net "BMC_I2C1_MINI1_SCL")
	)
	(segment
		(start 9.0424 -93.802454)
		(end 10.07237 -92.771976)
		(width 0.127)
		(layer "In2.Cu")
		(net "BMC_I2C1_MINI1_SCL")
	)
	(segment
		(start 12.614148 -92.771976)
		(end 14.972284 -90.41384)
		(width 0.127)
		(layer "In2.Cu")
		(net "BMC_I2C1_MINI1_SCL")
	)
	(segment
		(start 45.66666 -81.7372)
		(end 46.892718 -81.7372)
		(width 0.127)
		(layer "In2.Cu")
		(net "BMC_I2C1_MINI1_SCL")
	)
	(segment
		(start 18.21561 -88.1126)
		(end 19.63801 -86.6902)
		(width 0.127)
		(layer "In2.Cu")
		(net "BMC_I2C1_MINI1_SCL")
	)
	(segment
		(start 9.4488 -94.868746)
		(end 9.0424 -94.462346)
		(width 0.127)
		(layer "In2.Cu")
		(net "BMC_I2C1_MINI1_SCL")
	)
	(segment
		(start 34.671508 -83.2358)
		(end 35.357308 -83.9216)
		(width 0.127)
		(layer "In2.Cu")
		(net "BMC_I2C1_MINI1_SCL")
	)
	(segment
		(start 25.559766 -83.2358)
		(end 34.671508 -83.2358)
		(width 0.127)
		(layer "In2.Cu")
		(net "BMC_I2C1_MINI1_SCL")
	)
	(segment
		(start 14.972284 -90.397838)
		(end 16.139922 -89.2302)
		(width 0.127)
		(layer "In2.Cu")
		(net "BMC_I2C1_MINI1_SCL")
	)
	(segment
		(start 46.892718 -81.7372)
		(end 47.80534 -80.824578)
		(width 0.127)
		(layer "In2.Cu")
		(net "BMC_I2C1_MINI1_SCL")
	)
	(segment
		(start 9.783572 -95.736664)
		(end 9.5123 -96.007936)
		(width 0.127)
		(layer "In5.Cu")
		(net "BMC_I2C1_MINI1_SCL")
	)
	(segment
		(start 11.513058 -119.056912)
		(end 11.661648 -119.095012)
		(width 0.127)
		(layer "In5.Cu")
		(net "BMC_I2C1_MINI1_SCL")
	)
	(segment
		(start 10.7696 -107.756198)
		(end 10.7696 -118.313454)
		(width 0.127)
		(layer "In5.Cu")
		(net "BMC_I2C1_MINI1_SCL")
	)
	(segment
		(start 10.7696 -118.313454)
		(end 11.513058 -119.056912)
		(width 0.127)
		(layer "In5.Cu")
		(net "BMC_I2C1_MINI1_SCL")
	)
	(segment
		(start 9.5123 -106.498898)
		(end 10.7696 -107.756198)
		(width 0.127)
		(layer "In5.Cu")
		(net "BMC_I2C1_MINI1_SCL")
	)
	(segment
		(start 11.661648 -119.095012)
		(end 11.784584 -119.126508)
		(width 0.127)
		(layer "In5.Cu")
		(net "BMC_I2C1_MINI1_SCL")
	)
	(segment
		(start 11.939016 -119.035068)
		(end 12.124436 -118.311168)
		(width 0.127)
		(layer "In5.Cu")
		(net "BMC_I2C1_MINI1_SCL")
	)
	(segment
		(start 11.784584 -119.126508)
		(end 11.939016 -119.035068)
		(width 0.127)
		(layer "In5.Cu")
		(net "BMC_I2C1_MINI1_SCL")
	)
	(segment
		(start 9.5123 -96.007936)
		(end 9.5123 -106.498898)
		(width 0.127)
		(layer "In5.Cu")
		(net "BMC_I2C1_MINI1_SCL")
	)
	(segment
		(start 49.110138 -143.06423)
		(end 49.110138 -142.33525)
		(width 0.12065)
		(layer "F.Cu")
		(net "BMC_FW_DET_BOARD_VER_2")
	)
	(segment
		(start 49.110138 -142.33525)
		(end 48.525684 -141.750796)
		(width 0.12065)
		(layer "F.Cu")
		(net "BMC_FW_DET_BOARD_VER_2")
	)
	(segment
		(start 50.122836 -144.076928)
		(end 49.110138 -143.06423)
		(width 0.12065)
		(layer "F.Cu")
		(net "BMC_FW_DET_BOARD_VER_2")
	)
	(segment
		(start 50.165 -144.14246)
		(end 50.122836 -144.100296)
		(width 0.12065)
		(layer "F.Cu")
		(net "BMC_FW_DET_BOARD_VER_2")
	)
	(segment
		(start 50.122836 -144.100296)
		(end 50.122836 -144.076928)
		(width 0.12065)
		(layer "F.Cu")
		(net "BMC_FW_DET_BOARD_VER_2")
	)
	(segment
		(start 48.50384 -141.750796)
		(end 45.70476 -138.951716)
		(width 0.12065)
		(layer "F.Cu")
		(net "BMC_FW_DET_BOARD_VER_2")
	)
	(segment
		(start 48.525684 -141.750796)
		(end 48.50384 -141.750796)
		(width 0.12065)
		(layer "F.Cu")
		(net "BMC_FW_DET_BOARD_VER_2")
	)
	(segment
		(start 45.70476 -138.951716)
		(end 45.70476 -138.884914)
		(width 0.12065)
		(layer "F.Cu")
		(net "BMC_FW_DET_BOARD_VER_2")
	)
	(segment
		(start 50.165 -144.851628)
		(end 50.165 -144.14246)
		(width 0.12065)
		(layer "F.Cu")
		(net "BMC_FW_DET_BOARD_VER_2")
	)
	(via
		(at 50.122836 -144.076928)
		(size 0.508)
		(drill 0.254)
		(layers "F.Cu" "B.Cu")
		(net "BMC_FW_DET_BOARD_VER_2")
	)
	(via
		(at 49.1744 -144.7292)
		(size 0.7112)
		(drill 0.3556)
		(layers "F.Cu" "B.Cu")
		(net "BMC_FW_DET_BOARD_VER_2")
	)
	(segment
		(start 49.4157 -144.9705)
		(end 50.165 -144.9705)
		(width 0.12065)
		(layer "B.Cu")
		(net "BMC_FW_DET_BOARD_VER_2")
	)
	(segment
		(start 49.1744 -144.4244)
		(end 49.1744 -144.7292)
		(width 0.12065)
		(layer "B.Cu")
		(net "BMC_FW_DET_BOARD_VER_2")
	)
	(segment
		(start 49.521872 -144.076928)
		(end 49.1744 -144.4244)
		(width 0.12065)
		(layer "B.Cu")
		(net "BMC_FW_DET_BOARD_VER_2")
	)
	(segment
		(start 50.122836 -144.076928)
		(end 49.521872 -144.076928)
		(width 0.12065)
		(layer "B.Cu")
		(net "BMC_FW_DET_BOARD_VER_2")
	)
	(segment
		(start 49.1744 -144.7292)
		(end 49.4157 -144.9705)
		(width 0.12065)
		(layer "B.Cu")
		(net "BMC_FW_DET_BOARD_VER_2")
	)
	(segment
		(start 49.652428 -142.815056)
		(end 49.982628 -143.145256)
		(width 0.12065)
		(layer "F.Cu")
		(net "BMC_FW_DET_BOARD_VER_1")
	)
	(segment
		(start 50.312828 -143.480028)
		(end 50.312828 -143.475456)
		(width 0.12065)
		(layer "F.Cu")
		(net "BMC_FW_DET_BOARD_VER_1")
	)
	(segment
		(start 46.114208 -139.046712)
		(end 46.513496 -139.446)
		(width 0.12065)
		(layer "F.Cu")
		(net "BMC_FW_DET_BOARD_VER_1")
	)
	(segment
		(start 51.181 -144.851628)
		(end 51.181 -144.3482)
		(width 0.12065)
		(layer "F.Cu")
		(net "BMC_FW_DET_BOARD_VER_1")
	)
	(segment
		(start 51.181 -144.3482)
		(end 50.312828 -143.480028)
		(width 0.12065)
		(layer "F.Cu")
		(net "BMC_FW_DET_BOARD_VER_1")
	)
	(segment
		(start 46.513496 -139.446)
		(end 46.711108 -139.446)
		(width 0.12065)
		(layer "F.Cu")
		(net "BMC_FW_DET_BOARD_VER_1")
	)
	(segment
		(start 49.472088 -142.20698)
		(end 49.652428 -142.38732)
		(width 0.12065)
		(layer "F.Cu")
		(net "BMC_FW_DET_BOARD_VER_1")
	)
	(segment
		(start 45.561758 -138.494262)
		(end 45.866558 -138.494262)
		(width 0.12065)
		(layer "F.Cu")
		(net "BMC_FW_DET_BOARD_VER_1")
	)
	(segment
		(start 49.652428 -142.38732)
		(end 49.652428 -142.815056)
		(width 0.12065)
		(layer "F.Cu")
		(net "BMC_FW_DET_BOARD_VER_1")
	)
	(segment
		(start 49.015904 -141.750796)
		(end 49.037748 -141.750796)
		(width 0.12065)
		(layer "F.Cu")
		(net "BMC_FW_DET_BOARD_VER_1")
	)
	(segment
		(start 45.866558 -138.494262)
		(end 46.114208 -138.741912)
		(width 0.12065)
		(layer "F.Cu")
		(net "BMC_FW_DET_BOARD_VER_1")
	)
	(segment
		(start 45.15231 -138.084814)
		(end 45.561758 -138.494262)
		(width 0.12065)
		(layer "F.Cu")
		(net "BMC_FW_DET_BOARD_VER_1")
	)
	(segment
		(start 46.114208 -138.741912)
		(end 46.114208 -139.046712)
		(width 0.12065)
		(layer "F.Cu")
		(net "BMC_FW_DET_BOARD_VER_1")
	)
	(segment
		(start 49.472088 -142.185136)
		(end 49.472088 -142.20698)
		(width 0.12065)
		(layer "F.Cu")
		(net "BMC_FW_DET_BOARD_VER_1")
	)
	(segment
		(start 46.711108 -139.446)
		(end 49.015904 -141.750796)
		(width 0.12065)
		(layer "F.Cu")
		(net "BMC_FW_DET_BOARD_VER_1")
	)
	(segment
		(start 49.037748 -141.750796)
		(end 49.472088 -142.185136)
		(width 0.12065)
		(layer "F.Cu")
		(net "BMC_FW_DET_BOARD_VER_1")
	)
	(segment
		(start 50.312828 -143.475456)
		(end 49.982628 -143.145256)
		(width 0.12065)
		(layer "F.Cu")
		(net "BMC_FW_DET_BOARD_VER_1")
	)
	(segment
		(start 44.904914 -138.084814)
		(end 45.15231 -138.084814)
		(width 0.12065)
		(layer "F.Cu")
		(net "BMC_FW_DET_BOARD_VER_1")
	)
	(via
		(at 51.162966 -144.017238)
		(size 0.7112)
		(drill 0.3556)
		(layers "F.Cu" "B.Cu")
		(net "BMC_FW_DET_BOARD_VER_1")
	)
	(via
		(at 49.982628 -143.145256)
		(size 0.508)
		(drill 0.254)
		(layers "F.Cu" "B.Cu")
		(net "BMC_FW_DET_BOARD_VER_1")
	)
	(segment
		(start 49.982628 -143.145256)
		(end 50.312828 -143.475456)
		(width 0.12065)
		(layer "B.Cu")
		(net "BMC_FW_DET_BOARD_VER_1")
	)
	(segment
		(start 51.162966 -144.017238)
		(end 51.181 -144.035272)
		(width 0.12065)
		(layer "B.Cu")
		(net "BMC_FW_DET_BOARD_VER_1")
	)
	(segment
		(start 50.760884 -143.615156)
		(end 51.162966 -144.017238)
		(width 0.12065)
		(layer "B.Cu")
		(net "BMC_FW_DET_BOARD_VER_1")
	)
	(segment
		(start 50.312828 -143.475456)
		(end 50.548286 -143.475456)
		(width 0.12065)
		(layer "B.Cu")
		(net "BMC_FW_DET_BOARD_VER_1")
	)
	(segment
		(start 51.181 -144.035272)
		(end 51.181 -144.9705)
		(width 0.12065)
		(layer "B.Cu")
		(net "BMC_FW_DET_BOARD_VER_1")
	)
	(segment
		(start 50.548286 -143.475456)
		(end 50.687986 -143.615156)
		(width 0.12065)
		(layer "B.Cu")
		(net "BMC_FW_DET_BOARD_VER_1")
	)
	(segment
		(start 50.687986 -143.615156)
		(end 50.760884 -143.615156)
		(width 0.12065)
		(layer "B.Cu")
		(net "BMC_FW_DET_BOARD_VER_1")
	)
	(segment
		(start 50.009044 -139.596368)
		(end 50.231802 -139.819126)
		(width 0.12065)
		(layer "F.Cu")
		(net "BMC_FW_DET_BOARD_VER_0")
	)
	(segment
		(start 50.231802 -139.819126)
		(end 50.769266 -139.819126)
		(width 0.12065)
		(layer "F.Cu")
		(net "BMC_FW_DET_BOARD_VER_0")
	)
	(segment
		(start 47.145702 -136.894316)
		(end 49.847754 -139.596368)
		(width 0.12065)
		(layer "F.Cu")
		(net "BMC_FW_DET_BOARD_VER_0")
	)
	(segment
		(start 50.8 -139.807696)
		(end 51.149504 -139.807696)
		(width 0.12065)
		(layer "F.Cu")
		(net "BMC_FW_DET_BOARD_VER_0")
	)
	(segment
		(start 45.15231 -137.284968)
		(end 45.542962 -136.894316)
		(width 0.12065)
		(layer "F.Cu")
		(net "BMC_FW_DET_BOARD_VER_0")
	)
	(segment
		(start 50.769266 -139.819126)
		(end 50.780696 -139.807696)
		(width 0.12065)
		(layer "F.Cu")
		(net "BMC_FW_DET_BOARD_VER_0")
	)
	(segment
		(start 50.780696 -139.807696)
		(end 50.8 -139.807696)
		(width 0.12065)
		(layer "F.Cu")
		(net "BMC_FW_DET_BOARD_VER_0")
	)
	(segment
		(start 45.542962 -136.894316)
		(end 47.145702 -136.894316)
		(width 0.12065)
		(layer "F.Cu")
		(net "BMC_FW_DET_BOARD_VER_0")
	)
	(segment
		(start 51.7525 -139.319)
		(end 53.2765 -140.843)
		(width 0.12065)
		(layer "F.Cu")
		(net "BMC_FW_DET_BOARD_VER_0")
	)
	(segment
		(start 44.904914 -137.284968)
		(end 45.15231 -137.284968)
		(width 0.12065)
		(layer "F.Cu")
		(net "BMC_FW_DET_BOARD_VER_0")
	)
	(segment
		(start 49.847754 -139.596368)
		(end 50.009044 -139.596368)
		(width 0.12065)
		(layer "F.Cu")
		(net "BMC_FW_DET_BOARD_VER_0")
	)
	(segment
		(start 51.6382 -139.319)
		(end 51.7525 -139.319)
		(width 0.12065)
		(layer "F.Cu")
		(net "BMC_FW_DET_BOARD_VER_0")
	)
	(segment
		(start 51.149504 -139.807696)
		(end 51.6382 -139.319)
		(width 0.12065)
		(layer "F.Cu")
		(net "BMC_FW_DET_BOARD_VER_0")
	)
	(via
		(at 50.8 -139.807696)
		(size 0.7112)
		(drill 0.3556)
		(layers "F.Cu" "B.Cu")
		(net "BMC_FW_DET_BOARD_VER_0")
	)
	(via
		(at 51.6382 -139.319)
		(size 0.508)
		(drill 0.254)
		(layers "F.Cu" "B.Cu")
		(net "BMC_FW_DET_BOARD_VER_0")
	)
	(segment
		(start 53.2765 -139.827)
		(end 52.1462 -139.827)
		(width 0.12065)
		(layer "B.Cu")
		(net "BMC_FW_DET_BOARD_VER_0")
	)
	(segment
		(start 52.1462 -139.827)
		(end 51.6382 -139.319)
		(width 0.12065)
		(layer "B.Cu")
		(net "BMC_FW_DET_BOARD_VER_0")
	)
	(segment
		(start 191.61887 -7.75843)
		(end 192.072768 -7.75843)
		(width 0.12065)
		(layer "F.Cu")
		(net "BMC_ENCLOSURE_LED_R")
	)
	(segment
		(start 192.229232 -8.799068)
		(end 192.229232 -7.914894)
		(width 0.12065)
		(layer "F.Cu")
		(net "BMC_ENCLOSURE_LED_R")
	)
	(segment
		(start 191.4525 -7.9248)
		(end 191.61887 -7.75843)
		(width 0.12065)
		(layer "F.Cu")
		(net "BMC_ENCLOSURE_LED_R")
	)
	(segment
		(start 192.1129 -8.9154)
		(end 192.229232 -8.799068)
		(width 0.12065)
		(layer "F.Cu")
		(net "BMC_ENCLOSURE_LED_R")
	)
	(segment
		(start 190.4365 -7.9248)
		(end 191.4525 -7.9248)
		(width 0.12065)
		(layer "F.Cu")
		(net "BMC_ENCLOSURE_LED_R")
	)
	(segment
		(start 192.072768 -7.75843)
		(end 192.16751 -7.853172)
		(width 0.12065)
		(layer "F.Cu")
		(net "BMC_ENCLOSURE_LED_R")
	)
	(segment
		(start 192.229232 -7.914894)
		(end 192.16751 -7.853172)
		(width 0.12065)
		(layer "F.Cu")
		(net "BMC_ENCLOSURE_LED_R")
	)
	(via
		(at 192.16751 -7.853172)
		(size 0.7112)
		(drill 0.3556)
		(layers "F.Cu" "B.Cu")
		(net "BMC_ENCLOSURE_LED_R")
	)
	(segment
		(start 193.0019 -8.9154)
		(end 193.0019 -8.428228)
		(width 0.12065)
		(layer "F.Cu")
		(net "BMC_ENCLOSURE_LED")
	)
	(segment
		(start 193.456052 -7.974076)
		(end 193.456052 -5.949188)
		(width 0.12065)
		(layer "F.Cu")
		(net "BMC_ENCLOSURE_LED")
	)
	(segment
		(start 43.779948 -140.990828)
		(end 43.779948 -147.792948)
		(width 0.12065)
		(layer "F.Cu")
		(net "BMC_ENCLOSURE_LED")
	)
	(segment
		(start 45.005498 -148.59)
		(end 45.974 -148.59)
		(width 0.12065)
		(layer "F.Cu")
		(net "BMC_ENCLOSURE_LED")
	)
	(segment
		(start 185.60542 2.4511)
		(end 185.01233 1.85801)
		(width 0.12065)
		(layer "F.Cu")
		(net "BMC_ENCLOSURE_LED")
	)
	(segment
		(start 193.0019 -8.428228)
		(end 193.456052 -7.974076)
		(width 0.12065)
		(layer "F.Cu")
		(net "BMC_ENCLOSURE_LED")
	)
	(segment
		(start 192.437004 -4.93014)
		(end 192.437004 -3.4544)
		(width 0.12065)
		(layer "F.Cu")
		(net "BMC_ENCLOSURE_LED")
	)
	(segment
		(start 44.577 -148.59)
		(end 45.005498 -148.59)
		(width 0.12065)
		(layer "F.Cu")
		(net "BMC_ENCLOSURE_LED")
	)
	(segment
		(start 190.939166 1.387094)
		(end 189.87516 2.4511)
		(width 0.12065)
		(layer "F.Cu")
		(net "BMC_ENCLOSURE_LED")
	)
	(segment
		(start 192.437004 -3.4544)
		(end 190.939166 -1.956562)
		(width 0.12065)
		(layer "F.Cu")
		(net "BMC_ENCLOSURE_LED")
	)
	(segment
		(start 189.87516 2.4511)
		(end 185.60542 2.4511)
		(width 0.12065)
		(layer "F.Cu")
		(net "BMC_ENCLOSURE_LED")
	)
	(segment
		(start 190.939166 -1.956562)
		(end 190.939166 1.387094)
		(width 0.12065)
		(layer "F.Cu")
		(net "BMC_ENCLOSURE_LED")
	)
	(segment
		(start 41.704768 -138.884914)
		(end 41.704768 -138.915648)
		(width 0.12065)
		(layer "F.Cu")
		(net "BMC_ENCLOSURE_LED")
	)
	(segment
		(start 45.005498 -148.59)
		(end 45.005498 -148.904706)
		(width 0.12065)
		(layer "F.Cu")
		(net "BMC_ENCLOSURE_LED")
	)
	(segment
		(start 193.456052 -5.949188)
		(end 192.437004 -4.93014)
		(width 0.12065)
		(layer "F.Cu")
		(net "BMC_ENCLOSURE_LED")
	)
	(segment
		(start 43.779948 -147.792948)
		(end 44.577 -148.59)
		(width 0.12065)
		(layer "F.Cu")
		(net "BMC_ENCLOSURE_LED")
	)
	(segment
		(start 41.704768 -138.915648)
		(end 43.779948 -140.990828)
		(width 0.12065)
		(layer "F.Cu")
		(net "BMC_ENCLOSURE_LED")
	)
	(via
		(at 45.974 -148.59)
		(size 0.508)
		(drill 0.254)
		(layers "F.Cu" "B.Cu")
		(net "BMC_ENCLOSURE_LED")
	)
	(via
		(at 75.2348 -143.9926)
		(size 0.508)
		(drill 0.254)
		(layers "F.Cu" "B.Cu")
		(net "BMC_ENCLOSURE_LED")
	)
	(via
		(at 185.01233 1.85801)
		(size 0.508)
		(drill 0.254)
		(layers "F.Cu" "B.Cu")
		(net "BMC_ENCLOSURE_LED")
	)
	(via
		(at 79.218028 -78.8797)
		(size 0.508)
		(drill 0.254)
		(layers "F.Cu" "B.Cu")
		(net "BMC_ENCLOSURE_LED")
	)
	(via
		(at 45.005498 -148.904706)
		(size 0.7112)
		(drill 0.3556)
		(layers "F.Cu" "B.Cu")
		(net "BMC_ENCLOSURE_LED")
	)
	(segment
		(start 79.718408 -78.8797)
		(end 80.466946 -78.131162)
		(width 0.127)
		(layer "In2.Cu")
		(net "BMC_ENCLOSURE_LED")
	)
	(segment
		(start 95.0722 -65.67932)
		(end 95.0722 -52.585874)
		(width 0.127)
		(layer "In2.Cu")
		(net "BMC_ENCLOSURE_LED")
	)
	(segment
		(start 50.797206 -150.3934)
		(end 47.797212 -150.3934)
		(width 0.127)
		(layer "In2.Cu")
		(net "BMC_ENCLOSURE_LED")
	)
	(segment
		(start 83.044284 -76.8096)
		(end 83.94192 -76.8096)
		(width 0.127)
		(layer "In2.Cu")
		(net "BMC_ENCLOSURE_LED")
	)
	(segment
		(start 184.656222 2.01549)
		(end 184.813702 1.85801)
		(width 0.127)
		(layer "In2.Cu")
		(net "BMC_ENCLOSURE_LED")
	)
	(segment
		(start 95.072454 -52.270152)
		(end 93.34119 -50.538888)
		(width 0.127)
		(layer "In2.Cu")
		(net "BMC_ENCLOSURE_LED")
	)
	(segment
		(start 93.34119 -50.538888)
		(end 93.34119 -33.245806)
		(width 0.127)
		(layer "In2.Cu")
		(net "BMC_ENCLOSURE_LED")
	)
	(segment
		(start 84.4169 -76.334366)
		(end 84.4169 -75.903582)
		(width 0.127)
		(layer "In2.Cu")
		(net "BMC_ENCLOSURE_LED")
	)
	(segment
		(start 80.466946 -78.131162)
		(end 81.722722 -78.131162)
		(width 0.127)
		(layer "In2.Cu")
		(net "BMC_ENCLOSURE_LED")
	)
	(segment
		(start 66.7893 -146.2659)
		(end 65.4812 -147.574)
		(width 0.127)
		(layer "In2.Cu")
		(net "BMC_ENCLOSURE_LED")
	)
	(segment
		(start 81.722722 -78.131162)
		(end 83.044284 -76.8096)
		(width 0.127)
		(layer "In2.Cu")
		(net "BMC_ENCLOSURE_LED")
	)
	(segment
		(start 62.103 -147.574)
		(end 59.309 -150.368)
		(width 0.127)
		(layer "In2.Cu")
		(net "BMC_ENCLOSURE_LED")
	)
	(segment
		(start 93.34119 -33.245806)
		(end 120.32361 -6.263386)
		(width 0.127)
		(layer "In2.Cu")
		(net "BMC_ENCLOSURE_LED")
	)
	(segment
		(start 84.691982 -75.6285)
		(end 85.122766 -75.6285)
		(width 0.127)
		(layer "In2.Cu")
		(net "BMC_ENCLOSURE_LED")
	)
	(segment
		(start 120.32361 -6.263386)
		(end 121.240042 -6.263386)
		(width 0.127)
		(layer "In2.Cu")
		(net "BMC_ENCLOSURE_LED")
	)
	(segment
		(start 50.822606 -150.368)
		(end 50.797206 -150.3934)
		(width 0.127)
		(layer "In2.Cu")
		(net "BMC_ENCLOSURE_LED")
	)
	(segment
		(start 129.518918 2.01549)
		(end 184.656222 2.01549)
		(width 0.127)
		(layer "In2.Cu")
		(net "BMC_ENCLOSURE_LED")
	)
	(segment
		(start 70.968616 -143.9926)
		(end 68.695316 -146.2659)
		(width 0.127)
		(layer "In2.Cu")
		(net "BMC_ENCLOSURE_LED")
	)
	(segment
		(start 65.4812 -147.574)
		(end 62.103 -147.574)
		(width 0.127)
		(layer "In2.Cu")
		(net "BMC_ENCLOSURE_LED")
	)
	(segment
		(start 68.695316 -146.2659)
		(end 66.7893 -146.2659)
		(width 0.127)
		(layer "In2.Cu")
		(net "BMC_ENCLOSURE_LED")
	)
	(segment
		(start 86.07298 -74.67854)
		(end 86.105746 -74.67854)
		(width 0.127)
		(layer "In2.Cu")
		(net "BMC_ENCLOSURE_LED")
	)
	(segment
		(start 47.441612 -150.0378)
		(end 47.4218 -150.0378)
		(width 0.127)
		(layer "In2.Cu")
		(net "BMC_ENCLOSURE_LED")
	)
	(segment
		(start 59.309 -150.368)
		(end 50.822606 -150.368)
		(width 0.127)
		(layer "In2.Cu")
		(net "BMC_ENCLOSURE_LED")
	)
	(segment
		(start 75.2348 -143.9926)
		(end 70.968616 -143.9926)
		(width 0.127)
		(layer "In2.Cu")
		(net "BMC_ENCLOSURE_LED")
	)
	(segment
		(start 83.94192 -76.8096)
		(end 84.4169 -76.334366)
		(width 0.127)
		(layer "In2.Cu")
		(net "BMC_ENCLOSURE_LED")
	)
	(segment
		(start 86.105746 -74.67854)
		(end 86.60384 -74.180446)
		(width 0.127)
		(layer "In2.Cu")
		(net "BMC_ENCLOSURE_LED")
	)
	(segment
		(start 184.813702 1.85801)
		(end 185.01233 1.85801)
		(width 0.127)
		(layer "In2.Cu")
		(net "BMC_ENCLOSURE_LED")
	)
	(segment
		(start 84.4169 -75.903582)
		(end 84.691982 -75.6285)
		(width 0.127)
		(layer "In2.Cu")
		(net "BMC_ENCLOSURE_LED")
	)
	(segment
		(start 86.60384 -74.180446)
		(end 86.60384 -74.14768)
		(width 0.127)
		(layer "In2.Cu")
		(net "BMC_ENCLOSURE_LED")
	)
	(segment
		(start 47.797212 -150.3934)
		(end 47.441612 -150.0378)
		(width 0.127)
		(layer "In2.Cu")
		(net "BMC_ENCLOSURE_LED")
	)
	(segment
		(start 79.218028 -78.8797)
		(end 79.718408 -78.8797)
		(width 0.127)
		(layer "In2.Cu")
		(net "BMC_ENCLOSURE_LED")
	)
	(segment
		(start 47.4218 -150.0378)
		(end 45.974 -148.59)
		(width 0.127)
		(layer "In2.Cu")
		(net "BMC_ENCLOSURE_LED")
	)
	(segment
		(start 121.240042 -6.263386)
		(end 129.518918 2.01549)
		(width 0.127)
		(layer "In2.Cu")
		(net "BMC_ENCLOSURE_LED")
	)
	(segment
		(start 85.122766 -75.6285)
		(end 86.07298 -74.67854)
		(width 0.127)
		(layer "In2.Cu")
		(net "BMC_ENCLOSURE_LED")
	)
	(segment
		(start 95.072454 -52.58562)
		(end 95.072454 -52.270152)
		(width 0.127)
		(layer "In2.Cu")
		(net "BMC_ENCLOSURE_LED")
	)
	(segment
		(start 95.0722 -52.585874)
		(end 95.072454 -52.58562)
		(width 0.127)
		(layer "In2.Cu")
		(net "BMC_ENCLOSURE_LED")
	)
	(segment
		(start 86.60384 -74.14768)
		(end 95.0722 -65.67932)
		(width 0.127)
		(layer "In2.Cu")
		(net "BMC_ENCLOSURE_LED")
	)
	(segment
		(start 75.9968 -123.943364)
		(end 75.367388 -124.572776)
		(width 0.127)
		(layer "In5.Cu")
		(net "BMC_ENCLOSURE_LED")
	)
	(segment
		(start 75.367388 -127.7874)
		(end 74.1426 -129.012188)
		(width 0.127)
		(layer "In5.Cu")
		(net "BMC_ENCLOSURE_LED")
	)
	(segment
		(start 74.1426 -131.908042)
		(end 74.141584 -131.933696)
		(width 0.127)
		(layer "In5.Cu")
		(net "BMC_ENCLOSURE_LED")
	)
	(segment
		(start 77.86878 -93.453966)
		(end 75.972162 -95.350584)
		(width 0.127)
		(layer "In5.Cu")
		(net "BMC_ENCLOSURE_LED")
	)
	(segment
		(start 75.971908 -115.47475)
		(end 75.9968 -115.499642)
		(width 0.127)
		(layer "In5.Cu")
		(net "BMC_ENCLOSURE_LED")
	)
	(segment
		(start 75.9968 -115.499642)
		(end 75.9968 -123.943364)
		(width 0.127)
		(layer "In5.Cu")
		(net "BMC_ENCLOSURE_LED")
	)
	(segment
		(start 74.1426 -129.012188)
		(end 74.1426 -131.908042)
		(width 0.127)
		(layer "In5.Cu")
		(net "BMC_ENCLOSURE_LED")
	)
	(segment
		(start 75.972162 -95.914972)
		(end 75.971908 -95.91548)
		(width 0.127)
		(layer "In5.Cu")
		(net "BMC_ENCLOSURE_LED")
	)
	(segment
		(start 75.971908 -95.91548)
		(end 75.971908 -115.47475)
		(width 0.127)
		(layer "In5.Cu")
		(net "BMC_ENCLOSURE_LED")
	)
	(segment
		(start 74.141584 -131.933696)
		(end 74.1426 -131.939792)
		(width 0.127)
		(layer "In5.Cu")
		(net "BMC_ENCLOSURE_LED")
	)
	(segment
		(start 77.86878 -80.228948)
		(end 77.86878 -93.453966)
		(width 0.127)
		(layer "In5.Cu")
		(net "BMC_ENCLOSURE_LED")
	)
	(segment
		(start 74.1426 -131.939792)
		(end 74.1426 -141.5034)
		(width 0.127)
		(layer "In5.Cu")
		(net "BMC_ENCLOSURE_LED")
	)
	(segment
		(start 79.218028 -78.8797)
		(end 77.86878 -80.228948)
		(width 0.127)
		(layer "In5.Cu")
		(net "BMC_ENCLOSURE_LED")
	)
	(segment
		(start 75.972162 -95.350584)
		(end 75.972162 -95.914972)
		(width 0.127)
		(layer "In5.Cu")
		(net "BMC_ENCLOSURE_LED")
	)
	(segment
		(start 74.1426 -141.5034)
		(end 75.2348 -142.5956)
		(width 0.127)
		(layer "In5.Cu")
		(net "BMC_ENCLOSURE_LED")
	)
	(segment
		(start 75.2348 -142.5956)
		(end 75.2348 -143.9926)
		(width 0.127)
		(layer "In5.Cu")
		(net "BMC_ENCLOSURE_LED")
	)
	(segment
		(start 75.367388 -124.572776)
		(end 75.367388 -127.7874)
		(width 0.127)
		(layer "In5.Cu")
		(net "BMC_ENCLOSURE_LED")
	)
	(segment
		(start 26.416 -159.258)
		(end 25.2095 -160.4645)
		(width 0.12065)
		(layer "F.Cu")
		(net "BMC_DDR3_RST_N")
	)
	(segment
		(start 21.1328 -160.238948)
		(end 21.1328 -158.3436)
		(width 0.12065)
		(layer "F.Cu")
		(net "BMC_DDR3_RST_N")
	)
	(segment
		(start 29.768038 -156.379926)
		(end 27.92222 -158.225744)
		(width 0.12065)
		(layer "F.Cu")
		(net "BMC_DDR3_RST_N")
	)
	(segment
		(start 14.508734 -154.210766)
		(end 14.508734 -160.634426)
		(width 0.12065)
		(layer "F.Cu")
		(net "BMC_DDR3_RST_N")
	)
	(segment
		(start 15.748508 -161.8742)
		(end 18.3642 -161.8742)
		(width 0.12065)
		(layer "F.Cu")
		(net "BMC_DDR3_RST_N")
	)
	(segment
		(start 21.1328 -158.3436)
		(end 21.904452 -157.571948)
		(width 0.12065)
		(layer "F.Cu")
		(net "BMC_DDR3_RST_N")
	)
	(segment
		(start 21.904452 -157.571948)
		(end 23.510748 -157.571948)
		(width 0.12065)
		(layer "F.Cu")
		(net "BMC_DDR3_RST_N")
	)
	(segment
		(start 16.764 -150.9395)
		(end 16.764 -151.9555)
		(width 0.12065)
		(layer "F.Cu")
		(net "BMC_DDR3_RST_N")
	)
	(segment
		(start 18.3642 -161.8742)
		(end 19.694652 -160.543748)
		(width 0.12065)
		(layer "F.Cu")
		(net "BMC_DDR3_RST_N")
	)
	(segment
		(start 24.765 -158.8262)
		(end 24.765 -160.4645)
		(width 0.12065)
		(layer "F.Cu")
		(net "BMC_DDR3_RST_N")
	)
	(segment
		(start 23.510748 -157.571948)
		(end 24.765 -158.8262)
		(width 0.12065)
		(layer "F.Cu")
		(net "BMC_DDR3_RST_N")
	)
	(segment
		(start 27.92222 -158.225744)
		(end 27.448256 -158.225744)
		(width 0.12065)
		(layer "F.Cu")
		(net "BMC_DDR3_RST_N")
	)
	(segment
		(start 20.828 -160.543748)
		(end 21.1328 -160.238948)
		(width 0.12065)
		(layer "F.Cu")
		(net "BMC_DDR3_RST_N")
	)
	(segment
		(start 16.764 -151.9555)
		(end 14.508734 -154.210766)
		(width 0.12065)
		(layer "F.Cu")
		(net "BMC_DDR3_RST_N")
	)
	(segment
		(start 27.448256 -158.225744)
		(end 26.416 -159.258)
		(width 0.12065)
		(layer "F.Cu")
		(net "BMC_DDR3_RST_N")
	)
	(segment
		(start 19.694652 -160.543748)
		(end 20.828 -160.543748)
		(width 0.12065)
		(layer "F.Cu")
		(net "BMC_DDR3_RST_N")
	)
	(segment
		(start 25.2095 -160.4645)
		(end 24.765 -160.4645)
		(width 0.12065)
		(layer "F.Cu")
		(net "BMC_DDR3_RST_N")
	)
	(segment
		(start 14.508734 -160.634426)
		(end 15.748508 -161.8742)
		(width 0.12065)
		(layer "F.Cu")
		(net "BMC_DDR3_RST_N")
	)
	(via
		(at 26.416 -159.258)
		(size 0.7112)
		(drill 0.3556)
		(layers "F.Cu" "B.Cu")
		(net "BMC_DDR3_RST_N")
	)
	(segment
		(start 221.328996 -6.928104)
		(end 220.680026 -6.928104)
		(width 0.12065)
		(layer "F.Cu")
		(net "BMC_CONSOLE_LED0_R")
	)
	(segment
		(start 220.345 -6.593078)
		(end 220.680026 -6.928104)
		(width 0.12065)
		(layer "F.Cu")
		(net "BMC_CONSOLE_LED0_R")
	)
	(segment
		(start 220.345 -6.0325)
		(end 220.345 -6.593078)
		(width 0.12065)
		(layer "F.Cu")
		(net "BMC_CONSOLE_LED0_R")
	)
	(segment
		(start 221.8055 -6.4516)
		(end 221.328996 -6.928104)
		(width 0.12065)
		(layer "F.Cu")
		(net "BMC_CONSOLE_LED0_R")
	)
	(segment
		(start 221.8055 -5.68325)
		(end 221.8055 -6.4516)
		(width 0.12065)
		(layer "F.Cu")
		(net "BMC_CONSOLE_LED0_R")
	)
	(via
		(at 220.680026 -6.928104)
		(size 0.7112)
		(drill 0.3556)
		(layers "F.Cu" "B.Cu")
		(net "BMC_CONSOLE_LED0_R")
	)
	(segment
		(start 36.10483 -124.484892)
		(end 35.70478 -124.084842)
		(width 0.12065)
		(layer "F.Cu")
		(net "BMC_ADD2_R")
	)
	(via
		(at 33.771586 -117.020086)
		(size 0.7112)
		(drill 0.3556)
		(layers "F.Cu" "B.Cu")
		(net "BMC_ADD2_R")
	)
	(via
		(at 35.70478 -124.084842)
		(size 0.4572)
		(drill 0.2032)
		(layers "F.Cu" "B.Cu")
		(net "BMC_ADD2_R")
	)
	(segment
		(start 35.295586 -123.171204)
		(end 35.295586 -123.123198)
		(width 0.12065)
		(layer "B.Cu")
		(net "BMC_ADD2_R")
	)
	(segment
		(start 34.958782 -121.711974)
		(end 34.798 -121.551192)
		(width 0.12065)
		(layer "B.Cu")
		(net "BMC_ADD2_R")
	)
	(segment
		(start 34.798 -117.1575)
		(end 34.662618 -117.022118)
		(width 0.12065)
		(layer "B.Cu")
		(net "BMC_ADD2_R")
	)
	(segment
		(start 34.662618 -117.022118)
		(end 33.773618 -117.022118)
		(width 0.12065)
		(layer "B.Cu")
		(net "BMC_ADD2_R")
	)
	(segment
		(start 35.295586 -123.123198)
		(end 34.958782 -122.786394)
		(width 0.12065)
		(layer "B.Cu")
		(net "BMC_ADD2_R")
	)
	(segment
		(start 35.314382 -123.694444)
		(end 35.314382 -123.19)
		(width 0.12065)
		(layer "B.Cu")
		(net "BMC_ADD2_R")
	)
	(segment
		(start 33.773618 -117.022118)
		(end 33.771586 -117.020086)
		(width 0.12065)
		(layer "B.Cu")
		(net "BMC_ADD2_R")
	)
	(segment
		(start 35.70478 -124.084842)
		(end 35.314382 -123.694444)
		(width 0.12065)
		(layer "B.Cu")
		(net "BMC_ADD2_R")
	)
	(segment
		(start 34.798 -121.551192)
		(end 34.798 -117.1575)
		(width 0.12065)
		(layer "B.Cu")
		(net "BMC_ADD2_R")
	)
	(segment
		(start 35.314382 -123.19)
		(end 35.295586 -123.171204)
		(width 0.12065)
		(layer "B.Cu")
		(net "BMC_ADD2_R")
	)
	(segment
		(start 34.958782 -122.786394)
		(end 34.958782 -121.711974)
		(width 0.12065)
		(layer "B.Cu")
		(net "BMC_ADD2_R")
	)
	(segment
		(start 121.276364 -46.42358)
		(end 118.76405 -46.42358)
		(width 0.12065)
		(layer "F.Cu")
		(net "BMC_ADD2_PWR")
	)
	(segment
		(start 118.76405 -46.42358)
		(end 118.23319 -45.89272)
		(width 0.12065)
		(layer "F.Cu")
		(net "BMC_ADD2_PWR")
	)
	(segment
		(start 118.23319 -53.112162)
		(end 117.754146 -53.591206)
		(width 0.12065)
		(layer "F.Cu")
		(net "BMC_ADD2_GND")
	)
	(segment
		(start 118.23319 -50.97272)
		(end 118.23319 -53.112162)
		(width 0.12065)
		(layer "F.Cu")
		(net "BMC_ADD2_GND")
	)
	(via
		(at 144.0561 -105.6005)
		(size 0.508)
		(drill 0.254)
		(layers "F.Cu" "B.Cu")
		(net "BMC_ADD2")
	)
	(via
		(at 34.798 -114.6302)
		(size 0.508)
		(drill 0.254)
		(layers "F.Cu" "B.Cu")
		(net "BMC_ADD2")
	)
	(via
		(at 33.89376 -114.0841)
		(size 0.7112)
		(drill 0.3556)
		(layers "F.Cu" "B.Cu")
		(net "BMC_ADD2")
	)
	(segment
		(start 115.2144 -62.40907)
		(end 121.566178 -68.760848)
		(width 0.12065)
		(layer "B.Cu")
		(net "BMC_ADD2")
	)
	(segment
		(start 121.63425 -84.60232)
		(end 121.63425 -85.08365)
		(width 0.12065)
		(layer "B.Cu")
		(net "BMC_ADD2")
	)
	(segment
		(start 34.30016 -115.77066)
		(end 34.30016 -115.2398)
		(width 0.12065)
		(layer "B.Cu")
		(net "BMC_ADD2")
	)
	(segment
		(start 34.798 -116.2685)
		(end 34.30016 -115.77066)
		(width 0.12065)
		(layer "B.Cu")
		(net "BMC_ADD2")
	)
	(segment
		(start 121.566178 -68.760848)
		(end 121.566178 -79.144622)
		(width 0.12065)
		(layer "B.Cu")
		(net "BMC_ADD2")
	)
	(segment
		(start 142.2146 -103.759)
		(end 144.0561 -105.6005)
		(width 0.12065)
		(layer "B.Cu")
		(net "BMC_ADD2")
	)
	(segment
		(start 34.798 -114.74196)
		(end 34.798 -114.6302)
		(width 0.12065)
		(layer "B.Cu")
		(net "BMC_ADD2")
	)
	(segment
		(start 121.63425 -85.08365)
		(end 140.3096 -103.759)
		(width 0.12065)
		(layer "B.Cu")
		(net "BMC_ADD2")
	)
	(segment
		(start 34.2519 -114.0841)
		(end 34.798 -114.6302)
		(width 0.12065)
		(layer "B.Cu")
		(net "BMC_ADD2")
	)
	(segment
		(start 121.13006 -84.09813)
		(end 121.63425 -84.60232)
		(width 0.12065)
		(layer "B.Cu")
		(net "BMC_ADD2")
	)
	(segment
		(start 115.2144 -51.45151)
		(end 115.2144 -62.40907)
		(width 0.12065)
		(layer "B.Cu")
		(net "BMC_ADD2")
	)
	(segment
		(start 140.3096 -103.759)
		(end 142.2146 -103.759)
		(width 0.12065)
		(layer "B.Cu")
		(net "BMC_ADD2")
	)
	(segment
		(start 121.13006 -79.58074)
		(end 121.13006 -84.09813)
		(width 0.12065)
		(layer "B.Cu")
		(net "BMC_ADD2")
	)
	(segment
		(start 118.23319 -48.43272)
		(end 115.2144 -51.45151)
		(width 0.12065)
		(layer "B.Cu")
		(net "BMC_ADD2")
	)
	(segment
		(start 121.566178 -79.144622)
		(end 121.13006 -79.58074)
		(width 0.12065)
		(layer "B.Cu")
		(net "BMC_ADD2")
	)
	(segment
		(start 33.89376 -114.0841)
		(end 34.2519 -114.0841)
		(width 0.12065)
		(layer "B.Cu")
		(net "BMC_ADD2")
	)
	(segment
		(start 34.30016 -115.2398)
		(end 34.798 -114.74196)
		(width 0.12065)
		(layer "B.Cu")
		(net "BMC_ADD2")
	)
	(segment
		(start 85.194902 -111.656114)
		(end 138.000486 -111.656114)
		(width 0.127)
		(layer "In2.Cu")
		(net "BMC_ADD2")
	)
	(segment
		(start 60.47613 -107.0229)
		(end 60.48883 -107.0356)
		(width 0.127)
		(layer "In2.Cu")
		(net "BMC_ADD2")
	)
	(segment
		(start 59.685682 -107.0229)
		(end 60.47613 -107.0229)
		(width 0.127)
		(layer "In2.Cu")
		(net "BMC_ADD2")
	)
	(segment
		(start 80.155288 -106.6165)
		(end 85.194902 -111.656114)
		(width 0.127)
		(layer "In2.Cu")
		(net "BMC_ADD2")
	)
	(segment
		(start 63.4619 -106.891582)
		(end 63.736982 -106.6165)
		(width 0.127)
		(layer "In2.Cu")
		(net "BMC_ADD2")
	)
	(segment
		(start 63.352934 -107.0356)
		(end 63.4619 -106.926634)
		(width 0.127)
		(layer "In2.Cu")
		(net "BMC_ADD2")
	)
	(segment
		(start 47.682912 -104.9655)
		(end 55.8165 -104.9655)
		(width 0.127)
		(layer "In2.Cu")
		(net "BMC_ADD2")
	)
	(segment
		(start 63.4619 -106.926634)
		(end 63.4619 -106.891582)
		(width 0.127)
		(layer "In2.Cu")
		(net "BMC_ADD2")
	)
	(segment
		(start 34.3281 -114.1603)
		(end 34.3281 -110.463838)
		(width 0.127)
		(layer "In2.Cu")
		(net "BMC_ADD2")
	)
	(segment
		(start 60.48883 -107.0356)
		(end 63.352934 -107.0356)
		(width 0.127)
		(layer "In2.Cu")
		(net "BMC_ADD2")
	)
	(segment
		(start 34.3281 -110.463838)
		(end 37.273738 -107.5182)
		(width 0.127)
		(layer "In2.Cu")
		(net "BMC_ADD2")
	)
	(segment
		(start 138.000486 -111.656114)
		(end 144.0561 -105.6005)
		(width 0.127)
		(layer "In2.Cu")
		(net "BMC_ADD2")
	)
	(segment
		(start 45.130212 -107.5182)
		(end 47.682912 -104.9655)
		(width 0.127)
		(layer "In2.Cu")
		(net "BMC_ADD2")
	)
	(segment
		(start 57.4802 -106.6292)
		(end 59.291982 -106.6292)
		(width 0.127)
		(layer "In2.Cu")
		(net "BMC_ADD2")
	)
	(segment
		(start 34.798 -114.6302)
		(end 34.3281 -114.1603)
		(width 0.127)
		(layer "In2.Cu")
		(net "BMC_ADD2")
	)
	(segment
		(start 63.736982 -106.6165)
		(end 80.155288 -106.6165)
		(width 0.127)
		(layer "In2.Cu")
		(net "BMC_ADD2")
	)
	(segment
		(start 55.8165 -104.9655)
		(end 57.4802 -106.6292)
		(width 0.127)
		(layer "In2.Cu")
		(net "BMC_ADD2")
	)
	(segment
		(start 59.291982 -106.6292)
		(end 59.685682 -107.0229)
		(width 0.127)
		(layer "In2.Cu")
		(net "BMC_ADD2")
	)
	(segment
		(start 37.273738 -107.5182)
		(end 45.130212 -107.5182)
		(width 0.127)
		(layer "In2.Cu")
		(net "BMC_ADD2")
	)
	(segment
		(start 34.3535 -112.939322)
		(end 34.885376 -113.471198)
		(width 0.12065)
		(layer "F.Cu")
		(net "BMC_ADD1_R")
	)
	(segment
		(start 36.10483 -125.284992)
		(end 35.705034 -124.885196)
		(width 0.12065)
		(layer "F.Cu")
		(net "BMC_ADD1_R")
	)
	(segment
		(start 34.3535 -112.70996)
		(end 34.3535 -112.939322)
		(width 0.12065)
		(layer "F.Cu")
		(net "BMC_ADD1_R")
	)
	(via
		(at 35.705034 -124.885196)
		(size 0.4572)
		(drill 0.2032)
		(layers "F.Cu" "B.Cu")
		(net "BMC_ADD1_R")
	)
	(via
		(at 34.885376 -113.471198)
		(size 0.508)
		(drill 0.254)
		(layers "F.Cu" "B.Cu")
		(net "BMC_ADD1_R")
	)
	(via
		(at 34.185098 -112.77092)
		(size 0.7112)
		(drill 0.3556)
		(layers "F.Cu" "B.Cu")
		(net "BMC_ADD1_R")
	)
	(segment
		(start 34.185098 -112.77092)
		(end 34.885376 -113.471198)
		(width 0.12065)
		(layer "B.Cu")
		(net "BMC_ADD1_R")
	)
	(segment
		(start 34.88563 -113.85423)
		(end 35.29203 -114.26063)
		(width 0.127)
		(layer "In2.Cu")
		(net "BMC_ADD1_R")
	)
	(segment
		(start 35.306 -124.486162)
		(end 35.705034 -124.885196)
		(width 0.127)
		(layer "In2.Cu")
		(net "BMC_ADD1_R")
	)
	(segment
		(start 35.29203 -114.26063)
		(end 35.29203 -119.029988)
		(width 0.127)
		(layer "In2.Cu")
		(net "BMC_ADD1_R")
	)
	(segment
		(start 35.29203 -119.029988)
		(end 35.306 -119.043958)
		(width 0.127)
		(layer "In2.Cu")
		(net "BMC_ADD1_R")
	)
	(segment
		(start 34.88563 -113.471452)
		(end 34.88563 -113.85423)
		(width 0.127)
		(layer "In2.Cu")
		(net "BMC_ADD1_R")
	)
	(segment
		(start 34.885376 -113.471198)
		(end 34.88563 -113.471452)
		(width 0.127)
		(layer "In2.Cu")
		(net "BMC_ADD1_R")
	)
	(segment
		(start 35.306 -119.043958)
		(end 35.306 -124.486162)
		(width 0.127)
		(layer "In2.Cu")
		(net "BMC_ADD1_R")
	)
	(segment
		(start 124.371354 -51.2953)
		(end 124.069348 -50.993294)
		(width 0.12065)
		(layer "F.Cu")
		(net "BMC_ADD1_PWR")
	)
	(segment
		(start 126.5936 -51.2953)
		(end 124.371354 -51.2953)
		(width 0.12065)
		(layer "F.Cu")
		(net "BMC_ADD1_PWR")
	)
	(segment
		(start 124.6759 -42.164)
		(end 124.0917 -42.7482)
		(width 0.12065)
		(layer "F.Cu")
		(net "BMC_ADD1_GND")
	)
	(segment
		(start 124.0917 -42.7482)
		(end 124.0917 -45.890942)
		(width 0.12065)
		(layer "F.Cu")
		(net "BMC_ADD1_GND")
	)
	(segment
		(start 124.0917 -45.890942)
		(end 124.069348 -45.913294)
		(width 0.12065)
		(layer "F.Cu")
		(net "BMC_ADD1_GND")
	)
	(segment
		(start 33.441386 -110.9218)
		(end 33.36417 -110.999016)
		(width 0.12065)
		(layer "F.Cu")
		(net "BMC_ADD1")
	)
	(segment
		(start 34.798 -110.9218)
		(end 33.441386 -110.9218)
		(width 0.12065)
		(layer "F.Cu")
		(net "BMC_ADD1")
	)
	(segment
		(start 34.3535 -111.82096)
		(end 33.756346 -111.82096)
		(width 0.12065)
		(layer "F.Cu")
		(net "BMC_ADD1")
	)
	(segment
		(start 33.756346 -111.82096)
		(end 33.36417 -111.428784)
		(width 0.12065)
		(layer "F.Cu")
		(net "BMC_ADD1")
	)
	(segment
		(start 33.36417 -111.428784)
		(end 33.36417 -110.999016)
		(width 0.12065)
		(layer "F.Cu")
		(net "BMC_ADD1")
	)
	(via
		(at 33.36417 -110.999016)
		(size 0.7112)
		(drill 0.3556)
		(layers "F.Cu" "B.Cu")
		(net "BMC_ADD1")
	)
	(via
		(at 34.798 -110.9218)
		(size 0.508)
		(drill 0.254)
		(layers "F.Cu" "B.Cu")
		(net "BMC_ADD1")
	)
	(via
		(at 52.30241 -107.295696)
		(size 0.508)
		(drill 0.254)
		(layers "F.Cu" "B.Cu")
		(net "BMC_ADD1")
	)
	(via
		(at 67.8942 -91.9988)
		(size 0.508)
		(drill 0.254)
		(layers "F.Cu" "B.Cu")
		(net "BMC_ADD1")
	)
	(via
		(at 57.9374 -92.6084)
		(size 0.508)
		(drill 0.254)
		(layers "F.Cu" "B.Cu")
		(net "BMC_ADD1")
	)
	(segment
		(start 35.022282 -110.308644)
		(end 34.798 -110.532926)
		(width 0.127)
		(layer "In2.Cu")
		(net "BMC_ADD1")
	)
	(segment
		(start 58.547 -92.4306)
		(end 58.1152 -92.4306)
		(width 0.127)
		(layer "In2.Cu")
		(net "BMC_ADD1")
	)
	(segment
		(start 37.501576 -107.989624)
		(end 35.182556 -110.308644)
		(width 0.127)
		(layer "In2.Cu")
		(net "BMC_ADD1")
	)
	(segment
		(start 51.309524 -107.989624)
		(end 37.501576 -107.989624)
		(width 0.127)
		(layer "In2.Cu")
		(net "BMC_ADD1")
	)
	(segment
		(start 35.182556 -110.308644)
		(end 35.022282 -110.308644)
		(width 0.127)
		(layer "In2.Cu")
		(net "BMC_ADD1")
	)
	(segment
		(start 34.798 -110.532926)
		(end 34.798 -110.9218)
		(width 0.127)
		(layer "In2.Cu")
		(net "BMC_ADD1")
	)
	(segment
		(start 59.0296 -91.948)
		(end 58.547 -92.4306)
		(width 0.127)
		(layer "In2.Cu")
		(net "BMC_ADD1")
	)
	(segment
		(start 58.1152 -92.4306)
		(end 57.9374 -92.6084)
		(width 0.127)
		(layer "In2.Cu")
		(net "BMC_ADD1")
	)
	(segment
		(start 52.174902 -107.423204)
		(end 51.875944 -107.423204)
		(width 0.127)
		(layer "In2.Cu")
		(net "BMC_ADD1")
	)
	(segment
		(start 51.875944 -107.423204)
		(end 51.309524 -107.989624)
		(width 0.127)
		(layer "In2.Cu")
		(net "BMC_ADD1")
	)
	(segment
		(start 67.8434 -91.948)
		(end 59.0296 -91.948)
		(width 0.127)
		(layer "In2.Cu")
		(net "BMC_ADD1")
	)
	(segment
		(start 52.30241 -107.295696)
		(end 52.174902 -107.423204)
		(width 0.127)
		(layer "In2.Cu")
		(net "BMC_ADD1")
	)
	(segment
		(start 67.8942 -91.9988)
		(end 67.8434 -91.948)
		(width 0.127)
		(layer "In2.Cu")
		(net "BMC_ADD1")
	)
	(segment
		(start 120.097042 -52.4256)
		(end 112.8014 -52.4256)
		(width 0.127)
		(layer "In5.Cu")
		(net "BMC_ADD1")
	)
	(segment
		(start 57.6834 -92.8624)
		(end 57.9374 -92.6084)
		(width 0.127)
		(layer "In5.Cu")
		(net "BMC_ADD1")
	)
	(segment
		(start 124.069348 -48.453294)
		(end 120.097042 -52.4256)
		(width 0.127)
		(layer "In5.Cu")
		(net "BMC_ADD1")
	)
	(segment
		(start 76.327 -68.58)
		(end 69.4436 -75.4634)
		(width 0.127)
		(layer "In5.Cu")
		(net "BMC_ADD1")
	)
	(segment
		(start 57.6834 -102.1334)
		(end 57.6834 -92.8624)
		(width 0.127)
		(layer "In5.Cu")
		(net "BMC_ADD1")
	)
	(segment
		(start 52.521104 -107.295696)
		(end 57.6834 -102.1334)
		(width 0.127)
		(layer "In5.Cu")
		(net "BMC_ADD1")
	)
	(segment
		(start 67.4243 -91.5289)
		(end 67.8942 -91.9988)
		(width 0.127)
		(layer "In5.Cu")
		(net "BMC_ADD1")
	)
	(segment
		(start 69.4436 -76.770484)
		(end 67.4243 -78.789784)
		(width 0.127)
		(layer "In5.Cu")
		(net "BMC_ADD1")
	)
	(segment
		(start 67.4243 -78.789784)
		(end 67.4243 -91.5289)
		(width 0.127)
		(layer "In5.Cu")
		(net "BMC_ADD1")
	)
	(segment
		(start 52.30241 -107.295696)
		(end 52.521104 -107.295696)
		(width 0.127)
		(layer "In5.Cu")
		(net "BMC_ADD1")
	)
	(segment
		(start 69.4436 -75.4634)
		(end 69.4436 -76.770484)
		(width 0.127)
		(layer "In5.Cu")
		(net "BMC_ADD1")
	)
	(segment
		(start 112.8014 -52.4256)
		(end 96.647 -68.58)
		(width 0.127)
		(layer "In5.Cu")
		(net "BMC_ADD1")
	)
	(segment
		(start 96.647 -68.58)
		(end 76.327 -68.58)
		(width 0.127)
		(layer "In5.Cu")
		(net "BMC_ADD1")
	)
	(segment
		(start 251.599954 -35.999928)
		(end 252.099826 -35.500056)
		(width 0.12065)
		(layer "F.Cu")
		(net "AVS_ENB_R")
	)
	(via
		(at 252.099826 -35.500056)
		(size 0.4572)
		(drill 0.2032)
		(layers "F.Cu" "B.Cu")
		(net "AVS_ENB_R")
	)
	(via
		(at 252.6538 -27.5844)
		(size 0.7112)
		(drill 0.3556)
		(layers "F.Cu" "B.Cu")
		(net "AVS_ENB_R")
	)
	(segment
		(start 251.706126 -32.663384)
		(end 251.706126 -29.124402)
		(width 0.1016)
		(layer "B.Cu")
		(net "AVS_ENB_R")
	)
	(segment
		(start 252.6538 -28.176728)
		(end 252.6538 -27.5844)
		(width 0.12065)
		(layer "B.Cu")
		(net "AVS_ENB_R")
	)
	(segment
		(start 251.798328 -29.0322)
		(end 252.6538 -28.176728)
		(width 0.12065)
		(layer "B.Cu")
		(net "AVS_ENB_R")
	)
	(segment
		(start 252.1458 -33.103058)
		(end 251.706126 -32.663384)
		(width 0.1016)
		(layer "B.Cu")
		(net "AVS_ENB_R")
	)
	(segment
		(start 251.706126 -29.124402)
		(end 251.798328 -29.0322)
		(width 0.1016)
		(layer "B.Cu")
		(net "AVS_ENB_R")
	)
	(segment
		(start 252.6538 -27.5844)
		(end 252.6538 -26.5557)
		(width 0.12065)
		(layer "B.Cu")
		(net "AVS_ENB_R")
	)
	(segment
		(start 252.099826 -35.500056)
		(end 252.1458 -35.454082)
		(width 0.1016)
		(layer "B.Cu")
		(net "AVS_ENB_R")
	)
	(segment
		(start 252.1458 -35.454082)
		(end 252.1458 -33.103058)
		(width 0.1016)
		(layer "B.Cu")
		(net "AVS_ENB_R")
	)
	(segment
		(start 327.4695 -77.1271)
		(end 327.3806 -77.216)
		(width 0.12065)
		(layer "F.Cu")
		(net "AVS_ENB")
	)
	(segment
		(start 263.3345 -17.4625)
		(end 267.26896 -21.39696)
		(width 0.12065)
		(layer "F.Cu")
		(net "AVS_ENB")
	)
	(segment
		(start 327.4695 -76.2)
		(end 327.4695 -77.1271)
		(width 0.12065)
		(layer "F.Cu")
		(net "AVS_ENB")
	)
	(segment
		(start 262.993886 -12.319)
		(end 263.665208 -12.990322)
		(width 0.12065)
		(layer "F.Cu")
		(net "AVS_ENB")
	)
	(segment
		(start 263.665208 -14.66596)
		(end 263.3345 -14.996668)
		(width 0.12065)
		(layer "F.Cu")
		(net "AVS_ENB")
	)
	(segment
		(start 261.025386 -11.92403)
		(end 262.668258 -11.92403)
		(width 0.12065)
		(layer "F.Cu")
		(net "AVS_ENB")
	)
	(segment
		(start 151.008334 -53.34)
		(end 151.448262 -53.34)
		(width 0.12065)
		(layer "F.Cu")
		(net "AVS_ENB")
	)
	(segment
		(start 262.668258 -11.92403)
		(end 262.98017 -12.235942)
		(width 0.12065)
		(layer "F.Cu")
		(net "AVS_ENB")
	)
	(segment
		(start 262.98017 -12.24534)
		(end 262.993886 -12.259056)
		(width 0.12065)
		(layer "F.Cu")
		(net "AVS_ENB")
	)
	(segment
		(start 150.676102 -53.672232)
		(end 151.008334 -53.34)
		(width 0.12065)
		(layer "F.Cu")
		(net "AVS_ENB")
	)
	(segment
		(start 263.3345 -14.996668)
		(end 263.3345 -17.4625)
		(width 0.12065)
		(layer "F.Cu")
		(net "AVS_ENB")
	)
	(segment
		(start 267.26896 -22.89937)
		(end 268.478 -24.10841)
		(width 0.12065)
		(layer "F.Cu")
		(net "AVS_ENB")
	)
	(segment
		(start 260.205728 -11.104372)
		(end 261.025386 -11.92403)
		(width 0.12065)
		(layer "F.Cu")
		(net "AVS_ENB")
	)
	(segment
		(start 262.98017 -12.235942)
		(end 262.98017 -12.24534)
		(width 0.12065)
		(layer "F.Cu")
		(net "AVS_ENB")
	)
	(segment
		(start 263.665208 -12.990322)
		(end 263.665208 -14.66596)
		(width 0.12065)
		(layer "F.Cu")
		(net "AVS_ENB")
	)
	(segment
		(start 262.993886 -12.259056)
		(end 262.993886 -12.319)
		(width 0.12065)
		(layer "F.Cu")
		(net "AVS_ENB")
	)
	(segment
		(start 267.26896 -21.39696)
		(end 267.26896 -22.89937)
		(width 0.12065)
		(layer "F.Cu")
		(net "AVS_ENB")
	)
	(segment
		(start 268.478 -24.10841)
		(end 268.478 -27.3558)
		(width 0.12065)
		(layer "F.Cu")
		(net "AVS_ENB")
	)
	(via
		(at 195.269358 -43.5483)
		(size 0.508)
		(drill 0.254)
		(layers "F.Cu" "B.Cu")
		(net "AVS_ENB")
	)
	(via
		(at 260.205728 -11.104372)
		(size 0.508)
		(drill 0.254)
		(layers "F.Cu" "B.Cu")
		(net "AVS_ENB")
	)
	(via
		(at 327.3806 -77.216)
		(size 0.508)
		(drill 0.254)
		(layers "F.Cu" "B.Cu")
		(net "AVS_ENB")
	)
	(via
		(at 268.478 -27.3558)
		(size 0.508)
		(drill 0.254)
		(layers "F.Cu" "B.Cu")
		(net "AVS_ENB")
	)
	(via
		(at 326.26427 -78.33233)
		(size 0.7112)
		(drill 0.3556)
		(layers "F.Cu" "B.Cu")
		(net "AVS_ENB")
	)
	(via
		(at 151.448262 -53.34)
		(size 0.508)
		(drill 0.254)
		(layers "F.Cu" "B.Cu")
		(net "AVS_ENB")
	)
	(segment
		(start 276.2377 -78.994)
		(end 325.6026 -78.994)
		(width 0.12065)
		(layer "B.Cu")
		(net "AVS_ENB")
	)
	(segment
		(start 195.269358 -43.5483)
		(end 195.269358 -41.556178)
		(width 0.12065)
		(layer "B.Cu")
		(net "AVS_ENB")
	)
	(segment
		(start 252.630686 -12.823444)
		(end 252.904244 -13.097002)
		(width 0.12065)
		(layer "B.Cu")
		(net "AVS_ENB")
	)
	(segment
		(start 268.478 -71.2343)
		(end 276.2377 -78.994)
		(width 0.12065)
		(layer "B.Cu")
		(net "AVS_ENB")
	)
	(segment
		(start 252.904244 -13.097002)
		(end 256.575052 -13.097002)
		(width 0.12065)
		(layer "B.Cu")
		(net "AVS_ENB")
	)
	(segment
		(start 251.383546 -12.1158)
		(end 252.30963 -12.1158)
		(width 0.12065)
		(layer "B.Cu")
		(net "AVS_ENB")
	)
	(segment
		(start 325.6026 -78.994)
		(end 326.26427 -78.33233)
		(width 0.12065)
		(layer "B.Cu")
		(net "AVS_ENB")
	)
	(segment
		(start 214.658702 -16.326104)
		(end 219.170504 -16.326104)
		(width 0.12065)
		(layer "B.Cu")
		(net "AVS_ENB")
	)
	(segment
		(start 233.492548 -17.211548)
		(end 234.2134 -17.9324)
		(width 0.12065)
		(layer "B.Cu")
		(net "AVS_ENB")
	)
	(segment
		(start 234.2134 -17.9324)
		(end 238.7346 -17.9324)
		(width 0.12065)
		(layer "B.Cu")
		(net "AVS_ENB")
	)
	(segment
		(start 268.478 -27.3558)
		(end 268.478 -71.2343)
		(width 0.12065)
		(layer "B.Cu")
		(net "AVS_ENB")
	)
	(segment
		(start 220.055948 -17.211548)
		(end 233.492548 -17.211548)
		(width 0.12065)
		(layer "B.Cu")
		(net "AVS_ENB")
	)
	(segment
		(start 240.481104 -16.185896)
		(end 241.966242 -16.185896)
		(width 0.12065)
		(layer "B.Cu")
		(net "AVS_ENB")
	)
	(segment
		(start 241.966242 -16.185896)
		(end 243.623338 -14.5288)
		(width 0.12065)
		(layer "B.Cu")
		(net "AVS_ENB")
	)
	(segment
		(start 258.213098 -13.097002)
		(end 260.205728 -11.104372)
		(width 0.12065)
		(layer "B.Cu")
		(net "AVS_ENB")
	)
	(segment
		(start 266.7254 -23.0378)
		(end 268.478 -24.7904)
		(width 0.12065)
		(layer "B.Cu")
		(net "AVS_ENB")
	)
	(segment
		(start 238.7346 -17.9324)
		(end 240.481104 -16.185896)
		(width 0.12065)
		(layer "B.Cu")
		(net "AVS_ENB")
	)
	(segment
		(start 252.30963 -12.1158)
		(end 252.630686 -12.436856)
		(width 0.12065)
		(layer "B.Cu")
		(net "AVS_ENB")
	)
	(segment
		(start 257.063494 -12.995148)
		(end 257.165348 -13.097002)
		(width 0.12065)
		(layer "B.Cu")
		(net "AVS_ENB")
	)
	(segment
		(start 219.170504 -16.326104)
		(end 220.055948 -17.211548)
		(width 0.12065)
		(layer "B.Cu")
		(net "AVS_ENB")
	)
	(segment
		(start 257.165348 -13.097002)
		(end 258.213098 -13.097002)
		(width 0.12065)
		(layer "B.Cu")
		(net "AVS_ENB")
	)
	(segment
		(start 268.478 -24.7904)
		(end 268.478 -27.3558)
		(width 0.12065)
		(layer "B.Cu")
		(net "AVS_ENB")
	)
	(segment
		(start 252.6538 -25.6667)
		(end 252.6538 -23.7236)
		(width 0.12065)
		(layer "B.Cu")
		(net "AVS_ENB")
	)
	(segment
		(start 249.753628 -14.5288)
		(end 251.091192 -13.191236)
		(width 0.12065)
		(layer "B.Cu")
		(net "AVS_ENB")
	)
	(segment
		(start 210.693 -26.132536)
		(end 210.693 -20.291806)
		(width 0.12065)
		(layer "B.Cu")
		(net "AVS_ENB")
	)
	(segment
		(start 252.6538 -23.7236)
		(end 253.3396 -23.0378)
		(width 0.12065)
		(layer "B.Cu")
		(net "AVS_ENB")
	)
	(segment
		(start 251.091192 -12.408154)
		(end 251.383546 -12.1158)
		(width 0.12065)
		(layer "B.Cu")
		(net "AVS_ENB")
	)
	(segment
		(start 256.575052 -13.097002)
		(end 256.676906 -12.995148)
		(width 0.12065)
		(layer "B.Cu")
		(net "AVS_ENB")
	)
	(segment
		(start 210.693 -20.291806)
		(end 214.658702 -16.326104)
		(width 0.12065)
		(layer "B.Cu")
		(net "AVS_ENB")
	)
	(segment
		(start 251.091192 -13.191236)
		(end 251.091192 -12.408154)
		(width 0.12065)
		(layer "B.Cu")
		(net "AVS_ENB")
	)
	(segment
		(start 256.676906 -12.995148)
		(end 257.063494 -12.995148)
		(width 0.12065)
		(layer "B.Cu")
		(net "AVS_ENB")
	)
	(segment
		(start 326.26427 -78.33233)
		(end 327.3806 -77.216)
		(width 0.12065)
		(layer "B.Cu")
		(net "AVS_ENB")
	)
	(segment
		(start 243.623338 -14.5288)
		(end 249.753628 -14.5288)
		(width 0.12065)
		(layer "B.Cu")
		(net "AVS_ENB")
	)
	(segment
		(start 252.630686 -12.436856)
		(end 252.630686 -12.823444)
		(width 0.12065)
		(layer "B.Cu")
		(net "AVS_ENB")
	)
	(segment
		(start 253.3396 -23.0378)
		(end 266.7254 -23.0378)
		(width 0.12065)
		(layer "B.Cu")
		(net "AVS_ENB")
	)
	(segment
		(start 195.269358 -41.556178)
		(end 210.693 -26.132536)
		(width 0.12065)
		(layer "B.Cu")
		(net "AVS_ENB")
	)
	(segment
		(start 177.95875 -45.508418)
		(end 178.383184 -45.932852)
		(width 0.127)
		(layer "In5.Cu")
		(net "AVS_ENB")
	)
	(segment
		(start 157.192726 -54.384956)
		(end 163.411916 -54.384956)
		(width 0.127)
		(layer "In5.Cu")
		(net "AVS_ENB")
	)
	(segment
		(start 151.448262 -53.34)
		(end 152.240742 -52.54752)
		(width 0.127)
		(layer "In5.Cu")
		(net "AVS_ENB")
	)
	(segment
		(start 155.35529 -52.54752)
		(end 157.192726 -54.384956)
		(width 0.127)
		(layer "In5.Cu")
		(net "AVS_ENB")
	)
	(segment
		(start 178.383184 -45.932852)
		(end 192.884806 -45.932852)
		(width 0.127)
		(layer "In5.Cu")
		(net "AVS_ENB")
	)
	(segment
		(start 163.411916 -54.384956)
		(end 164.866574 -52.930298)
		(width 0.127)
		(layer "In5.Cu")
		(net "AVS_ENB")
	)
	(segment
		(start 164.866574 -51.314604)
		(end 165.694868 -50.48631)
		(width 0.127)
		(layer "In5.Cu")
		(net "AVS_ENB")
	)
	(segment
		(start 175.5521 -45.508418)
		(end 177.95875 -45.508418)
		(width 0.127)
		(layer "In5.Cu")
		(net "AVS_ENB")
	)
	(segment
		(start 152.240742 -52.54752)
		(end 155.35529 -52.54752)
		(width 0.127)
		(layer "In5.Cu")
		(net "AVS_ENB")
	)
	(segment
		(start 164.866574 -52.930298)
		(end 164.866574 -51.314604)
		(width 0.127)
		(layer "In5.Cu")
		(net "AVS_ENB")
	)
	(segment
		(start 192.884806 -45.932852)
		(end 195.269358 -43.5483)
		(width 0.127)
		(layer "In5.Cu")
		(net "AVS_ENB")
	)
	(segment
		(start 170.574208 -50.48631)
		(end 175.5521 -45.508418)
		(width 0.127)
		(layer "In5.Cu")
		(net "AVS_ENB")
	)
	(segment
		(start 165.694868 -50.48631)
		(end 170.574208 -50.48631)
		(width 0.127)
		(layer "In5.Cu")
		(net "AVS_ENB")
	)
	(segment
		(start 86.0171 -55.5625)
		(end 85.1281 -54.6735)
		(width 0.12065)
		(layer "F.Cu")
		(net "AS_ROMA0_R")
	)
	(segment
		(start 85.1281 -54.6735)
		(end 85.1281 -52.8955)
		(width 0.12065)
		(layer "F.Cu")
		(net "AS_ROMA0_R")
	)
	(segment
		(start 85.1281 -52.8955)
		(end 85.3948 -52.6288)
		(width 0.12065)
		(layer "F.Cu")
		(net "AS_ROMA0_R")
	)
	(segment
		(start 86.0171 -56.388)
		(end 86.0171 -55.5625)
		(width 0.12065)
		(layer "F.Cu")
		(net "AS_ROMA0_R")
	)
	(segment
		(start 44.169838 -36.289996)
		(end 45.884846 -36.289996)
		(width 0.508)
		(layer "F.Cu")
		(net "AGND_USB")
	)
	(segment
		(start 29.314902 -36.289996)
		(end 31.02991 -36.289996)
		(width 0.508)
		(layer "F.Cu")
		(net "AGND_USB")
	)
	(segment
		(start 31.02991 -36.289996)
		(end 31.02991 -38.005004)
		(width 0.508)
		(layer "F.Cu")
		(net "AGND_USB")
	)
	(segment
		(start 42.45483 -36.289996)
		(end 44.169838 -36.289996)
		(width 0.508)
		(layer "F.Cu")
		(net "AGND_USB")
	)
	(segment
		(start 31.02991 -36.289996)
		(end 32.744918 -36.289996)
		(width 0.508)
		(layer "F.Cu")
		(net "AGND_USB")
	)
	(segment
		(start 44.169838 -34.574988)
		(end 44.169838 -36.289996)
		(width 0.508)
		(layer "F.Cu")
		(net "AGND_USB")
	)
	(segment
		(start 44.169838 -36.289996)
		(end 44.169838 -38.005004)
		(width 0.508)
		(layer "F.Cu")
		(net "AGND_USB")
	)
	(segment
		(start 31.02991 -34.574988)
		(end 31.02991 -36.289996)
		(width 0.508)
		(layer "F.Cu")
		(net "AGND_USB")
	)
	(segment
		(start 67.1576 -32.004)
		(end 65.913 -33.2486)
		(width 0.508)
		(layer "F.Cu")
		(net "AGND_P3V3_STBY")
	)
	(segment
		(start 70.485 -33.9725)
		(end 69.6595 -33.9725)
		(width 0.508)
		(layer "F.Cu")
		(net "AGND_P3V3_STBY")
	)
	(segment
		(start 73.66 -35.8394)
		(end 73.66 -37.62756)
		(width 0.508)
		(layer "F.Cu")
		(net "AGND_P3V3_STBY")
	)
	(segment
		(start 64.516 -33.401)
		(end 64.6684 -33.2486)
		(width 0.508)
		(layer "F.Cu")
		(net "AGND_P3V3_STBY")
	)
	(segment
		(start 68.5165 -32.004)
		(end 67.1576 -32.004)
		(width 0.508)
		(layer "F.Cu")
		(net "AGND_P3V3_STBY")
	)
	(segment
		(start 64.6684 -33.2486)
		(end 65.913 -33.2486)
		(width 0.508)
		(layer "F.Cu")
		(net "AGND_P3V3_STBY")
	)
	(segment
		(start 73.66 -37.62756)
		(end 73.35266 -37.9349)
		(width 0.508)
		(layer "F.Cu")
		(net "AGND_P3V3_STBY")
	)
	(via
		(at 64.516 -33.401)
		(size 0.508)
		(drill 0.254)
		(layers "F.Cu" "B.Cu")
		(net "AGND_P3V3_STBY")
	)
	(via
		(at 73.66 -35.8394)
		(size 0.508)
		(drill 0.254)
		(layers "F.Cu" "B.Cu")
		(net "AGND_P3V3_STBY")
	)
	(via
		(at 63.38062 -33.5915)
		(size 0.7112)
		(drill 0.3556)
		(layers "F.Cu" "B.Cu")
		(net "AGND_P3V3_STBY")
	)
	(via
		(at 69.6595 -33.9725)
		(size 0.508)
		(drill 0.254)
		(layers "F.Cu" "B.Cu")
		(net "AGND_P3V3_STBY")
	)
	(segment
		(start 63.38062 -33.5915)
		(end 64.3255 -33.5915)
		(width 0.508)
		(layer "B.Cu")
		(net "AGND_P3V3_STBY")
	)
	(segment
		(start 60.325 -33.5915)
		(end 61.341 -33.5915)
		(width 0.508)
		(layer "B.Cu")
		(net "AGND_P3V3_STBY")
	)
	(segment
		(start 62.357 -33.5915)
		(end 63.38062 -33.5915)
		(width 0.508)
		(layer "B.Cu")
		(net "AGND_P3V3_STBY")
	)
	(segment
		(start 61.341 -33.5915)
		(end 62.357 -33.5915)
		(width 0.508)
		(layer "B.Cu")
		(net "AGND_P3V3_STBY")
	)
	(segment
		(start 64.3255 -33.5915)
		(end 64.516 -33.401)
		(width 0.508)
		(layer "B.Cu")
		(net "AGND_P3V3_STBY")
	)
	(segment
		(start 65.0875 -33.9725)
		(end 69.6595 -33.9725)
		(width 0.508)
		(layer "In2.Cu")
		(net "AGND_P3V3_STBY")
	)
	(segment
		(start 64.516 -33.401)
		(end 65.0875 -33.9725)
		(width 0.508)
		(layer "In2.Cu")
		(net "AGND_P3V3_STBY")
	)
	(segment
		(start 69.6595 -33.9725)
		(end 71.1581 -33.9725)
		(width 0.508)
		(layer "In2.Cu")
		(net "AGND_P3V3_STBY")
	)
	(segment
		(start 71.8439 -34.6583)
		(end 72.4789 -34.6583)
		(width 0.508)
		(layer "In2.Cu")
		(net "AGND_P3V3_STBY")
	)
	(segment
		(start 72.4789 -34.6583)
		(end 73.66 -35.8394)
		(width 0.508)
		(layer "In2.Cu")
		(net "AGND_P3V3_STBY")
	)
	(segment
		(start 71.1581 -33.9725)
		(end 71.8439 -34.6583)
		(width 0.508)
		(layer "In2.Cu")
		(net "AGND_P3V3_STBY")
	)
	(segment
		(start 339.598 -72.0344)
		(end 339.598 -72.898)
		(width 0.508)
		(layer "F.Cu")
		(net "AGND_P0V9_E")
	)
	(segment
		(start 341.9856 -72.0344)
		(end 339.598 -72.0344)
		(width 0.508)
		(layer "F.Cu")
		(net "AGND_P0V9_E")
	)
	(segment
		(start 330.0222 -74.3458)
		(end 330.835 -73.533)
		(width 0.508)
		(layer "F.Cu")
		(net "AGND_P0V9_E")
	)
	(segment
		(start 344.17 -72.7202)
		(end 342.6714 -72.7202)
		(width 0.508)
		(layer "F.Cu")
		(net "AGND_P0V9_E")
	)
	(segment
		(start 337.5025 -73.787)
		(end 338.709 -73.787)
		(width 0.508)
		(layer "F.Cu")
		(net "AGND_P0V9_E")
	)
	(segment
		(start 339.598 -72.898)
		(end 338.709 -73.787)
		(width 0.508)
		(layer "F.Cu")
		(net "AGND_P0V9_E")
	)
	(segment
		(start 330.835 -73.533)
		(end 331.1398 -73.533)
		(width 0.508)
		(layer "F.Cu")
		(net "AGND_P0V9_E")
	)
	(segment
		(start 329.7682 -74.3458)
		(end 330.0222 -74.3458)
		(width 0.508)
		(layer "F.Cu")
		(net "AGND_P0V9_E")
	)
	(segment
		(start 342.6714 -72.7202)
		(end 341.9856 -72.0344)
		(width 0.508)
		(layer "F.Cu")
		(net "AGND_P0V9_E")
	)
	(via
		(at 336.677 -73.5076)
		(size 0.7112)
		(drill 0.3556)
		(layers "F.Cu" "B.Cu")
		(net "AGND_P0V9_E")
	)
	(via
		(at 338.709 -73.787)
		(size 0.508)
		(drill 0.254)
		(layers "F.Cu" "B.Cu")
		(net "AGND_P0V9_E")
	)
	(via
		(at 331.1398 -73.533)
		(size 0.508)
		(drill 0.254)
		(layers "F.Cu" "B.Cu")
		(net "AGND_P0V9_E")
	)
	(via
		(at 344.17 -72.7202)
		(size 0.508)
		(drill 0.254)
		(layers "F.Cu" "B.Cu")
		(net "AGND_P0V9_E")
	)
	(segment
		(start 331.1398 -73.533)
		(end 331.1652 -73.5076)
		(width 0.508)
		(layer "B.Cu")
		(net "AGND_P0V9_E")
	)
	(segment
		(start 338.709 -73.787)
		(end 338.4296 -73.5076)
		(width 0.508)
		(layer "B.Cu")
		(net "AGND_P0V9_E")
	)
	(segment
		(start 331.1652 -73.5076)
		(end 336.677 -73.5076)
		(width 0.508)
		(layer "B.Cu")
		(net "AGND_P0V9_E")
	)
	(segment
		(start 343.3826 -72.7202)
		(end 344.17 -72.7202)
		(width 0.508)
		(layer "B.Cu")
		(net "AGND_P0V9_E")
	)
	(segment
		(start 343.154 -71.9455)
		(end 343.154 -72.4916)
		(width 0.508)
		(layer "B.Cu")
		(net "AGND_P0V9_E")
	)
	(segment
		(start 344.849196 -72.7202)
		(end 344.17 -72.7202)
		(width 0.508)
		(layer "B.Cu")
		(net "AGND_P0V9_E")
	)
	(segment
		(start 344.17 -71.9455)
		(end 344.17 -72.7202)
		(width 0.508)
		(layer "B.Cu")
		(net "AGND_P0V9_E")
	)
	(segment
		(start 343.154 -72.4916)
		(end 343.3826 -72.7202)
		(width 0.508)
		(layer "B.Cu")
		(net "AGND_P0V9_E")
	)
	(segment
		(start 345.186 -71.9455)
		(end 345.186 -72.383396)
		(width 0.508)
		(layer "B.Cu")
		(net "AGND_P0V9_E")
	)
	(segment
		(start 338.4296 -73.5076)
		(end 336.677 -73.5076)
		(width 0.508)
		(layer "B.Cu")
		(net "AGND_P0V9_E")
	)
	(segment
		(start 345.186 -72.383396)
		(end 344.849196 -72.7202)
		(width 0.508)
		(layer "B.Cu")
		(net "AGND_P0V9_E")
	)
	(segment
		(start 151.933402 -56.009032)
		(end 151.844502 -56.097932)
		(width 0.508)
		(layer "F.Cu")
		(net "AGND_P0V9")
	)
	(segment
		(start 153.254202 -56.009032)
		(end 151.933402 -56.009032)
		(width 0.508)
		(layer "F.Cu")
		(net "AGND_P0V9")
	)
	(segment
		(start 154.129232 -52.104798)
		(end 154.129232 -53.570632)
		(width 0.508)
		(layer "F.Cu")
		(net "AGND_P0V9")
	)
	(segment
		(start 154.129232 -53.570632)
		(end 154.3558 -53.7972)
		(width 0.508)
		(layer "F.Cu")
		(net "AGND_P0V9")
	)
	(segment
		(start 155.476702 -54.256432)
		(end 155.476702 -55.394098)
		(width 0.508)
		(layer "F.Cu")
		(net "AGND_P0V9")
	)
	(segment
		(start 155.476702 -55.394098)
		(end 154.6352 -56.2356)
		(width 0.508)
		(layer "F.Cu")
		(net "AGND_P0V9")
	)
	(via
		(at 154.3558 -53.7972)
		(size 0.508)
		(drill 0.254)
		(layers "F.Cu" "B.Cu")
		(net "AGND_P0V9")
	)
	(via
		(at 151.844502 -56.097932)
		(size 0.508)
		(drill 0.254)
		(layers "F.Cu" "B.Cu")
		(net "AGND_P0V9")
	)
	(via
		(at 154.6352 -56.2356)
		(size 0.508)
		(drill 0.254)
		(layers "F.Cu" "B.Cu")
		(net "AGND_P0V9")
	)
	(via
		(at 153.203402 -56.097932)
		(size 0.7112)
		(drill 0.3556)
		(layers "F.Cu" "B.Cu")
		(net "AGND_P0V9")
	)
	(segment
		(start 151.844502 -56.097932)
		(end 151.883872 -56.137302)
		(width 0.508)
		(layer "B.Cu")
		(net "AGND_P0V9")
	)
	(segment
		(start 150.460202 -56.097932)
		(end 150.499572 -56.137302)
		(width 0.508)
		(layer "B.Cu")
		(net "AGND_P0V9")
	)
	(segment
		(start 150.499572 -56.137302)
		(end 151.805132 -56.137302)
		(width 0.508)
		(layer "B.Cu")
		(net "AGND_P0V9")
	)
	(segment
		(start 151.805132 -56.137302)
		(end 151.844502 -56.097932)
		(width 0.508)
		(layer "B.Cu")
		(net "AGND_P0V9")
	)
	(segment
		(start 153.146252 -56.137302)
		(end 153.185622 -56.097932)
		(width 0.508)
		(layer "B.Cu")
		(net "AGND_P0V9")
	)
	(segment
		(start 153.185622 -56.097932)
		(end 153.203402 -56.097932)
		(width 0.508)
		(layer "B.Cu")
		(net "AGND_P0V9")
	)
	(segment
		(start 149.444202 -56.097932)
		(end 148.428202 -56.097932)
		(width 0.508)
		(layer "B.Cu")
		(net "AGND_P0V9")
	)
	(segment
		(start 154.536902 -56.137302)
		(end 154.6352 -56.2356)
		(width 0.508)
		(layer "B.Cu")
		(net "AGND_P0V9")
	)
	(segment
		(start 153.242772 -56.137302)
		(end 154.536902 -56.137302)
		(width 0.508)
		(layer "B.Cu")
		(net "AGND_P0V9")
	)
	(segment
		(start 150.460202 -56.097932)
		(end 149.444202 -56.097932)
		(width 0.508)
		(layer "B.Cu")
		(net "AGND_P0V9")
	)
	(segment
		(start 153.203402 -56.097932)
		(end 153.242772 -56.137302)
		(width 0.508)
		(layer "B.Cu")
		(net "AGND_P0V9")
	)
	(segment
		(start 151.883872 -56.137302)
		(end 153.146252 -56.137302)
		(width 0.508)
		(layer "B.Cu")
		(net "AGND_P0V9")
	)
	(segment
		(start 154.6352 -56.2356)
		(end 154.6352 -54.0766)
		(width 0.508)
		(layer "In2.Cu")
		(net "AGND_P0V9")
	)
	(segment
		(start 154.6352 -54.0766)
		(end 154.3558 -53.7972)
		(width 0.508)
		(layer "In2.Cu")
		(net "AGND_P0V9")
	)
	(segment
		(start 10.668 -178.9684)
		(end 10.7442 -179.0446)
		(width 0.508)
		(layer "F.Cu")
		(net "AGND_CURRENT_MON")
	)
	(segment
		(start 10.9982 -179.2986)
		(end 10.9982 -180.2511)
		(width 0.508)
		(layer "F.Cu")
		(net "AGND_CURRENT_MON")
	)
	(segment
		(start 14.3764 -182.9816)
		(end 14.37386 -182.98414)
		(width 0.3048)
		(layer "F.Cu")
		(net "AGND_CURRENT_MON")
	)
	(segment
		(start 14.542262 -184.1881)
		(end 14.542262 -183.152542)
		(width 0.3048)
		(layer "F.Cu")
		(net "AGND_CURRENT_MON")
	)
	(segment
		(start 21.0947 -192.5066)
		(end 22.0726 -192.5066)
		(width 0.508)
		(layer "F.Cu")
		(net "AGND_CURRENT_MON")
	)
	(segment
		(start 22.6822 -190.3222)
		(end 22.7076 -190.2968)
		(width 0.508)
		(layer "F.Cu")
		(net "AGND_CURRENT_MON")
	)
	(segment
		(start 13.5001 -196.7611)
		(end 13.335 -196.9262)
		(width 0.508)
		(layer "F.Cu")
		(net "AGND_CURRENT_MON")
	)
	(segment
		(start 6.096 -190.8048)
		(end 6.096 -190.8556)
		(width 0.508)
		(layer "F.Cu")
		(net "AGND_CURRENT_MON")
	)
	(segment
		(start 14.9479 -181.102)
		(end 15.748 -181.102)
		(width 0.381)
		(layer "F.Cu")
		(net "AGND_CURRENT_MON")
	)
	(segment
		(start 22.6568 -187.0456)
		(end 22.6822 -187.0202)
		(width 0.508)
		(layer "F.Cu")
		(net "AGND_CURRENT_MON")
	)
	(segment
		(start 9.4742 -178.9684)
		(end 10.668 -178.9684)
		(width 0.508)
		(layer "F.Cu")
		(net "AGND_CURRENT_MON")
	)
	(segment
		(start 21.7932 -193.6496)
		(end 22.7076 -193.6496)
		(width 0.508)
		(layer "F.Cu")
		(net "AGND_CURRENT_MON")
	)
	(segment
		(start 13.335 -196.9262)
		(end 13.335 -198.0184)
		(width 0.508)
		(layer "F.Cu")
		(net "AGND_CURRENT_MON")
	)
	(segment
		(start 12.0142 -180.2511)
		(end 12.0142 -178.9176)
		(width 0.508)
		(layer "F.Cu")
		(net "AGND_CURRENT_MON")
	)
	(segment
		(start 10.8966 -194.7545)
		(end 10.8966 -195.5546)
		(width 0.508)
		(layer "F.Cu")
		(net "AGND_CURRENT_MON")
	)
	(segment
		(start 15.113 -182.2196)
		(end 14.3764 -182.9562)
		(width 0.3048)
		(layer "F.Cu")
		(net "AGND_CURRENT_MON")
	)
	(segment
		(start 21.7932 -187.0456)
		(end 22.6568 -187.0456)
		(width 0.508)
		(layer "F.Cu")
		(net "AGND_CURRENT_MON")
	)
	(segment
		(start 10.7442 -179.0446)
		(end 10.9982 -179.2986)
		(width 0.508)
		(layer "F.Cu")
		(net "AGND_CURRENT_MON")
	)
	(segment
		(start 10.8966 -195.5546)
		(end 10.8712 -195.58)
		(width 0.508)
		(layer "F.Cu")
		(net "AGND_CURRENT_MON")
	)
	(segment
		(start 14.3764 -182.9562)
		(end 14.3764 -182.9816)
		(width 0.3048)
		(layer "F.Cu")
		(net "AGND_CURRENT_MON")
	)
	(segment
		(start 13.5001 -195.7832)
		(end 13.5001 -196.7611)
		(width 0.508)
		(layer "F.Cu")
		(net "AGND_CURRENT_MON")
	)
	(segment
		(start 21.8186 -190.3222)
		(end 22.6822 -190.3222)
		(width 0.508)
		(layer "F.Cu")
		(net "AGND_CURRENT_MON")
	)
	(segment
		(start 21.0947 -191.4398)
		(end 22.733 -191.4398)
		(width 0.508)
		(layer "F.Cu")
		(net "AGND_CURRENT_MON")
	)
	(segment
		(start 6.3627 -189.7126)
		(end 6.3627 -190.5381)
		(width 0.508)
		(layer "F.Cu")
		(net "AGND_CURRENT_MON")
	)
	(segment
		(start 6.3627 -190.5381)
		(end 6.096 -190.8048)
		(width 0.508)
		(layer "F.Cu")
		(net "AGND_CURRENT_MON")
	)
	(segment
		(start 13.2842 -194.7291)
		(end 12.5857 -195.4276)
		(width 0.508)
		(layer "F.Cu")
		(net "AGND_CURRENT_MON")
	)
	(segment
		(start 22.733 -191.4398)
		(end 22.8092 -191.3636)
		(width 0.508)
		(layer "F.Cu")
		(net "AGND_CURRENT_MON")
	)
	(segment
		(start 17.7292 -195.3006)
		(end 17.7292 -196.2658)
		(width 0.508)
		(layer "F.Cu")
		(net "AGND_CURRENT_MON")
	)
	(segment
		(start 12.1412 -195.4276)
		(end 12.1412 -196.3166)
		(width 0.508)
		(layer "F.Cu")
		(net "AGND_CURRENT_MON")
	)
	(segment
		(start 6.096 -190.8556)
		(end 6.858 -191.6176)
		(width 0.508)
		(layer "F.Cu")
		(net "AGND_CURRENT_MON")
	)
	(segment
		(start 12.5857 -195.4276)
		(end 12.1412 -195.4276)
		(width 0.508)
		(layer "F.Cu")
		(net "AGND_CURRENT_MON")
	)
	(segment
		(start 8.89 -194.7799)
		(end 8.89 -195.5546)
		(width 0.508)
		(layer "F.Cu")
		(net "AGND_CURRENT_MON")
	)
	(segment
		(start 9.906 -194.7799)
		(end 9.906 -195.5546)
		(width 0.508)
		(layer "F.Cu")
		(net "AGND_CURRENT_MON")
	)
	(segment
		(start 16.4846 -197.3326)
		(end 16.4846 -198.247)
		(width 0.508)
		(layer "F.Cu")
		(net "AGND_CURRENT_MON")
	)
	(segment
		(start 18.8722 -194.6021)
		(end 18.8722 -195.5673)
		(width 0.508)
		(layer "F.Cu")
		(net "AGND_CURRENT_MON")
	)
	(segment
		(start 14.542262 -183.152542)
		(end 14.37386 -182.98414)
		(width 0.3048)
		(layer "F.Cu")
		(net "AGND_CURRENT_MON")
	)
	(via
		(at 22.6822 -187.0202)
		(size 0.508)
		(drill 0.254)
		(layers "F.Cu" "B.Cu")
		(net "AGND_CURRENT_MON")
	)
	(via
		(at 12.5222 -186.6646)
		(size 0.508)
		(drill 0.254)
		(layers "F.Cu" "B.Cu")
		(net "AGND_CURRENT_MON")
	)
	(via
		(at 22.7076 -190.2968)
		(size 0.508)
		(drill 0.254)
		(layers "F.Cu" "B.Cu")
		(net "AGND_CURRENT_MON")
	)
	(via
		(at 16.4846 -198.247)
		(size 0.508)
		(drill 0.254)
		(layers "F.Cu" "B.Cu")
		(net "AGND_CURRENT_MON")
	)
	(via
		(at 17.7292 -196.2658)
		(size 0.508)
		(drill 0.254)
		(layers "F.Cu" "B.Cu")
		(net "AGND_CURRENT_MON")
	)
	(via
		(at 6.096 -190.8048)
		(size 0.7112)
		(drill 0.3556)
		(layers "F.Cu" "B.Cu")
		(net "AGND_CURRENT_MON")
	)
	(via
		(at 18.8722 -195.5673)
		(size 0.508)
		(drill 0.254)
		(layers "F.Cu" "B.Cu")
		(net "AGND_CURRENT_MON")
	)
	(via
		(at 6.858 -191.6176)
		(size 0.508)
		(drill 0.254)
		(layers "F.Cu" "B.Cu")
		(net "AGND_CURRENT_MON")
	)
	(via
		(at 22.7076 -193.6496)
		(size 0.508)
		(drill 0.254)
		(layers "F.Cu" "B.Cu")
		(net "AGND_CURRENT_MON")
	)
	(via
		(at 10.8712 -195.58)
		(size 0.508)
		(drill 0.254)
		(layers "F.Cu" "B.Cu")
		(net "AGND_CURRENT_MON")
	)
	(via
		(at 8.89 -195.5546)
		(size 0.508)
		(drill 0.254)
		(layers "F.Cu" "B.Cu")
		(net "AGND_CURRENT_MON")
	)
	(via
		(at 13.7922 -187.9346)
		(size 0.508)
		(drill 0.254)
		(layers "F.Cu" "B.Cu")
		(net "AGND_CURRENT_MON")
	)
	(via
		(at 15.748 -181.102)
		(size 0.508)
		(drill 0.254)
		(layers "F.Cu" "B.Cu")
		(net "AGND_CURRENT_MON")
	)
	(via
		(at 22.8092 -191.3636)
		(size 0.508)
		(drill 0.254)
		(layers "F.Cu" "B.Cu")
		(net "AGND_CURRENT_MON")
	)
	(via
		(at 22.0726 -192.5066)
		(size 0.508)
		(drill 0.254)
		(layers "F.Cu" "B.Cu")
		(net "AGND_CURRENT_MON")
	)
	(via
		(at 9.906 -195.5546)
		(size 0.508)
		(drill 0.254)
		(layers "F.Cu" "B.Cu")
		(net "AGND_CURRENT_MON")
	)
	(via
		(at 13.7922 -186.6646)
		(size 0.508)
		(drill 0.254)
		(layers "F.Cu" "B.Cu")
		(net "AGND_CURRENT_MON")
	)
	(via
		(at 12.1412 -196.3166)
		(size 0.508)
		(drill 0.254)
		(layers "F.Cu" "B.Cu")
		(net "AGND_CURRENT_MON")
	)
	(via
		(at 14.37386 -182.98414)
		(size 0.508)
		(drill 0.254)
		(layers "F.Cu" "B.Cu")
		(net "AGND_CURRENT_MON")
	)
	(via
		(at 12.0142 -178.9176)
		(size 0.508)
		(drill 0.254)
		(layers "F.Cu" "B.Cu")
		(net "AGND_CURRENT_MON")
	)
	(via
		(at 10.7442 -179.0446)
		(size 0.508)
		(drill 0.254)
		(layers "F.Cu" "B.Cu")
		(net "AGND_CURRENT_MON")
	)
	(via
		(at 15.0622 -186.6646)
		(size 0.508)
		(drill 0.254)
		(layers "F.Cu" "B.Cu")
		(net "AGND_CURRENT_MON")
	)
	(via
		(at 13.7922 -185.3946)
		(size 0.508)
		(drill 0.254)
		(layers "F.Cu" "B.Cu")
		(net "AGND_CURRENT_MON")
	)
	(via
		(at 13.335 -198.0184)
		(size 0.508)
		(drill 0.254)
		(layers "F.Cu" "B.Cu")
		(net "AGND_CURRENT_MON")
	)
	(segment
		(start 45.70476 -132.484876)
		(end 46.104556 -132.08508)
		(width 0.3556)
		(layer "F.Cu")
		(net "ADCVREXT")
	)
	(via
		(at 46.104556 -132.08508)
		(size 0.4572)
		(drill 0.2032)
		(layers "F.Cu" "B.Cu")
		(net "ADCVREXT")
	)
	(via
		(at 48.000412 -133.226302)
		(size 0.7112)
		(drill 0.3556)
		(layers "F.Cu" "B.Cu")
		(net "ADCVREXT")
	)
	(segment
		(start 46.104556 -132.08508)
		(end 46.750478 -132.731002)
		(width 0.254)
		(layer "B.Cu")
		(net "ADCVREXT")
	)
	(segment
		(start 47.505112 -132.731002)
		(end 48.000412 -133.226302)
		(width 0.254)
		(layer "B.Cu")
		(net "ADCVREXT")
	)
	(segment
		(start 46.750478 -132.731002)
		(end 47.505112 -132.731002)
		(width 0.254)
		(layer "B.Cu")
		(net "ADCVREXT")
	)
	(segment
		(start 46.1645 -131.445)
		(end 46.1645 -132.025136)
		(width 0.508)
		(layer "B.Cu")
		(net "ADCVREXT")
	)
	(segment
		(start 46.1645 -132.025136)
		(end 46.104556 -132.08508)
		(width 0.508)
		(layer "B.Cu")
		(net "ADCVREXT")
	)
	(segment
		(start 53.084476 -129.474976)
		(end 50.348642 -129.474976)
		(width 0.508)
		(layer "F.Cu")
		(net "ADCVREFFP")
	)
	(segment
		(start 53.213 -129.6035)
		(end 53.084476 -129.474976)
		(width 0.508)
		(layer "F.Cu")
		(net "ADCVREFFP")
	)
	(segment
		(start 50.348642 -129.474976)
		(end 47.563024 -129.474976)
		(width 0.508)
		(layer "F.Cu")
		(net "ADCVREFFP")
	)
	(segment
		(start 47.373032 -129.284984)
		(end 46.50486 -129.284984)
		(width 0.2032)
		(layer "F.Cu")
		(net "ADCVREFFP")
	)
	(segment
		(start 54.229 -129.6035)
		(end 53.213 -129.6035)
		(width 0.508)
		(layer "F.Cu")
		(net "ADCVREFFP")
	)
	(segment
		(start 47.563024 -129.474976)
		(end 47.373032 -129.284984)
		(width 0.2032)
		(layer "F.Cu")
		(net "ADCVREFFP")
	)
	(via
		(at 50.348642 -129.474976)
		(size 0.7112)
		(drill 0.3556)
		(layers "F.Cu" "B.Cu")
		(net "ADCVREFFP")
	)
	(segment
		(start 51.324256 -130.288284)
		(end 47.514002 -130.288284)
		(width 0.508)
		(layer "F.Cu")
		(net "ADCVREFFN")
	)
	(segment
		(start 52.417472 -131.3815)
		(end 51.324256 -130.288284)
		(width 0.508)
		(layer "F.Cu")
		(net "ADCVREFFN")
	)
	(segment
		(start 47.514002 -130.288284)
		(end 47.449232 -130.223514)
		(width 0.508)
		(layer "F.Cu")
		(net "ADCVREFFN")
	)
	(segment
		(start 53.213 -131.3815)
		(end 52.417472 -131.3815)
		(width 0.508)
		(layer "F.Cu")
		(net "ADCVREFFN")
	)
	(segment
		(start 46.09846 -129.678684)
		(end 45.70476 -129.284984)
		(width 0.1778)
		(layer "F.Cu")
		(net "ADCVREFFN")
	)
	(segment
		(start 53.213 -131.3815)
		(end 53.213 -130.4925)
		(width 0.508)
		(layer "F.Cu")
		(net "ADCVREFFN")
	)
	(segment
		(start 46.904402 -129.678684)
		(end 46.09846 -129.678684)
		(width 0.1778)
		(layer "F.Cu")
		(net "ADCVREFFN")
	)
	(segment
		(start 53.2765 -131.445)
		(end 53.213 -131.3815)
		(width 0.508)
		(layer "F.Cu")
		(net "ADCVREFFN")
	)
	(segment
		(start 47.449232 -130.223514)
		(end 46.904402 -129.678684)
		(width 0.1778)
		(layer "F.Cu")
		(net "ADCVREFFN")
	)
	(via
		(at 51.324256 -130.288284)
		(size 0.7112)
		(drill 0.3556)
		(layers "F.Cu" "B.Cu")
		(net "ADCVREFFN")
	)
	(segment
		(start 54.39791 -130.4925)
		(end 54.229 -130.4925)
		(width 0.508)
		(layer "F.Cu")
		(net "ADCAV33")
	)
	(segment
		(start 55.7022 -129.2098)
		(end 56.0959 -129.6035)
		(width 0.508)
		(layer "F.Cu")
		(net "ADCAV33")
	)
	(segment
		(start 55.085742 -131.180332)
		(end 54.39791 -130.4925)
		(width 0.508)
		(layer "F.Cu")
		(net "ADCAV33")
	)
	(segment
		(start 58.7248 -129.413)
		(end 58.5343 -129.6035)
		(width 0.508)
		(layer "F.Cu")
		(net "ADCAV33")
	)
	(segment
		(start 44.904914 -132.484876)
		(end 45.30471 -132.08508)
		(width 0.3556)
		(layer "F.Cu")
		(net "ADCAV33")
	)
	(segment
		(start 58.5343 -129.6035)
		(end 57.404 -129.6035)
		(width 0.508)
		(layer "F.Cu")
		(net "ADCAV33")
	)
	(segment
		(start 56.0959 -129.6035)
		(end 56.515 -129.6035)
		(width 0.508)
		(layer "F.Cu")
		(net "ADCAV33")
	)
	(segment
		(start 57.404 -129.6035)
		(end 56.515 -129.6035)
		(width 0.508)
		(layer "F.Cu")
		(net "ADCAV33")
	)
	(via
		(at 55.085742 -131.180332)
		(size 0.508)
		(drill 0.254)
		(layers "F.Cu" "B.Cu")
		(net "ADCAV33")
	)
	(via
		(at 56.515 -130.683)
		(size 0.7112)
		(drill 0.3556)
		(layers "F.Cu" "B.Cu")
		(net "ADCAV33")
	)
	(via
		(at 45.30471 -132.08508)
		(size 0.4572)
		(drill 0.2032)
		(layers "F.Cu" "B.Cu")
		(net "ADCAV33")
	)
	(via
		(at 55.7022 -129.2098)
		(size 0.508)
		(drill 0.254)
		(layers "F.Cu" "B.Cu")
		(net "ADCAV33")
	)
	(segment
		(start 55.085742 -131.180332)
		(end 55.128668 -131.180332)
		(width 0.254)
		(layer "B.Cu")
		(net "ADCAV33")
	)
	(segment
		(start 55.299356 -131.009644)
		(end 56.188356 -131.009644)
		(width 0.254)
		(layer "B.Cu")
		(net "ADCAV33")
	)
	(segment
		(start 56.188356 -131.009644)
		(end 56.515 -130.683)
		(width 0.254)
		(layer "B.Cu")
		(net "ADCAV33")
	)
	(segment
		(start 55.128668 -131.180332)
		(end 55.299356 -131.009644)
		(width 0.254)
		(layer "B.Cu")
		(net "ADCAV33")
	)
	(segment
		(start 55.075074 -131.191)
		(end 48.4886 -131.191)
		(width 0.4318)
		(layer "In2.Cu")
		(net "ADCAV33")
	)
	(segment
		(start 55.085742 -131.180332)
		(end 55.075074 -131.191)
		(width 0.4318)
		(layer "In2.Cu")
		(net "ADCAV33")
	)
	(segment
		(start 46.651164 -130.738626)
		(end 45.30471 -132.08508)
		(width 0.4318)
		(layer "In2.Cu")
		(net "ADCAV33")
	)
	(segment
		(start 48.4886 -131.191)
		(end 48.036226 -130.738626)
		(width 0.4318)
		(layer "In2.Cu")
		(net "ADCAV33")
	)
	(segment
		(start 48.036226 -130.738626)
		(end 46.651164 -130.738626)
		(width 0.4318)
		(layer "In2.Cu")
		(net "ADCAV33")
	)
	(segment
		(start 55.7022 -129.2098)
		(end 55.6768 -129.2352)
		(width 0.508)
		(layer "In5.Cu")
		(net "ADCAV33")
	)
	(segment
		(start 54.6608 -130.75539)
		(end 55.085742 -131.180332)
		(width 0.508)
		(layer "In5.Cu")
		(net "ADCAV33")
	)
	(segment
		(start 54.6608 -129.7432)
		(end 54.6608 -130.75539)
		(width 0.508)
		(layer "In5.Cu")
		(net "ADCAV33")
	)
	(segment
		(start 55.1688 -129.2352)
		(end 54.6608 -129.7432)
		(width 0.508)
		(layer "In5.Cu")
		(net "ADCAV33")
	)
	(segment
		(start 55.6768 -129.2352)
		(end 55.1688 -129.2352)
		(width 0.508)
		(layer "In5.Cu")
		(net "ADCAV33")
	)
	(segment
		(start 61.595 -132.63753)
		(end 61.595 -132.3975)
		(width 0.12065)
		(layer "F.Cu")
		(net "ADC0_12V_BMC")
	)
	(segment
		(start 59.987942 -132.192776)
		(end 59.763914 -132.416804)
		(width 0.12065)
		(layer "F.Cu")
		(net "ADC0_12V_BMC")
	)
	(segment
		(start 59.97702 -132.853938)
		(end 61.378592 -132.853938)
		(width 0.12065)
		(layer "F.Cu")
		(net "ADC0_12V_BMC")
	)
	(segment
		(start 60.787534 -132.354574)
		(end 60.625736 -132.192776)
		(width 0.12065)
		(layer "F.Cu")
		(net "ADC0_12V_BMC")
	)
	(segment
		(start 59.763914 -132.640832)
		(end 59.97702 -132.853938)
		(width 0.12065)
		(layer "F.Cu")
		(net "ADC0_12V_BMC")
	)
	(segment
		(start 60.625736 -132.192776)
		(end 59.987942 -132.192776)
		(width 0.12065)
		(layer "F.Cu")
		(net "ADC0_12V_BMC")
	)
	(segment
		(start 61.378592 -132.853938)
		(end 61.595 -132.63753)
		(width 0.12065)
		(layer "F.Cu")
		(net "ADC0_12V_BMC")
	)
	(segment
		(start 59.763914 -132.416804)
		(end 59.763914 -132.640832)
		(width 0.12065)
		(layer "F.Cu")
		(net "ADC0_12V_BMC")
	)
	(segment
		(start 43.304714 -130.08483)
		(end 43.70451 -129.685034)
		(width 0.12065)
		(layer "F.Cu")
		(net "ADC0_12V_BMC")
	)
	(via
		(at 60.787534 -132.354574)
		(size 0.508)
		(drill 0.254)
		(layers "F.Cu" "B.Cu")
		(net "ADC0_12V_BMC")
	)
	(via
		(at 43.70451 -129.685034)
		(size 0.4572)
		(drill 0.2032)
		(layers "F.Cu" "B.Cu")
		(net "ADC0_12V_BMC")
	)
	(via
		(at 59.763914 -132.416804)
		(size 0.7112)
		(drill 0.3556)
		(layers "F.Cu" "B.Cu")
		(net "ADC0_12V_BMC")
	)
	(segment
		(start 44.9072 -130.330702)
		(end 44.9072 -132.244592)
		(width 0.127)
		(layer "In2.Cu")
		(net "ADC0_12V_BMC")
	)
	(segment
		(start 43.70451 -129.685034)
		(end 43.947588 -129.685034)
		(width 0.127)
		(layer "In2.Cu")
		(net "ADC0_12V_BMC")
	)
	(segment
		(start 44.9072 -132.244592)
		(end 45.141388 -132.47878)
		(width 0.127)
		(layer "In2.Cu")
		(net "ADC0_12V_BMC")
	)
	(segment
		(start 43.947588 -129.685034)
		(end 44.341288 -130.078734)
		(width 0.127)
		(layer "In2.Cu")
		(net "ADC0_12V_BMC")
	)
	(segment
		(start 55.029862 -132.47878)
		(end 55.050182 -132.4991)
		(width 0.127)
		(layer "In2.Cu")
		(net "ADC0_12V_BMC")
	)
	(segment
		(start 45.141388 -132.47878)
		(end 55.029862 -132.47878)
		(width 0.127)
		(layer "In2.Cu")
		(net "ADC0_12V_BMC")
	)
	(segment
		(start 44.341288 -130.078734)
		(end 44.655232 -130.078734)
		(width 0.127)
		(layer "In2.Cu")
		(net "ADC0_12V_BMC")
	)
	(segment
		(start 55.439818 -132.4991)
		(end 55.584344 -132.354574)
		(width 0.127)
		(layer "In2.Cu")
		(net "ADC0_12V_BMC")
	)
	(segment
		(start 55.584344 -132.354574)
		(end 60.787534 -132.354574)
		(width 0.127)
		(layer "In2.Cu")
		(net "ADC0_12V_BMC")
	)
	(segment
		(start 55.050182 -132.4991)
		(end 55.439818 -132.4991)
		(width 0.127)
		(layer "In2.Cu")
		(net "ADC0_12V_BMC")
	)
	(segment
		(start 44.655232 -130.078734)
		(end 44.9072 -130.330702)
		(width 0.127)
		(layer "In2.Cu")
		(net "ADC0_12V_BMC")
	)
	(segment
		(start 44.104814 -130.08483)
		(end 44.50461 -129.685034)
		(width 0.12065)
		(layer "F.Cu")
		(net "ADC_P5V_STBY_BMC")
	)
	(via
		(at 44.50461 -129.685034)
		(size 0.4572)
		(drill 0.2032)
		(layers "F.Cu" "B.Cu")
		(net "ADC_P5V_STBY_BMC")
	)
	(via
		(at 51.2826 -133.477)
		(size 0.7112)
		(drill 0.3556)
		(layers "F.Cu" "B.Cu")
		(net "ADC_P5V_STBY_BMC")
	)
	(segment
		(start 45.468794 -130.0734)
		(end 47.455328 -130.0734)
		(width 0.12065)
		(layer "B.Cu")
		(net "ADC_P5V_STBY_BMC")
	)
	(segment
		(start 51.2826 -133.477)
		(end 53.2765 -133.477)
		(width 0.12065)
		(layer "B.Cu")
		(net "ADC_P5V_STBY_BMC")
	)
	(segment
		(start 47.455328 -130.0734)
		(end 50.858928 -133.477)
		(width 0.12065)
		(layer "B.Cu")
		(net "ADC_P5V_STBY_BMC")
	)
	(segment
		(start 45.142912 -130.075686)
		(end 45.466508 -130.075686)
		(width 0.12065)
		(layer "B.Cu")
		(net "ADC_P5V_STBY_BMC")
	)
	(segment
		(start 45.140626 -130.0734)
		(end 45.142912 -130.075686)
		(width 0.12065)
		(layer "B.Cu")
		(net "ADC_P5V_STBY_BMC")
	)
	(segment
		(start 44.50461 -129.685034)
		(end 44.892976 -130.0734)
		(width 0.12065)
		(layer "B.Cu")
		(net "ADC_P5V_STBY_BMC")
	)
	(segment
		(start 45.466508 -130.075686)
		(end 45.468794 -130.0734)
		(width 0.12065)
		(layer "B.Cu")
		(net "ADC_P5V_STBY_BMC")
	)
	(segment
		(start 50.858928 -133.477)
		(end 51.2826 -133.477)
		(width 0.12065)
		(layer "B.Cu")
		(net "ADC_P5V_STBY_BMC")
	)
	(segment
		(start 44.892976 -130.0734)
		(end 45.140626 -130.0734)
		(width 0.12065)
		(layer "B.Cu")
		(net "ADC_P5V_STBY_BMC")
	)
	(via
		(at 55.191914 -133.34238)
		(size 0.7112)
		(drill 0.3556)
		(layers "F.Cu" "B.Cu")
		(net "ADC_P5V_STBY")
	)
	(segment
		(start 56.134 -133.5405)
		(end 55.93588 -133.34238)
		(width 0.12065)
		(layer "B.Cu")
		(net "ADC_P5V_STBY")
	)
	(segment
		(start 55.191914 -133.34238)
		(end 54.30012 -133.34238)
		(width 0.12065)
		(layer "B.Cu")
		(net "ADC_P5V_STBY")
	)
	(segment
		(start 55.93588 -133.34238)
		(end 55.191914 -133.34238)
		(width 0.12065)
		(layer "B.Cu")
		(net "ADC_P5V_STBY")
	)
	(segment
		(start 57.15 -133.5405)
		(end 56.134 -133.5405)
		(width 0.12065)
		(layer "B.Cu")
		(net "ADC_P5V_STBY")
	)
	(segment
		(start 54.30012 -133.34238)
		(end 54.1655 -133.477)
		(width 0.12065)
		(layer "B.Cu")
		(net "ADC_P5V_STBY")
	)
	(segment
		(start 58.166 -133.5405)
		(end 57.15 -133.5405)
		(width 0.12065)
		(layer "B.Cu")
		(net "ADC_P5V_STBY")
	)
	(segment
		(start 44.904914 -130.08483)
		(end 45.30471 -129.685034)
		(width 0.12065)
		(layer "F.Cu")
		(net "ADC_P3V3_STBY_BMC")
	)
	(via
		(at 45.30471 -129.685034)
		(size 0.4572)
		(drill 0.2032)
		(layers "F.Cu" "B.Cu")
		(net "ADC_P3V3_STBY_BMC")
	)
	(via
		(at 52.07 -132.461)
		(size 0.7112)
		(drill 0.3556)
		(layers "F.Cu" "B.Cu")
		(net "ADC_P3V3_STBY_BMC")
	)
	(segment
		(start 52.07 -132.461)
		(end 53.2765 -132.461)
		(width 0.12065)
		(layer "B.Cu")
		(net "ADC_P3V3_STBY_BMC")
	)
	(segment
		(start 45.30471 -129.685034)
		(end 47.579026 -129.685034)
		(width 0.12065)
		(layer "B.Cu")
		(net "ADC_P3V3_STBY_BMC")
	)
	(segment
		(start 47.579026 -129.685034)
		(end 50.354992 -132.461)
		(width 0.12065)
		(layer "B.Cu")
		(net "ADC_P3V3_STBY_BMC")
	)
	(segment
		(start 50.354992 -132.461)
		(end 52.07 -132.461)
		(width 0.12065)
		(layer "B.Cu")
		(net "ADC_P3V3_STBY_BMC")
	)
	(via
		(at 59.360054 -132.743194)
		(size 0.7112)
		(drill 0.3556)
		(layers "F.Cu" "B.Cu")
		(net "ADC_P3V3_STBY")
	)
	(segment
		(start 59.14136 -132.5245)
		(end 59.360054 -132.743194)
		(width 0.12065)
		(layer "B.Cu")
		(net "ADC_P3V3_STBY")
	)
	(segment
		(start 57.15 -132.5245)
		(end 58.166 -132.5245)
		(width 0.12065)
		(layer "B.Cu")
		(net "ADC_P3V3_STBY")
	)
	(segment
		(start 58.166 -132.5245)
		(end 59.14136 -132.5245)
		(width 0.12065)
		(layer "B.Cu")
		(net "ADC_P3V3_STBY")
	)
	(segment
		(start 55.61203 -132.5245)
		(end 55.551578 -132.584952)
		(width 0.12065)
		(layer "B.Cu")
		(net "ADC_P3V3_STBY")
	)
	(segment
		(start 55.014622 -132.584952)
		(end 54.95417 -132.5245)
		(width 0.12065)
		(layer "B.Cu")
		(net "ADC_P3V3_STBY")
	)
	(segment
		(start 56.134 -132.5245)
		(end 55.61203 -132.5245)
		(width 0.12065)
		(layer "B.Cu")
		(net "ADC_P3V3_STBY")
	)
	(segment
		(start 57.15 -132.5245)
		(end 56.134 -132.5245)
		(width 0.12065)
		(layer "B.Cu")
		(net "ADC_P3V3_STBY")
	)
	(segment
		(start 54.229 -132.5245)
		(end 54.1655 -132.461)
		(width 0.12065)
		(layer "B.Cu")
		(net "ADC_P3V3_STBY")
	)
	(segment
		(start 54.95417 -132.5245)
		(end 54.229 -132.5245)
		(width 0.12065)
		(layer "B.Cu")
		(net "ADC_P3V3_STBY")
	)
	(segment
		(start 55.551578 -132.584952)
		(end 55.014622 -132.584952)
		(width 0.12065)
		(layer "B.Cu")
		(net "ADC_P3V3_STBY")
	)
	(segment
		(start 51.8668 -132.7404)
		(end 52.0954 -132.7404)
		(width 0.12065)
		(layer "F.Cu")
		(net "ADC_P1V8_STBY_BMC")
	)
	(segment
		(start 48.298354 -132.097018)
		(end 50.436018 -132.097018)
		(width 0.12065)
		(layer "F.Cu")
		(net "ADC_P1V8_STBY_BMC")
	)
	(segment
		(start 52.832 -133.477)
		(end 53.2765 -133.477)
		(width 0.12065)
		(layer "F.Cu")
		(net "ADC_P1V8_STBY_BMC")
	)
	(segment
		(start 50.991262 -132.699252)
		(end 51.038252 -132.699252)
		(width 0.12065)
		(layer "F.Cu")
		(net "ADC_P1V8_STBY_BMC")
	)
	(segment
		(start 52.0954 -132.7404)
		(end 52.832 -133.477)
		(width 0.12065)
		(layer "F.Cu")
		(net "ADC_P1V8_STBY_BMC")
	)
	(segment
		(start 46.655736 -130.4544)
		(end 48.298354 -132.097018)
		(width 0.12065)
		(layer "F.Cu")
		(net "ADC_P1V8_STBY_BMC")
	)
	(segment
		(start 51.0794 -132.7404)
		(end 51.8668 -132.7404)
		(width 0.12065)
		(layer "F.Cu")
		(net "ADC_P1V8_STBY_BMC")
	)
	(segment
		(start 50.436018 -132.097018)
		(end 50.658268 -132.319268)
		(width 0.12065)
		(layer "F.Cu")
		(net "ADC_P1V8_STBY_BMC")
	)
	(segment
		(start 50.658268 -132.366258)
		(end 50.991262 -132.699252)
		(width 0.12065)
		(layer "F.Cu")
		(net "ADC_P1V8_STBY_BMC")
	)
	(segment
		(start 46.07433 -130.4544)
		(end 46.655736 -130.4544)
		(width 0.12065)
		(layer "F.Cu")
		(net "ADC_P1V8_STBY_BMC")
	)
	(segment
		(start 51.038252 -132.699252)
		(end 51.0794 -132.7404)
		(width 0.12065)
		(layer "F.Cu")
		(net "ADC_P1V8_STBY_BMC")
	)
	(segment
		(start 45.70476 -130.08483)
		(end 46.07433 -130.4544)
		(width 0.12065)
		(layer "F.Cu")
		(net "ADC_P1V8_STBY_BMC")
	)
	(segment
		(start 50.658268 -132.319268)
		(end 50.658268 -132.366258)
		(width 0.12065)
		(layer "F.Cu")
		(net "ADC_P1V8_STBY_BMC")
	)
	(via
		(at 51.8668 -132.7404)
		(size 0.7112)
		(drill 0.3556)
		(layers "F.Cu" "B.Cu")
		(net "ADC_P1V8_STBY_BMC")
	)
	(segment
		(start 57.15 -133.5405)
		(end 56.134 -133.5405)
		(width 0.12065)
		(layer "F.Cu")
		(net "ADC_P1V8_STBY")
	)
	(segment
		(start 57.15 -133.5405)
		(end 58.166 -133.5405)
		(width 0.12065)
		(layer "F.Cu")
		(net "ADC_P1V8_STBY")
	)
	(segment
		(start 54.374542 -133.686042)
		(end 54.1655 -133.477)
		(width 0.12065)
		(layer "F.Cu")
		(net "ADC_P1V8_STBY")
	)
	(segment
		(start 56.134 -133.5405)
		(end 55.988458 -133.686042)
		(width 0.12065)
		(layer "F.Cu")
		(net "ADC_P1V8_STBY")
	)
	(segment
		(start 58.166 -133.5405)
		(end 59.127898 -133.5405)
		(width 0.12065)
		(layer "F.Cu")
		(net "ADC_P1V8_STBY")
	)
	(segment
		(start 59.127898 -133.5405)
		(end 59.207654 -133.620256)
		(width 0.12065)
		(layer "F.Cu")
		(net "ADC_P1V8_STBY")
	)
	(segment
		(start 55.988458 -133.686042)
		(end 54.374542 -133.686042)
		(width 0.12065)
		(layer "F.Cu")
		(net "ADC_P1V8_STBY")
	)
	(via
		(at 59.207654 -133.620256)
		(size 0.7112)
		(drill 0.3556)
		(layers "F.Cu" "B.Cu")
		(net "ADC_P1V8_STBY")
	)
	(segment
		(start 55.159402 -132.990844)
		(end 54.695344 -132.990844)
		(width 0.12065)
		(layer "F.Cu")
		(net "ADC_P1V53V")
	)
	(segment
		(start 57.1246 -132.5245)
		(end 56.134 -132.5245)
		(width 0.12065)
		(layer "F.Cu")
		(net "ADC_P1V53V")
	)
	(segment
		(start 55.667656 -132.990844)
		(end 55.159402 -132.990844)
		(width 0.12065)
		(layer "F.Cu")
		(net "ADC_P1V53V")
	)
	(segment
		(start 57.15 -132.5499)
		(end 57.1246 -132.5245)
		(width 0.12065)
		(layer "F.Cu")
		(net "ADC_P1V53V")
	)
	(segment
		(start 57.15 -132.5499)
		(end 58.166 -132.5499)
		(width 0.12065)
		(layer "F.Cu")
		(net "ADC_P1V53V")
	)
	(segment
		(start 56.134 -132.5245)
		(end 55.667656 -132.990844)
		(width 0.12065)
		(layer "F.Cu")
		(net "ADC_P1V53V")
	)
	(segment
		(start 54.695344 -132.990844)
		(end 54.1655 -132.461)
		(width 0.12065)
		(layer "F.Cu")
		(net "ADC_P1V53V")
	)
	(via
		(at 55.159402 -132.990844)
		(size 0.7112)
		(drill 0.3556)
		(layers "F.Cu" "B.Cu")
		(net "ADC_P1V53V")
	)
	(segment
		(start 50.855118 -131.468622)
		(end 48.105822 -131.468622)
		(width 0.12065)
		(layer "F.Cu")
		(net "ADC_P1V53_BMC")
	)
	(segment
		(start 46.72203 -130.08483)
		(end 46.50486 -130.08483)
		(width 0.12065)
		(layer "F.Cu")
		(net "ADC_P1V53_BMC")
	)
	(segment
		(start 52.269898 -132.025898)
		(end 52.705 -132.461)
		(width 0.12065)
		(layer "F.Cu")
		(net "ADC_P1V53_BMC")
	)
	(segment
		(start 48.105822 -131.468622)
		(end 46.72203 -130.08483)
		(width 0.12065)
		(layer "F.Cu")
		(net "ADC_P1V53_BMC")
	)
	(segment
		(start 52.705 -132.461)
		(end 53.2765 -132.461)
		(width 0.12065)
		(layer "F.Cu")
		(net "ADC_P1V53_BMC")
	)
	(segment
		(start 51.457606 -132.025898)
		(end 52.269898 -132.025898)
		(width 0.12065)
		(layer "F.Cu")
		(net "ADC_P1V53_BMC")
	)
	(segment
		(start 50.90033 -131.468622)
		(end 51.457606 -132.025898)
		(width 0.12065)
		(layer "F.Cu")
		(net "ADC_P1V53_BMC")
	)
	(segment
		(start 50.855118 -131.468622)
		(end 50.90033 -131.468622)
		(width 0.12065)
		(layer "F.Cu")
		(net "ADC_P1V53_BMC")
	)
	(via
		(at 50.855118 -131.468622)
		(size 0.7112)
		(drill 0.3556)
		(layers "F.Cu" "B.Cu")
		(net "ADC_P1V53_BMC")
	)
	(segment
		(start 44.104814 -130.88493)
		(end 44.50461 -130.485134)
		(width 0.12065)
		(layer "F.Cu")
		(net "ADC_P0V9_E_BMC")
	)
	(via
		(at 44.50461 -130.485134)
		(size 0.4572)
		(drill 0.2032)
		(layers "F.Cu" "B.Cu")
		(net "ADC_P0V9_E_BMC")
	)
	(via
		(at 51.1556 -135.2296)
		(size 0.7112)
		(drill 0.3556)
		(layers "F.Cu" "B.Cu")
		(net "ADC_P0V9_E_BMC")
	)
	(segment
		(start 51.689 -135.763)
		(end 53.2765 -135.763)
		(width 0.12065)
		(layer "B.Cu")
		(net "ADC_P0V9_E_BMC")
	)
	(segment
		(start 51.1556 -134.874)
		(end 51.1556 -135.2296)
		(width 0.12065)
		(layer "B.Cu")
		(net "ADC_P0V9_E_BMC")
	)
	(segment
		(start 44.905676 -130.8862)
		(end 47.1678 -130.8862)
		(width 0.12065)
		(layer "B.Cu")
		(net "ADC_P0V9_E_BMC")
	)
	(segment
		(start 51.1556 -135.2296)
		(end 51.689 -135.763)
		(width 0.12065)
		(layer "B.Cu")
		(net "ADC_P0V9_E_BMC")
	)
	(segment
		(start 44.50461 -130.485134)
		(end 44.905676 -130.8862)
		(width 0.12065)
		(layer "B.Cu")
		(net "ADC_P0V9_E_BMC")
	)
	(segment
		(start 47.1678 -130.8862)
		(end 51.1556 -134.874)
		(width 0.12065)
		(layer "B.Cu")
		(net "ADC_P0V9_E_BMC")
	)
	(via
		(at 59.0804 -135.89)
		(size 0.7112)
		(drill 0.3556)
		(layers "F.Cu" "B.Cu")
		(net "ADC_P0V9_E")
	)
	(segment
		(start 56.134 -135.8265)
		(end 55.118 -135.8265)
		(width 0.12065)
		(layer "B.Cu")
		(net "ADC_P0V9_E")
	)
	(segment
		(start 59.0169 -135.8265)
		(end 59.0804 -135.89)
		(width 0.12065)
		(layer "B.Cu")
		(net "ADC_P0V9_E")
	)
	(segment
		(start 54.229 -135.8265)
		(end 54.1655 -135.763)
		(width 0.12065)
		(layer "B.Cu")
		(net "ADC_P0V9_E")
	)
	(segment
		(start 57.15 -135.8265)
		(end 56.134 -135.8265)
		(width 0.12065)
		(layer "B.Cu")
		(net "ADC_P0V9_E")
	)
	(segment
		(start 55.118 -135.8265)
		(end 54.229 -135.8265)
		(width 0.12065)
		(layer "B.Cu")
		(net "ADC_P0V9_E")
	)
	(segment
		(start 57.15 -135.8265)
		(end 59.0169 -135.8265)
		(width 0.12065)
		(layer "B.Cu")
		(net "ADC_P0V9_E")
	)
	(segment
		(start 60.688474 -134.28472)
		(end 61.432694 -133.5405)
		(width 0.12065)
		(layer "F.Cu")
		(net "ADC_P0V9_BMC")
	)
	(segment
		(start 60.1472 -133.6802)
		(end 60.1472 -134.036054)
		(width 0.12065)
		(layer "F.Cu")
		(net "ADC_P0V9_BMC")
	)
	(segment
		(start 61.432694 -133.5405)
		(end 61.595 -133.5405)
		(width 0.12065)
		(layer "F.Cu")
		(net "ADC_P0V9_BMC")
	)
	(segment
		(start 60.457842 -133.369558)
		(end 60.1472 -133.6802)
		(width 0.12065)
		(layer "F.Cu")
		(net "ADC_P0V9_BMC")
	)
	(segment
		(start 60.395866 -134.28472)
		(end 60.688474 -134.28472)
		(width 0.12065)
		(layer "F.Cu")
		(net "ADC_P0V9_BMC")
	)
	(segment
		(start 60.741306 -133.369558)
		(end 60.457842 -133.369558)
		(width 0.12065)
		(layer "F.Cu")
		(net "ADC_P0V9_BMC")
	)
	(segment
		(start 60.1472 -134.036054)
		(end 60.395866 -134.28472)
		(width 0.12065)
		(layer "F.Cu")
		(net "ADC_P0V9_BMC")
	)
	(segment
		(start 43.304714 -130.88493)
		(end 43.70451 -130.485134)
		(width 0.12065)
		(layer "F.Cu")
		(net "ADC_P0V9_BMC")
	)
	(via
		(at 60.395866 -134.28472)
		(size 0.7112)
		(drill 0.3556)
		(layers "F.Cu" "B.Cu")
		(net "ADC_P0V9_BMC")
	)
	(via
		(at 43.70451 -130.485134)
		(size 0.4572)
		(drill 0.2032)
		(layers "F.Cu" "B.Cu")
		(net "ADC_P0V9_BMC")
	)
	(via
		(at 60.741306 -133.369558)
		(size 0.508)
		(drill 0.254)
		(layers "F.Cu" "B.Cu")
		(net "ADC_P0V9_BMC")
	)
	(segment
		(start 44.111164 -130.891788)
		(end 44.111164 -132.721604)
		(width 0.127)
		(layer "In2.Cu")
		(net "ADC_P0V9_BMC")
	)
	(segment
		(start 44.11091 -132.721858)
		(end 44.11091 -133.048502)
		(width 0.127)
		(layer "In2.Cu")
		(net "ADC_P0V9_BMC")
	)
	(segment
		(start 44.11091 -133.048502)
		(end 44.341288 -133.27888)
		(width 0.127)
		(layer "In2.Cu")
		(net "ADC_P0V9_BMC")
	)
	(segment
		(start 44.341288 -133.27888)
		(end 58.58256 -133.27888)
		(width 0.127)
		(layer "In2.Cu")
		(net "ADC_P0V9_BMC")
	)
	(segment
		(start 58.673238 -133.369558)
		(end 60.741306 -133.369558)
		(width 0.127)
		(layer "In2.Cu")
		(net "ADC_P0V9_BMC")
	)
	(segment
		(start 58.58256 -133.27888)
		(end 58.673238 -133.369558)
		(width 0.127)
		(layer "In2.Cu")
		(net "ADC_P0V9_BMC")
	)
	(segment
		(start 43.70451 -130.485134)
		(end 44.111164 -130.891788)
		(width 0.127)
		(layer "In2.Cu")
		(net "ADC_P0V9_BMC")
	)
	(segment
		(start 44.111164 -132.721604)
		(end 44.11091 -132.721858)
		(width 0.127)
		(layer "In2.Cu")
		(net "ADC_P0V9_BMC")
	)
	(segment
		(start 63.649098 -135.232902)
		(end 63.417196 -135.232902)
		(width 0.12065)
		(layer "F.Cu")
		(net "ADC_P0V9")
	)
	(segment
		(start 61.595 -134.4295)
		(end 62.611 -134.4295)
		(width 0.12065)
		(layer "F.Cu")
		(net "ADC_P0V9")
	)
	(segment
		(start 63.046102 -135.232902)
		(end 62.611 -134.7978)
		(width 0.12065)
		(layer "F.Cu")
		(net "ADC_P0V9")
	)
	(segment
		(start 64.389 -134.493)
		(end 63.649098 -135.232902)
		(width 0.12065)
		(layer "F.Cu")
		(net "ADC_P0V9")
	)
	(segment
		(start 65.405 -134.4295)
		(end 64.389 -134.4295)
		(width 0.12065)
		(layer "F.Cu")
		(net "ADC_P0V9")
	)
	(segment
		(start 64.389 -134.4295)
		(end 64.389 -134.493)
		(width 0.12065)
		(layer "F.Cu")
		(net "ADC_P0V9")
	)
	(segment
		(start 62.611 -134.7978)
		(end 62.611 -134.4295)
		(width 0.12065)
		(layer "F.Cu")
		(net "ADC_P0V9")
	)
	(segment
		(start 63.417196 -135.232902)
		(end 63.046102 -135.232902)
		(width 0.12065)
		(layer "F.Cu")
		(net "ADC_P0V9")
	)
	(via
		(at 63.417196 -135.232902)
		(size 0.7112)
		(drill 0.3556)
		(layers "F.Cu" "B.Cu")
		(net "ADC_P0V9")
	)
	(segment
		(start 64.09563 -130.600196)
		(end 64.389 -130.893566)
		(width 0.12065)
		(layer "F.Cu")
		(net "ADC_12V")
	)
	(segment
		(start 65.532 -131.5085)
		(end 64.389 -131.5085)
		(width 0.12065)
		(layer "F.Cu")
		(net "ADC_12V")
	)
	(segment
		(start 63.398654 -130.600196)
		(end 62.763146 -130.600196)
		(width 0.12065)
		(layer "F.Cu")
		(net "ADC_12V")
	)
	(segment
		(start 64.389 -130.893566)
		(end 64.389 -131.5085)
		(width 0.12065)
		(layer "F.Cu")
		(net "ADC_12V")
	)
	(segment
		(start 62.611 -130.752342)
		(end 62.611 -131.5085)
		(width 0.12065)
		(layer "F.Cu")
		(net "ADC_12V")
	)
	(segment
		(start 61.595 -131.5085)
		(end 62.611 -131.5085)
		(width 0.12065)
		(layer "F.Cu")
		(net "ADC_12V")
	)
	(segment
		(start 62.763146 -130.600196)
		(end 62.611 -130.752342)
		(width 0.12065)
		(layer "F.Cu")
		(net "ADC_12V")
	)
	(segment
		(start 63.398654 -130.600196)
		(end 64.09563 -130.600196)
		(width 0.12065)
		(layer "F.Cu")
		(net "ADC_12V")
	)
	(via
		(at 63.398654 -130.600196)
		(size 0.7112)
		(drill 0.3556)
		(layers "F.Cu" "B.Cu")
		(net "ADC_12V")
	)
	(segment
		(start 319.884552 -23.930356)
		(end 319.884298 -23.930102)
		(width 0.136652)
		(layer "F.Cu")
		(net "8644_USB_DP8")
	)
	(segment
		(start 322.095114 -30.358334)
		(end 319.74536 -28.00858)
		(width 0.136652)
		(layer "F.Cu")
		(net "8644_USB_DP8")
	)
	(segment
		(start 319.710816 -26.85288)
		(end 319.71107 -26.85288)
		(width 0.136652)
		(layer "F.Cu")
		(net "8644_USB_DP8")
	)
	(segment
		(start 319.705228 -27.911806)
		(end 319.705228 -26.891742)
		(width 0.136652)
		(layer "F.Cu")
		(net "8644_USB_DP8")
	)
	(segment
		(start 320.150236 -26.042112)
		(end 320.150236 -25.306782)
		(width 0.136652)
		(layer "F.Cu")
		(net "8644_USB_DP8")
	)
	(segment
		(start 322.224654 -32.487108)
		(end 322.224654 -30.670754)
		(width 0.136652)
		(layer "F.Cu")
		(net "8644_USB_DP8")
	)
	(segment
		(start 319.819782 -26.669746)
		(end 319.940432 -26.549096)
		(width 0.136652)
		(layer "F.Cu")
		(net "8644_USB_DP8")
	)
	(segment
		(start 319.884552 -24.664924)
		(end 319.884552 -23.930356)
		(width 0.136652)
		(layer "F.Cu")
		(net "8644_USB_DP8")
	)
	(arc
		(start 319.776856 -26.719784)
		(mid 319.797368 -26.693949)
		(end 319.819782 -26.669746)
		(width 0.136652)
		(layer "F.Cu")
		(net "8644_USB_DP8")
	)
	(arc
		(start 319.71107 -26.85288)
		(mid 319.738225 -26.783497)
		(end 319.776856 -26.719784)
		(width 0.136652)
		(layer "F.Cu")
		(net "8644_USB_DP8")
	)
	(arc
		(start 319.954148 -26.535126)
		(mid 320.099539 -26.307439)
		(end 320.150236 -26.042112)
		(width 0.136652)
		(layer "F.Cu")
		(net "8644_USB_DP8")
	)
	(arc
		(start 322.58127 -33.063434)
		(mid 322.32107 -32.825956)
		(end 322.224654 -32.487108)
		(width 0.136652)
		(layer "F.Cu")
		(net "8644_USB_DP8")
	)
	(arc
		(start 322.224654 -30.670754)
		(mid 322.190929 -30.501677)
		(end 322.095114 -30.358334)
		(width 0.136652)
		(layer "F.Cu")
		(net "8644_USB_DP8")
	)
	(arc
		(start 320.150236 -25.306782)
		(mid 320.097478 -25.041076)
		(end 319.947036 -24.8158)
		(width 0.136652)
		(layer "F.Cu")
		(net "8644_USB_DP8")
	)
	(arc
		(start 319.947036 -24.8158)
		(mid 319.900783 -24.746578)
		(end 319.884552 -24.664924)
		(width 0.136652)
		(layer "F.Cu")
		(net "8644_USB_DP8")
	)
	(arc
		(start 319.940432 -26.549096)
		(mid 319.947338 -26.542158)
		(end 319.954148 -26.535126)
		(width 0.136652)
		(layer "F.Cu")
		(net "8644_USB_DP8")
	)
	(arc
		(start 319.74536 -28.00858)
		(mid 319.715639 -27.964194)
		(end 319.705228 -27.911806)
		(width 0.136652)
		(layer "F.Cu")
		(net "8644_USB_DP8")
	)
	(arc
		(start 319.705228 -26.891742)
		(mid 319.706632 -26.872111)
		(end 319.710816 -26.85288)
		(width 0.136652)
		(layer "F.Cu")
		(net "8644_USB_DP8")
	)
	(segment
		(start 308.940454 -26.549096)
		(end 308.819804 -26.669746)
		(width 0.136652)
		(layer "F.Cu")
		(net "8644_USB_DP7")
	)
	(segment
		(start 308.884574 -23.930356)
		(end 308.884574 -24.664924)
		(width 0.136652)
		(layer "F.Cu")
		(net "8644_USB_DP7")
	)
	(segment
		(start 308.701694 -26.954988)
		(end 308.701694 -32.4866)
		(width 0.136652)
		(layer "F.Cu")
		(net "8644_USB_DP7")
	)
	(segment
		(start 309.150258 -25.306782)
		(end 309.150258 -26.04262)
		(width 0.136652)
		(layer "F.Cu")
		(net "8644_USB_DP7")
	)
	(segment
		(start 308.88432 -23.930102)
		(end 308.884574 -23.930356)
		(width 0.136652)
		(layer "F.Cu")
		(net "8644_USB_DP7")
	)
	(segment
		(start 308.840632 -32.822388)
		(end 309.055008 -33.03651)
		(width 0.136652)
		(layer "F.Cu")
		(net "8644_USB_DP7")
	)
	(arc
		(start 308.819804 -26.669746)
		(mid 308.732359 -26.800616)
		(end 308.701694 -26.954988)
		(width 0.136652)
		(layer "F.Cu")
		(net "8644_USB_DP7")
	)
	(arc
		(start 308.884574 -24.664924)
		(mid 308.900815 -24.746573)
		(end 308.947058 -24.8158)
		(width 0.136652)
		(layer "F.Cu")
		(net "8644_USB_DP7")
	)
	(arc
		(start 309.150258 -26.04262)
		(mid 309.095734 -26.316728)
		(end 308.940454 -26.549096)
		(width 0.136652)
		(layer "F.Cu")
		(net "8644_USB_DP7")
	)
	(arc
		(start 308.947058 -24.8158)
		(mid 309.097492 -25.041079)
		(end 309.150258 -25.306782)
		(width 0.136652)
		(layer "F.Cu")
		(net "8644_USB_DP7")
	)
	(arc
		(start 308.701694 -32.4866)
		(mid 308.737747 -32.668323)
		(end 308.840632 -32.822388)
		(width 0.136652)
		(layer "F.Cu")
		(net "8644_USB_DP7")
	)
	(segment
		(start 297.7007 -32.579564)
		(end 297.7007 -32.22879)
		(width 0.136652)
		(layer "F.Cu")
		(net "8644_USB_DP6")
	)
	(segment
		(start 298.150026 -26.042112)
		(end 298.150026 -25.306782)
		(width 0.136652)
		(layer "F.Cu")
		(net "8644_USB_DP6")
	)
	(segment
		(start 297.819572 -26.669746)
		(end 297.940222 -26.549096)
		(width 0.136652)
		(layer "F.Cu")
		(net "8644_USB_DP6")
	)
	(segment
		(start 297.884342 -24.664924)
		(end 297.884342 -23.930102)
		(width 0.136652)
		(layer "F.Cu")
		(net "8644_USB_DP6")
	)
	(segment
		(start 297.7007 -32.22879)
		(end 297.701208 -26.975816)
		(width 0.136652)
		(layer "F.Cu")
		(net "8644_USB_DP6")
	)
	(segment
		(start 298.063666 -33.050734)
		(end 297.777154 -32.764222)
		(width 0.136652)
		(layer "F.Cu")
		(net "8644_USB_DP6")
	)
	(segment
		(start 297.701208 -26.975816)
		(end 297.700954 -26.975562)
		(width 0.136652)
		(layer "F.Cu")
		(net "8644_USB_DP6")
	)
	(segment
		(start 297.700954 -26.975562)
		(end 297.700954 -26.956258)
		(width 0.136652)
		(layer "F.Cu")
		(net "8644_USB_DP6")
	)
	(arc
		(start 297.940222 -26.549096)
		(mid 297.947128 -26.542158)
		(end 297.953938 -26.535126)
		(width 0.136652)
		(layer "F.Cu")
		(net "8644_USB_DP6")
	)
	(arc
		(start 298.150026 -25.306782)
		(mid 298.097268 -25.041076)
		(end 297.946826 -24.8158)
		(width 0.136652)
		(layer "F.Cu")
		(net "8644_USB_DP6")
	)
	(arc
		(start 297.700954 -26.956258)
		(mid 297.731793 -26.801221)
		(end 297.819572 -26.669746)
		(width 0.136652)
		(layer "F.Cu")
		(net "8644_USB_DP6")
	)
	(arc
		(start 297.946826 -24.8158)
		(mid 297.900573 -24.746578)
		(end 297.884342 -24.664924)
		(width 0.136652)
		(layer "F.Cu")
		(net "8644_USB_DP6")
	)
	(arc
		(start 297.777154 -32.764222)
		(mid 297.720545 -32.6795)
		(end 297.7007 -32.579564)
		(width 0.136652)
		(layer "F.Cu")
		(net "8644_USB_DP6")
	)
	(arc
		(start 297.953938 -26.535126)
		(mid 298.099329 -26.307439)
		(end 298.150026 -26.042112)
		(width 0.136652)
		(layer "F.Cu")
		(net "8644_USB_DP6")
	)
	(segment
		(start 286.291782 -24.279352)
		(end 280.694892 -24.279352)
		(width 0.136652)
		(layer "B.Cu")
		(net "8644_USB_DP5")
	)
	(segment
		(start 270.366744 -17.734788)
		(end 270.016732 -17.384776)
		(width 0.136652)
		(layer "B.Cu")
		(net "8644_USB_DP5")
	)
	(segment
		(start 274.150328 -17.734788)
		(end 270.366744 -17.734788)
		(width 0.136652)
		(layer "B.Cu")
		(net "8644_USB_DP5")
	)
	(segment
		(start 280.694892 -24.279352)
		(end 274.150328 -17.734788)
		(width 0.136652)
		(layer "B.Cu")
		(net "8644_USB_DP5")
	)
	(segment
		(start 270.016732 -17.384776)
		(end 269.580868 -17.384776)
		(width 0.136652)
		(layer "B.Cu")
		(net "8644_USB_DP5")
	)
	(arc
		(start 286.884364 -23.930102)
		(mid 286.635695 -24.185519)
		(end 286.291782 -24.279352)
		(width 0.136652)
		(layer "B.Cu")
		(net "8644_USB_DP5")
	)
	(segment
		(start 167.736266 -25.807416)
		(end 167.409368 -25.329388)
		(width 0.136652)
		(layer "F.Cu")
		(net "8644_USB_DP4")
	)
	(segment
		(start 171.454572 -30.296612)
		(end 170.592496 -29.692854)
		(width 0.136652)
		(layer "F.Cu")
		(net "8644_USB_DP4")
	)
	(segment
		(start 168.965626 -27.070304)
		(end 168.516046 -26.428446)
		(width 0.136652)
		(layer "F.Cu")
		(net "8644_USB_DP4")
	)
	(segment
		(start 168.264078 -26.176224)
		(end 167.736266 -25.807416)
		(width 0.136652)
		(layer "F.Cu")
		(net "8644_USB_DP4")
	)
	(segment
		(start 178.434492 -28.221178)
		(end 175.506126 -30.271974)
		(width 0.136652)
		(layer "F.Cu")
		(net "8644_USB_DP4")
	)
	(segment
		(start 175.128936 -30.428184)
		(end 173.689772 -30.68193)
		(width 0.136652)
		(layer "F.Cu")
		(net "8644_USB_DP4")
	)
	(segment
		(start 173.315884 -30.68193)
		(end 171.694094 -30.395926)
		(width 0.136652)
		(layer "F.Cu")
		(net "8644_USB_DP4")
	)
	(segment
		(start 167.393366 -25.305766)
		(end 167.373554 -25.2857)
		(width 0.136652)
		(layer "F.Cu")
		(net "8644_USB_DP4")
	)
	(segment
		(start 184.713372 -27.6606)
		(end 181.088284 -27.6606)
		(width 0.136652)
		(layer "F.Cu")
		(net "8644_USB_DP4")
	)
	(segment
		(start 167.409368 -25.329134)
		(end 167.393366 -25.305766)
		(width 0.136652)
		(layer "F.Cu")
		(net "8644_USB_DP4")
	)
	(segment
		(start 167.373554 -25.2857)
		(end 167.181784 -25.09393)
		(width 0.136652)
		(layer "F.Cu")
		(net "8644_USB_DP4")
	)
	(segment
		(start 167.409368 -25.329388)
		(end 167.409368 -25.329134)
		(width 0.136652)
		(layer "F.Cu")
		(net "8644_USB_DP4")
	)
	(segment
		(start 169.205402 -27.788108)
		(end 169.162984 -27.546808)
		(width 0.136652)
		(layer "F.Cu")
		(net "8644_USB_DP4")
	)
	(segment
		(start 186.77382 -27.79014)
		(end 186.77382 -27.926284)
		(width 0.136652)
		(layer "F.Cu")
		(net "8644_USB_DP4")
	)
	(segment
		(start 185.365898 -28.086812)
		(end 185.099706 -27.82062)
		(width 0.136652)
		(layer "F.Cu")
		(net "8644_USB_DP4")
	)
	(segment
		(start 180.506624 -27.7114)
		(end 179.042568 -27.969718)
		(width 0.136652)
		(layer "F.Cu")
		(net "8644_USB_DP4")
	)
	(segment
		(start 166.88435 -24.356822)
		(end 166.88435 -23.930102)
		(width 0.136652)
		(layer "F.Cu")
		(net "8644_USB_DP4")
	)
	(segment
		(start 186.47283 -28.227274)
		(end 185.704734 -28.227274)
		(width 0.136652)
		(layer "F.Cu")
		(net "8644_USB_DP4")
	)
	(segment
		(start 170.188382 -29.28874)
		(end 169.3037 -28.025598)
		(width 0.136652)
		(layer "F.Cu")
		(net "8644_USB_DP4")
	)
	(segment
		(start 168.516046 -26.428446)
		(end 168.264078 -26.176224)
		(width 0.136652)
		(layer "F.Cu")
		(net "8644_USB_DP4")
	)
	(arc
		(start 179.042568 -27.969718)
		(mid 178.724759 -28.062144)
		(end 178.434492 -28.221178)
		(width 0.136652)
		(layer "F.Cu")
		(net "8644_USB_DP4")
	)
	(arc
		(start 167.181784 -25.09393)
		(mid 166.961542 -24.754242)
		(end 166.88435 -24.356822)
		(width 0.136652)
		(layer "F.Cu")
		(net "8644_USB_DP4")
	)
	(arc
		(start 175.506126 -30.271974)
		(mid 175.326089 -30.370747)
		(end 175.128936 -30.428184)
		(width 0.136652)
		(layer "F.Cu")
		(net "8644_USB_DP4")
	)
	(arc
		(start 173.689772 -30.68193)
		(mid 173.502828 -30.698282)
		(end 173.315884 -30.68193)
		(width 0.136652)
		(layer "F.Cu")
		(net "8644_USB_DP4")
	)
	(arc
		(start 169.162984 -27.546808)
		(mid 169.090443 -27.297731)
		(end 168.965626 -27.070304)
		(width 0.136652)
		(layer "F.Cu")
		(net "8644_USB_DP4")
	)
	(arc
		(start 171.694094 -30.395926)
		(mid 171.568904 -30.35937)
		(end 171.454572 -30.296612)
		(width 0.136652)
		(layer "F.Cu")
		(net "8644_USB_DP4")
	)
	(arc
		(start 185.704734 -28.227274)
		(mid 185.521368 -28.190707)
		(end 185.365898 -28.086812)
		(width 0.136652)
		(layer "F.Cu")
		(net "8644_USB_DP4")
	)
	(arc
		(start 186.77382 -27.926284)
		(mid 186.685662 -28.139116)
		(end 186.47283 -28.227274)
		(width 0.136652)
		(layer "F.Cu")
		(net "8644_USB_DP4")
	)
	(arc
		(start 181.088284 -27.6606)
		(mid 180.796345 -27.6733)
		(end 180.506624 -27.7114)
		(width 0.136652)
		(layer "F.Cu")
		(net "8644_USB_DP4")
	)
	(arc
		(start 170.592496 -29.692854)
		(mid 170.372773 -29.508463)
		(end 170.188382 -29.28874)
		(width 0.136652)
		(layer "F.Cu")
		(net "8644_USB_DP4")
	)
	(arc
		(start 185.099706 -27.82062)
		(mid 184.922454 -27.702184)
		(end 184.713372 -27.6606)
		(width 0.136652)
		(layer "F.Cu")
		(net "8644_USB_DP4")
	)
	(arc
		(start 169.3037 -28.025598)
		(mid 169.241525 -27.912244)
		(end 169.205402 -27.788108)
		(width 0.136652)
		(layer "F.Cu")
		(net "8644_USB_DP4")
	)
	(segment
		(start 156.316426 -25.82545)
		(end 156.316426 -25.546812)
		(width 0.136652)
		(layer "F.Cu")
		(net "8644_USB_DP3")
	)
	(segment
		(start 156.138118 -25.03043)
		(end 156.138118 -25.030176)
		(width 0.136652)
		(layer "F.Cu")
		(net "8644_USB_DP3")
	)
	(segment
		(start 156.898594 -32.977074)
		(end 156.519118 -32.597598)
		(width 0.136652)
		(layer "F.Cu")
		(net "8644_USB_DP3")
	)
	(segment
		(start 156.519118 -32.597598)
		(end 156.519118 -30.149546)
		(width 0.136652)
		(layer "F.Cu")
		(net "8644_USB_DP3")
	)
	(segment
		(start 155.9179 -26.733754)
		(end 156.034232 -26.617422)
		(width 0.136652)
		(layer "F.Cu")
		(net "8644_USB_DP3")
	)
	(segment
		(start 155.753054 -28.967176)
		(end 155.753054 -27.131772)
		(width 0.136652)
		(layer "F.Cu")
		(net "8644_USB_DP3")
	)
	(segment
		(start 156.389578 -29.837126)
		(end 155.918154 -29.365702)
		(width 0.136652)
		(layer "F.Cu")
		(net "8644_USB_DP3")
	)
	(segment
		(start 155.884372 -24.417528)
		(end 155.884372 -23.930102)
		(width 0.136652)
		(layer "F.Cu")
		(net "8644_USB_DP3")
	)
	(arc
		(start 156.240988 -26.284174)
		(mid 156.297445 -26.057894)
		(end 156.316426 -25.82545)
		(width 0.136652)
		(layer "F.Cu")
		(net "8644_USB_DP3")
	)
	(arc
		(start 156.138118 -25.030176)
		(mid 155.950303 -24.749091)
		(end 155.884372 -24.417528)
		(width 0.136652)
		(layer "F.Cu")
		(net "8644_USB_DP3")
	)
	(arc
		(start 156.316426 -25.546812)
		(mid 156.270624 -25.273656)
		(end 156.138118 -25.03043)
		(width 0.136652)
		(layer "F.Cu")
		(net "8644_USB_DP3")
	)
	(arc
		(start 155.7909 -26.92908)
		(mid 155.844165 -26.824759)
		(end 155.9179 -26.733754)
		(width 0.136652)
		(layer "F.Cu")
		(net "8644_USB_DP3")
	)
	(arc
		(start 156.519118 -30.149546)
		(mid 156.485393 -29.980469)
		(end 156.389578 -29.837126)
		(width 0.136652)
		(layer "F.Cu")
		(net "8644_USB_DP3")
	)
	(arc
		(start 155.918154 -29.365702)
		(mid 155.795981 -29.182857)
		(end 155.753054 -28.967176)
		(width 0.136652)
		(layer "F.Cu")
		(net "8644_USB_DP3")
	)
	(arc
		(start 156.202634 -26.37917)
		(mid 156.223228 -26.332244)
		(end 156.240988 -26.284174)
		(width 0.136652)
		(layer "F.Cu")
		(net "8644_USB_DP3")
	)
	(arc
		(start 156.034232 -26.617422)
		(mid 156.1286 -26.505483)
		(end 156.202634 -26.37917)
		(width 0.136652)
		(layer "F.Cu")
		(net "8644_USB_DP3")
	)
	(arc
		(start 155.753054 -27.131772)
		(mid 155.762623 -27.02868)
		(end 155.7909 -26.92908)
		(width 0.136652)
		(layer "F.Cu")
		(net "8644_USB_DP3")
	)
	(segment
		(start 144.34693 -27.296618)
		(end 144.34693 -32.598868)
		(width 0.136652)
		(layer "F.Cu")
		(net "8644_USB_DP2")
	)
	(segment
		(start 144.873218 -26.507186)
		(end 144.532858 -26.847546)
		(width 0.136652)
		(layer "F.Cu")
		(net "8644_USB_DP2")
	)
	(segment
		(start 144.884394 -23.930102)
		(end 144.884394 -24.562816)
		(width 0.136652)
		(layer "F.Cu")
		(net "8644_USB_DP2")
	)
	(segment
		(start 145.148554 -25.3238)
		(end 145.148554 -25.842468)
		(width 0.136652)
		(layer "F.Cu")
		(net "8644_USB_DP2")
	)
	(arc
		(start 144.983708 -24.84882)
		(mid 145.106204 -25.072396)
		(end 145.148554 -25.3238)
		(width 0.136652)
		(layer "F.Cu")
		(net "8644_USB_DP2")
	)
	(arc
		(start 144.897602 -24.673306)
		(mid 144.931239 -24.765684)
		(end 144.983708 -24.84882)
		(width 0.136652)
		(layer "F.Cu")
		(net "8644_USB_DP2")
	)
	(arc
		(start 144.532858 -26.847546)
		(mid 144.395189 -27.053582)
		(end 144.34693 -27.296618)
		(width 0.136652)
		(layer "F.Cu")
		(net "8644_USB_DP2")
	)
	(arc
		(start 144.884394 -24.562816)
		(mid 144.88767 -24.618458)
		(end 144.897602 -24.673306)
		(width 0.136652)
		(layer "F.Cu")
		(net "8644_USB_DP2")
	)
	(arc
		(start 144.34693 -32.598868)
		(mid 144.448376 -32.872915)
		(end 144.7038 -33.01492)
		(width 0.136652)
		(layer "F.Cu")
		(net "8644_USB_DP2")
	)
	(arc
		(start 145.148554 -25.842468)
		(mid 145.076982 -26.202197)
		(end 144.873218 -26.507186)
		(width 0.136652)
		(layer "F.Cu")
		(net "8644_USB_DP2")
	)
	(segment
		(start 127.704342 -31.629858)
		(end 127.704342 -32.6898)
		(width 0.136652)
		(layer "F.Cu")
		(net "8644_USB_DP1")
	)
	(segment
		(start 133.884416 -23.930102)
		(end 133.884162 -23.930356)
		(width 0.136652)
		(layer "F.Cu")
		(net "8644_USB_DP1")
	)
	(segment
		(start 134.07898 -24.958294)
		(end 134.082536 -24.962612)
		(width 0.136652)
		(layer "F.Cu")
		(net "8644_USB_DP1")
	)
	(segment
		(start 129.13106 -30.68574)
		(end 128.64846 -30.68574)
		(width 0.136652)
		(layer "F.Cu")
		(net "8644_USB_DP1")
	)
	(segment
		(start 133.960362 -24.792178)
		(end 134.07898 -24.958294)
		(width 0.136652)
		(layer "F.Cu")
		(net "8644_USB_DP1")
	)
	(segment
		(start 133.884162 -23.930356)
		(end 133.884162 -24.474678)
		(width 0.136652)
		(layer "F.Cu")
		(net "8644_USB_DP1")
	)
	(segment
		(start 134.025132 -26.124408)
		(end 129.69875 -30.45079)
		(width 0.136652)
		(layer "F.Cu")
		(net "8644_USB_DP1")
	)
	(segment
		(start 133.946646 -24.763984)
		(end 133.960362 -24.792178)
		(width 0.136652)
		(layer "F.Cu")
		(net "8644_USB_DP1")
	)
	(arc
		(start 134.082536 -24.962612)
		(mid 134.277759 -25.554558)
		(end 134.025132 -26.124408)
		(width 0.136652)
		(layer "F.Cu")
		(net "8644_USB_DP1")
	)
	(arc
		(start 133.904482 -24.642572)
		(mid 133.907308 -24.653899)
		(end 133.910324 -24.665178)
		(width 0.136652)
		(layer "F.Cu")
		(net "8644_USB_DP1")
	)
	(arc
		(start 133.884162 -24.474678)
		(mid 133.889211 -24.559244)
		(end 133.904482 -24.642572)
		(width 0.136652)
		(layer "F.Cu")
		(net "8644_USB_DP1")
	)
	(arc
		(start 129.69875 -30.45079)
		(mid 129.43829 -30.624764)
		(end 129.13106 -30.68574)
		(width 0.136652)
		(layer "F.Cu")
		(net "8644_USB_DP1")
	)
	(arc
		(start 127.704342 -32.6898)
		(mid 127.809964 -32.985361)
		(end 128.078992 -33.147)
		(width 0.136652)
		(layer "F.Cu")
		(net "8644_USB_DP1")
	)
	(arc
		(start 128.64846 -30.68574)
		(mid 127.980868 -30.962266)
		(end 127.704342 -31.629858)
		(width 0.136652)
		(layer "F.Cu")
		(net "8644_USB_DP1")
	)
	(arc
		(start 133.910324 -24.665178)
		(mid 133.926617 -24.715268)
		(end 133.946646 -24.763984)
		(width 0.136652)
		(layer "F.Cu")
		(net "8644_USB_DP1")
	)
	(segment
		(start 319.13449 -24.981154)
		(end 319.13449 -25.33015)
		(width 0.136652)
		(layer "F.Cu")
		(net "8644_USB_DN8")
	)
	(segment
		(start 319.845436 -26.042112)
		(end 319.845436 -25.306782)
		(width 0.136652)
		(layer "F.Cu")
		(net "8644_USB_DN8")
	)
	(segment
		(start 319.73139 -25.031446)
		(end 319.55359 -24.853646)
		(width 0.136652)
		(layer "F.Cu")
		(net "8644_USB_DN8")
	)
	(segment
		(start 319.370202 -24.7777)
		(end 319.320418 -24.7777)
		(width 0.136652)
		(layer "F.Cu")
		(net "8644_USB_DN8")
	)
	(segment
		(start 321.9196 -32.4866)
		(end 321.919854 -32.486346)
		(width 0.136652)
		(layer "F.Cu")
		(net "8644_USB_DN8")
	)
	(segment
		(start 319.602612 -26.455624)
		(end 319.724786 -26.33345)
		(width 0.136652)
		(layer "F.Cu")
		(net "8644_USB_DN8")
	)
	(segment
		(start 321.919854 -32.486346)
		(end 321.919854 -30.671008)
		(width 0.136652)
		(layer "F.Cu")
		(net "8644_USB_DN8")
	)
	(segment
		(start 321.879468 -30.57398)
		(end 319.529714 -28.224226)
		(width 0.136652)
		(layer "F.Cu")
		(net "8644_USB_DN8")
	)
	(segment
		(start 319.400428 -27.911806)
		(end 319.400428 -26.891488)
		(width 0.136652)
		(layer "F.Cu")
		(net "8644_USB_DN8")
	)
	(arc
		(start 319.55359 -24.853646)
		(mid 319.552451 -24.852499)
		(end 319.551304 -24.85136)
		(width 0.136652)
		(layer "F.Cu")
		(net "8644_USB_DN8")
	)
	(arc
		(start 319.400428 -26.891488)
		(mid 319.404026 -26.834632)
		(end 319.414906 -26.778712)
		(width 0.136652)
		(layer "F.Cu")
		(net "8644_USB_DN8")
	)
	(arc
		(start 319.53073 -26.539444)
		(mid 319.565063 -26.496155)
		(end 319.602612 -26.455624)
		(width 0.136652)
		(layer "F.Cu")
		(net "8644_USB_DN8")
	)
	(arc
		(start 319.414906 -26.778712)
		(mid 319.416657 -26.772608)
		(end 319.418462 -26.76652)
		(width 0.136652)
		(layer "F.Cu")
		(net "8644_USB_DN8")
	)
	(arc
		(start 319.197736 -24.8285)
		(mid 319.150938 -24.898538)
		(end 319.13449 -24.981154)
		(width 0.136652)
		(layer "F.Cu")
		(net "8644_USB_DN8")
	)
	(arc
		(start 321.563238 -33.063688)
		(mid 321.823342 -32.82573)
		(end 321.9196 -32.4866)
		(width 0.136652)
		(layer "F.Cu")
		(net "8644_USB_DN8")
	)
	(arc
		(start 319.418462 -26.76652)
		(mid 319.464772 -26.648124)
		(end 319.53073 -26.539444)
		(width 0.136652)
		(layer "F.Cu")
		(net "8644_USB_DN8")
	)
	(arc
		(start 319.320418 -24.7777)
		(mid 319.254029 -24.790906)
		(end 319.197736 -24.8285)
		(width 0.136652)
		(layer "F.Cu")
		(net "8644_USB_DN8")
	)
	(arc
		(start 319.551304 -24.85136)
		(mid 319.467963 -24.796793)
		(end 319.370202 -24.7777)
		(width 0.136652)
		(layer "F.Cu")
		(net "8644_USB_DN8")
	)
	(arc
		(start 319.529714 -28.224226)
		(mid 319.434021 -28.080871)
		(end 319.400428 -27.911806)
		(width 0.136652)
		(layer "F.Cu")
		(net "8644_USB_DN8")
	)
	(arc
		(start 321.919854 -30.671008)
		(mid 321.909379 -30.618436)
		(end 321.879468 -30.57398)
		(width 0.136652)
		(layer "F.Cu")
		(net "8644_USB_DN8")
	)
	(arc
		(start 319.724786 -26.33345)
		(mid 319.814099 -26.199783)
		(end 319.845436 -26.042112)
		(width 0.136652)
		(layer "F.Cu")
		(net "8644_USB_DN8")
	)
	(arc
		(start 319.845436 -25.306782)
		(mid 319.815796 -25.157772)
		(end 319.73139 -25.031446)
		(width 0.136652)
		(layer "F.Cu")
		(net "8644_USB_DN8")
	)
	(segment
		(start 308.396894 -32.4866)
		(end 308.39664 -32.4866)
		(width 0.136652)
		(layer "F.Cu")
		(net "8644_USB_DN7")
	)
	(segment
		(start 308.39664 -32.4866)
		(end 308.396894 -32.486346)
		(width 0.136652)
		(layer "F.Cu")
		(net "8644_USB_DN7")
	)
	(segment
		(start 308.370224 -24.7777)
		(end 308.32044 -24.7777)
		(width 0.136652)
		(layer "F.Cu")
		(net "8644_USB_DN7")
	)
	(segment
		(start 308.845458 -26.042112)
		(end 308.845458 -25.306782)
		(width 0.136652)
		(layer "F.Cu")
		(net "8644_USB_DN7")
	)
	(segment
		(start 308.731412 -25.031446)
		(end 308.553612 -24.853646)
		(width 0.136652)
		(layer "F.Cu")
		(net "8644_USB_DN7")
	)
	(segment
		(start 308.134512 -24.981154)
		(end 308.134512 -25.33015)
		(width 0.136652)
		(layer "F.Cu")
		(net "8644_USB_DN7")
	)
	(segment
		(start 308.037992 -33.03651)
		(end 308.261766 -32.812482)
		(width 0.136652)
		(layer "F.Cu")
		(net "8644_USB_DN7")
	)
	(segment
		(start 308.396894 -32.486346)
		(end 308.396894 -26.955242)
		(width 0.136652)
		(layer "F.Cu")
		(net "8644_USB_DN7")
	)
	(segment
		(start 308.604158 -26.4541)
		(end 308.724808 -26.33345)
		(width 0.136652)
		(layer "F.Cu")
		(net "8644_USB_DN7")
	)
	(arc
		(start 308.396894 -26.955242)
		(mid 308.450667 -26.684054)
		(end 308.604158 -26.4541)
		(width 0.136652)
		(layer "F.Cu")
		(net "8644_USB_DN7")
	)
	(arc
		(start 308.261766 -32.812482)
		(mid 308.361752 -32.662981)
		(end 308.396894 -32.4866)
		(width 0.136652)
		(layer "F.Cu")
		(net "8644_USB_DN7")
	)
	(arc
		(start 308.553612 -24.853646)
		(mid 308.552473 -24.852499)
		(end 308.551326 -24.85136)
		(width 0.136652)
		(layer "F.Cu")
		(net "8644_USB_DN7")
	)
	(arc
		(start 308.724808 -26.33345)
		(mid 308.814121 -26.199783)
		(end 308.845458 -26.042112)
		(width 0.136652)
		(layer "F.Cu")
		(net "8644_USB_DN7")
	)
	(arc
		(start 308.32044 -24.7777)
		(mid 308.254051 -24.790906)
		(end 308.197758 -24.8285)
		(width 0.136652)
		(layer "F.Cu")
		(net "8644_USB_DN7")
	)
	(arc
		(start 308.551326 -24.85136)
		(mid 308.467985 -24.796793)
		(end 308.370224 -24.7777)
		(width 0.136652)
		(layer "F.Cu")
		(net "8644_USB_DN7")
	)
	(arc
		(start 308.845458 -25.306782)
		(mid 308.815818 -25.157772)
		(end 308.731412 -25.031446)
		(width 0.136652)
		(layer "F.Cu")
		(net "8644_USB_DN7")
	)
	(arc
		(start 308.197758 -24.8285)
		(mid 308.15096 -24.898538)
		(end 308.134512 -24.981154)
		(width 0.136652)
		(layer "F.Cu")
		(net "8644_USB_DN7")
	)
	(segment
		(start 297.55338 -24.853646)
		(end 297.73118 -25.031446)
		(width 0.136652)
		(layer "F.Cu")
		(net "8644_USB_DN6")
	)
	(segment
		(start 297.310302 -32.786574)
		(end 297.044618 -33.052004)
		(width 0.136652)
		(layer "F.Cu")
		(net "8644_USB_DN6")
	)
	(segment
		(start 297.13428 -25.33015)
		(end 297.13428 -24.981154)
		(width 0.136652)
		(layer "F.Cu")
		(net "8644_USB_DN6")
	)
	(segment
		(start 297.845226 -25.306782)
		(end 297.845226 -26.042112)
		(width 0.136652)
		(layer "F.Cu")
		(net "8644_USB_DN6")
	)
	(segment
		(start 297.320208 -24.7777)
		(end 297.369992 -24.7777)
		(width 0.136652)
		(layer "F.Cu")
		(net "8644_USB_DN6")
	)
	(segment
		(start 297.724576 -26.33345)
		(end 297.602402 -26.455624)
		(width 0.136652)
		(layer "F.Cu")
		(net "8644_USB_DN6")
	)
	(segment
		(start 297.3959 -28.790138)
		(end 297.3959 -32.579564)
		(width 0.136652)
		(layer "F.Cu")
		(net "8644_USB_DN6")
	)
	(segment
		(start 297.396154 -26.950416)
		(end 297.3959 -28.790138)
		(width 0.136652)
		(layer "F.Cu")
		(net "8644_USB_DN6")
	)
	(arc
		(start 297.73118 -25.031446)
		(mid 297.815588 -25.157771)
		(end 297.845226 -25.306782)
		(width 0.136652)
		(layer "F.Cu")
		(net "8644_USB_DN6")
	)
	(arc
		(start 297.3959 -32.579564)
		(mid 297.37371 -32.691594)
		(end 297.310302 -32.786574)
		(width 0.136652)
		(layer "F.Cu")
		(net "8644_USB_DN6")
	)
	(arc
		(start 297.53052 -26.539444)
		(mid 297.430601 -26.734227)
		(end 297.396154 -26.950416)
		(width 0.136652)
		(layer "F.Cu")
		(net "8644_USB_DN6")
	)
	(arc
		(start 297.602402 -26.455624)
		(mid 297.564851 -26.496153)
		(end 297.53052 -26.539444)
		(width 0.136652)
		(layer "F.Cu")
		(net "8644_USB_DN6")
	)
	(arc
		(start 297.369992 -24.7777)
		(mid 297.46774 -24.796827)
		(end 297.551094 -24.85136)
		(width 0.136652)
		(layer "F.Cu")
		(net "8644_USB_DN6")
	)
	(arc
		(start 297.551094 -24.85136)
		(mid 297.552241 -24.852499)
		(end 297.55338 -24.853646)
		(width 0.136652)
		(layer "F.Cu")
		(net "8644_USB_DN6")
	)
	(arc
		(start 297.845226 -26.042112)
		(mid 297.813865 -26.199773)
		(end 297.724576 -26.33345)
		(width 0.136652)
		(layer "F.Cu")
		(net "8644_USB_DN6")
	)
	(arc
		(start 297.197526 -24.8285)
		(mid 297.253813 -24.79089)
		(end 297.320208 -24.7777)
		(width 0.136652)
		(layer "F.Cu")
		(net "8644_USB_DN6")
	)
	(arc
		(start 297.13428 -24.981154)
		(mid 297.150714 -24.898533)
		(end 297.197526 -24.8285)
		(width 0.136652)
		(layer "F.Cu")
		(net "8644_USB_DN6")
	)
	(segment
		(start 282.776676 -24.7396)
		(end 282.621228 -24.584152)
		(width 0.136652)
		(layer "B.Cu")
		(net "8644_USB_DN5")
	)
	(segment
		(start 284.472888 -24.584152)
		(end 284.31744 -24.7396)
		(width 0.136652)
		(layer "B.Cu")
		(net "8644_USB_DN5")
	)
	(segment
		(start 282.621228 -24.584152)
		(end 280.5684 -24.584152)
		(width 0.136652)
		(layer "B.Cu")
		(net "8644_USB_DN5")
	)
	(segment
		(start 280.5684 -24.584152)
		(end 274.023836 -18.039588)
		(width 0.136652)
		(layer "B.Cu")
		(net "8644_USB_DN5")
	)
	(segment
		(start 274.023836 -18.039588)
		(end 270.366744 -18.039588)
		(width 0.136652)
		(layer "B.Cu")
		(net "8644_USB_DN5")
	)
	(segment
		(start 283.186632 -24.7396)
		(end 282.776676 -24.7396)
		(width 0.136652)
		(layer "B.Cu")
		(net "8644_USB_DN5")
	)
	(segment
		(start 283.752036 -24.584152)
		(end 283.34208 -24.584152)
		(width 0.136652)
		(layer "B.Cu")
		(net "8644_USB_DN5")
	)
	(segment
		(start 283.34208 -24.584152)
		(end 283.186632 -24.7396)
		(width 0.136652)
		(layer "B.Cu")
		(net "8644_USB_DN5")
	)
	(segment
		(start 285.75 -24.584152)
		(end 284.472888 -24.584152)
		(width 0.136652)
		(layer "B.Cu")
		(net "8644_USB_DN5")
	)
	(segment
		(start 284.31744 -24.7396)
		(end 283.907484 -24.7396)
		(width 0.136652)
		(layer "B.Cu")
		(net "8644_USB_DN5")
	)
	(segment
		(start 270.016732 -18.3896)
		(end 269.594584 -18.3896)
		(width 0.136652)
		(layer "B.Cu")
		(net "8644_USB_DN5")
	)
	(segment
		(start 270.366744 -18.039588)
		(end 270.016732 -18.3896)
		(width 0.136652)
		(layer "B.Cu")
		(net "8644_USB_DN5")
	)
	(segment
		(start 283.907484 -24.7396)
		(end 283.752036 -24.584152)
		(width 0.136652)
		(layer "B.Cu")
		(net "8644_USB_DN5")
	)
	(arc
		(start 286.134302 -25.33015)
		(mid 286.169621 -24.83994)
		(end 285.75 -24.584152)
		(width 0.136652)
		(layer "B.Cu")
		(net "8644_USB_DN5")
	)
	(segment
		(start 166.992554 -25.336246)
		(end 166.841424 -25.184862)
		(width 0.136652)
		(layer "F.Cu")
		(net "8644_USB_DN4")
	)
	(segment
		(start 168.905174 -27.84094)
		(end 168.862756 -27.59964)
		(width 0.136652)
		(layer "F.Cu")
		(net "8644_USB_DN4")
	)
	(segment
		(start 171.279566 -30.546294)
		(end 170.41749 -29.94279)
		(width 0.136652)
		(layer "F.Cu")
		(net "8644_USB_DN4")
	)
	(segment
		(start 186.7789 -28.96108)
		(end 186.7789 -28.838144)
		(width 0.136652)
		(layer "F.Cu")
		(net "8644_USB_DN4")
	)
	(segment
		(start 167.515794 -26.025602)
		(end 167.157654 -25.501346)
		(width 0.136652)
		(layer "F.Cu")
		(net "8644_USB_DN4")
	)
	(segment
		(start 180.559456 -28.011628)
		(end 179.0954 -28.269946)
		(width 0.136652)
		(layer "F.Cu")
		(net "8644_USB_DN4")
	)
	(segment
		(start 167.157654 -25.501346)
		(end 166.992554 -25.336246)
		(width 0.136652)
		(layer "F.Cu")
		(net "8644_USB_DN4")
	)
	(segment
		(start 184.713372 -27.9654)
		(end 181.08803 -27.9654)
		(width 0.136652)
		(layer "F.Cu")
		(net "8644_USB_DN4")
	)
	(segment
		(start 185.150252 -28.302458)
		(end 184.88406 -28.036266)
		(width 0.136652)
		(layer "F.Cu")
		(net "8644_USB_DN4")
	)
	(segment
		(start 173.263052 -30.982158)
		(end 171.641262 -30.696154)
		(width 0.136652)
		(layer "F.Cu")
		(net "8644_USB_DN4")
	)
	(segment
		(start 168.281604 -26.625042)
		(end 168.067228 -26.41092)
		(width 0.136652)
		(layer "F.Cu")
		(net "8644_USB_DN4")
	)
	(segment
		(start 168.715944 -27.24531)
		(end 168.281604 -26.625042)
		(width 0.136652)
		(layer "F.Cu")
		(net "8644_USB_DN4")
	)
	(segment
		(start 168.067228 -26.41092)
		(end 167.515794 -26.025602)
		(width 0.136652)
		(layer "F.Cu")
		(net "8644_USB_DN4")
	)
	(segment
		(start 169.938446 -29.463746)
		(end 169.053764 -28.200604)
		(width 0.136652)
		(layer "F.Cu")
		(net "8644_USB_DN4")
	)
	(segment
		(start 166.244016 -25.22093)
		(end 166.134542 -25.33015)
		(width 0.136652)
		(layer "F.Cu")
		(net "8644_USB_DN4")
	)
	(segment
		(start 166.624 -25.094946)
		(end 166.5478 -25.094946)
		(width 0.136652)
		(layer "F.Cu")
		(net "8644_USB_DN4")
	)
	(segment
		(start 178.609498 -28.471114)
		(end 175.681132 -30.52191)
		(width 0.136652)
		(layer "F.Cu")
		(net "8644_USB_DN4")
	)
	(segment
		(start 175.181768 -30.728412)
		(end 173.742604 -30.982158)
		(width 0.136652)
		(layer "F.Cu")
		(net "8644_USB_DN4")
	)
	(segment
		(start 186.47283 -28.532074)
		(end 185.704734 -28.532074)
		(width 0.136652)
		(layer "F.Cu")
		(net "8644_USB_DN4")
	)
	(arc
		(start 184.88406 -28.036266)
		(mid 184.805763 -27.983856)
		(end 184.713372 -27.9654)
		(width 0.136652)
		(layer "F.Cu")
		(net "8644_USB_DN4")
	)
	(arc
		(start 173.742604 -30.982158)
		(mid 173.502828 -31.003123)
		(end 173.263052 -30.982158)
		(width 0.136652)
		(layer "F.Cu")
		(net "8644_USB_DN4")
	)
	(arc
		(start 185.704734 -28.532074)
		(mid 185.404658 -28.472403)
		(end 185.150252 -28.302458)
		(width 0.136652)
		(layer "F.Cu")
		(net "8644_USB_DN4")
	)
	(arc
		(start 171.641262 -30.696154)
		(mid 171.452195 -30.641059)
		(end 171.279566 -30.546294)
		(width 0.136652)
		(layer "F.Cu")
		(net "8644_USB_DN4")
	)
	(arc
		(start 186.7789 -28.838144)
		(mid 186.689254 -28.62172)
		(end 186.47283 -28.532074)
		(width 0.136652)
		(layer "F.Cu")
		(net "8644_USB_DN4")
	)
	(arc
		(start 166.5478 -25.094946)
		(mid 166.383389 -25.127743)
		(end 166.244016 -25.22093)
		(width 0.136652)
		(layer "F.Cu")
		(net "8644_USB_DN4")
	)
	(arc
		(start 169.053764 -28.200604)
		(mid 168.959735 -28.028923)
		(end 168.905174 -27.84094)
		(width 0.136652)
		(layer "F.Cu")
		(net "8644_USB_DN4")
	)
	(arc
		(start 175.681132 -30.52191)
		(mid 175.442754 -30.652491)
		(end 175.181768 -30.728412)
		(width 0.136652)
		(layer "F.Cu")
		(net "8644_USB_DN4")
	)
	(arc
		(start 166.841424 -25.184862)
		(mid 166.741654 -25.118291)
		(end 166.624 -25.094946)
		(width 0.136652)
		(layer "F.Cu")
		(net "8644_USB_DN4")
	)
	(arc
		(start 170.41749 -29.94279)
		(mid 170.15702 -29.724216)
		(end 169.938446 -29.463746)
		(width 0.136652)
		(layer "F.Cu")
		(net "8644_USB_DN4")
	)
	(arc
		(start 179.0954 -28.269946)
		(mid 178.841426 -28.343908)
		(end 178.609498 -28.471114)
		(width 0.136652)
		(layer "F.Cu")
		(net "8644_USB_DN4")
	)
	(arc
		(start 168.862756 -27.59964)
		(mid 168.808815 -27.414407)
		(end 168.715944 -27.24531)
		(width 0.136652)
		(layer "F.Cu")
		(net "8644_USB_DN4")
	)
	(arc
		(start 181.08803 -27.9654)
		(mid 180.822734 -27.976977)
		(end 180.559456 -28.011628)
		(width 0.136652)
		(layer "F.Cu")
		(net "8644_USB_DN4")
	)
	(segment
		(start 156.214318 -32.644842)
		(end 156.214318 -30.1498)
		(width 0.136652)
		(layer "F.Cu")
		(net "8644_USB_DN3")
	)
	(segment
		(start 155.423108 -24.822658)
		(end 155.335986 -24.822658)
		(width 0.136652)
		(layer "F.Cu")
		(net "8644_USB_DN3")
	)
	(segment
		(start 155.867354 -25.183846)
		(end 155.56484 -24.881332)
		(width 0.136652)
		(layer "F.Cu")
		(net "8644_USB_DN3")
	)
	(segment
		(start 156.011626 -25.82545)
		(end 156.011626 -25.546558)
		(width 0.136652)
		(layer "F.Cu")
		(net "8644_USB_DN3")
	)
	(segment
		(start 155.882086 -32.977074)
		(end 156.214318 -32.644842)
		(width 0.136652)
		(layer "F.Cu")
		(net "8644_USB_DN3")
	)
	(segment
		(start 155.50642 -26.819098)
		(end 155.513024 -26.802334)
		(width 0.136652)
		(layer "F.Cu")
		(net "8644_USB_DN3")
	)
	(segment
		(start 156.173932 -30.052772)
		(end 155.702508 -29.581348)
		(width 0.136652)
		(layer "F.Cu")
		(net "8644_USB_DN3")
	)
	(segment
		(start 155.134564 -25.11552)
		(end 155.134564 -25.33015)
		(width 0.136652)
		(layer "F.Cu")
		(net "8644_USB_DN3")
	)
	(segment
		(start 155.689554 -26.530808)
		(end 155.816554 -26.403808)
		(width 0.136652)
		(layer "F.Cu")
		(net "8644_USB_DN3")
	)
	(segment
		(start 155.816554 -26.403808)
		(end 155.819094 -26.401014)
		(width 0.136652)
		(layer "F.Cu")
		(net "8644_USB_DN3")
	)
	(segment
		(start 155.448254 -28.967176)
		(end 155.448254 -27.131518)
		(width 0.136652)
		(layer "F.Cu")
		(net "8644_USB_DN3")
	)
	(arc
		(start 155.240736 -24.859234)
		(mid 155.162168 -24.976819)
		(end 155.134564 -25.11552)
		(width 0.136652)
		(layer "F.Cu")
		(net "8644_USB_DN3")
	)
	(arc
		(start 155.95219 -26.186638)
		(mid 155.996695 -26.008476)
		(end 156.011626 -25.82545)
		(width 0.136652)
		(layer "F.Cu")
		(net "8644_USB_DN3")
	)
	(arc
		(start 155.898342 -25.218644)
		(mid 155.883372 -25.200778)
		(end 155.867354 -25.183846)
		(width 0.136652)
		(layer "F.Cu")
		(net "8644_USB_DN3")
	)
	(arc
		(start 155.819094 -26.401014)
		(mid 155.898044 -26.301522)
		(end 155.95219 -26.186638)
		(width 0.136652)
		(layer "F.Cu")
		(net "8644_USB_DN3")
	)
	(arc
		(start 156.011626 -25.546558)
		(mid 155.982501 -25.373097)
		(end 155.898342 -25.218644)
		(width 0.136652)
		(layer "F.Cu")
		(net "8644_USB_DN3")
	)
	(arc
		(start 155.448254 -27.131518)
		(mid 155.462927 -26.972627)
		(end 155.50642 -26.819098)
		(width 0.136652)
		(layer "F.Cu")
		(net "8644_USB_DN3")
	)
	(arc
		(start 155.513024 -26.802334)
		(mid 155.587082 -26.657334)
		(end 155.689554 -26.530808)
		(width 0.136652)
		(layer "F.Cu")
		(net "8644_USB_DN3")
	)
	(arc
		(start 156.214318 -30.1498)
		(mid 156.203843 -30.097228)
		(end 156.173932 -30.052772)
		(width 0.136652)
		(layer "F.Cu")
		(net "8644_USB_DN3")
	)
	(arc
		(start 155.702508 -29.581348)
		(mid 155.514309 -29.299548)
		(end 155.448254 -28.967176)
		(width 0.136652)
		(layer "F.Cu")
		(net "8644_USB_DN3")
	)
	(arc
		(start 155.56484 -24.881332)
		(mid 155.499813 -24.837882)
		(end 155.423108 -24.822658)
		(width 0.136652)
		(layer "F.Cu")
		(net "8644_USB_DN3")
	)
	(arc
		(start 155.335986 -24.822658)
		(mid 155.287155 -24.837804)
		(end 155.240736 -24.859234)
		(width 0.136652)
		(layer "F.Cu")
		(net "8644_USB_DN3")
	)
	(segment
		(start 144.55521 -24.844756)
		(end 144.70888 -24.998172)
		(width 0.136652)
		(layer "F.Cu")
		(net "8644_USB_DN2")
	)
	(segment
		(start 144.843754 -25.323546)
		(end 144.843754 -25.842214)
		(width 0.136652)
		(layer "F.Cu")
		(net "8644_USB_DN2")
	)
	(segment
		(start 144.134332 -25.33015)
		(end 144.134332 -25.12568)
		(width 0.136652)
		(layer "F.Cu")
		(net "8644_USB_DN2")
	)
	(segment
		(start 144.657826 -26.291286)
		(end 144.317466 -26.631646)
		(width 0.136652)
		(layer "F.Cu")
		(net "8644_USB_DN2")
	)
	(segment
		(start 144.04213 -27.296364)
		(end 144.04213 -32.5882)
		(width 0.136652)
		(layer "F.Cu")
		(net "8644_USB_DN2")
	)
	(arc
		(start 144.04213 -32.5882)
		(mid 143.941156 -32.866345)
		(end 143.68526 -33.01492)
		(width 0.136652)
		(layer "F.Cu")
		(net "8644_USB_DN2")
	)
	(arc
		(start 144.134332 -25.12568)
		(mid 144.165499 -24.968991)
		(end 144.25422 -24.83612)
		(width 0.136652)
		(layer "F.Cu")
		(net "8644_USB_DN2")
	)
	(arc
		(start 144.25422 -24.83612)
		(mid 144.336284 -24.80198)
		(end 144.4244 -24.7904)
		(width 0.136652)
		(layer "F.Cu")
		(net "8644_USB_DN2")
	)
	(arc
		(start 144.4244 -24.7904)
		(mid 144.495206 -24.804578)
		(end 144.55521 -24.844756)
		(width 0.136652)
		(layer "F.Cu")
		(net "8644_USB_DN2")
	)
	(arc
		(start 144.317466 -26.631646)
		(mid 144.113634 -26.936607)
		(end 144.04213 -27.296364)
		(width 0.136652)
		(layer "F.Cu")
		(net "8644_USB_DN2")
	)
	(arc
		(start 144.843754 -25.842214)
		(mid 144.795418 -26.085218)
		(end 144.657826 -26.291286)
		(width 0.136652)
		(layer "F.Cu")
		(net "8644_USB_DN2")
	)
	(arc
		(start 144.70888 -24.998172)
		(mid 144.727237 -25.017596)
		(end 144.74444 -25.03805)
		(width 0.136652)
		(layer "F.Cu")
		(net "8644_USB_DN2")
	)
	(arc
		(start 144.74444 -25.03805)
		(mid 144.818214 -25.172413)
		(end 144.843754 -25.323546)
		(width 0.136652)
		(layer "F.Cu")
		(net "8644_USB_DN2")
	)
	(segment
		(start 127.399542 -31.629858)
		(end 127.399542 -32.6898)
		(width 0.136652)
		(layer "F.Cu")
		(net "8644_USB_DN1")
	)
	(segment
		(start 133.809486 -25.908762)
		(end 129.483104 -30.235144)
		(width 0.136652)
		(layer "F.Cu")
		(net "8644_USB_DN1")
	)
	(segment
		(start 129.131314 -30.38094)
		(end 128.64846 -30.38094)
		(width 0.136652)
		(layer "F.Cu")
		(net "8644_USB_DN1")
	)
	(segment
		(start 133.836918 -25.144222)
		(end 133.846824 -25.15616)
		(width 0.136652)
		(layer "F.Cu")
		(net "8644_USB_DN1")
	)
	(segment
		(start 133.134354 -25.33015)
		(end 133.134608 -25.062688)
		(width 0.136652)
		(layer "F.Cu")
		(net "8644_USB_DN1")
	)
	(segment
		(start 133.648196 -24.900382)
		(end 133.70052 -24.95296)
		(width 0.136652)
		(layer "F.Cu")
		(net "8644_USB_DN1")
	)
	(segment
		(start 133.70052 -24.95296)
		(end 133.836918 -25.144222)
		(width 0.136652)
		(layer "F.Cu")
		(net "8644_USB_DN1")
	)
	(arc
		(start 133.576822 -24.843232)
		(mid 133.588902 -24.851151)
		(end 133.600698 -24.859488)
		(width 0.136652)
		(layer "F.Cu")
		(net "8644_USB_DN1")
	)
	(arc
		(start 127.399542 -32.6898)
		(mid 127.309441 -32.976086)
		(end 127.071628 -33.159192)
		(width 0.136652)
		(layer "F.Cu")
		(net "8644_USB_DN1")
	)
	(arc
		(start 133.355334 -24.779224)
		(mid 133.470613 -24.795523)
		(end 133.576822 -24.843232)
		(width 0.136652)
		(layer "F.Cu")
		(net "8644_USB_DN1")
	)
	(arc
		(start 133.134608 -25.062688)
		(mid 133.196375 -24.883131)
		(end 133.355334 -24.779224)
		(width 0.136652)
		(layer "F.Cu")
		(net "8644_USB_DN1")
	)
	(arc
		(start 129.483104 -30.235144)
		(mid 129.321716 -30.343044)
		(end 129.131314 -30.38094)
		(width 0.136652)
		(layer "F.Cu")
		(net "8644_USB_DN1")
	)
	(arc
		(start 133.600698 -24.859488)
		(mid 133.625228 -24.879028)
		(end 133.648196 -24.900382)
		(width 0.136652)
		(layer "F.Cu")
		(net "8644_USB_DN1")
	)
	(arc
		(start 133.846824 -25.15616)
		(mid 133.973132 -25.539633)
		(end 133.809486 -25.908762)
		(width 0.136652)
		(layer "F.Cu")
		(net "8644_USB_DN1")
	)
	(arc
		(start 128.64846 -30.38094)
		(mid 127.765342 -30.74674)
		(end 127.399542 -31.629858)
		(width 0.136652)
		(layer "F.Cu")
		(net "8644_USB_DN1")
	)
	(via
		(at 275.717 0.762)
		(size 0.7112)
		(drill 0.3556)
		(layers "F.Cu" "B.Cu")
		(net "8644_SDA_R_8")
	)
	(segment
		(start 318.1731 -8.792972)
		(end 312.669174 -3.289046)
		(width 0.12065)
		(layer "B.Cu")
		(net "8644_SDA_R_8")
	)
	(segment
		(start 273.6977 0.0635)
		(end 273.0246 0.7366)
		(width 0.12065)
		(layer "B.Cu")
		(net "8644_SDA_R_8")
	)
	(segment
		(start 319.884298 -16.330168)
		(end 319.199768 -16.330168)
		(width 0.12065)
		(layer "B.Cu")
		(net "8644_SDA_R_8")
	)
	(segment
		(start 281.723846 -3.289046)
		(end 277.6728 0.762)
		(width 0.12065)
		(layer "B.Cu")
		(net "8644_SDA_R_8")
	)
	(segment
		(start 275.564854 0.762)
		(end 274.869148 0.066294)
		(width 0.12065)
		(layer "B.Cu")
		(net "8644_SDA_R_8")
	)
	(segment
		(start 271.7038 0.330454)
		(end 271.7038 -1.1557)
		(width 0.12065)
		(layer "B.Cu")
		(net "8644_SDA_R_8")
	)
	(segment
		(start 275.717 0.762)
		(end 275.564854 0.762)
		(width 0.12065)
		(layer "B.Cu")
		(net "8644_SDA_R_8")
	)
	(segment
		(start 272.109946 0.7366)
		(end 271.7038 0.330454)
		(width 0.12065)
		(layer "B.Cu")
		(net "8644_SDA_R_8")
	)
	(segment
		(start 274.869148 0.066294)
		(end 274.869148 -0.085852)
		(width 0.12065)
		(layer "B.Cu")
		(net "8644_SDA_R_8")
	)
	(segment
		(start 318.1731 -15.3035)
		(end 318.1731 -8.792972)
		(width 0.12065)
		(layer "B.Cu")
		(net "8644_SDA_R_8")
	)
	(segment
		(start 274.066 -0.889)
		(end 273.6977 -0.889)
		(width 0.12065)
		(layer "B.Cu")
		(net "8644_SDA_R_8")
	)
	(segment
		(start 274.869148 -0.085852)
		(end 274.066 -0.889)
		(width 0.12065)
		(layer "B.Cu")
		(net "8644_SDA_R_8")
	)
	(segment
		(start 273.6977 -0.889)
		(end 273.6977 0.0635)
		(width 0.12065)
		(layer "B.Cu")
		(net "8644_SDA_R_8")
	)
	(segment
		(start 273.0246 0.7366)
		(end 272.109946 0.7366)
		(width 0.12065)
		(layer "B.Cu")
		(net "8644_SDA_R_8")
	)
	(segment
		(start 312.669174 -3.289046)
		(end 281.723846 -3.289046)
		(width 0.12065)
		(layer "B.Cu")
		(net "8644_SDA_R_8")
	)
	(segment
		(start 277.6728 0.762)
		(end 275.717 0.762)
		(width 0.12065)
		(layer "B.Cu")
		(net "8644_SDA_R_8")
	)
	(segment
		(start 319.199768 -16.330168)
		(end 318.1731 -15.3035)
		(width 0.12065)
		(layer "B.Cu")
		(net "8644_SDA_R_8")
	)
	(segment
		(start 278.406098 -2.552954)
		(end 278.364442 -2.511298)
		(width 0.12065)
		(layer "F.Cu")
		(net "8644_SDA_R_7")
	)
	(segment
		(start 306.640992 -14.08684)
		(end 306.640992 -9.465056)
		(width 0.12065)
		(layer "F.Cu")
		(net "8644_SDA_R_7")
	)
	(segment
		(start 277.095966 -2.304796)
		(end 277.0505 -2.25933)
		(width 0.12065)
		(layer "F.Cu")
		(net "8644_SDA_R_7")
	)
	(segment
		(start 306.640992 -9.465056)
		(end 299.72889 -2.552954)
		(width 0.12065)
		(layer "F.Cu")
		(net "8644_SDA_R_7")
	)
	(segment
		(start 277.5077 -2.304796)
		(end 277.095966 -2.304796)
		(width 0.12065)
		(layer "F.Cu")
		(net "8644_SDA_R_7")
	)
	(segment
		(start 299.72889 -2.552954)
		(end 278.406098 -2.552954)
		(width 0.12065)
		(layer "F.Cu")
		(net "8644_SDA_R_7")
	)
	(segment
		(start 277.714202 -2.511298)
		(end 277.5077 -2.304796)
		(width 0.12065)
		(layer "F.Cu")
		(net "8644_SDA_R_7")
	)
	(segment
		(start 277.0505 -1.27)
		(end 277.0505 -0.127)
		(width 0.12065)
		(layer "F.Cu")
		(net "8644_SDA_R_7")
	)
	(segment
		(start 308.88432 -16.330168)
		(end 306.640992 -14.08684)
		(width 0.12065)
		(layer "F.Cu")
		(net "8644_SDA_R_7")
	)
	(segment
		(start 277.0505 -2.25933)
		(end 277.0505 -1.27)
		(width 0.12065)
		(layer "F.Cu")
		(net "8644_SDA_R_7")
	)
	(segment
		(start 278.364442 -2.511298)
		(end 277.714202 -2.511298)
		(width 0.12065)
		(layer "F.Cu")
		(net "8644_SDA_R_7")
	)
	(via
		(at 277.095966 -2.304796)
		(size 0.7112)
		(drill 0.3556)
		(layers "F.Cu" "B.Cu")
		(net "8644_SDA_R_7")
	)
	(segment
		(start 275.241258 -7.312152)
		(end 275.999702 -8.070596)
		(width 0.12065)
		(layer "F.Cu")
		(net "8644_SDA_R_6")
	)
	(segment
		(start 273.331432 -6.8453)
		(end 273.798284 -7.312152)
		(width 0.12065)
		(layer "F.Cu")
		(net "8644_SDA_R_6")
	)
	(segment
		(start 282.956 -5.74675)
		(end 280.52395 -8.1788)
		(width 0.12065)
		(layer "F.Cu")
		(net "8644_SDA_R_6")
	)
	(segment
		(start 292.203886 -5.74675)
		(end 282.956 -5.74675)
		(width 0.12065)
		(layer "F.Cu")
		(net "8644_SDA_R_6")
	)
	(segment
		(start 293.56685 -7.109714)
		(end 292.203886 -5.74675)
		(width 0.12065)
		(layer "F.Cu")
		(net "8644_SDA_R_6")
	)
	(segment
		(start 273.258026 -5.7023)
		(end 273.258026 -6.8453)
		(width 0.12065)
		(layer "F.Cu")
		(net "8644_SDA_R_6")
	)
	(segment
		(start 276.107906 -8.1788)
		(end 275.999702 -8.070596)
		(width 0.12065)
		(layer "F.Cu")
		(net "8644_SDA_R_6")
	)
	(segment
		(start 274.833588 -7.312152)
		(end 274.839938 -7.305802)
		(width 0.12065)
		(layer "F.Cu")
		(net "8644_SDA_R_6")
	)
	(segment
		(start 293.56685 -14.120114)
		(end 293.56685 -7.109714)
		(width 0.12065)
		(layer "F.Cu")
		(net "8644_SDA_R_6")
	)
	(segment
		(start 295.776904 -16.330168)
		(end 293.56685 -14.120114)
		(width 0.12065)
		(layer "F.Cu")
		(net "8644_SDA_R_6")
	)
	(segment
		(start 273.798284 -7.312152)
		(end 274.833588 -7.312152)
		(width 0.12065)
		(layer "F.Cu")
		(net "8644_SDA_R_6")
	)
	(segment
		(start 275.232876 -7.312152)
		(end 275.241258 -7.312152)
		(width 0.12065)
		(layer "F.Cu")
		(net "8644_SDA_R_6")
	)
	(segment
		(start 275.226526 -7.305802)
		(end 275.232876 -7.312152)
		(width 0.12065)
		(layer "F.Cu")
		(net "8644_SDA_R_6")
	)
	(segment
		(start 297.884342 -16.330168)
		(end 295.776904 -16.330168)
		(width 0.12065)
		(layer "F.Cu")
		(net "8644_SDA_R_6")
	)
	(segment
		(start 274.839938 -7.305802)
		(end 275.226526 -7.305802)
		(width 0.12065)
		(layer "F.Cu")
		(net "8644_SDA_R_6")
	)
	(segment
		(start 280.52395 -8.1788)
		(end 276.107906 -8.1788)
		(width 0.12065)
		(layer "F.Cu")
		(net "8644_SDA_R_6")
	)
	(segment
		(start 273.258026 -6.8453)
		(end 273.331432 -6.8453)
		(width 0.12065)
		(layer "F.Cu")
		(net "8644_SDA_R_6")
	)
	(via
		(at 275.999702 -8.070596)
		(size 0.7112)
		(drill 0.3556)
		(layers "F.Cu" "B.Cu")
		(net "8644_SDA_R_6")
	)
	(segment
		(start 278.397462 -10.964926)
		(end 275.051266 -10.964926)
		(width 0.12065)
		(layer "F.Cu")
		(net "8644_SDA_R_5")
	)
	(segment
		(start 282.517088 -16.330168)
		(end 280.15692 -13.97)
		(width 0.12065)
		(layer "F.Cu")
		(net "8644_SDA_R_5")
	)
	(segment
		(start 286.884364 -16.330168)
		(end 282.517088 -16.330168)
		(width 0.12065)
		(layer "F.Cu")
		(net "8644_SDA_R_5")
	)
	(segment
		(start 272.657062 -10.046716)
		(end 272.175986 -9.56564)
		(width 0.12065)
		(layer "F.Cu")
		(net "8644_SDA_R_5")
	)
	(segment
		(start 272.175986 -9.56564)
		(end 272.175986 -8.973566)
		(width 0.12065)
		(layer "F.Cu")
		(net "8644_SDA_R_5")
	)
	(segment
		(start 280.15692 -12.724384)
		(end 278.397462 -10.964926)
		(width 0.12065)
		(layer "F.Cu")
		(net "8644_SDA_R_5")
	)
	(segment
		(start 272.245836 -8.903716)
		(end 272.175986 -8.973566)
		(width 0.12065)
		(layer "F.Cu")
		(net "8644_SDA_R_5")
	)
	(segment
		(start 280.15692 -13.97)
		(end 280.15692 -12.724384)
		(width 0.12065)
		(layer "F.Cu")
		(net "8644_SDA_R_5")
	)
	(segment
		(start 273.398996 -8.903716)
		(end 272.245836 -8.903716)
		(width 0.12065)
		(layer "F.Cu")
		(net "8644_SDA_R_5")
	)
	(segment
		(start 275.051266 -10.964926)
		(end 274.622768 -10.536428)
		(width 0.12065)
		(layer "F.Cu")
		(net "8644_SDA_R_5")
	)
	(segment
		(start 274.622768 -10.536428)
		(end 273.888708 -10.536428)
		(width 0.12065)
		(layer "F.Cu")
		(net "8644_SDA_R_5")
	)
	(segment
		(start 273.888708 -10.536428)
		(end 273.398996 -10.046716)
		(width 0.12065)
		(layer "F.Cu")
		(net "8644_SDA_R_5")
	)
	(segment
		(start 273.398996 -10.046716)
		(end 272.657062 -10.046716)
		(width 0.12065)
		(layer "F.Cu")
		(net "8644_SDA_R_5")
	)
	(via
		(at 272.175986 -8.973566)
		(size 0.7112)
		(drill 0.3556)
		(layers "F.Cu" "B.Cu")
		(net "8644_SDA_R_5")
	)
	(via
		(at 165.021768 -31.79064)
		(size 0.7112)
		(drill 0.3556)
		(layers "F.Cu" "B.Cu")
		(net "8644_SDA_R_4")
	)
	(segment
		(start 165.021768 -32.878268)
		(end 165.021768 -31.79064)
		(width 0.12065)
		(layer "B.Cu")
		(net "8644_SDA_R_4")
	)
	(segment
		(start 166.88435 -18.15465)
		(end 166.328598 -18.710402)
		(width 0.12065)
		(layer "B.Cu")
		(net "8644_SDA_R_4")
	)
	(segment
		(start 166.690294 -21.76018)
		(end 165.021768 -23.428706)
		(width 0.12065)
		(layer "B.Cu")
		(net "8644_SDA_R_4")
	)
	(segment
		(start 165.227 -33.0835)
		(end 165.021768 -32.878268)
		(width 0.12065)
		(layer "B.Cu")
		(net "8644_SDA_R_4")
	)
	(segment
		(start 166.328598 -18.710402)
		(end 166.328598 -20.938236)
		(width 0.12065)
		(layer "B.Cu")
		(net "8644_SDA_R_4")
	)
	(segment
		(start 166.328598 -20.938236)
		(end 166.690294 -21.299932)
		(width 0.12065)
		(layer "B.Cu")
		(net "8644_SDA_R_4")
	)
	(segment
		(start 166.88435 -16.330168)
		(end 166.88435 -18.15465)
		(width 0.12065)
		(layer "B.Cu")
		(net "8644_SDA_R_4")
	)
	(segment
		(start 165.227 -33.0835)
		(end 164.084 -33.0835)
		(width 0.12065)
		(layer "B.Cu")
		(net "8644_SDA_R_4")
	)
	(segment
		(start 165.021768 -23.428706)
		(end 165.021768 -31.79064)
		(width 0.12065)
		(layer "B.Cu")
		(net "8644_SDA_R_4")
	)
	(segment
		(start 166.690294 -21.299932)
		(end 166.690294 -21.76018)
		(width 0.12065)
		(layer "B.Cu")
		(net "8644_SDA_R_4")
	)
	(via
		(at 155.357068 -31.32836)
		(size 0.7112)
		(drill 0.3556)
		(layers "F.Cu" "B.Cu")
		(net "8644_SDA_R_3")
	)
	(segment
		(start 155.32862 -20.938236)
		(end 155.690316 -21.299932)
		(width 0.12065)
		(layer "B.Cu")
		(net "8644_SDA_R_3")
	)
	(segment
		(start 155.32862 -18.91538)
		(end 155.32862 -20.938236)
		(width 0.12065)
		(layer "B.Cu")
		(net "8644_SDA_R_3")
	)
	(segment
		(start 155.690316 -22.340824)
		(end 153.85415 -24.17699)
		(width 0.12065)
		(layer "B.Cu")
		(net "8644_SDA_R_3")
	)
	(segment
		(start 155.690316 -21.299932)
		(end 155.690316 -22.340824)
		(width 0.12065)
		(layer "B.Cu")
		(net "8644_SDA_R_3")
	)
	(segment
		(start 155.884372 -16.330168)
		(end 155.884372 -18.359628)
		(width 0.12065)
		(layer "B.Cu")
		(net "8644_SDA_R_3")
	)
	(segment
		(start 153.85415 -24.17699)
		(end 153.85415 -27.496262)
		(width 0.12065)
		(layer "B.Cu")
		(net "8644_SDA_R_3")
	)
	(segment
		(start 155.454604 -33.147508)
		(end 156.470604 -33.147508)
		(width 0.12065)
		(layer "B.Cu")
		(net "8644_SDA_R_3")
	)
	(segment
		(start 155.884372 -18.359628)
		(end 155.32862 -18.91538)
		(width 0.12065)
		(layer "B.Cu")
		(net "8644_SDA_R_3")
	)
	(segment
		(start 155.357068 -31.32836)
		(end 155.357068 -33.049972)
		(width 0.12065)
		(layer "B.Cu")
		(net "8644_SDA_R_3")
	)
	(segment
		(start 153.85415 -27.496262)
		(end 155.357068 -28.99918)
		(width 0.12065)
		(layer "B.Cu")
		(net "8644_SDA_R_3")
	)
	(segment
		(start 155.357068 -28.99918)
		(end 155.357068 -31.32836)
		(width 0.12065)
		(layer "B.Cu")
		(net "8644_SDA_R_3")
	)
	(segment
		(start 155.357068 -33.049972)
		(end 155.454604 -33.147508)
		(width 0.12065)
		(layer "B.Cu")
		(net "8644_SDA_R_3")
	)
	(via
		(at 145.55597 -30.954726)
		(size 0.7112)
		(drill 0.3556)
		(layers "F.Cu" "B.Cu")
		(net "8644_SDA_R_2")
	)
	(segment
		(start 143.890746 -22.987254)
		(end 143.886682 -22.987254)
		(width 0.12065)
		(layer "B.Cu")
		(net "8644_SDA_R_2")
	)
	(segment
		(start 144.690084 -22.187916)
		(end 143.890746 -22.987254)
		(width 0.12065)
		(layer "B.Cu")
		(net "8644_SDA_R_2")
	)
	(segment
		(start 145.55597 -31.820104)
		(end 146.269964 -32.534098)
		(width 0.12065)
		(layer "B.Cu")
		(net "8644_SDA_R_2")
	)
	(segment
		(start 144.690084 -20.992084)
		(end 144.690084 -22.187916)
		(width 0.12065)
		(layer "B.Cu")
		(net "8644_SDA_R_2")
	)
	(segment
		(start 143.886682 -22.987254)
		(end 142.47495 -24.398986)
		(width 0.12065)
		(layer "B.Cu")
		(net "8644_SDA_R_2")
	)
	(segment
		(start 145.55597 -30.954726)
		(end 145.55597 -31.820104)
		(width 0.12065)
		(layer "B.Cu")
		(net "8644_SDA_R_2")
	)
	(segment
		(start 144.272 -20.574)
		(end 144.690084 -20.992084)
		(width 0.12065)
		(layer "B.Cu")
		(net "8644_SDA_R_2")
	)
	(segment
		(start 145.88363 -33.09112)
		(end 144.86763 -33.09112)
		(width 0.12065)
		(layer "B.Cu")
		(net "8644_SDA_R_2")
	)
	(segment
		(start 144.272 -18.796)
		(end 144.272 -20.574)
		(width 0.12065)
		(layer "B.Cu")
		(net "8644_SDA_R_2")
	)
	(segment
		(start 142.47495 -26.835354)
		(end 145.55597 -29.916374)
		(width 0.12065)
		(layer "B.Cu")
		(net "8644_SDA_R_2")
	)
	(segment
		(start 144.884394 -16.330168)
		(end 144.884394 -18.183606)
		(width 0.12065)
		(layer "B.Cu")
		(net "8644_SDA_R_2")
	)
	(segment
		(start 144.884394 -18.183606)
		(end 144.272 -18.796)
		(width 0.12065)
		(layer "B.Cu")
		(net "8644_SDA_R_2")
	)
	(segment
		(start 145.55597 -29.916374)
		(end 145.55597 -30.954726)
		(width 0.12065)
		(layer "B.Cu")
		(net "8644_SDA_R_2")
	)
	(segment
		(start 146.269964 -32.534098)
		(end 146.269964 -32.704786)
		(width 0.12065)
		(layer "B.Cu")
		(net "8644_SDA_R_2")
	)
	(segment
		(start 146.269964 -32.704786)
		(end 145.88363 -33.09112)
		(width 0.12065)
		(layer "B.Cu")
		(net "8644_SDA_R_2")
	)
	(segment
		(start 142.47495 -24.398986)
		(end 142.47495 -26.835354)
		(width 0.12065)
		(layer "B.Cu")
		(net "8644_SDA_R_2")
	)
	(via
		(at 130.86588 -32.11576)
		(size 0.7112)
		(drill 0.3556)
		(layers "F.Cu" "B.Cu")
		(net "8644_SDA_R_1")
	)
	(segment
		(start 131.33705 -29.39415)
		(end 130.86588 -29.86532)
		(width 0.12065)
		(layer "B.Cu")
		(net "8644_SDA_R_1")
	)
	(segment
		(start 133.884416 -18.591784)
		(end 133.0706 -19.4056)
		(width 0.12065)
		(layer "B.Cu")
		(net "8644_SDA_R_1")
	)
	(segment
		(start 130.51028 -33.10128)
		(end 131.52628 -33.10128)
		(width 0.12065)
		(layer "B.Cu")
		(net "8644_SDA_R_1")
	)
	(segment
		(start 133.690106 -21.299932)
		(end 133.690106 -21.884894)
		(width 0.12065)
		(layer "B.Cu")
		(net "8644_SDA_R_1")
	)
	(segment
		(start 131.33705 -24.23795)
		(end 131.33705 -29.39415)
		(width 0.12065)
		(layer "B.Cu")
		(net "8644_SDA_R_1")
	)
	(segment
		(start 133.690106 -21.884894)
		(end 131.33705 -24.23795)
		(width 0.12065)
		(layer "B.Cu")
		(net "8644_SDA_R_1")
	)
	(segment
		(start 133.884416 -16.330168)
		(end 133.884416 -18.591784)
		(width 0.12065)
		(layer "B.Cu")
		(net "8644_SDA_R_1")
	)
	(segment
		(start 131.52628 -33.10128)
		(end 131.52628 -32.77616)
		(width 0.12065)
		(layer "B.Cu")
		(net "8644_SDA_R_1")
	)
	(segment
		(start 130.86588 -29.86532)
		(end 130.86588 -32.11576)
		(width 0.12065)
		(layer "B.Cu")
		(net "8644_SDA_R_1")
	)
	(segment
		(start 133.0706 -19.4056)
		(end 133.0706 -20.680426)
		(width 0.12065)
		(layer "B.Cu")
		(net "8644_SDA_R_1")
	)
	(segment
		(start 131.52628 -32.77616)
		(end 130.86588 -32.11576)
		(width 0.12065)
		(layer "B.Cu")
		(net "8644_SDA_R_1")
	)
	(segment
		(start 133.0706 -20.680426)
		(end 133.690106 -21.299932)
		(width 0.12065)
		(layer "B.Cu")
		(net "8644_SDA_R_1")
	)
	(via
		(at 276.479762 -0.914654)
		(size 0.7112)
		(drill 0.3556)
		(layers "F.Cu" "B.Cu")
		(net "8644_CBL_PRSNT_R_8")
	)
	(segment
		(start 273.7231 -1.9558)
		(end 273.6977 -1.9304)
		(width 0.12065)
		(layer "B.Cu")
		(net "8644_CBL_PRSNT_R_8")
	)
	(segment
		(start 317.81115 -17.960086)
		(end 317.81115 -8.943086)
		(width 0.12065)
		(layer "B.Cu")
		(net "8644_CBL_PRSNT_R_8")
	)
	(segment
		(start 278.862536 -0.9398)
		(end 276.504908 -0.9398)
		(width 0.12065)
		(layer "B.Cu")
		(net "8644_CBL_PRSNT_R_8")
	)
	(segment
		(start 317.81115 -8.943086)
		(end 312.519314 -3.65125)
		(width 0.12065)
		(layer "B.Cu")
		(net "8644_CBL_PRSNT_R_8")
	)
	(segment
		(start 312.519314 -3.65125)
		(end 281.573986 -3.65125)
		(width 0.12065)
		(layer "B.Cu")
		(net "8644_CBL_PRSNT_R_8")
	)
	(segment
		(start 273.6977 -1.9304)
		(end 274.8661 -0.762)
		(width 0.12065)
		(layer "B.Cu")
		(net "8644_CBL_PRSNT_R_8")
	)
	(segment
		(start 276.327108 -0.762)
		(end 276.479762 -0.914654)
		(width 0.12065)
		(layer "B.Cu")
		(net "8644_CBL_PRSNT_R_8")
	)
	(segment
		(start 281.573986 -3.65125)
		(end 278.862536 -0.9398)
		(width 0.12065)
		(layer "B.Cu")
		(net "8644_CBL_PRSNT_R_8")
	)
	(segment
		(start 274.8661 -0.762)
		(end 276.327108 -0.762)
		(width 0.12065)
		(layer "B.Cu")
		(net "8644_CBL_PRSNT_R_8")
	)
	(segment
		(start 319.884298 -20.033234)
		(end 317.81115 -17.960086)
		(width 0.12065)
		(layer "B.Cu")
		(net "8644_CBL_PRSNT_R_8")
	)
	(segment
		(start 276.504908 -0.9398)
		(end 276.479762 -0.914654)
		(width 0.12065)
		(layer "B.Cu")
		(net "8644_CBL_PRSNT_R_8")
	)
	(segment
		(start 319.884298 -20.130008)
		(end 319.884298 -20.033234)
		(width 0.12065)
		(layer "B.Cu")
		(net "8644_CBL_PRSNT_R_8")
	)
	(segment
		(start 273.7231 -3.1496)
		(end 273.7231 -1.9558)
		(width 0.12065)
		(layer "B.Cu")
		(net "8644_CBL_PRSNT_R_8")
	)
	(segment
		(start 278.638 -0.381)
		(end 278.765 -0.381)
		(width 0.12065)
		(layer "F.Cu")
		(net "8644_CBL_PRSNT_R_7")
	)
	(segment
		(start 280.575004 -2.191004)
		(end 299.879004 -2.191004)
		(width 0.12065)
		(layer "F.Cu")
		(net "8644_CBL_PRSNT_R_7")
	)
	(segment
		(start 273.255486 -1.397)
		(end 273.255486 -0.127)
		(width 0.12065)
		(layer "F.Cu")
		(net "8644_CBL_PRSNT_R_7")
	)
	(segment
		(start 307.002942 -13.936726)
		(end 308.560216 -15.494)
		(width 0.12065)
		(layer "F.Cu")
		(net "8644_CBL_PRSNT_R_7")
	)
	(segment
		(start 299.879004 -2.191004)
		(end 307.002942 -9.314942)
		(width 0.12065)
		(layer "F.Cu")
		(net "8644_CBL_PRSNT_R_7")
	)
	(segment
		(start 277.33117 0.92583)
		(end 278.638 -0.381)
		(width 0.12065)
		(layer "F.Cu")
		(net "8644_CBL_PRSNT_R_7")
	)
	(segment
		(start 314.0456 -15.494)
		(end 314.8584 -16.3068)
		(width 0.12065)
		(layer "F.Cu")
		(net "8644_CBL_PRSNT_R_7")
	)
	(segment
		(start 314.8584 -17.5006)
		(end 313.1566 -19.2024)
		(width 0.12065)
		(layer "F.Cu")
		(net "8644_CBL_PRSNT_R_7")
	)
	(segment
		(start 307.002942 -9.314942)
		(end 307.002942 -13.936726)
		(width 0.12065)
		(layer "F.Cu")
		(net "8644_CBL_PRSNT_R_7")
	)
	(segment
		(start 273.699732 0.92583)
		(end 277.33117 0.92583)
		(width 0.12065)
		(layer "F.Cu")
		(net "8644_CBL_PRSNT_R_7")
	)
	(segment
		(start 308.560216 -15.494)
		(end 314.0456 -15.494)
		(width 0.12065)
		(layer "F.Cu")
		(net "8644_CBL_PRSNT_R_7")
	)
	(segment
		(start 273.255486 -0.127)
		(end 273.255486 0.481584)
		(width 0.12065)
		(layer "F.Cu")
		(net "8644_CBL_PRSNT_R_7")
	)
	(segment
		(start 309.811928 -19.2024)
		(end 308.88432 -20.130008)
		(width 0.12065)
		(layer "F.Cu")
		(net "8644_CBL_PRSNT_R_7")
	)
	(segment
		(start 313.1566 -19.2024)
		(end 309.811928 -19.2024)
		(width 0.12065)
		(layer "F.Cu")
		(net "8644_CBL_PRSNT_R_7")
	)
	(segment
		(start 273.255486 0.481584)
		(end 273.699732 0.92583)
		(width 0.12065)
		(layer "F.Cu")
		(net "8644_CBL_PRSNT_R_7")
	)
	(segment
		(start 314.8584 -16.3068)
		(end 314.8584 -17.5006)
		(width 0.12065)
		(layer "F.Cu")
		(net "8644_CBL_PRSNT_R_7")
	)
	(segment
		(start 278.765 -0.381)
		(end 280.575004 -2.191004)
		(width 0.12065)
		(layer "F.Cu")
		(net "8644_CBL_PRSNT_R_7")
	)
	(via
		(at 278.638 -0.381)
		(size 0.7112)
		(drill 0.3556)
		(layers "F.Cu" "B.Cu")
		(net "8644_CBL_PRSNT_R_7")
	)
	(segment
		(start 297.884342 -20.130008)
		(end 299.04055 -18.9738)
		(width 0.12065)
		(layer "F.Cu")
		(net "8644_CBL_PRSNT_R_6")
	)
	(segment
		(start 292.354 -5.3848)
		(end 282.055316 -5.3848)
		(width 0.12065)
		(layer "F.Cu")
		(net "8644_CBL_PRSNT_R_6")
	)
	(segment
		(start 299.04055 -18.9738)
		(end 302.4886 -18.9738)
		(width 0.12065)
		(layer "F.Cu")
		(net "8644_CBL_PRSNT_R_6")
	)
	(segment
		(start 303.7332 -17.7292)
		(end 303.7332 -15.572486)
		(width 0.12065)
		(layer "F.Cu")
		(net "8644_CBL_PRSNT_R_6")
	)
	(segment
		(start 280.470356 -6.96976)
		(end 276.95398 -6.96976)
		(width 0.12065)
		(layer "F.Cu")
		(net "8644_CBL_PRSNT_R_6")
	)
	(segment
		(start 293.9288 -6.9596)
		(end 292.354 -5.3848)
		(width 0.12065)
		(layer "F.Cu")
		(net "8644_CBL_PRSNT_R_6")
	)
	(segment
		(start 303.7332 -15.572486)
		(end 303.273714 -15.113)
		(width 0.12065)
		(layer "F.Cu")
		(net "8644_CBL_PRSNT_R_6")
	)
	(segment
		(start 276.95398 -6.96976)
		(end 276.95398 -5.82676)
		(width 0.12065)
		(layer "F.Cu")
		(net "8644_CBL_PRSNT_R_6")
	)
	(segment
		(start 293.9288 -13.97)
		(end 293.9288 -6.9596)
		(width 0.12065)
		(layer "F.Cu")
		(net "8644_CBL_PRSNT_R_6")
	)
	(segment
		(start 302.4886 -18.9738)
		(end 303.7332 -17.7292)
		(width 0.12065)
		(layer "F.Cu")
		(net "8644_CBL_PRSNT_R_6")
	)
	(segment
		(start 282.055316 -5.3848)
		(end 280.470356 -6.96976)
		(width 0.12065)
		(layer "F.Cu")
		(net "8644_CBL_PRSNT_R_6")
	)
	(segment
		(start 303.273714 -15.113)
		(end 295.0718 -15.113)
		(width 0.12065)
		(layer "F.Cu")
		(net "8644_CBL_PRSNT_R_6")
	)
	(segment
		(start 295.0718 -15.113)
		(end 293.9288 -13.97)
		(width 0.12065)
		(layer "F.Cu")
		(net "8644_CBL_PRSNT_R_6")
	)
	(segment
		(start 278.652224 -10.384282)
		(end 280.782014 -12.514072)
		(width 0.12065)
		(layer "F.Cu")
		(net "8644_CBL_PRSNT_R_5")
	)
	(segment
		(start 277.051516 -10.384282)
		(end 277.051516 -9.241282)
		(width 0.12065)
		(layer "F.Cu")
		(net "8644_CBL_PRSNT_R_5")
	)
	(segment
		(start 280.782014 -12.514072)
		(end 280.782014 -13.911072)
		(width 0.12065)
		(layer "F.Cu")
		(net "8644_CBL_PRSNT_R_5")
	)
	(segment
		(start 277.051516 -10.384282)
		(end 278.652224 -10.384282)
		(width 0.12065)
		(layer "F.Cu")
		(net "8644_CBL_PRSNT_R_5")
	)
	(via
		(at 280.782014 -13.911072)
		(size 0.508)
		(drill 0.254)
		(layers "F.Cu" "B.Cu")
		(net "8644_CBL_PRSNT_R_5")
	)
	(segment
		(start 286.144208 -20.130008)
		(end 286.884364 -20.130008)
		(width 0.127)
		(layer "In5.Cu")
		(net "8644_CBL_PRSNT_R_5")
	)
	(segment
		(start 280.782014 -13.911072)
		(end 280.4922 -14.200886)
		(width 0.127)
		(layer "In5.Cu")
		(net "8644_CBL_PRSNT_R_5")
	)
	(segment
		(start 280.4922 -14.478)
		(end 286.144208 -20.130008)
		(width 0.127)
		(layer "In5.Cu")
		(net "8644_CBL_PRSNT_R_5")
	)
	(segment
		(start 280.4922 -14.200886)
		(end 280.4922 -14.478)
		(width 0.127)
		(layer "In5.Cu")
		(net "8644_CBL_PRSNT_R_5")
	)
	(via
		(at 166.37 -31.84144)
		(size 0.7112)
		(drill 0.3556)
		(layers "F.Cu" "B.Cu")
		(net "8644_CBL_PRSNT_R_4")
	)
	(segment
		(start 166.88435 -20.130008)
		(end 166.88435 -20.981924)
		(width 0.12065)
		(layer "B.Cu")
		(net "8644_CBL_PRSNT_R_4")
	)
	(segment
		(start 165.383718 -23.57882)
		(end 165.383718 -30.674818)
		(width 0.12065)
		(layer "B.Cu")
		(net "8644_CBL_PRSNT_R_4")
	)
	(segment
		(start 167.052244 -21.910294)
		(end 165.383718 -23.57882)
		(width 0.12065)
		(layer "B.Cu")
		(net "8644_CBL_PRSNT_R_4")
	)
	(segment
		(start 167.052244 -21.149818)
		(end 167.052244 -21.910294)
		(width 0.12065)
		(layer "B.Cu")
		(net "8644_CBL_PRSNT_R_4")
	)
	(segment
		(start 166.37 -33.0835)
		(end 167.513 -33.0835)
		(width 0.12065)
		(layer "B.Cu")
		(net "8644_CBL_PRSNT_R_4")
	)
	(segment
		(start 166.88435 -20.981924)
		(end 167.052244 -21.149818)
		(width 0.12065)
		(layer "B.Cu")
		(net "8644_CBL_PRSNT_R_4")
	)
	(segment
		(start 166.37 -33.0835)
		(end 166.37 -31.84144)
		(width 0.12065)
		(layer "B.Cu")
		(net "8644_CBL_PRSNT_R_4")
	)
	(segment
		(start 166.37 -31.6611)
		(end 166.37 -31.84144)
		(width 0.12065)
		(layer "B.Cu")
		(net "8644_CBL_PRSNT_R_4")
	)
	(segment
		(start 165.383718 -30.674818)
		(end 166.37 -31.6611)
		(width 0.12065)
		(layer "B.Cu")
		(net "8644_CBL_PRSNT_R_4")
	)
	(via
		(at 156.619956 -31.463234)
		(size 0.7112)
		(drill 0.3556)
		(layers "F.Cu" "B.Cu")
		(net "8644_CBL_PRSNT_R_3")
	)
	(segment
		(start 156.052266 -21.149818)
		(end 156.052266 -22.490938)
		(width 0.12065)
		(layer "B.Cu")
		(net "8644_CBL_PRSNT_R_3")
	)
	(segment
		(start 157.492192 -33.145476)
		(end 156.619956 -32.27324)
		(width 0.12065)
		(layer "B.Cu")
		(net "8644_CBL_PRSNT_R_3")
	)
	(segment
		(start 156.619956 -29.750004)
		(end 156.619956 -31.463234)
		(width 0.12065)
		(layer "B.Cu")
		(net "8644_CBL_PRSNT_R_3")
	)
	(segment
		(start 154.2161 -27.346148)
		(end 156.619956 -29.750004)
		(width 0.12065)
		(layer "B.Cu")
		(net "8644_CBL_PRSNT_R_3")
	)
	(segment
		(start 154.2161 -24.327104)
		(end 154.2161 -27.346148)
		(width 0.12065)
		(layer "B.Cu")
		(net "8644_CBL_PRSNT_R_3")
	)
	(segment
		(start 157.492192 -33.145476)
		(end 158.508192 -33.145476)
		(width 0.12065)
		(layer "B.Cu")
		(net "8644_CBL_PRSNT_R_3")
	)
	(segment
		(start 155.884372 -20.981924)
		(end 156.052266 -21.149818)
		(width 0.12065)
		(layer "B.Cu")
		(net "8644_CBL_PRSNT_R_3")
	)
	(segment
		(start 156.052266 -22.490938)
		(end 154.2161 -24.327104)
		(width 0.12065)
		(layer "B.Cu")
		(net "8644_CBL_PRSNT_R_3")
	)
	(segment
		(start 156.619956 -32.27324)
		(end 156.619956 -31.463234)
		(width 0.12065)
		(layer "B.Cu")
		(net "8644_CBL_PRSNT_R_3")
	)
	(segment
		(start 155.884372 -20.130008)
		(end 155.884372 -20.981924)
		(width 0.12065)
		(layer "B.Cu")
		(net "8644_CBL_PRSNT_R_3")
	)
	(via
		(at 146.643344 -31.857696)
		(size 0.7112)
		(drill 0.3556)
		(layers "F.Cu" "B.Cu")
		(net "8644_CBL_PRSNT_R_2")
	)
	(segment
		(start 142.8369 -26.68524)
		(end 146.643344 -30.491684)
		(width 0.12065)
		(layer "B.Cu")
		(net "8644_CBL_PRSNT_R_2")
	)
	(segment
		(start 145.052034 -20.84197)
		(end 145.052034 -22.33803)
		(width 0.12065)
		(layer "B.Cu")
		(net "8644_CBL_PRSNT_R_2")
	)
	(segment
		(start 146.643344 -32.803846)
		(end 146.643344 -31.857696)
		(width 0.12065)
		(layer "B.Cu")
		(net "8644_CBL_PRSNT_R_2")
	)
	(segment
		(start 146.930618 -33.09112)
		(end 146.643344 -32.803846)
		(width 0.12065)
		(layer "B.Cu")
		(net "8644_CBL_PRSNT_R_2")
	)
	(segment
		(start 144.884394 -20.130008)
		(end 144.884394 -20.67433)
		(width 0.12065)
		(layer "B.Cu")
		(net "8644_CBL_PRSNT_R_2")
	)
	(segment
		(start 144.884394 -20.67433)
		(end 145.052034 -20.84197)
		(width 0.12065)
		(layer "B.Cu")
		(net "8644_CBL_PRSNT_R_2")
	)
	(segment
		(start 144.04086 -23.349204)
		(end 144.036796 -23.349204)
		(width 0.12065)
		(layer "B.Cu")
		(net "8644_CBL_PRSNT_R_2")
	)
	(segment
		(start 146.930618 -33.09112)
		(end 147.946618 -33.09112)
		(width 0.12065)
		(layer "B.Cu")
		(net "8644_CBL_PRSNT_R_2")
	)
	(segment
		(start 145.052034 -22.33803)
		(end 144.04086 -23.349204)
		(width 0.12065)
		(layer "B.Cu")
		(net "8644_CBL_PRSNT_R_2")
	)
	(segment
		(start 142.8369 -24.5491)
		(end 142.8369 -26.68524)
		(width 0.12065)
		(layer "B.Cu")
		(net "8644_CBL_PRSNT_R_2")
	)
	(segment
		(start 144.036796 -23.349204)
		(end 142.8369 -24.5491)
		(width 0.12065)
		(layer "B.Cu")
		(net "8644_CBL_PRSNT_R_2")
	)
	(segment
		(start 146.643344 -30.491684)
		(end 146.643344 -31.857696)
		(width 0.12065)
		(layer "B.Cu")
		(net "8644_CBL_PRSNT_R_2")
	)
	(via
		(at 132.31114 -31.59506)
		(size 0.7112)
		(drill 0.3556)
		(layers "F.Cu" "B.Cu")
		(net "8644_CBL_PRSNT_R_1")
	)
	(segment
		(start 132.54228 -33.10128)
		(end 132.54228 -31.8262)
		(width 0.12065)
		(layer "B.Cu")
		(net "8644_CBL_PRSNT_R_1")
	)
	(segment
		(start 132.54228 -33.10128)
		(end 133.55828 -33.10128)
		(width 0.12065)
		(layer "B.Cu")
		(net "8644_CBL_PRSNT_R_1")
	)
	(segment
		(start 132.31114 -30.23108)
		(end 132.31114 -31.59506)
		(width 0.12065)
		(layer "B.Cu")
		(net "8644_CBL_PRSNT_R_1")
	)
	(segment
		(start 131.699 -29.61894)
		(end 132.31114 -30.23108)
		(width 0.12065)
		(layer "B.Cu")
		(net "8644_CBL_PRSNT_R_1")
	)
	(segment
		(start 133.884416 -20.130008)
		(end 133.884416 -20.982178)
		(width 0.12065)
		(layer "B.Cu")
		(net "8644_CBL_PRSNT_R_1")
	)
	(segment
		(start 133.884416 -20.982178)
		(end 134.052056 -21.149818)
		(width 0.12065)
		(layer "B.Cu")
		(net "8644_CBL_PRSNT_R_1")
	)
	(segment
		(start 134.052056 -21.149818)
		(end 134.052056 -22.035008)
		(width 0.12065)
		(layer "B.Cu")
		(net "8644_CBL_PRSNT_R_1")
	)
	(segment
		(start 131.699 -24.388064)
		(end 131.699 -29.61894)
		(width 0.12065)
		(layer "B.Cu")
		(net "8644_CBL_PRSNT_R_1")
	)
	(segment
		(start 132.54228 -31.8262)
		(end 132.31114 -31.59506)
		(width 0.12065)
		(layer "B.Cu")
		(net "8644_CBL_PRSNT_R_1")
	)
	(segment
		(start 134.052056 -22.035008)
		(end 131.699 -24.388064)
		(width 0.12065)
		(layer "B.Cu")
		(net "8644_CBL_PRSNT_R_1")
	)
	(segment
		(start 7.253478 -92.533978)
		(end 8.855964 -92.533978)
		(width 0.1524)
		(layer "F.Cu")
		(net "50M_CLK_OUT_R")
	)
	(segment
		(start 6.858 -92.1385)
		(end 7.253478 -92.533978)
		(width 0.1524)
		(layer "F.Cu")
		(net "50M_CLK_OUT_R")
	)
	(segment
		(start 6.97738 -91.13012)
		(end 6.858 -91.2495)
		(width 0.1524)
		(layer "F.Cu")
		(net "50M_CLK_OUT")
	)
	(segment
		(start 6.97738 -88.977978)
		(end 6.97738 -91.13012)
		(width 0.1524)
		(layer "F.Cu")
		(net "50M_CLK_OUT")
	)
	(segment
		(start 9.0551 -100.1014)
		(end 8.855964 -99.902264)
		(width 0.1524)
		(layer "F.Cu")
		(net "50M_CLK_OE")
	)
	(segment
		(start 8.855964 -99.1616)
		(end 8.855964 -97.613978)
		(width 0.1524)
		(layer "F.Cu")
		(net "50M_CLK_OE")
	)
	(segment
		(start 8.855964 -99.902264)
		(end 8.855964 -99.1616)
		(width 0.1524)
		(layer "F.Cu")
		(net "50M_CLK_OE")
	)
	(via
		(at 8.855964 -99.1616)
		(size 0.7112)
		(drill 0.3556)
		(layers "F.Cu" "B.Cu")
		(net "50M_CLK_OE")
	)
	(zone
		(layer "F.Cu")
		(hatch none 0.5)
		(connect_pads
			(clearance 0)
		)
		(min_thickness 0.25)
		(keepout
			(tracks not_allowed)
			(vias allowed)
			(pads allowed)
			(copperpour not_allowed)
			(footprints allowed)
		)
		(placement
			(enabled no)
			(sheetname "")
		)
		(fill
			(thermal_gap 0.5)
			(thermal_bridge_width 0.5)
			(island_removal_mode 0)
		)
		(polygon
			(pts
				(arc
					(start 133.852158 -35.229292)
					(mid 133.341618 -35.739832)
					(end 133.852158 -36.250372)
				)
				(arc
					(start 134.664704 -36.250372)
					(mid 135.175498 -35.739959)
					(end 134.664958 -35.229292)
				)
				(arc
					(start 134.480554 -35.229292)
					(mid 134.485594 -35.261581)
					(end 134.48919 -35.294062)
				)
				(xy 134.489952 -35.294824)
				(arc
					(start 134.49554 -35.429698)
					(mid 134.501553 -35.475221)
					(end 134.51586 -35.518852)
				)
				(arc
					(start 134.51586 -35.518852)
					(mid 134.878536 -35.899353)
					(end 134.410704 -35.659568)
				)
				(arc
					(start 134.410704 -35.659568)
					(mid 134.361806 -35.569981)
					(end 134.336536 -35.4711)
				)
				(xy 134.335012 -35.46983)
				(arc
					(start 134.329424 -35.334956)
					(mid 134.324769 -35.281793)
					(end 134.3152 -35.229292)
				)
				(arc
					(start 134.167372 -35.229292)
					(mid 134.179143 -35.275899)
					(end 134.18566 -35.323526)
				)
				(xy 134.187184 -35.32505) (xy 134.187184 -35.51936)
				(arc
					(start 134.185406 -35.521392)
					(mid 134.162313 -35.612623)
					(end 134.114794 -35.693858)
				)
				(arc
					(start 134.114794 -35.693858)
					(mid 133.62265 -35.875542)
					(end 134.019036 -35.531806)
				)
				(arc
					(start 134.019036 -35.531806)
					(mid 134.023625 -35.509024)
					(end 134.025132 -35.485832)
				)
				(arc
					(start 134.025132 -35.358578)
					(mid 134.01664 -35.291841)
					(end 133.991858 -35.229292)
				)
			)
		)
	)
	(zone
		(layer "F.Cu")
		(hatch none 0.5)
		(connect_pads
			(clearance 0)
		)
		(min_thickness 0.25)
		(keepout
			(tracks not_allowed)
			(vias allowed)
			(pads allowed)
			(copperpour not_allowed)
			(footprints allowed)
		)
		(placement
			(enabled no)
			(sheetname "")
		)
		(fill
			(thermal_gap 0.5)
			(thermal_bridge_width 0.5)
			(island_removal_mode 0)
		)
		(polygon
			(pts
				(arc
					(start 63.693802 -210.385914)
					(mid 63.183008 -210.896327)
					(end 63.693548 -211.406994)
				)
				(xy 63.860172 -211.406994)
				(arc
					(start 63.860172 -211.325206)
					(mid 63.846579 -211.227758)
					(end 63.806832 -211.137754)
				)
				(arc
					(start 63.806832 -211.137754)
					(mid 63.511882 -210.701189)
					(end 63.926974 -211.02574)
				)
				(arc
					(start 63.926974 -211.02574)
					(mid 63.992217 -211.15159)
					(end 64.020954 -211.290408)
				)
				(xy 64.022224 -211.291678) (xy 64.022224 -211.406994) (xy 64.164972 -211.406994) (xy 64.164972 -211.291678)
				(arc
					(start 64.166242 -211.290408)
					(mid 64.198213 -211.14811)
					(end 64.27089 -211.021676)
				)
				(arc
					(start 64.27089 -211.021676)
					(mid 64.692172 -210.705168)
					(end 64.387984 -211.135468)
				)
				(arc
					(start 64.387984 -211.135468)
					(mid 64.342655 -211.225564)
					(end 64.327024 -211.325206)
				)
				(xy 64.327024 -211.406994)
				(arc
					(start 64.506348 -211.406994)
					(mid 65.016888 -210.896454)
					(end 64.506348 -210.385914)
				)
			)
		)
	)
	(zone
		(layer "F.Cu")
		(hatch none 0.5)
		(connect_pads
			(clearance 0)
		)
		(min_thickness 0.25)
		(keepout
			(tracks not_allowed)
			(vias allowed)
			(pads allowed)
			(copperpour not_allowed)
			(footprints allowed)
		)
		(placement
			(enabled no)
			(sheetname "")
		)
		(fill
			(thermal_gap 0.5)
			(thermal_bridge_width 0.5)
			(island_removal_mode 0)
		)
		(polygon
			(pts
				(arc
					(start 270.894048 -210.385914)
					(mid 270.383254 -210.896327)
					(end 270.893794 -211.406994)
				)
				(xy 271.060418 -211.406994)
				(arc
					(start 271.060418 -211.3026)
					(mid 271.047634 -211.215736)
					(end 271.01038 -211.13623)
				)
				(arc
					(start 271.01038 -211.13623)
					(mid 270.709244 -210.704032)
					(end 271.12849 -211.022946)
				)
				(arc
					(start 271.12849 -211.022946)
					(mid 271.192489 -211.138693)
					(end 271.2212 -211.267802)
				)
				(xy 271.22247 -211.269072) (xy 271.22247 -211.406994) (xy 271.365218 -211.406994) (xy 271.365218 -211.25688)
				(arc
					(start 271.366742 -211.255356)
					(mid 271.395946 -211.135939)
					(end 271.459706 -211.03082)
				)
				(xy 271.459706 -211.028788)
				(arc
					(start 271.469612 -211.018882)
					(mid 271.894352 -210.707143)
					(end 271.584928 -211.13369)
				)
				(arc
					(start 271.584928 -211.13369)
					(mid 271.542097 -211.206903)
					(end 271.52727 -211.290408)
				)
				(xy 271.52727 -211.406994)
				(arc
					(start 271.706594 -211.406994)
					(mid 272.217134 -210.896454)
					(end 271.706594 -210.385914)
				)
			)
		)
	)
	(zone
		(layer "F.Cu")
		(hatch none 0.5)
		(connect_pads
			(clearance 0)
		)
		(min_thickness 0.25)
		(keepout
			(tracks allowed)
			(vias allowed)
			(pads allowed)
			(copperpour allowed)
			(footprints not_allowed)
		)
		(placement
			(enabled no)
			(sheetname "")
		)
		(fill
			(thermal_gap 0.5)
			(thermal_bridge_width 0.5)
			(island_removal_mode 0)
		)
		(polygon
			(pts
				(arc
					(start 5.999988 -203.499974)
					(mid 9.99998 -199.499982)
					(end 13.999972 -203.499974)
				)
				(arc
					(start 13.999972 -203.499974)
					(mid 9.99998 -207.499966)
					(end 5.999988 -203.499974)
				)
			)
		)
	)
	(zone
		(layer "F.Cu")
		(hatch none 0.5)
		(connect_pads
			(clearance 0)
		)
		(min_thickness 0.25)
		(keepout
			(tracks not_allowed)
			(vias allowed)
			(pads allowed)
			(copperpour not_allowed)
			(footprints allowed)
		)
		(placement
			(enabled no)
			(sheetname "")
		)
		(fill
			(thermal_gap 0.5)
			(thermal_bridge_width 0.5)
			(island_removal_mode 0)
		)
		(polygon
			(pts
				(arc
					(start 82.893916 -210.385914)
					(mid 82.383122 -210.896327)
					(end 82.893662 -211.406994)
				)
				(xy 83.060286 -211.406994)
				(arc
					(start 83.060286 -211.3026)
					(mid 83.047502 -211.215736)
					(end 83.010248 -211.13623)
				)
				(arc
					(start 83.010248 -211.13623)
					(mid 82.709112 -210.704032)
					(end 83.128358 -211.022946)
				)
				(arc
					(start 83.128358 -211.022946)
					(mid 83.192357 -211.138693)
					(end 83.221068 -211.267802)
				)
				(xy 83.222338 -211.269072) (xy 83.222338 -211.406994) (xy 83.365086 -211.406994) (xy 83.365086 -211.279994)
				(arc
					(start 83.366356 -211.278724)
					(mid 83.398404 -211.141609)
					(end 83.470496 -211.02066)
				)
				(arc
					(start 83.470496 -211.02066)
					(mid 83.893202 -210.706099)
					(end 83.586828 -211.134706)
				)
				(arc
					(start 83.586828 -211.134706)
					(mid 83.542457 -211.219136)
					(end 83.527138 -211.313268)
				)
				(xy 83.527138 -211.406994)
				(arc
					(start 83.706462 -211.406994)
					(mid 84.217002 -210.896454)
					(end 83.706462 -210.385914)
				)
			)
		)
	)
	(zone
		(net "GND")
		(layer "F.Cu")
		(hatch none 0.5)
		(connect_pads
			(clearance 0.5)
		)
		(min_thickness 0.25)
		(fill yes
			(thermal_gap 0.5)
			(thermal_bridge_width 0.5)
			(island_removal_mode 0)
		)
		(polygon
			(pts
				(xy 11.684 -106.045) (xy 11.43 -106.299) (xy 11.43 -109.855) (xy 9.525 -111.76) (xy 6.223 -111.76)
				(xy 6.096 -111.887) (xy 6.096 -114.173) (xy 6.477 -114.554) (xy 12.065 -114.554) (xy 13.081 -113.538)
				(xy 13.081 -107.442) (xy 13.208 -107.315) (xy 14.478 -107.315) (xy 14.859 -106.934) (xy 14.859 -106.426)
				(xy 14.478 -106.045)
			)
		)
	)
	(zone
		(net "P1V8_PWR")
		(layer "F.Cu")
		(hatch none 0.5)
		(connect_pads
			(clearance 0.5)
		)
		(min_thickness 0.25)
		(fill yes
			(thermal_gap 0.5)
			(thermal_bridge_width 0.5)
			(island_removal_mode 0)
		)
		(polygon
			(pts
				(xy 142.7988 -83.9216) (xy 142.4178 -84.3026) (xy 142.4178 -86.3346) (xy 142.494 -86.4108) (xy 143.129 -86.4108)
				(xy 143.2814 -86.5632) (xy 143.2814 -88.0872) (xy 142.7226 -88.646) (xy 142.7226 -89.7128) (xy 142.8242 -89.8144)
				(xy 144.5006 -89.8144) (xy 145.085562 -89.229438) (xy 150.35403 -89.229438) (xy 150.437596 -89.145872)
				(xy 150.437596 -87.546942) (xy 150.04542 -87.154766) (xy 150.04542 -85.49132) (xy 150.2156 -85.32114)
				(xy 150.2156 -84.0486) (xy 150.0886 -83.9216)
			)
		)
		(polygon
			(pts
				(xy 143.111474 -85.69452) (xy 142.908274 -85.69452) (xy 142.908274 -85.89772) (xy 143.111474 -85.89772)
			)
		)
		(polygon
			(pts
				(xy 143.060674 -85.26272) (xy 142.857474 -85.26272) (xy 142.857474 -85.46592) (xy 143.060674 -85.46592)
			)
		)
		(polygon
			(pts
				(xy 143.060674 -84.70392) (xy 142.857474 -84.70392) (xy 142.857474 -84.90712) (xy 143.060674 -84.90712)
			)
		)
	)
	(zone
		(net "DUT_VDDO")
		(layer "F.Cu")
		(hatch none 0.5)
		(connect_pads
			(clearance 0.5)
		)
		(min_thickness 0.25)
		(fill yes
			(thermal_gap 0.5)
			(thermal_bridge_width 0.5)
			(island_removal_mode 0)
		)
		(polygon
			(pts
				(xy 141.16431 -81.7118) (xy 140.938758 -81.937352) (xy 140.938758 -83.570318) (xy 141.13764 -83.7692)
				(xy 145.6944 -83.7692) (xy 145.8468 -83.6168) (xy 147.574 -83.6168) (xy 147.6756 -83.5152) (xy 147.6756 -82.5246)
				(xy 146.8628 -81.7118)
			)
		)
	)
	(zone
		(layer "F.Cu")
		(hatch none 0.5)
		(connect_pads
			(clearance 0)
		)
		(min_thickness 0.25)
		(keepout
			(tracks allowed)
			(vias allowed)
			(pads allowed)
			(copperpour allowed)
			(footprints not_allowed)
		)
		(placement
			(enabled no)
			(sheetname "")
		)
		(fill
			(thermal_gap 0.5)
			(thermal_bridge_width 0.5)
			(island_removal_mode 0)
		)
		(polygon
			(pts
				(xy 3.999992 -77.0001) (xy 0 -77.0001) (xy 0 -76.499974) (xy 8.772144 -76.499974) (xy 8.772144 -51.999896)
				(xy 25.472136 -51.999896) (xy 25.472136 -49.9999) (xy 89.562178 -49.9999) (xy 89.562178 -77.0001)
			)
		)
	)
	(zone
		(layer "F.Cu")
		(hatch none 0.5)
		(connect_pads
			(clearance 0)
		)
		(min_thickness 0.25)
		(keepout
			(tracks not_allowed)
			(vias allowed)
			(pads allowed)
			(copperpour not_allowed)
			(footprints allowed)
		)
		(placement
			(enabled no)
			(sheetname "")
		)
		(fill
			(thermal_gap 0.5)
			(thermal_bridge_width 0.5)
			(island_removal_mode 0)
		)
		(polygon
			(pts
				(arc
					(start 300.6852 -24.224996)
					(mid 300.429168 -23.379176)
					(end 299.583348 -23.635208)
				)
				(arc
					(start 298.837604 -25.027636)
					(mid 299.085738 -25.879089)
					(end 299.935392 -25.625044)
				)
				(xy 300.014386 -25.47747)
				(arc
					(start 300.014386 -25.306782)
					(mid 299.990831 -25.188833)
					(end 299.923962 -25.08885)
				)
				(xy 299.72254 -24.887174) (xy 299.72254 -24.88692)
				(arc
					(start 299.672248 -24.833072)
					(mid 299.540435 -24.847693)
					(end 299.46727 -24.958294)
				)
				(arc
					(start 299.46727 -24.958294)
					(mid 299.383041 -25.711167)
					(end 299.30344 -24.957786)
				)
				(xy 299.30344 -24.947626)
				(arc
					(start 299.305472 -24.945594)
					(mid 299.464716 -24.704202)
					(end 299.753528 -24.69134)
				)
				(arc
					(start 299.753528 -24.69134)
					(mid 299.768159 -24.699957)
					(end 299.780706 -24.711406)
				)
				(arc
					(start 299.780706 -24.711406)
					(mid 299.818944 -24.753269)
					(end 299.85843 -24.793956)
				)
				(xy 299.86097 -24.796496) (xy 300.062392 -24.997918)
				(arc
					(start 300.062392 -24.999696)
					(mid 300.125031 -25.093039)
					(end 300.163738 -25.198578)
				)
				(arc
					(start 300.253654 -25.030684)
					(mid 300.202914 -24.947394)
					(end 300.139608 -24.873204)
				)
				(arc
					(start 300.139608 -24.873204)
					(mid 300.083248 -24.79399)
					(end 300.055788 -24.700738)
				)
				(xy 300.053248 -24.698198)
				(arc
					(start 300.053248 -24.302466)
					(mid 300.134274 -23.549024)
					(end 300.2153 -24.302466)
				)
				(xy 300.2153 -24.631142) (xy 300.215554 -24.631396)
				(arc
					(start 300.215554 -24.664924)
					(mid 300.22571 -24.715512)
					(end 300.254416 -24.758396)
				)
				(arc
					(start 300.254416 -24.758396)
					(mid 300.300982 -24.809378)
					(end 300.342808 -24.864314)
				)
			)
		)
	)
	(zone
		(layer "F.Cu")
		(hatch none 0.5)
		(connect_pads
			(clearance 0)
		)
		(min_thickness 0.25)
		(keepout
			(tracks not_allowed)
			(vias allowed)
			(pads allowed)
			(copperpour not_allowed)
			(footprints allowed)
		)
		(placement
			(enabled no)
			(sheetname "")
		)
		(fill
			(thermal_gap 0.5)
			(thermal_bridge_width 0.5)
			(island_removal_mode 0)
		)
		(polygon
			(pts
				(arc
					(start 144.789906 -24.966168)
					(mid 144.866222 -25.078834)
					(end 144.91208 -25.20696)
				)
				(arc
					(start 145.004028 -25.035256)
					(mid 144.966109 -24.964727)
					(end 144.920208 -24.899112)
				)
				(arc
					(start 144.920208 -24.899112)
					(mid 144.858515 -24.801406)
					(end 144.818862 -24.692864)
				)
				(arc
					(start 144.818862 -24.69261)
					(mid 144.809505 -24.645307)
					(end 144.804384 -24.59736)
				)
				(xy 144.803368 -24.596344) (xy 144.803368 -24.564594) (xy 144.803368 -24.562816)
				(arc
					(start 144.803368 -24.302466)
					(mid 144.884394 -23.549024)
					(end 144.96542 -24.302466)
				)
				(arc
					(start 144.96542 -24.564594)
					(mid 144.968217 -24.609624)
					(end 144.976342 -24.654002)
				)
				(arc
					(start 144.976342 -24.654002)
					(mid 145.004043 -24.730057)
					(end 145.047208 -24.798528)
				)
				(arc
					(start 145.047208 -24.798528)
					(mid 145.071892 -24.831351)
					(end 145.09496 -24.86533)
				)
				(xy 145.437352 -24.22652) (xy 145.437098 -24.226266)
				(arc
					(start 145.435066 -24.22525)
					(mid 145.17939 -23.379349)
					(end 144.333468 -23.635208)
				)
				(xy 144.331436 -23.633938) (xy 143.581374 -25.033986)
				(arc
					(start 143.583406 -25.035256)
					(mid 143.839438 -25.881076)
					(end 144.685258 -25.625044)
				)
				(xy 144.68729 -25.626314) (xy 144.762728 -25.485598)
				(arc
					(start 144.762728 -25.3238)
					(mid 144.733759 -25.178635)
					(end 144.651476 -25.055576)
				)
				(xy 144.583404 -24.98725)
				(arc
					(start 144.497298 -24.901652)
					(mid 144.46384 -24.879299)
					(end 144.4244 -24.871426)
				)
				(arc
					(start 144.424146 -24.871426)
					(mid 144.36226 -24.878956)
					(end 144.304004 -24.901144)
				)
				(arc
					(start 144.304004 -24.901144)
					(mid 144.277462 -24.933369)
					(end 144.255236 -24.968708)
				)
				(arc
					(start 144.255236 -24.968708)
					(mid 144.098736 -25.709402)
					(end 144.084802 -24.952452)
				)
				(arc
					(start 144.084802 -24.952452)
					(mid 144.131557 -24.85962)
					(end 144.196816 -24.778716)
				)
				(arc
					(start 144.196816 -24.778716)
					(mid 144.204783 -24.771818)
					(end 144.21358 -24.766016)
				)
				(arc
					(start 144.21358 -24.766016)
					(mid 144.315127 -24.723822)
					(end 144.424146 -24.709374)
				)
				(arc
					(start 144.4244 -24.709374)
					(mid 144.509263 -24.723349)
					(end 144.585182 -24.76373)
				)
				(xy 144.588738 -24.76373) (xy 144.611598 -24.78659) (xy 144.61236 -24.787352) (xy 144.674082 -24.84882)
				(xy 144.697704 -24.872442) (xy 144.72158 -24.896064) (xy 144.72158 -24.896318) (xy 144.789906 -24.964644)
			)
		)
	)
	(zone
		(layer "F.Cu")
		(hatch none 0.5)
		(connect_pads
			(clearance 0)
		)
		(min_thickness 0.25)
		(keepout
			(tracks allowed)
			(vias allowed)
			(pads allowed)
			(copperpour allowed)
			(footprints allowed)
		)
		(placement
			(enabled no)
			(sheetname "")
		)
		(fill
			(thermal_gap 0.5)
			(thermal_bridge_width 0.5)
			(island_removal_mode 0)
		)
		(polygon
			(pts
				(xy 153.135584 -34.396934) (xy 154.13228 -34.396934) (xy 154.493722 -34.035492) (xy 154.493722 -32.598106)
				(xy 154.20467 -32.309054) (xy 153.18613 -32.309054) (xy 152.97658 -32.518604) (xy 152.97658 -34.23793)
			)
		)
	)
	(zone
		(layer "F.Cu")
		(hatch none 0.5)
		(connect_pads
			(clearance 0)
		)
		(min_thickness 0.25)
		(keepout
			(tracks not_allowed)
			(vias allowed)
			(pads allowed)
			(copperpour not_allowed)
			(footprints allowed)
		)
		(placement
			(enabled no)
			(sheetname "")
		)
		(fill
			(thermal_gap 0.5)
			(thermal_bridge_width 0.5)
			(island_removal_mode 0)
		)
		(polygon
			(pts
				(arc
					(start 297.812206 -24.999696)
					(mid 297.875778 -25.094651)
					(end 297.914568 -25.202134)
				)
				(arc
					(start 298.004992 -25.033478)
					(mid 297.953705 -24.948655)
					(end 297.889422 -24.873204)
				)
				(arc
					(start 297.889422 -24.873204)
					(mid 297.833062 -24.79399)
					(end 297.805602 -24.700738)
				)
				(xy 297.803316 -24.698452)
				(arc
					(start 297.803316 -24.302466)
					(mid 297.884342 -23.549024)
					(end 297.965368 -24.302466)
				)
				(arc
					(start 297.965368 -24.664924)
					(mid 297.975524 -24.715512)
					(end 298.00423 -24.758396)
				)
				(arc
					(start 298.00423 -24.758396)
					(mid 298.051651 -24.810583)
					(end 298.094146 -24.866854)
				)
				(xy 298.4373 -24.22652) (xy 298.437046 -24.226266)
				(arc
					(start 298.435014 -24.22525)
					(mid 298.179338 -23.379349)
					(end 297.333416 -23.635208)
				)
				(xy 297.331384 -23.633938) (xy 296.581322 -25.033986)
				(arc
					(start 296.583354 -25.035256)
					(mid 296.839386 -25.881076)
					(end 297.685206 -25.625044)
				)
				(xy 297.687238 -25.626314) (xy 297.7642 -25.482804)
				(arc
					(start 297.7642 -25.306782)
					(mid 297.740645 -25.188833)
					(end 297.673776 -25.08885)
				)
				(arc
					(start 297.494198 -24.909018)
					(mid 297.437004 -24.871732)
					(end 297.369992 -24.858726)
				)
				(arc
					(start 297.320208 -24.858726)
					(mid 297.28488 -24.865847)
					(end 297.25493 -24.885904)
				)
				(arc
					(start 297.25493 -24.885904)
					(mid 297.230508 -24.919181)
					(end 297.217338 -24.958294)
				)
				(arc
					(start 297.217338 -24.958294)
					(mid 297.132731 -25.711222)
					(end 297.053254 -24.957786)
				)
				(xy 297.053254 -24.947626)
				(arc
					(start 297.055286 -24.94534)
					(mid 297.083098 -24.851107)
					(end 297.140122 -24.771096)
				)
				(arc
					(start 297.140122 -24.771096)
					(mid 297.206299 -24.72347)
					(end 297.28414 -24.699214)
				)
				(xy 297.28668 -24.696674) (xy 297.40352 -24.696674)
				(arc
					(start 297.405298 -24.698452)
					(mid 297.500228 -24.722514)
					(end 297.584368 -24.77262)
				)
				(xy 297.586908 -24.77262) (xy 297.608244 -24.793956) (xy 297.610784 -24.796496) (xy 297.812206 -24.997918)
			)
		)
	)
	(zone
		(layer "F.Cu")
		(hatch none 0.5)
		(connect_pads
			(clearance 0)
		)
		(min_thickness 0.25)
		(keepout
			(tracks not_allowed)
			(vias allowed)
			(pads allowed)
			(copperpour not_allowed)
			(footprints allowed)
		)
		(placement
			(enabled no)
			(sheetname "")
		)
		(fill
			(thermal_gap 0.5)
			(thermal_bridge_width 0.5)
			(island_removal_mode 0)
		)
		(polygon
			(pts
				(arc
					(start 193.69405 -210.385914)
					(mid 193.183256 -210.896327)
					(end 193.693796 -211.406994)
				)
				(xy 193.86042 -211.406994)
				(arc
					(start 193.86042 -211.307172)
					(mid 193.847556 -211.218153)
					(end 193.809874 -211.136484)
				)
				(arc
					(start 193.809874 -211.136484)
					(mid 193.509652 -210.703635)
					(end 193.928238 -211.023454)
				)
				(arc
					(start 193.928238 -211.023454)
					(mid 193.992502 -211.141275)
					(end 194.021202 -211.272374)
				)
				(xy 194.022472 -211.273644) (xy 194.022472 -211.406994) (xy 194.16522 -211.406994) (xy 194.16522 -211.273644)
				(arc
					(start 194.16649 -211.27212)
					(mid 194.19865 -211.138098)
					(end 194.270376 -211.020406)
				)
				(arc
					(start 194.270376 -211.020406)
					(mid 194.693163 -210.705924)
					(end 194.386454 -211.134452)
				)
				(arc
					(start 194.386454 -211.134452)
					(mid 194.342526 -211.215894)
					(end 194.327272 -211.307172)
				)
				(xy 194.327272 -211.406994)
				(arc
					(start 194.506596 -211.406994)
					(mid 195.017136 -210.896454)
					(end 194.506596 -210.385914)
				)
			)
		)
	)
	(zone
		(layer "F.Cu")
		(hatch none 0.5)
		(connect_pads
			(clearance 0)
		)
		(min_thickness 0.25)
		(keepout
			(tracks allowed)
			(vias allowed)
			(pads allowed)
			(copperpour allowed)
			(footprints not_allowed)
		)
		(placement
			(enabled no)
			(sheetname "")
		)
		(fill
			(thermal_gap 0.5)
			(thermal_bridge_width 0.5)
			(island_removal_mode 0)
		)
		(polygon
			(pts
				(arc
					(start 199.021954 -72.00011)
					(mid 200.622154 -70.39991)
					(end 202.2221 -72.00011)
				)
				(arc
					(start 202.2221 -72.00011)
					(mid 200.622154 -73.600056)
					(end 199.021954 -72.00011)
				)
			)
		)
	)
	(zone
		(layer "F.Cu")
		(hatch none 0.5)
		(connect_pads
			(clearance 0)
		)
		(min_thickness 0.25)
		(keepout
			(tracks allowed)
			(vias allowed)
			(pads allowed)
			(copperpour allowed)
			(footprints allowed)
		)
		(placement
			(enabled no)
			(sheetname "")
		)
		(fill
			(thermal_gap 0.5)
			(thermal_bridge_width 0.5)
			(island_removal_mode 0)
		)
		(polygon
			(pts
				(xy 180.4416 -29.0322) (xy 180.4416 -25.5778) (xy 183.4134 -25.5778) (xy 183.4134 -29.0322)
			)
		)
	)
	(zone
		(layer "F.Cu")
		(hatch none 0.5)
		(connect_pads
			(clearance 0)
		)
		(min_thickness 0.25)
		(keepout
			(tracks not_allowed)
			(vias allowed)
			(pads allowed)
			(copperpour not_allowed)
			(footprints allowed)
		)
		(placement
			(enabled no)
			(sheetname "")
		)
		(fill
			(thermal_gap 0.5)
			(thermal_bridge_width 0.5)
			(island_removal_mode 0)
		)
		(polygon
			(pts
				(arc
					(start 335.69402 -210.385914)
					(mid 335.183226 -210.896327)
					(end 335.693766 -211.406994)
				)
				(xy 335.86039 -211.406994)
				(arc
					(start 335.86039 -211.2518)
					(mid 335.848785 -211.188683)
					(end 335.815686 -211.13369)
				)
				(arc
					(start 335.815686 -211.13369)
					(mid 335.50536 -210.707646)
					(end 335.930748 -211.018882)
				)
				(xy 335.946242 -211.034376)
				(arc
					(start 335.946242 -211.036916)
					(mid 335.99652 -211.121289)
					(end 336.020664 -211.216494)
				)
				(xy 336.022442 -211.218272) (xy 336.022442 -211.406994) (xy 336.16519 -211.406994) (xy 336.16519 -211.218272)
				(arc
					(start 336.166968 -211.216494)
					(mid 336.187975 -211.133884)
					(end 336.230976 -211.060284)
				)
				(xy 336.230976 -211.05749) (xy 336.254598 -211.033868) (xy 336.254598 -211.033614)
				(arc
					(start 336.269584 -211.018882)
					(mid 336.695178 -210.707842)
					(end 336.384138 -211.133436)
				)
				(arc
					(start 336.369152 -211.148422)
					(mid 336.338137 -211.194934)
					(end 336.327242 -211.249768)
				)
				(xy 336.327242 -211.2518) (xy 336.327242 -211.406994)
				(arc
					(start 336.506566 -211.406994)
					(mid 337.017106 -210.896454)
					(end 336.506566 -210.385914)
				)
			)
		)
	)
	(zone
		(layer "F.Cu")
		(hatch none 0.5)
		(connect_pads
			(clearance 0)
		)
		(min_thickness 0.25)
		(keepout
			(tracks allowed)
			(vias allowed)
			(pads allowed)
			(copperpour allowed)
			(footprints allowed)
		)
		(placement
			(enabled no)
			(sheetname "")
		)
		(fill
			(thermal_gap 0.5)
			(thermal_bridge_width 0.5)
			(island_removal_mode 0)
		)
		(polygon
			(pts
				(xy 215.9 -12.446) (xy 215.9 -13.716) (xy 210.947 -13.716) (xy 210.947 -12.446)
			)
		)
	)
	(zone
		(net "P5V_STBY_LR")
		(layer "F.Cu")
		(hatch none 0.5)
		(connect_pads
			(clearance 0.5)
		)
		(min_thickness 0.25)
		(fill yes
			(thermal_gap 0.5)
			(thermal_bridge_width 0.5)
			(island_removal_mode 0)
		)
		(polygon
			(pts
				(xy 37.9222 -69.85) (xy 37.6936 -70.0786) (xy 37.6936 -76.581) (xy 38.3286 -77.216) (xy 41.6814 -77.216)
				(xy 41.9608 -76.9366) (xy 41.9608 -70.0532) (xy 41.7576 -69.85)
			)
		)
	)
	(zone
		(layer "F.Cu")
		(hatch none 0.5)
		(connect_pads
			(clearance 0)
		)
		(min_thickness 0.25)
		(keepout
			(tracks not_allowed)
			(vias allowed)
			(pads allowed)
			(copperpour not_allowed)
			(footprints allowed)
		)
		(placement
			(enabled no)
			(sheetname "")
		)
		(fill
			(thermal_gap 0.5)
			(thermal_bridge_width 0.5)
			(island_removal_mode 0)
		)
		(polygon
			(pts
				(arc
					(start 183.59374 -25.946354)
					(mid 183.083327 -25.43556)
					(end 182.57266 -25.9461)
				)
				(xy 182.57266 -26.119074)
				(arc
					(start 182.646066 -26.119074)
					(mid 182.748435 -26.104177)
					(end 182.842408 -26.060908)
				)
				(arc
					(start 182.842408 -26.060908)
					(mid 183.277018 -25.762807)
					(end 182.955184 -26.180034)
				)
				(arc
					(start 182.955184 -26.180034)
					(mid 182.825124 -26.24945)
					(end 182.680864 -26.279856)
				)
				(xy 182.679594 -26.281126) (xy 182.57266 -26.281126) (xy 182.57266 -26.423874) (xy 182.679594 -26.423874)
				(arc
					(start 182.680864 -26.425144)
					(mid 182.825138 -26.455514)
					(end 182.955184 -26.524966)
				)
				(arc
					(start 182.955184 -26.524966)
					(mid 183.276952 -26.94213)
					(end 182.842408 -26.644092)
				)
				(arc
					(start 182.842408 -26.644092)
					(mid 182.748453 -26.600763)
					(end 182.646066 -26.585926)
				)
				(xy 182.57266 -26.585926)
				(arc
					(start 182.57266 -26.7589)
					(mid 183.0832 -27.26944)
					(end 183.59374 -26.7589)
				)
			)
		)
	)
	(zone
		(layer "F.Cu")
		(hatch none 0.5)
		(connect_pads
			(clearance 0)
		)
		(min_thickness 0.25)
		(keepout
			(tracks not_allowed)
			(vias allowed)
			(pads allowed)
			(copperpour not_allowed)
			(footprints allowed)
		)
		(placement
			(enabled no)
			(sheetname "")
		)
		(fill
			(thermal_gap 0.5)
			(thermal_bridge_width 0.5)
			(island_removal_mode 0)
		)
		(polygon
			(pts
				(arc
					(start 172.89399 -210.385914)
					(mid 172.383196 -210.896327)
					(end 172.893736 -211.406994)
				)
				(xy 173.06036 -211.406994)
				(arc
					(start 173.06036 -211.287868)
					(mid 173.048076 -211.207976)
					(end 173.012354 -211.135468)
				)
				(arc
					(start 173.012354 -211.135468)
					(mid 172.707607 -210.705263)
					(end 173.129448 -211.021422)
				)
				(arc
					(start 173.129448 -211.021422)
					(mid 173.192331 -211.130334)
					(end 173.220888 -211.252816)
				)
				(xy 173.222412 -211.25434) (xy 173.222412 -211.406994) (xy 173.36516 -211.406994) (xy 173.36516 -211.25434)
				(arc
					(start 173.366684 -211.252816)
					(mid 173.395402 -211.135723)
					(end 173.45787 -211.032598)
				)
				(xy 173.45787 -211.030566)
				(arc
					(start 173.469554 -211.018882)
					(mid 173.894947 -210.707641)
					(end 173.584616 -211.13369)
				)
				(arc
					(start 173.584616 -211.13369)
					(mid 173.541977 -211.205597)
					(end 173.527212 -211.287868)
				)
				(xy 173.527212 -211.406994)
				(arc
					(start 173.706536 -211.406994)
					(mid 174.217076 -210.896454)
					(end 173.706536 -210.385914)
				)
			)
		)
	)
	(zone
		(net "GND")
		(layer "F.Cu")
		(hatch none 0.5)
		(connect_pads
			(clearance 0.5)
		)
		(min_thickness 0.25)
		(fill yes
			(thermal_gap 0.5)
			(thermal_bridge_width 0.5)
			(island_removal_mode 0)
		)
		(polygon
			(pts
				(xy 346.8878 -50.6222) (xy 346.71 -50.8) (xy 346.71 -63.754) (xy 346.964 -64.008) (xy 349.758 -64.008)
				(xy 350.139 -63.627) (xy 350.139 -51.435) (xy 349.631 -50.927) (xy 348.869 -50.927) (xy 348.5642 -50.6222)
			)
		)
	)
	(zone
		(layer "F.Cu")
		(hatch none 0.5)
		(connect_pads
			(clearance 0)
		)
		(min_thickness 0.25)
		(keepout
			(tracks not_allowed)
			(vias allowed)
			(pads allowed)
			(copperpour not_allowed)
			(footprints allowed)
		)
		(placement
			(enabled no)
			(sheetname "")
		)
		(fill
			(thermal_gap 0.5)
			(thermal_bridge_width 0.5)
			(island_removal_mode 0)
		)
		(polygon
			(pts
				(xy 138.52017 -21.205444) (xy 138.516614 -21.201888)
				(arc
					(start 138.516614 -21.200872)
					(mid 138.458147 -21.129539)
					(end 138.408156 -21.052028)
				)
				(arc
					(start 138.408156 -21.052028)
					(mid 138.366469 -20.966922)
					(end 138.335004 -20.87753)
				)
				(arc
					(start 138.33475 -20.87753)
					(mid 138.313876 -20.783695)
					(end 138.30427 -20.688046)
				)
				(xy 138.303508 -20.687284) (xy 138.303508 -20.655534) (xy 138.303508 -20.653756)
				(arc
					(start 138.303508 -20.502372)
					(mid 138.384534 -19.74893)
					(end 138.46556 -20.502372)
				)
				(arc
					(start 138.46556 -20.65528)
					(mid 138.471946 -20.744929)
					(end 138.490706 -20.832826)
				)
				(arc
					(start 138.490706 -20.832826)
					(mid 138.515949 -20.904272)
					(end 138.54938 -20.972272)
				)
				(arc
					(start 138.54938 -20.972272)
					(mid 138.574459 -21.013)
					(end 138.602466 -21.051774)
				)
				(xy 138.937492 -20.426172)
				(arc
					(start 138.93546 -20.424902)
					(mid 138.679428 -19.579082)
					(end 137.833608 -19.835114)
				)
				(xy 137.831576 -19.833844) (xy 137.081514 -21.233638) (xy 137.081768 -21.233892)
				(arc
					(start 137.0838 -21.234908)
					(mid 137.339476 -22.080809)
					(end 138.185398 -21.82495)
				)
				(xy 138.18743 -21.82622) (xy 138.369548 -21.486114) (xy 138.32459 -21.44141) (xy 138.323828 -21.440394)
				(xy 138.300968 -21.417534)
				(arc
					(start 138.300968 -21.416772)
					(mid 138.218756 -21.31893)
					(end 138.148314 -21.212302)
				)
				(arc
					(start 138.041126 -21.105114)
					(mid 137.934446 -21.060926)
					(end 137.827766 -21.105114)
				)
				(arc
					(start 137.795508 -21.137372)
					(mid 137.779901 -21.154265)
					(end 137.76579 -21.172424)
				)
				(arc
					(start 137.76579 -21.172424)
					(mid 137.588413 -21.90836)
					(end 137.5918 -21.151342)
				)
				(arc
					(start 137.5918 -21.151342)
					(mid 137.620822 -21.097612)
					(end 137.657078 -21.048472)
				)
				(xy 137.657078 -21.04644) (xy 137.736834 -20.966684)
				(arc
					(start 137.739628 -20.966684)
					(mid 137.934446 -20.898692)
					(end 138.129264 -20.966684)
				)
				(xy 138.132058 -20.966684) (xy 138.294364 -21.12899)
				(arc
					(start 138.294364 -21.140674)
					(mid 138.360634 -21.237722)
					(end 138.438382 -21.32584)
				)
				(xy 138.449558 -21.337016)
			)
		)
	)
	(zone
		(net "P5V_STBY_LX")
		(layer "F.Cu")
		(hatch none 0.5)
		(connect_pads
			(clearance 0.5)
		)
		(min_thickness 0.25)
		(fill yes
			(thermal_gap 0.5)
			(thermal_bridge_width 0.5)
			(island_removal_mode 0)
		)
		(polygon
			(pts
				(xy 34.2646 -70.231) (xy 34.0614 -70.4342) (xy 34.0614 -71.8058) (xy 33.5534 -72.3138) (xy 32.512 -72.3138)
				(xy 32.4358 -72.39) (xy 32.4358 -73.5838) (xy 32.5628 -73.7108) (xy 33.2486 -73.7108) (xy 33.7058 -74.168)
				(xy 33.7058 -75.4888) (xy 33.909 -75.692) (xy 36.5252 -75.692) (xy 37.0586 -75.1586) (xy 37.0586 -70.358)
				(xy 36.9316 -70.231)
			)
		)
	)
	(zone
		(layer "F.Cu")
		(hatch none 0.5)
		(connect_pads
			(clearance 0)
		)
		(min_thickness 0.25)
		(keepout
			(tracks not_allowed)
			(vias allowed)
			(pads allowed)
			(copperpour not_allowed)
			(footprints allowed)
		)
		(placement
			(enabled no)
			(sheetname "")
		)
		(fill
			(thermal_gap 0.5)
			(thermal_bridge_width 0.5)
			(island_removal_mode 0)
		)
		(polygon
			(pts
				(arc
					(start 101.293676 -210.385914)
					(mid 100.783136 -210.896454)
					(end 101.293676 -211.406994)
				)
				(xy 101.4603 -211.406994)
				(arc
					(start 101.4603 -211.294218)
					(mid 101.447881 -211.211284)
					(end 101.411532 -211.135722)
				)
				(arc
					(start 101.411532 -211.135722)
					(mid 101.107736 -210.705401)
					(end 101.52888 -211.02193)
				)
				(arc
					(start 101.52888 -211.02193)
					(mid 101.592389 -211.133785)
					(end 101.621082 -211.259166)
				)
				(xy 101.622352 -211.26069) (xy 101.622352 -211.406994) (xy 101.7651 -211.406994) (xy 101.7651 -211.26069)
				(arc
					(start 101.765608 -211.259928)
					(mid 101.791702 -211.141512)
					(end 101.853492 -211.03717)
				)
				(xy 101.853492 -211.034884)
				(arc
					(start 101.869494 -211.018882)
					(mid 102.294435 -210.707343)
					(end 101.984302 -211.133436)
				)
				(arc
					(start 101.984302 -211.133436)
					(mid 101.941992 -211.202168)
					(end 101.927152 -211.281518)
				)
				(xy 101.927152 -211.294472) (xy 101.927152 -211.406994)
				(arc
					(start 102.106222 -211.406994)
					(mid 102.617016 -210.896581)
					(end 102.106476 -210.385914)
				)
			)
		)
	)
	(zone
		(net "P12V")
		(layer "F.Cu")
		(hatch none 0.5)
		(connect_pads
			(clearance 0.5)
		)
		(min_thickness 0.25)
		(fill yes
			(thermal_gap 0.5)
			(thermal_bridge_width 0.5)
			(island_removal_mode 0)
		)
		(polygon
			(pts
				(xy 31.623 -69.2912) (xy 31.2928 -69.6214) (xy 31.2928 -71.7296) (xy 31.4452 -71.882) (xy 31.4452 -73.5584)
				(xy 31.496 -73.6092) (xy 32.0802 -73.6092) (xy 32.131 -73.5584) (xy 32.131 -71.882) (xy 32.2707 -71.7423)
				(xy 33.6169 -71.7423) (xy 33.7566 -71.6026) (xy 33.7566 -69.5071) (xy 33.5407 -69.2912)
			)
		)
	)
	(zone
		(net "P1V26_PWR")
		(layer "F.Cu")
		(hatch none 0.5)
		(connect_pads
			(clearance 0.5)
		)
		(min_thickness 0.25)
		(fill yes
			(thermal_gap 0.5)
			(thermal_bridge_width 0.5)
			(island_removal_mode 0)
		)
		(polygon
			(pts
				(xy 16.383 -107.442) (xy 15.24 -108.585) (xy 13.462 -108.585) (xy 13.335 -108.712) (xy 13.335 -113.0554)
				(xy 13.4366 -113.157) (xy 17.272 -113.157) (xy 17.399 -113.03) (xy 17.399 -108.712) (xy 17.78 -108.331)
				(xy 17.78 -107.569) (xy 17.653 -107.442)
			)
		)
		(polygon
			(pts
				(xy 17.1958 -107.9754) (xy 16.9926 -107.9754) (xy 16.9926 -108.1786) (xy 17.1958 -108.1786)
			)
		)
		(polygon
			(pts
				(xy 16.764 -107.9246) (xy 16.5608 -107.9246) (xy 16.5608 -108.1278) (xy 16.764 -108.1278)
			)
		)
	)
	(zone
		(net "GND")
		(layer "F.Cu")
		(hatch none 0.5)
		(connect_pads
			(clearance 0.5)
		)
		(min_thickness 0.25)
		(fill yes
			(thermal_gap 0.5)
			(thermal_bridge_width 0.5)
			(island_removal_mode 0)
		)
		(polygon
			(pts
				(xy 33.7312 -208.9658) (xy 33.528 -209.169) (xy 33.528 -212.471) (xy 34.671 -213.614) (xy 34.671 -223.266)
				(xy 34.036 -223.901) (xy 34.036 -224.0534) (xy 38.3286 -224.0534) (xy 38.354 -224.028) (xy 38.354 -209.1944)
				(xy 38.1254 -208.9658)
			)
		)
		(polygon
			(pts
				(xy 34.3408 -212.4202) (xy 34.1376 -212.4202) (xy 34.1376 -212.6234) (xy 34.3408 -212.6234)
			)
		)
		(polygon
			(pts
				(xy 34.3408 -211.5566) (xy 34.1376 -211.5566) (xy 34.1376 -211.7598) (xy 34.3408 -211.7598)
			)
		)
	)
	(zone
		(layer "F.Cu")
		(hatch none 0.5)
		(connect_pads
			(clearance 0)
		)
		(min_thickness 0.25)
		(keepout
			(tracks not_allowed)
			(vias allowed)
			(pads allowed)
			(copperpour not_allowed)
			(footprints allowed)
		)
		(placement
			(enabled no)
			(sheetname "")
		)
		(fill
			(thermal_gap 0.5)
			(thermal_bridge_width 0.5)
			(island_removal_mode 0)
		)
		(polygon
			(pts
				(arc
					(start 323.612764 -34.458402)
					(mid 323.10197 -34.968815)
					(end 323.61251 -35.479482)
				)
				(arc
					(start 324.42531 -35.479482)
					(mid 324.93585 -34.968942)
					(end 324.42531 -34.458402)
				)
				(xy 324.265036 -34.458402)
				(arc
					(start 324.265036 -34.536888)
					(mid 324.277923 -34.634689)
					(end 324.315582 -34.725864)
				)
				(arc
					(start 324.315582 -34.725864)
					(mid 324.604807 -35.166193)
					(end 324.193662 -34.836862)
				)
				(arc
					(start 324.193662 -34.836862)
					(mid 324.131396 -34.710168)
					(end 324.104 -34.571686)
				)
				(xy 324.102984 -34.570416) (xy 324.102984 -34.458402) (xy 323.960236 -34.458402) (xy 323.960236 -34.570416)
				(arc
					(start 323.958966 -34.571686)
					(mid 323.925356 -34.71702)
					(end 323.84873 -34.84499)
				)
				(arc
					(start 323.84873 -34.84499)
					(mid 323.425491 -35.159174)
					(end 323.732398 -34.73069)
				)
				(arc
					(start 323.732398 -34.73069)
					(mid 323.781263 -34.639343)
					(end 323.798184 -34.537142)
				)
				(xy 323.798184 -34.458402)
			)
		)
	)
	(zone
		(layer "F.Cu")
		(hatch none 0.5)
		(connect_pads
			(clearance 0)
		)
		(min_thickness 0.25)
		(keepout
			(tracks not_allowed)
			(vias allowed)
			(pads allowed)
			(copperpour not_allowed)
			(footprints allowed)
		)
		(placement
			(enabled no)
			(sheetname "")
		)
		(fill
			(thermal_gap 0.5)
			(thermal_bridge_width 0.5)
			(island_removal_mode 0)
		)
		(polygon
			(pts
				(arc
					(start 79.69377 -210.385914)
					(mid 79.182976 -210.896327)
					(end 79.693516 -211.406994)
				)
				(xy 79.86014 -211.406994)
				(arc
					(start 79.86014 -211.2518)
					(mid 79.848535 -211.188683)
					(end 79.815436 -211.13369)
				)
				(arc
					(start 79.815436 -211.13369)
					(mid 79.50511 -210.707646)
					(end 79.930498 -211.018882)
				)
				(xy 79.945992 -211.034376)
				(arc
					(start 79.945992 -211.036916)
					(mid 79.99627 -211.121289)
					(end 80.020414 -211.216494)
				)
				(xy 80.022192 -211.218272) (xy 80.022192 -211.406994) (xy 80.16494 -211.406994) (xy 80.16494 -211.229956)
				(arc
					(start 80.166718 -211.228178)
					(mid 80.190635 -211.133926)
					(end 80.240378 -211.050378)
				)
				(xy 80.240378 -211.047838) (xy 80.264 -211.023962)
				(arc
					(start 80.269334 -211.018882)
					(mid 80.694928 -210.707842)
					(end 80.383888 -211.133436)
				)
				(arc
					(start 80.378808 -211.13877)
					(mid 80.340492 -211.195974)
					(end 80.326992 -211.263484)
				)
				(xy 80.326992 -211.406994)
				(arc
					(start 80.506316 -211.406994)
					(mid 81.016856 -210.896454)
					(end 80.506316 -210.385914)
				)
			)
		)
	)
	(zone
		(layer "F.Cu")
		(hatch none 0.5)
		(connect_pads
			(clearance 0)
		)
		(min_thickness 0.25)
		(keepout
			(tracks allowed)
			(vias allowed)
			(pads allowed)
			(copperpour allowed)
			(footprints allowed)
		)
		(placement
			(enabled no)
			(sheetname "")
		)
		(fill
			(thermal_gap 0.5)
			(thermal_bridge_width 0.5)
			(island_removal_mode 0)
		)
		(polygon
			(pts
				(xy 224.972372 -1.803146) (xy 226.62642 -1.803146) (xy 226.662742 -1.766824) (xy 226.662742 -0.510032)
				(xy 226.662742 -0.02921) (xy 226.550982 0.08255) (xy 225.015806 0.08255) (xy 224.910904 -0.022352)
				(xy 224.910904 -0.517144) (xy 224.925382 -0.531622) (xy 224.925382 -1.756156)
			)
		)
	)
	(zone
		(layer "F.Cu")
		(hatch none 0.5)
		(connect_pads
			(clearance 0)
		)
		(min_thickness 0.25)
		(keepout
			(tracks allowed)
			(vias allowed)
			(pads allowed)
			(copperpour allowed)
			(footprints not_allowed)
		)
		(placement
			(enabled no)
			(sheetname "")
		)
		(fill
			(thermal_gap 0.5)
			(thermal_bridge_width 0.5)
			(island_removal_mode 0)
		)
		(polygon
			(pts
				(arc
					(start 0 -28.010104)
					(mid 0.585785 -26.595893)
					(end 1.999996 -26.010108)
				)
				(arc
					(start 49.950116 -26.010108)
					(mid 51.364327 -25.424323)
					(end 51.950112 -24.010112)
				)
				(arc
					(start 51.950112 -1.999996)
					(mid 52.535897 -0.585785)
					(end 53.950108 0)
				)
				(xy 67.449954 0) (xy 67.449954 -29.99994) (xy 86.559898 -29.99994) (xy 86.559898 -34.239962) (xy 90.950034 -34.239962)
				(xy 90.950034 -77.0001) (xy 89.562178 -77.0001) (xy 89.562178 -49.9999) (xy 25.472136 -49.9999)
				(xy 25.472136 -51.999896) (xy 8.772144 -51.999896) (xy 8.772144 -76.499974) (xy 0 -76.499974)
			)
		)
	)
	(zone
		(net "GND")
		(layer "F.Cu")
		(hatch none 0.5)
		(connect_pads
			(clearance 0.5)
		)
		(min_thickness 0.25)
		(fill yes
			(thermal_gap 0.5)
			(thermal_bridge_width 0.5)
			(island_removal_mode 0)
		)
		(polygon
			(pts
				(xy 174.244 -86.36) (xy 170.434 -90.17) (xy 170.434 -99.822) (xy 170.688 -100.076) (xy 177.038 -100.076)
				(xy 182.753 -94.361) (xy 229.362 -94.361) (xy 229.489 -94.234) (xy 229.489 -93.472) (xy 229.108 -93.091)
				(xy 228.473 -93.091) (xy 225.806 -90.424) (xy 225.806 -87.757) (xy 224.409 -86.36)
			)
		)
	)
	(zone
		(layer "F.Cu")
		(hatch none 0.5)
		(connect_pads
			(clearance 0)
		)
		(min_thickness 0.25)
		(keepout
			(tracks not_allowed)
			(vias allowed)
			(pads allowed)
			(copperpour not_allowed)
			(footprints allowed)
		)
		(placement
			(enabled no)
			(sheetname "")
		)
		(fill
			(thermal_gap 0.5)
			(thermal_bridge_width 0.5)
			(island_removal_mode 0)
		)
		(polygon
			(pts
				(arc
					(start 161.277554 -34.51098)
					(mid 160.76676 -35.021393)
					(end 161.2773 -35.53206)
				)
				(arc
					(start 162.0901 -35.53206)
					(mid 162.60064 -35.02152)
					(end 162.0901 -34.51098)
				)
				(xy 161.884106 -34.51098)
				(arc
					(start 161.884106 -34.60496)
					(mid 161.898623 -34.706801)
					(end 161.941002 -34.80054)
				)
				(arc
					(start 161.941002 -34.80054)
					(mid 162.301188 -35.184357)
					(end 161.837878 -34.934652)
				)
				(arc
					(start 161.837878 -34.934652)
					(mid 161.757947 -34.796005)
					(end 161.723324 -34.639758)
				)
				(xy 161.722054 -34.638488) (xy 161.722054 -34.51098) (xy 161.579306 -34.51098) (xy 161.579306 -34.638488)
				(arc
					(start 161.57829 -34.639504)
					(mid 161.556454 -34.76678)
					(end 161.50717 -34.886138)
				)
				(arc
					(start 161.50717 -34.886138)
					(mid 161.101525 -35.222198)
					(end 161.381186 -34.775902)
				)
				(arc
					(start 161.381186 -34.775902)
					(mid 161.40815 -34.692316)
					(end 161.417254 -34.60496)
				)
				(xy 161.417254 -34.51098)
			)
		)
	)
	(zone
		(layer "F.Cu")
		(hatch none 0.5)
		(connect_pads
			(clearance 0)
		)
		(min_thickness 0.25)
		(keepout
			(tracks not_allowed)
			(vias allowed)
			(pads allowed)
			(copperpour not_allowed)
			(footprints allowed)
		)
		(placement
			(enabled no)
			(sheetname "")
		)
		(fill
			(thermal_gap 0.5)
			(thermal_bridge_width 0.5)
			(island_removal_mode 0)
		)
		(polygon
			(pts
				(arc
					(start 134.017004 -25.010872)
					(mid 133.936123 -24.910313)
					(end 133.872986 -24.797766)
				)
				(arc
					(start 133.872986 -24.797512)
					(mid 133.850586 -24.743161)
					(end 133.832346 -24.687276)
				)
				(xy 133.832346 -24.686768)
				(arc
					(start 133.825742 -24.661876)
					(mid 133.811015 -24.585965)
					(end 133.803898 -24.508968)
				)
				(xy 133.803136 -24.508206) (xy 133.803136 -24.476202) (xy 133.803136 -24.474678)
				(arc
					(start 133.803136 -24.302212)
					(mid 133.885193 -23.549165)
					(end 133.965188 -24.302466)
				)
				(arc
					(start 133.965188 -24.475948)
					(mid 133.969759 -24.550152)
					(end 133.983222 -24.623268)
				)
				(xy 133.983222 -24.623522)
				(arc
					(start 133.988302 -24.643334)
					(mid 134.002666 -24.687497)
					(end 134.020306 -24.730456)
				)
				(arc
					(start 134.020306 -24.730456)
					(mid 134.055662 -24.796724)
					(end 134.098792 -24.858218)
				)
				(xy 134.437374 -24.226266)
				(arc
					(start 134.435342 -24.224996)
					(mid 134.17931 -23.379176)
					(end 133.33349 -23.635208)
				)
				(xy 133.331458 -23.633938) (xy 132.581396 -25.033732) (xy 132.58165 -25.033986)
				(arc
					(start 132.583682 -25.035002)
					(mid 132.839358 -25.880903)
					(end 133.68528 -25.625044)
				)
				(xy 133.687312 -25.626314) (xy 133.843268 -25.33523) (xy 133.84276 -25.333198) (xy 133.831584 -25.310592)
				(xy 133.834124 -25.302718)
				(arc
					(start 133.824472 -25.27681)
					(mid 133.809546 -25.245918)
					(end 133.791706 -25.216612)
				)
				(arc
					(start 133.791706 -25.216612)
					(mid 133.706746 -25.114117)
					(end 133.634988 -25.001982)
				)
				(arc
					(start 133.590792 -24.957532)
					(mid 133.572363 -24.940426)
					(end 133.552692 -24.924766)
				)
				(arc
					(start 133.533642 -24.911812)
					(mid 133.453133 -24.874916)
					(end 133.365748 -24.860504)
				)
				(arc
					(start 133.365748 -24.860504)
					(mid 133.292553 -24.89977)
					(end 133.240018 -24.964136)
				)
				(arc
					(start 133.240018 -24.964136)
					(mid 133.113374 -25.710533)
					(end 133.069584 -24.954738)
				)
				(arc
					(start 133.069584 -24.954738)
					(mid 133.169137 -24.792749)
					(end 133.335522 -24.700738)
				)
				(arc
					(start 133.335522 -24.700738)
					(mid 133.34535 -24.698863)
					(end 133.355334 -24.698198)
				)
				(arc
					(start 133.356096 -24.698198)
					(mid 133.493446 -24.71778)
					(end 133.620002 -24.774652)
				)
				(xy 133.648704 -24.79421) (xy 133.6802 -24.819356) (xy 133.681978 -24.819356) (xy 133.781546 -24.919686)
				(xy 133.781546 -24.924766)
				(arc
					(start 133.781546 -24.932132)
					(mid 133.842236 -25.024885)
					(end 133.913626 -25.109678)
				)
				(xy 133.921246 -25.119076) (xy 133.942074 -25.15108)
			)
		)
	)
	(zone
		(layer "F.Cu")
		(hatch none 0.5)
		(connect_pads
			(clearance 0)
		)
		(min_thickness 0.25)
		(keepout
			(tracks not_allowed)
			(vias allowed)
			(pads allowed)
			(copperpour not_allowed)
			(footprints allowed)
		)
		(placement
			(enabled no)
			(sheetname "")
		)
		(fill
			(thermal_gap 0.5)
			(thermal_bridge_width 0.5)
			(island_removal_mode 0)
		)
		(polygon
			(pts
				(arc
					(start 349.600012 -203.499974)
					(mid 345.60002 -207.499966)
					(end 341.600028 -203.499974)
				)
				(arc
					(start 341.600028 -203.499974)
					(mid 345.60002 -199.499982)
					(end 349.600012 -203.499974)
				)
			)
		)
	)
	(zone
		(net "DUT_VDDO")
		(layer "F.Cu")
		(hatch none 0.5)
		(connect_pads
			(clearance 0.5)
		)
		(min_thickness 0.25)
		(fill yes
			(thermal_gap 0.5)
			(thermal_bridge_width 0.5)
			(island_removal_mode 0)
		)
		(polygon
			(pts
				(xy 242.57 -9.398) (xy 242.316 -9.652) (xy 242.316 -12.954) (xy 242.443 -13.081) (xy 250.724416 -13.081)
				(xy 250.944634 -12.860782) (xy 250.944634 -10.103612) (xy 250.715272 -9.87425) (xy 249.915934 -9.87425)
				(xy 249.601736 -9.560052) (xy 249.601736 -9.47039) (xy 249.529346 -9.398)
			)
		)
	)
	(zone
		(layer "F.Cu")
		(hatch none 0.5)
		(connect_pads
			(clearance 0)
		)
		(min_thickness 0.25)
		(keepout
			(tracks allowed)
			(vias allowed)
			(pads allowed)
			(copperpour allowed)
			(footprints not_allowed)
		)
		(placement
			(enabled no)
			(sheetname "")
		)
		(fill
			(thermal_gap 0.5)
			(thermal_bridge_width 0.5)
			(island_removal_mode 0)
		)
		(polygon
			(pts
				(xy 90.950034 -80.000094) (xy 90.950034 -77.0001) (xy 55.950104 -77.0001) (xy 55.950104 -80.000094)
			)
		)
	)
	(zone
		(net "GND")
		(layer "F.Cu")
		(hatch none 0.5)
		(connect_pads
			(clearance 0.5)
		)
		(min_thickness 0.25)
		(fill yes
			(thermal_gap 0.5)
			(thermal_bridge_width 0.5)
			(island_removal_mode 0)
		)
		(polygon
			(pts
				(xy 65.913 -152.9588) (xy 65.8114 -153.0604) (xy 65.8114 -158.7246) (xy 65.024 -159.512) (xy 65.024 -162.179)
				(xy 64.77 -162.433) (xy 63.881 -162.433) (xy 63.246 -163.068) (xy 63.246 -164.338) (xy 63.627 -164.719)
				(xy 67.056 -164.719) (xy 67.183 -164.592) (xy 67.183 -163.449) (xy 66.802 -163.068) (xy 66.802 -159.258)
				(xy 67.564 -158.496) (xy 70.866 -158.496) (xy 70.993 -158.369) (xy 70.993 -153.289) (xy 70.6628 -152.9588)
			)
		)
		(polygon
			(pts
				(xy 66.7258 -164.0332) (xy 66.5226 -164.0332) (xy 66.5226 -164.2364) (xy 66.7258 -164.2364)
			)
		)
	)
	(zone
		(layer "F.Cu")
		(hatch none 0.5)
		(connect_pads
			(clearance 0)
		)
		(min_thickness 0.25)
		(keepout
			(tracks not_allowed)
			(vias allowed)
			(pads allowed)
			(copperpour not_allowed)
			(footprints allowed)
		)
		(placement
			(enabled no)
			(sheetname "")
		)
		(fill
			(thermal_gap 0.5)
			(thermal_bridge_width 0.5)
			(island_removal_mode 0)
		)
		(polygon
			(pts
				(arc
					(start 162.6997 -81.15046)
					(mid 162.18916 -81.661)
					(end 162.6997 -82.17154)
				)
				(xy 162.885374 -82.17154)
				(arc
					(start 162.885374 -82.117946)
					(mid 162.867823 -82.003954)
					(end 162.816794 -81.900522)
				)
				(arc
					(start 162.816794 -81.900522)
					(mid 162.514788 -81.468363)
					(end 162.93465 -81.787238)
				)
				(arc
					(start 162.93465 -81.787238)
					(mid 163.01261 -81.92685)
					(end 163.04641 -82.083148)
				)
				(xy 163.047426 -82.084418) (xy 163.047426 -82.17154) (xy 163.190174 -82.17154) (xy 163.190174 -82.084672)
				(arc
					(start 163.19119 -82.083656)
					(mid 163.218926 -81.934422)
					(end 163.283138 -81.79689)
				)
				(arc
					(start 163.283138 -81.79689)
					(mid 163.688622 -81.460865)
					(end 163.406836 -81.905856)
				)
				(arc
					(start 163.406836 -81.905856)
					(mid 163.366101 -82.008574)
					(end 163.352226 -82.1182)
				)
				(xy 163.352226 -82.17154)
				(arc
					(start 163.512246 -82.17154)
					(mid 164.02304 -81.661127)
					(end 163.5125 -81.15046)
				)
			)
		)
	)
	(zone
		(layer "F.Cu")
		(hatch none 0.5)
		(connect_pads
			(clearance 0)
		)
		(min_thickness 0.25)
		(keepout
			(tracks not_allowed)
			(vias allowed)
			(pads allowed)
			(copperpour not_allowed)
			(footprints allowed)
		)
		(placement
			(enabled no)
			(sheetname "")
		)
		(fill
			(thermal_gap 0.5)
			(thermal_bridge_width 0.5)
			(island_removal_mode 0)
		)
		(polygon
			(pts
				(arc
					(start 15.799054 -72.706484)
					(mid 15.28826 -73.216897)
					(end 15.7988 -73.727564)
				)
				(arc
					(start 16.6116 -73.727564)
					(mid 17.12214 -73.217024)
					(end 16.6116 -72.706484)
				)
				(xy 16.536416 -72.706484) (xy 16.44142 -72.801226) (xy 16.44142 -72.954896)
				(arc
					(start 16.474694 -72.98817)
					(mid 16.80017 -73.405594)
					(end 16.382746 -73.080118)
				)
				(xy 16.311372 -73.008744) (xy 16.311372 -72.747378) (xy 16.352012 -72.706484) (xy 16.09852 -72.706484)
				(xy 16.09852 -73.009252)
				(arc
					(start 16.027654 -73.080118)
					(mid 15.61023 -73.405594)
					(end 15.935706 -72.98817)
				)
				(xy 15.968472 -72.955404) (xy 15.968472 -72.706484)
			)
		)
	)
	(zone
		(layer "F.Cu")
		(hatch none 0.5)
		(connect_pads
			(clearance 0)
		)
		(min_thickness 0.25)
		(keepout
			(tracks not_allowed)
			(vias allowed)
			(pads allowed)
			(copperpour not_allowed)
			(footprints allowed)
		)
		(placement
			(enabled no)
			(sheetname "")
		)
		(fill
			(thermal_gap 0.5)
			(thermal_bridge_width 0.5)
			(island_removal_mode 0)
		)
		(polygon
			(pts
				(arc
					(start 161.7853 -37.50056)
					(mid 161.27476 -38.0111)
					(end 161.7853 -38.52164)
				)
				(arc
					(start 162.597846 -38.52164)
					(mid 163.10864 -38.011227)
					(end 162.5981 -37.50056)
				)
				(arc
					(start 162.470084 -37.50056)
					(mid 162.496415 -37.628092)
					(end 162.539426 -37.751004)
				)
				(arc
					(start 162.539426 -37.751004)
					(mid 162.733124 -38.241343)
					(end 162.39871 -37.833808)
				)
				(arc
					(start 162.39871 -37.833808)
					(mid 162.339945 -37.670689)
					(end 162.306508 -37.50056)
				)
				(arc
					(start 162.146234 -37.50056)
					(mid 162.097883 -37.69182)
					(end 162.010852 -37.86886)
				)
				(arc
					(start 162.010852 -37.86886)
					(mid 161.6138 -38.215353)
					(end 161.885122 -37.763704)
				)
				(arc
					(start 161.885122 -37.763704)
					(mid 161.945494 -37.636507)
					(end 161.98215 -37.50056)
				)
			)
		)
	)
	(zone
		(layer "F.Cu")
		(hatch none 0.5)
		(connect_pads
			(clearance 0)
		)
		(min_thickness 0.25)
		(keepout
			(tracks allowed)
			(vias allowed)
			(pads allowed)
			(copperpour allowed)
			(footprints allowed)
		)
		(placement
			(enabled no)
			(sheetname "")
		)
		(fill
			(thermal_gap 0.5)
			(thermal_bridge_width 0.5)
			(island_removal_mode 0)
		)
		(polygon
			(pts
				(xy 159.9184 -95.758) (xy 159.9184 -92.6846) (xy 163.9062 -92.6846) (xy 163.9062 -95.758)
			)
		)
	)
	(zone
		(net "NIC0_CT_POWER")
		(layer "F.Cu")
		(hatch none 0.5)
		(connect_pads
			(clearance 0.5)
		)
		(min_thickness 0.25)
		(fill yes
			(thermal_gap 0.5)
			(thermal_bridge_width 0.5)
			(island_removal_mode 0)
		)
		(polygon
			(pts
				(xy 10.6172 -40.5892) (xy 7.112 -44.0944) (xy 5.1816 -44.0944) (xy 5.1562 -44.069) (xy 4.4958 -44.069)
				(xy 4.1656 -44.3992) (xy 4.1656 -48.641) (xy 4.6736 -49.149) (xy 6.0452 -49.149) (xy 6.2992 -49.403)
				(xy 9.8552 -49.403) (xy 11.811 -47.4472) (xy 11.811 -44.4754) (xy 12.192 -44.0944) (xy 19.1516 -44.0944)
				(xy 19.4564 -44.3992) (xy 19.4564 -46.1518) (xy 21.0058 -47.7012) (xy 21.0058 -48.5394) (xy 21.336 -48.8696)
				(xy 25.908 -48.8696) (xy 25.9588 -48.8188) (xy 25.9588 -45.8724) (xy 25.8572 -45.7708) (xy 24.9682 -45.7708)
				(xy 24.6126 -45.4152) (xy 24.6126 -44.6278) (xy 20.574 -40.5892)
			)
		)
		(polygon
			(pts
				(xy 5.969 -48.4378) (xy 5.7658 -48.4378) (xy 5.7658 -48.641) (xy 5.969 -48.641)
			)
		)
		(polygon
			(pts
				(xy 5.3594 -48.4378) (xy 5.1562 -48.4378) (xy 5.1562 -48.641) (xy 5.3594 -48.641)
			)
		)
		(polygon
			(pts
				(xy 25.4254 -48.006) (xy 25.2222 -48.006) (xy 25.2222 -48.2092) (xy 25.4254 -48.2092)
			)
		)
		(polygon
			(pts
				(xy 25.4254 -46.2788) (xy 25.2222 -46.2788) (xy 25.2222 -46.482) (xy 25.4254 -46.482)
			)
		)
		(polygon
			(pts
				(xy 5.9436 -45.5168) (xy 5.7404 -45.5168) (xy 5.7404 -45.72) (xy 5.9436 -45.72)
			)
		)
		(polygon
			(pts
				(xy 5.334 -45.5168) (xy 5.1308 -45.5168) (xy 5.1308 -45.72) (xy 5.334 -45.72)
			)
		)
		(polygon
			(pts
				(xy 5.9944 -44.6024) (xy 5.7912 -44.6024) (xy 5.7912 -44.8056) (xy 5.9944 -44.8056)
			)
		)
		(polygon
			(pts
				(xy 5.3848 -44.6024) (xy 5.1816 -44.6024) (xy 5.1816 -44.8056) (xy 5.3848 -44.8056)
			)
		)
	)
	(zone
		(net "GND")
		(layer "F.Cu")
		(hatch none 0.5)
		(connect_pads
			(clearance 0.5)
		)
		(min_thickness 0.25)
		(fill yes
			(thermal_gap 0.5)
			(thermal_bridge_width 0.5)
			(island_removal_mode 0)
		)
		(polygon
			(pts
				(xy 245.999 -13.716) (xy 245.745 -13.97) (xy 245.745 -16.129) (xy 245.999 -16.383) (xy 249.301 -16.383)
				(xy 249.555 -16.129) (xy 249.912378 -15.771622) (xy 249.912378 -13.943584) (xy 249.684794 -13.716)
				(xy 249.301 -13.716)
			)
		)
	)
	(zone
		(layer "F.Cu")
		(hatch none 0.5)
		(connect_pads
			(clearance 0)
		)
		(min_thickness 0.25)
		(keepout
			(tracks not_allowed)
			(vias allowed)
			(pads allowed)
			(copperpour not_allowed)
			(footprints allowed)
		)
		(placement
			(enabled no)
			(sheetname "")
		)
		(fill
			(thermal_gap 0.5)
			(thermal_bridge_width 0.5)
			(island_removal_mode 0)
		)
		(polygon
			(pts
				(arc
					(start 302.504856 -25.033478)
					(mid 302.453692 -24.948669)
					(end 302.38954 -24.873204)
				)
				(arc
					(start 302.38954 -24.873204)
					(mid 302.33318 -24.79399)
					(end 302.30572 -24.700738)
				)
				(xy 302.303434 -24.698452)
				(arc
					(start 302.303434 -24.302466)
					(mid 302.38446 -23.549024)
					(end 302.465486 -24.302466)
				)
				(arc
					(start 302.465486 -24.664924)
					(mid 302.475642 -24.715512)
					(end 302.504348 -24.758396)
				)
				(arc
					(start 302.504348 -24.758396)
					(mid 302.551767 -24.810453)
					(end 302.594264 -24.8666)
				)
				(xy 302.937418 -24.226266)
				(arc
					(start 302.935386 -24.224996)
					(mid 302.679354 -23.379176)
					(end 301.833534 -23.635208)
				)
				(xy 301.831502 -23.633938) (xy 301.08144 -25.033732) (xy 301.081694 -25.033986)
				(arc
					(start 301.083726 -25.035002)
					(mid 301.339402 -25.880903)
					(end 302.185324 -25.625044)
				)
				(xy 302.187356 -25.626314) (xy 302.264318 -25.48255)
				(arc
					(start 302.264318 -25.306782)
					(mid 302.240763 -25.188833)
					(end 302.173894 -25.08885)
				)
				(arc
					(start 301.994316 -24.909018)
					(mid 301.937122 -24.871732)
					(end 301.87011 -24.858726)
				)
				(arc
					(start 301.820326 -24.858726)
					(mid 301.784998 -24.865847)
					(end 301.755048 -24.885904)
				)
				(arc
					(start 301.755048 -24.885904)
					(mid 301.730626 -24.919181)
					(end 301.717456 -24.958294)
				)
				(arc
					(start 301.717456 -24.958294)
					(mid 301.632849 -25.711222)
					(end 301.553372 -24.957786)
				)
				(xy 301.553372 -24.947626)
				(arc
					(start 301.555404 -24.94534)
					(mid 301.583216 -24.851107)
					(end 301.64024 -24.771096)
				)
				(arc
					(start 301.64024 -24.771096)
					(mid 301.706417 -24.72347)
					(end 301.784258 -24.699214)
				)
				(xy 301.786798 -24.696674) (xy 301.903638 -24.696674)
				(arc
					(start 301.905416 -24.698452)
					(mid 302.000346 -24.722514)
					(end 302.084486 -24.77262)
				)
				(xy 302.087026 -24.77262) (xy 302.108362 -24.793956) (xy 302.110902 -24.796496) (xy 302.312324 -24.997918)
				(arc
					(start 302.312324 -24.999696)
					(mid 302.375896 -25.094651)
					(end 302.414686 -25.202134)
				)
			)
		)
	)
	(zone
		(net "DUT_AVD_PCIE")
		(layer "F.Cu")
		(hatch none 0.5)
		(connect_pads
			(clearance 0.5)
		)
		(min_thickness 0.25)
		(fill yes
			(thermal_gap 0.5)
			(thermal_bridge_width 0.5)
			(island_removal_mode 0)
		)
		(polygon
			(pts
				(xy 252.1712 -33.274) (xy 251.968 -33.4772) (xy 251.968 -40.5384) (xy 252.5014 -41.0718) (xy 252.73 -41.0718)
				(xy 253.3396 -40.4622) (xy 253.3396 -34.5948) (xy 254.3302 -33.6042) (xy 254.3302 -33.3756) (xy 254.2286 -33.274)
			)
		)
	)
	(zone
		(layer "F.Cu")
		(hatch none 0.5)
		(connect_pads
			(clearance 0)
		)
		(min_thickness 0.25)
		(keepout
			(tracks not_allowed)
			(vias allowed)
			(pads allowed)
			(copperpour not_allowed)
			(footprints allowed)
		)
		(placement
			(enabled no)
			(sheetname "")
		)
		(fill
			(thermal_gap 0.5)
			(thermal_bridge_width 0.5)
			(island_removal_mode 0)
		)
		(polygon
			(pts
				(arc
					(start 137.5664 -34.482786)
					(mid 137.05586 -34.993326)
					(end 137.5664 -35.503866)
				)
				(arc
					(start 138.378946 -35.503866)
					(mid 138.88974 -34.993453)
					(end 138.3792 -34.482786)
				)
				(xy 138.206226 -34.482786)
				(arc
					(start 138.206226 -34.682176)
					(mid 138.21101 -34.729754)
					(end 138.225276 -34.775394)
				)
				(arc
					(start 138.225276 -34.775394)
					(mid 138.597149 -35.147226)
					(end 138.122914 -34.91992)
				)
				(arc
					(start 138.122914 -34.91992)
					(mid 138.070224 -34.823934)
					(end 138.045698 -34.717228)
				)
				(xy 138.044174 -34.715704) (xy 138.044174 -34.482786) (xy 137.901426 -34.482786) (xy 137.901426 -34.772854)
				(arc
					(start 137.899648 -34.774886)
					(mid 137.876555 -34.866117)
					(end 137.829036 -34.947352)
				)
				(arc
					(start 137.829036 -34.947352)
					(mid 137.336892 -35.129036)
					(end 137.733278 -34.7853)
				)
				(arc
					(start 137.733278 -34.7853)
					(mid 137.737867 -34.762518)
					(end 137.739374 -34.739326)
				)
				(xy 137.739374 -34.482786)
			)
		)
	)
	(zone
		(layer "F.Cu")
		(hatch none 0.5)
		(connect_pads
			(clearance 0)
		)
		(min_thickness 0.25)
		(keepout
			(tracks not_allowed)
			(vias allowed)
			(pads allowed)
			(copperpour not_allowed)
			(footprints allowed)
		)
		(placement
			(enabled no)
			(sheetname "")
		)
		(fill
			(thermal_gap 0.5)
			(thermal_bridge_width 0.5)
			(island_removal_mode 0)
		)
		(polygon
			(pts
				(xy 149.51329 -25.017984)
				(arc
					(start 149.476714 -24.979122)
					(mid 149.375606 -24.844083)
					(end 149.316694 -24.686006)
				)
				(xy 149.31644 -24.684736) (xy 149.314662 -24.676862)
				(arc
					(start 149.313646 -24.67102)
					(mid 149.307854 -24.633194)
					(end 149.304502 -24.595074)
				)
				(xy 149.303486 -24.594058) (xy 149.303486 -24.563324) (xy 149.303486 -24.56053)
				(arc
					(start 149.303486 -24.302466)
					(mid 149.384512 -23.549024)
					(end 149.465538 -24.302466)
				)
				(arc
					(start 149.465538 -24.56307)
					(mid 149.467407 -24.60261)
					(end 149.472904 -24.64181)
				)
				(xy 149.473412 -24.643334) (xy 149.473412 -24.64435)
				(arc
					(start 149.474682 -24.64943)
					(mid 149.517403 -24.765314)
					(end 149.591268 -24.864314)
				)
				(xy 149.591522 -24.864568) (xy 149.594062 -24.867108) (xy 149.93747 -24.226266)
				(arc
					(start 149.935438 -24.224996)
					(mid 149.679406 -23.379176)
					(end 148.833586 -23.635208)
				)
				(xy 148.831554 -23.633938) (xy 148.081492 -25.033732) (xy 148.081746 -25.033986)
				(arc
					(start 148.083778 -25.035002)
					(mid 148.339454 -25.880903)
					(end 149.185376 -25.625044)
				)
				(xy 149.187408 -25.626314)
				(arc
					(start 149.35327 -25.316688)
					(mid 149.311402 -25.252526)
					(end 149.261068 -25.194768)
				)
				(arc
					(start 148.96465 -24.898096)
					(mid 148.920935 -24.868949)
					(end 148.8694 -24.858726)
				)
				(arc
					(start 148.8694 -24.858726)
					(mid 148.83819 -24.861504)
					(end 148.807932 -24.869648)
				)
				(arc
					(start 148.807932 -24.869648)
					(mid 148.772622 -24.915079)
					(end 148.745194 -24.96566)
				)
				(arc
					(start 148.745194 -24.96566)
					(mid 148.60659 -25.710165)
					(end 148.577046 -24.953468)
				)
				(arc
					(start 148.577046 -24.953468)
					(mid 148.627731 -24.841014)
					(end 148.703792 -24.743918)
				)
				(arc
					(start 148.703792 -24.743918)
					(mid 148.714875 -24.73473)
					(end 148.727414 -24.727662)
				)
				(arc
					(start 148.727414 -24.727662)
					(mid 148.796739 -24.704517)
					(end 148.8694 -24.696674)
				)
				(arc
					(start 148.8694 -24.696674)
					(mid 148.966271 -24.712935)
					(end 149.052534 -24.75992)
				)
				(xy 149.055582 -24.75992) (xy 149.079204 -24.783542) (xy 149.079458 -24.783542) (xy 149.399498 -25.103836)
				(arc
					(start 149.399498 -25.105106)
					(mid 149.420489 -25.129163)
					(end 149.440392 -25.154128)
				)
			)
		)
	)
	(zone
		(net "GND")
		(layer "F.Cu")
		(hatch none 0.5)
		(connect_pads
			(clearance 0.5)
		)
		(min_thickness 0.25)
		(fill yes
			(thermal_gap 0.5)
			(thermal_bridge_width 0.5)
			(island_removal_mode 0)
		)
		(polygon
			(pts
				(arc
					(start 235.412026 -161.967926)
					(mid 233.077159 -162.935059)
					(end 232.110026 -165.269926)
				)
				(arc
					(start 232.110026 -208.499964)
					(mid 231.240722 -210.59865)
					(end 229.142036 -211.467954)
				)
				(arc
					(start 221.600014 -211.467954)
					(mid 219.243954 -212.443866)
					(end 218.268042 -214.799926)
				)
				(arc
					(start 218.268042 -219.976192)
					(mid 217.591957 -220.295637)
					(end 217.038682 -220.798644)
				)
				(xy 217.042492 -220.802708) (xy 216.9922 -220.853) (xy 216.9922 -223.2406) (xy 217.043 -223.2914)
				(xy 217.551 -223.2914) (xy 217.736928 -223.105472)
				(arc
					(start 217.736928 -222.39986)
					(mid 218.106894 -221.506938)
					(end 218.999816 -221.136972)
				)
				(xy 219.537026 -221.136972)
				(arc
					(start 219.537026 -214.799926)
					(mid 220.141261 -213.341173)
					(end 221.600014 -212.736938)
				)
				(arc
					(start 229.142036 -212.736938)
					(mid 232.138029 -211.495957)
					(end 233.37901 -208.499964)
				)
				(arc
					(start 233.37901 -165.269926)
					(mid 233.974467 -163.832367)
					(end 235.412026 -163.23691)
				)
				(arc
					(start 249.871992 -163.23691)
					(mid 251.309551 -163.832367)
					(end 251.905008 -165.269926)
				)
				(arc
					(start 251.905008 -208.499964)
					(mid 253.145989 -211.495957)
					(end 256.141982 -212.736938)
				)
				(arc
					(start 257.400044 -212.736938)
					(mid 258.858797 -213.341173)
					(end 259.463032 -214.799926)
				)
				(xy 259.463032 -221.136972)
				(arc
					(start 260.000242 -221.136972)
					(mid 260.893164 -221.506938)
					(end 261.26313 -222.39986)
				)
				(xy 261.26313 -222.777304) (xy 262.532114 -222.777304)
				(arc
					(start 262.532114 -222.39986)
					(mid 262.032805 -220.890373)
					(end 260.732016 -219.976192)
				)
				(arc
					(start 260.732016 -214.799926)
					(mid 259.756104 -212.443866)
					(end 257.400044 -211.467954)
				)
				(arc
					(start 256.141982 -211.467954)
					(mid 254.043296 -210.59865)
					(end 253.173992 -208.499964)
				)
				(arc
					(start 253.173992 -165.269926)
					(mid 252.206859 -162.935059)
					(end 249.871992 -161.967926)
				)
			)
		)
	)
	(zone
		(layer "F.Cu")
		(hatch none 0.5)
		(connect_pads
			(clearance 0)
		)
		(min_thickness 0.25)
		(keepout
			(tracks allowed)
			(vias allowed)
			(pads allowed)
			(copperpour allowed)
			(footprints allowed)
		)
		(placement
			(enabled no)
			(sheetname "")
		)
		(fill
			(thermal_gap 0.5)
			(thermal_bridge_width 0.5)
			(island_removal_mode 0)
		)
		(polygon
			(pts
				(xy 37.95014 -99.192842) (xy 38.121082 -99.363784) (xy 40.32377 -99.363784) (xy 40.54602 -99.141534)
				(xy 40.54602 -98.061018) (xy 40.11041 -97.625408) (xy 38.007544 -97.625408) (xy 37.95014 -97.682812)
			)
		)
	)
	(zone
		(net "P1V8_STBY")
		(layer "F.Cu")
		(hatch none 0.5)
		(connect_pads
			(clearance 0.5)
		)
		(min_thickness 0.25)
		(fill yes
			(thermal_gap 0.5)
			(thermal_bridge_width 0.5)
			(island_removal_mode 0)
		)
		(polygon
			(pts
				(xy 128.924558 -62.08776) (xy 128.727708 -62.284356) (xy 128.727708 -69.33311) (xy 128.731772 -69.337428)
				(xy 128.731772 -71.562722) (xy 127.954278 -72.340216) (xy 127.954278 -74.336402) (xy 128.090676 -74.4728)
				(xy 128.8034 -74.4728) (xy 129.033524 -74.702924) (xy 129.033524 -75.360276) (xy 129.240026 -75.567032)
				(xy 130.25882 -75.567032) (xy 130.718052 -75.1078) (xy 130.718052 -73.538588) (xy 130.720846 -73.037954)
				(xy 131.2037 -72.5551) (xy 132.471922 -72.5551) (xy 132.607558 -72.419464) (xy 132.607558 -70.847204)
				(xy 132.249418 -70.489064) (xy 131.553712 -70.489064) (xy 131.305808 -70.24116) (xy 131.305808 -68.817998)
				(xy 131.287774 -68.799964) (xy 131.287774 -65.957704) (xy 131.262374 -65.932304) (xy 131.262374 -62.350904)
				(xy 130.99923 -62.08776)
			)
		)
		(polygon
			(pts
				(xy 128.797558 -73.74636) (xy 128.594358 -73.74636) (xy 128.594358 -73.94956) (xy 128.797558 -73.94956)
			)
		)
	)
	(zone
		(layer "F.Cu")
		(hatch none 0.5)
		(connect_pads
			(clearance 0)
		)
		(min_thickness 0.25)
		(keepout
			(tracks not_allowed)
			(vias allowed)
			(pads allowed)
			(copperpour not_allowed)
			(footprints allowed)
		)
		(placement
			(enabled no)
			(sheetname "")
		)
		(fill
			(thermal_gap 0.5)
			(thermal_bridge_width 0.5)
			(island_removal_mode 0)
		)
		(polygon
			(pts
				(arc
					(start 319.694052 -210.385914)
					(mid 319.183258 -210.896327)
					(end 319.693798 -211.406994)
				)
				(xy 319.860422 -211.406994)
				(arc
					(start 319.860422 -211.305648)
					(mid 319.847468 -211.217389)
					(end 319.809876 -211.136484)
				)
				(arc
					(start 319.809876 -211.136484)
					(mid 319.509654 -210.703635)
					(end 319.92824 -211.023454)
				)
				(arc
					(start 319.92824 -211.023454)
					(mid 319.992463 -211.140489)
					(end 320.021204 -211.27085)
				)
				(xy 320.022474 -211.27212) (xy 320.022474 -211.406994) (xy 320.165222 -211.406994) (xy 320.165222 -211.28101)
				(arc
					(start 320.166492 -211.27974)
					(mid 320.198518 -211.142256)
					(end 320.270632 -211.020914)
				)
				(arc
					(start 320.270632 -211.020914)
					(mid 320.6933 -210.705896)
					(end 320.386964 -211.13496)
				)
				(arc
					(start 320.386964 -211.13496)
					(mid 320.342587 -211.219919)
					(end 320.327274 -211.314538)
				)
				(xy 320.327274 -211.406994)
				(arc
					(start 320.506598 -211.406994)
					(mid 321.017138 -210.896454)
					(end 320.506598 -210.385914)
				)
			)
		)
	)
	(zone
		(layer "F.Cu")
		(hatch none 0.5)
		(connect_pads
			(clearance 0)
		)
		(min_thickness 0.25)
		(keepout
			(tracks not_allowed)
			(vias allowed)
			(pads allowed)
			(copperpour not_allowed)
			(footprints allowed)
		)
		(placement
			(enabled no)
			(sheetname "")
		)
		(fill
			(thermal_gap 0.5)
			(thermal_bridge_width 0.5)
			(island_removal_mode 0)
		)
		(polygon
			(pts
				(arc
					(start 283.69387 -210.385914)
					(mid 283.183076 -210.896327)
					(end 283.693616 -211.406994)
				)
				(xy 283.86024 -211.406994)
				(arc
					(start 283.86024 -211.2772)
					(mid 283.848149 -211.202193)
					(end 283.81325 -211.134706)
				)
				(arc
					(start 283.81325 -211.134706)
					(mid 283.506916 -210.70614)
					(end 283.929582 -211.02066)
				)
				(arc
					(start 283.929582 -211.02066)
					(mid 283.992091 -211.124447)
					(end 284.020768 -211.242148)
				)
				(xy 284.022292 -211.243672) (xy 284.022292 -211.406994) (xy 284.16504 -211.406994) (xy 284.16504 -211.243418)
				(arc
					(start 284.166818 -211.24164)
					(mid 284.193258 -211.134823)
					(end 284.249876 -211.040472)
				)
				(xy 284.249876 -211.038186)
				(arc
					(start 284.269434 -211.018628)
					(mid 284.695599 -210.708423)
					(end 284.383988 -211.133436)
				)
				(arc
					(start 284.383988 -211.133436)
					(mid 284.341932 -211.199516)
					(end 284.327092 -211.276438)
				)
				(xy 284.327092 -211.406994)
				(arc
					(start 284.506416 -211.406994)
					(mid 285.016956 -210.896454)
					(end 284.506416 -210.385914)
				)
			)
		)
	)
	(zone
		(layer "F.Cu")
		(hatch none 0.5)
		(connect_pads
			(clearance 0)
		)
		(min_thickness 0.25)
		(keepout
			(tracks not_allowed)
			(vias allowed)
			(pads allowed)
			(copperpour not_allowed)
			(footprints allowed)
		)
		(placement
			(enabled no)
			(sheetname "")
		)
		(fill
			(thermal_gap 0.5)
			(thermal_bridge_width 0.5)
			(island_removal_mode 0)
		)
		(polygon
			(pts
				(arc
					(start 301.65929 -34.515806)
					(mid 301.14875 -35.026346)
					(end 301.65929 -35.536886)
				)
				(arc
					(start 302.471836 -35.536886)
					(mid 302.98263 -35.026473)
					(end 302.47209 -34.515806)
				)
				(xy 302.311816 -34.515806)
				(arc
					(start 302.311816 -34.594292)
					(mid 302.324703 -34.692093)
					(end 302.362362 -34.783268)
				)
				(arc
					(start 302.362362 -34.783268)
					(mid 302.651587 -35.223597)
					(end 302.240442 -34.894266)
				)
				(arc
					(start 302.240442 -34.894266)
					(mid 302.178176 -34.767572)
					(end 302.15078 -34.62909)
				)
				(xy 302.149764 -34.62782) (xy 302.149764 -34.515806) (xy 302.007016 -34.515806) (xy 302.007016 -34.62782)
				(arc
					(start 302.005746 -34.62909)
					(mid 301.972136 -34.774424)
					(end 301.89551 -34.902394)
				)
				(arc
					(start 301.89551 -34.902394)
					(mid 301.472271 -35.216578)
					(end 301.779178 -34.788094)
				)
				(arc
					(start 301.779178 -34.788094)
					(mid 301.828043 -34.696747)
					(end 301.844964 -34.594546)
				)
				(xy 301.844964 -34.515806)
			)
		)
	)
	(zone
		(layer "F.Cu")
		(hatch none 0.5)
		(connect_pads
			(clearance 0)
		)
		(min_thickness 0.25)
		(keepout
			(tracks allowed)
			(vias allowed)
			(pads allowed)
			(copperpour allowed)
			(footprints allowed)
		)
		(placement
			(enabled no)
			(sheetname "")
		)
		(fill
			(thermal_gap 0.5)
			(thermal_bridge_width 0.5)
			(island_removal_mode 0)
		)
		(polygon
			(pts
				(xy 16.51 -68.7832) (xy 17.526 -68.7832) (xy 19.4564 -70.7136) (xy 19.4564 -71.8566) (xy 15.494 -71.8566)
				(xy 15.3416 -72.009) (xy 14.224 -72.009) (xy 13.716 -71.501) (xy 13.716 -70.485) (xy 13.283438 -70.052438)
				(xy 13.283438 -68.682362) (xy 14.7701 -67.1957) (xy 15.0622 -66.9036) (xy 15.6972 -66.9036) (xy 16.3068 -67.5132)
				(xy 16.3068 -68.58)
			)
		)
	)
	(zone
		(layer "F.Cu")
		(hatch none 0.5)
		(connect_pads
			(clearance 0)
		)
		(min_thickness 0.25)
		(keepout
			(tracks not_allowed)
			(vias allowed)
			(pads allowed)
			(copperpour not_allowed)
			(footprints allowed)
		)
		(placement
			(enabled no)
			(sheetname "")
		)
		(fill
			(thermal_gap 0.5)
			(thermal_bridge_width 0.5)
			(island_removal_mode 0)
		)
		(polygon
			(pts
				(arc
					(start 312.67654 -35.675062)
					(mid 312.165746 -36.185475)
					(end 312.676286 -36.696142)
				)
				(arc
					(start 313.489086 -36.696142)
					(mid 313.999626 -36.185602)
					(end 313.489086 -35.675062)
				)
				(xy 313.328812 -35.675062)
				(arc
					(start 313.328812 -35.753548)
					(mid 313.341699 -35.851349)
					(end 313.379358 -35.942524)
				)
				(arc
					(start 313.379358 -35.942524)
					(mid 313.668583 -36.382853)
					(end 313.257438 -36.053522)
				)
				(arc
					(start 313.257438 -36.053522)
					(mid 313.195172 -35.926828)
					(end 313.167776 -35.788346)
				)
				(xy 313.16676 -35.787076) (xy 313.16676 -35.675062) (xy 313.024012 -35.675062) (xy 313.024012 -35.787076)
				(arc
					(start 313.022742 -35.788346)
					(mid 312.989132 -35.93368)
					(end 312.912506 -36.06165)
				)
				(arc
					(start 312.912506 -36.06165)
					(mid 312.489267 -36.375834)
					(end 312.796174 -35.94735)
				)
				(arc
					(start 312.796174 -35.94735)
					(mid 312.845039 -35.856003)
					(end 312.86196 -35.753802)
				)
				(xy 312.86196 -35.675062)
			)
		)
	)
	(zone
		(layer "F.Cu")
		(hatch none 0.5)
		(connect_pads
			(clearance 0)
		)
		(min_thickness 0.25)
		(keepout
			(tracks not_allowed)
			(vias allowed)
			(pads allowed)
			(copperpour not_allowed)
			(footprints allowed)
		)
		(placement
			(enabled no)
			(sheetname "")
		)
		(fill
			(thermal_gap 0.5)
			(thermal_bridge_width 0.5)
			(island_removal_mode 0)
		)
		(polygon
			(pts
				(arc
					(start 16.69034 -66.224404)
					(mid 16.179927 -65.71361)
					(end 15.66926 -66.22415)
				)
				(xy 15.66926 -66.394584) (xy 15.917164 -66.394584)
				(arc
					(start 15.950946 -66.361056)
					(mid 16.36837 -66.03558)
					(end 16.042894 -66.453004)
				)
				(xy 15.971012 -66.524886) (xy 15.971012 -66.52514) (xy 15.66926 -66.52514) (xy 15.66926 -66.737484)
				(xy 15.972536 -66.737484) (xy 15.972536 -66.737738)
				(arc
					(start 16.042894 -66.808096)
					(mid 16.36837 -67.22552)
					(end 15.950946 -66.900044)
				)
				(xy 15.918688 -66.86804) (xy 15.66926 -66.86804)
				(arc
					(start 15.66926 -67.03695)
					(mid 16.1798 -67.54749)
					(end 16.69034 -67.03695)
				)
			)
		)
	)
	(zone
		(net "P5V_USB_BP1_F")
		(layer "F.Cu")
		(hatch none 0.5)
		(connect_pads
			(clearance 0.5)
		)
		(min_thickness 0.25)
		(fill yes
			(thermal_gap 0.5)
			(thermal_bridge_width 0.5)
			(island_removal_mode 0)
		)
		(polygon
			(pts
				(xy 34.29 -57.15) (xy 33.8582 -57.5818) (xy 33.8582 -66.2432) (xy 34.036 -66.421) (xy 34.417 -66.421)
				(xy 34.7218 -66.7258) (xy 34.7218 -67.8942) (xy 35.3568 -68.5292) (xy 36.9824 -68.5292) (xy 37.211 -68.3006)
				(xy 37.211 -66.6242) (xy 37.465 -66.3702) (xy 37.465 -59.436) (xy 38.1 -58.801) (xy 38.1 -57.277)
				(xy 37.973 -57.15)
			)
		)
		(polygon
			(pts
				(xy 35.8521 -68.1863) (xy 35.6489 -68.1863) (xy 35.6489 -68.3895) (xy 35.8521 -68.3895)
			)
		)
		(polygon
			(pts
				(xy 35.3822 -67.3354) (xy 35.179 -67.3354) (xy 35.179 -67.5386) (xy 35.3822 -67.5386)
			)
		)
		(polygon
			(pts
				(xy 36.9951 -66.7893) (xy 36.7919 -66.7893) (xy 36.7919 -66.9925) (xy 36.9951 -66.9925)
			)
		)
		(polygon
			(pts
				(xy 35.8521 -66.7893) (xy 35.6489 -66.7893) (xy 35.6489 -66.9925) (xy 35.8521 -66.9925)
			)
		)
		(polygon
			(pts
				(xy 35.3822 -66.7258) (xy 35.179 -66.7258) (xy 35.179 -66.929) (xy 35.3822 -66.929)
			)
		)
	)
	(zone
		(net "P0V9_E_LX")
		(layer "F.Cu")
		(hatch none 0.5)
		(connect_pads
			(clearance 0.5)
		)
		(min_thickness 0.25)
		(fill yes
			(thermal_gap 0.5)
			(thermal_bridge_width 0.5)
			(island_removal_mode 0)
		)
		(polygon
			(pts
				(xy 332.232 -58.928) (xy 331.978 -59.182) (xy 331.978 -66.802) (xy 332.232 -67.056) (xy 337.693 -67.056)
				(xy 337.693 -63.863474) (xy 336.648806 -62.81928) (xy 336.648806 -59.250326) (xy 336.32648 -58.928)
			)
		)
	)
	(zone
		(net "VR_P1V26_STBY_IN")
		(layer "F.Cu")
		(hatch none 0.5)
		(connect_pads
			(clearance 0.5)
		)
		(min_thickness 0.25)
		(fill yes
			(thermal_gap 0.5)
			(thermal_bridge_width 0.5)
			(island_removal_mode 0)
		)
		(polygon
			(pts
				(xy 9.6774 -108.585) (xy 8.5598 -109.7026) (xy 7.0866 -109.7026) (xy 6.8834 -109.9058) (xy 4.874006 -109.9058)
				(xy 4.699254 -110.080552) (xy 4.699254 -110.974124) (xy 4.82473 -111.0996) (xy 9.525 -111.0996)
				(xy 11.0744 -109.5502) (xy 11.0744 -109.0422) (xy 10.1854 -109.0422) (xy 10.1854 -108.8644) (xy 11.0744 -108.8644)
				(xy 11.0744 -108.585)
			)
		)
		(polygon
			(pts
				(xy 6.8834 -110.0328) (xy 6.6802 -110.0328) (xy 6.6802 -110.236) (xy 6.8834 -110.236)
			)
		)
		(polygon
			(pts
				(xy 6.0198 -110.0328) (xy 5.8166 -110.0328) (xy 5.8166 -110.236) (xy 6.0198 -110.236)
			)
		)
	)
	(zone
		(layer "F.Cu")
		(hatch none 0.5)
		(connect_pads
			(clearance 0)
		)
		(min_thickness 0.25)
		(keepout
			(tracks not_allowed)
			(vias allowed)
			(pads allowed)
			(copperpour not_allowed)
			(footprints allowed)
		)
		(placement
			(enabled no)
			(sheetname "")
		)
		(fill
			(thermal_gap 0.5)
			(thermal_bridge_width 0.5)
			(island_removal_mode 0)
		)
		(polygon
			(pts
				(arc
					(start 277.293832 -210.385914)
					(mid 276.783038 -210.896327)
					(end 277.293578 -211.406994)
				)
				(xy 277.460202 -211.406994)
				(arc
					(start 277.460202 -211.2772)
					(mid 277.448111 -211.202193)
					(end 277.413212 -211.134706)
				)
				(arc
					(start 277.413212 -211.134706)
					(mid 277.106878 -210.70614)
					(end 277.529544 -211.02066)
				)
				(arc
					(start 277.529544 -211.02066)
					(mid 277.592053 -211.124447)
					(end 277.62073 -211.242148)
				)
				(xy 277.622254 -211.243672) (xy 277.622254 -211.406994) (xy 277.765002 -211.406994) (xy 277.765002 -211.243418)
				(arc
					(start 277.76678 -211.24164)
					(mid 277.79322 -211.134823)
					(end 277.849838 -211.040472)
				)
				(xy 277.849838 -211.038186)
				(arc
					(start 277.869396 -211.018628)
					(mid 278.295561 -210.708423)
					(end 277.98395 -211.133436)
				)
				(arc
					(start 277.98395 -211.133436)
					(mid 277.941894 -211.199516)
					(end 277.927054 -211.276438)
				)
				(xy 277.927054 -211.406994)
				(arc
					(start 278.106378 -211.406994)
					(mid 278.616918 -210.896454)
					(end 278.106378 -210.385914)
				)
			)
		)
	)
	(zone
		(layer "F.Cu")
		(hatch none 0.5)
		(connect_pads
			(clearance 0)
		)
		(min_thickness 0.25)
		(keepout
			(tracks not_allowed)
			(vias allowed)
			(pads allowed)
			(copperpour not_allowed)
			(footprints allowed)
		)
		(placement
			(enabled no)
			(sheetname "")
		)
		(fill
			(thermal_gap 0.5)
			(thermal_bridge_width 0.5)
			(island_removal_mode 0)
		)
		(polygon
			(pts
				(arc
					(start 291.935408 -24.224996)
					(mid 291.679376 -23.379176)
					(end 290.833556 -23.635208)
				)
				(xy 290.831524 -23.633938) (xy 290.081462 -25.033732) (xy 290.081716 -25.033986)
				(arc
					(start 290.083748 -25.035002)
					(mid 290.339424 -25.880903)
					(end 291.185346 -25.625044)
				)
				(xy 291.187378 -25.626314) (xy 291.219128 -25.567132)
				(arc
					(start 291.219128 -25.272492)
					(mid 291.200142 -25.109675)
					(end 291.144452 -24.9555)
				)
				(arc
					(start 291.144452 -24.9555)
					(mid 291.085067 -24.857103)
					(end 291.010594 -24.769572)
				)
				(arc
					(start 290.961318 -24.720296)
					(mid 290.848036 -24.668042)
					(end 290.727892 -24.701754)
				)
				(arc
					(start 290.727892 -24.701754)
					(mid 290.642032 -24.811024)
					(end 290.627054 -24.94915)
				)
				(arc
					(start 290.627054 -24.94915)
					(mid 290.723337 -25.700768)
					(end 290.469066 -24.986996)
				)
				(xy 290.465002 -24.970232)
				(arc
					(start 290.466018 -24.968454)
					(mid 290.49362 -24.746134)
					(end 290.632896 -24.57069)
				)
				(arc
					(start 290.632896 -24.57069)
					(mid 290.84321 -24.505493)
					(end 291.04971 -24.581866)
				)
				(xy 291.05225 -24.581866) (xy 291.149024 -24.67864)
				(arc
					(start 291.149024 -24.679656)
					(mid 291.226625 -24.776506)
					(end 291.28974 -24.883364)
				)
				(arc
					(start 291.28974 -24.883364)
					(mid 291.353897 -25.056232)
					(end 291.380418 -25.23871)
				)
				(xy 291.38118 -25.239472) (xy 291.38118 -25.264618)
				(arc
					(start 291.498274 -25.045924)
					(mid 291.46459 -24.930376)
					(end 291.417502 -24.81961)
				)
				(arc
					(start 291.417502 -24.81961)
					(mid 291.336354 -24.599803)
					(end 291.303964 -24.367744)
				)
				(xy 291.303456 -24.367236)
				(arc
					(start 291.303456 -24.302466)
					(mid 291.384482 -23.549024)
					(end 291.465508 -24.302466)
				)
				(arc
					(start 291.465508 -24.333708)
					(mid 291.490178 -24.546228)
					(end 291.56279 -24.747474)
				)
				(arc
					(start 291.56279 -24.747474)
					(mid 291.585493 -24.795878)
					(end 291.60597 -24.845264)
				)
				(xy 291.93744 -24.226266)
			)
		)
	)
	(zone
		(layer "F.Cu")
		(hatch none 0.5)
		(connect_pads
			(clearance 0)
		)
		(min_thickness 0.25)
		(keepout
			(tracks allowed)
			(vias allowed)
			(pads allowed)
			(copperpour allowed)
			(footprints not_allowed)
		)
		(placement
			(enabled no)
			(sheetname "")
		)
		(fill
			(thermal_gap 0.5)
			(thermal_bridge_width 0.5)
			(island_removal_mode 0)
		)
		(polygon
			(pts
				(xy 121.637552 -25.80005) (xy 121.637552 -15.80007) (xy 115.24742 -15.80007) (xy 115.24742 -25.80005)
			)
		)
	)
	(zone
		(layer "F.Cu")
		(hatch none 0.5)
		(connect_pads
			(clearance 0)
		)
		(min_thickness 0.25)
		(keepout
			(tracks not_allowed)
			(vias allowed)
			(pads allowed)
			(copperpour not_allowed)
			(footprints allowed)
		)
		(placement
			(enabled no)
			(sheetname "")
		)
		(fill
			(thermal_gap 0.5)
			(thermal_bridge_width 0.5)
			(island_removal_mode 0)
		)
		(polygon
			(pts
				(arc
					(start 166.493952 -210.385914)
					(mid 165.983158 -210.896327)
					(end 166.493698 -211.406994)
				)
				(xy 166.660322 -211.406994)
				(arc
					(start 166.660322 -211.2899)
					(mid 166.647978 -211.209)
					(end 166.612062 -211.135468)
				)
				(arc
					(start 166.612062 -211.135468)
					(mid 166.307852 -210.705145)
					(end 166.729156 -211.021676)
				)
				(arc
					(start 166.729156 -211.021676)
					(mid 166.792229 -211.131486)
					(end 166.82085 -211.254848)
				)
				(xy 166.822374 -211.256372) (xy 166.822374 -211.406994) (xy 166.965122 -211.406994) (xy 166.965122 -211.256372)
				(arc
					(start 166.966646 -211.254848)
					(mid 166.995812 -211.13596)
					(end 167.059356 -211.031328)
				)
				(xy 167.059356 -211.029296)
				(arc
					(start 167.069516 -211.019136)
					(mid 167.494791 -210.707358)
					(end 167.184832 -211.133944)
				)
				(arc
					(start 167.184832 -211.133944)
					(mid 167.142066 -211.206773)
					(end 167.127174 -211.2899)
				)
				(xy 167.127174 -211.406994)
				(arc
					(start 167.306498 -211.406994)
					(mid 167.817038 -210.896454)
					(end 167.306498 -210.385914)
				)
			)
		)
	)
	(zone
		(layer "F.Cu")
		(hatch none 0.5)
		(connect_pads
			(clearance 0)
		)
		(min_thickness 0.25)
		(keepout
			(tracks not_allowed)
			(vias allowed)
			(pads allowed)
			(copperpour not_allowed)
			(footprints allowed)
		)
		(placement
			(enabled no)
			(sheetname "")
		)
		(fill
			(thermal_gap 0.5)
			(thermal_bridge_width 0.5)
			(island_removal_mode 0)
		)
		(polygon
			(pts
				(arc
					(start 151.294084 -210.385914)
					(mid 150.78329 -210.896327)
					(end 151.29383 -211.406994)
				)
				(xy 151.460454 -211.406994)
				(arc
					(start 151.460454 -211.2772)
					(mid 151.448363 -211.202193)
					(end 151.413464 -211.134706)
				)
				(arc
					(start 151.413464 -211.134706)
					(mid 151.10713 -210.70614)
					(end 151.529796 -211.02066)
				)
				(arc
					(start 151.529796 -211.02066)
					(mid 151.592305 -211.124447)
					(end 151.620982 -211.242148)
				)
				(xy 151.622506 -211.243672) (xy 151.622506 -211.406994) (xy 151.765254 -211.406994) (xy 151.765254 -211.243418)
				(arc
					(start 151.767032 -211.24164)
					(mid 151.793472 -211.134823)
					(end 151.85009 -211.040472)
				)
				(xy 151.85009 -211.038186)
				(arc
					(start 151.869648 -211.018628)
					(mid 152.295813 -210.708423)
					(end 151.984202 -211.133436)
				)
				(arc
					(start 151.984202 -211.133436)
					(mid 151.942146 -211.199516)
					(end 151.927306 -211.276438)
				)
				(xy 151.927306 -211.406994)
				(arc
					(start 152.10663 -211.406994)
					(mid 152.61717 -210.896454)
					(end 152.10663 -210.385914)
				)
			)
		)
	)
	(zone
		(layer "F.Cu")
		(hatch none 0.5)
		(connect_pads
			(clearance 0)
		)
		(min_thickness 0.25)
		(keepout
			(tracks not_allowed)
			(vias allowed)
			(pads allowed)
			(copperpour not_allowed)
			(footprints allowed)
		)
		(placement
			(enabled no)
			(sheetname "")
		)
		(fill
			(thermal_gap 0.5)
			(thermal_bridge_width 0.5)
			(island_removal_mode 0)
		)
		(polygon
			(pts
				(xy 19.147028 -54.487572) (xy 19.147028 -54.790086) (xy 19.146774 -54.790086)
				(arc
					(start 19.075654 -54.861206)
					(mid 19.113478 -54.998112)
					(end 19.075654 -55.135018)
				)
				(xy 19.146774 -55.206138) (xy 19.147028 -55.206138) (xy 19.147028 -55.508652) (xy 19.359372 -55.508652)
				(xy 19.359372 -55.206138) (xy 19.359626 -55.206138)
				(arc
					(start 19.430746 -55.135018)
					(mid 19.392922 -54.998112)
					(end 19.430746 -54.861206)
				)
				(xy 19.359626 -54.790086) (xy 19.359372 -54.790086) (xy 19.359372 -54.487572)
			)
		)
	)
	(zone
		(net "GND")
		(layer "F.Cu")
		(hatch none 0.5)
		(connect_pads
			(clearance 0.5)
		)
		(min_thickness 0.25)
		(fill yes
			(thermal_gap 0.5)
			(thermal_bridge_width 0.5)
			(island_removal_mode 0)
		)
		(polygon
			(pts
				(xy 132.144008 -47.42942) (xy 132.093208 -47.48022) (xy 132.093208 -49.94402) (xy 133.363208 -51.21402)
				(xy 141.125702 -51.21402) (xy 141.338808 -51.000914) (xy 141.338808 -47.65802) (xy 141.110208 -47.42942)
			)
		)
	)
	(zone
		(layer "F.Cu")
		(hatch none 0.5)
		(connect_pads
			(clearance 0)
		)
		(min_thickness 0.25)
		(keepout
			(tracks allowed)
			(vias allowed)
			(pads allowed)
			(copperpour allowed)
			(footprints not_allowed)
		)
		(placement
			(enabled no)
			(sheetname "")
		)
		(fill
			(thermal_gap 0.5)
			(thermal_bridge_width 0.5)
			(island_removal_mode 0)
		)
		(polygon
			(pts
				(arc
					(start 341.600028 -34.500058)
					(mid 345.60002 -30.500066)
					(end 349.600012 -34.500058)
				)
				(arc
					(start 349.600012 -34.500058)
					(mid 345.60002 -38.50005)
					(end 341.600028 -34.500058)
				)
			)
		)
	)
	(zone
		(net "P1V53_PWR")
		(layer "F.Cu")
		(hatch none 0.5)
		(connect_pads
			(clearance 0.5)
		)
		(min_thickness 0.25)
		(fill yes
			(thermal_gap 0.5)
			(thermal_bridge_width 0.5)
			(island_removal_mode 0)
		)
		(polygon
			(pts
				(xy 62.865 -152.781) (xy 62.611 -153.035) (xy 62.611 -160.0708) (xy 62.7634 -160.2232) (xy 63.2714 -160.2232)
				(xy 63.8048 -160.7566) (xy 63.8048 -161.1122) (xy 63.8556 -161.163) (xy 64.643 -161.163) (xy 64.77 -161.036)
				(xy 64.77 -159.1056) (xy 65.1256 -158.75) (xy 65.1256 -153.1112) (xy 64.7954 -152.781)
			)
		)
	)
	(zone
		(layer "F.Cu")
		(hatch none 0.5)
		(connect_pads
			(clearance 0)
		)
		(min_thickness 0.25)
		(keepout
			(tracks allowed)
			(vias allowed)
			(pads allowed)
			(copperpour allowed)
			(footprints not_allowed)
		)
		(placement
			(enabled no)
			(sheetname "")
		)
		(fill
			(thermal_gap 0.5)
			(thermal_bridge_width 0.5)
			(island_removal_mode 0)
		)
		(polygon
			(pts
				(arc
					(start 199.021954 -59.99988)
					(mid 200.622154 -58.39968)
					(end 202.2221 -59.99988)
				)
				(arc
					(start 202.2221 -59.99988)
					(mid 200.622154 -61.599826)
					(end 199.021954 -59.99988)
				)
			)
		)
	)
	(zone
		(net "P0V9_E")
		(layer "F.Cu")
		(hatch none 0.5)
		(connect_pads
			(clearance 0.5)
		)
		(min_thickness 0.25)
		(fill yes
			(thermal_gap 0.5)
			(thermal_bridge_width 0.5)
			(island_removal_mode 0)
		)
		(polygon
			(pts
				(xy 311.2262 -54.753002) (xy 310.261 -55.718202) (xy 310.261 -68.072) (xy 310.3118 -68.1228) (xy 310.3118 -68.6308)
				(xy 310.4896 -68.8086) (xy 324.6374 -68.8086) (xy 325.628 -67.818) (xy 325.628 -56.007) (xy 324.374002 -54.753002)
			)
		)
	)
	(zone
		(layer "F.Cu")
		(hatch none 0.5)
		(connect_pads
			(clearance 0)
		)
		(min_thickness 0.25)
		(keepout
			(tracks allowed)
			(vias allowed)
			(pads allowed)
			(copperpour allowed)
			(footprints not_allowed)
		)
		(placement
			(enabled no)
			(sheetname "")
		)
		(fill
			(thermal_gap 0.5)
			(thermal_bridge_width 0.5)
			(island_removal_mode 0)
		)
		(polygon
			(pts
				(xy 121.637552 0) (xy 67.449954 0) (xy 67.449954 -29.99994) (xy 86.559898 -29.99994) (xy 86.559898 -34.239962)
				(xy 90.950034 -34.239962) (xy 90.950034 -208.499964) (xy 115.24742 -208.499964) (xy 115.24742 -15.80007)
				(xy 121.637552 -15.80007)
			)
		)
	)
	(zone
		(layer "F.Cu")
		(hatch none 0.5)
		(connect_pads
			(clearance 0)
		)
		(min_thickness 0.25)
		(keepout
			(tracks not_allowed)
			(vias allowed)
			(pads allowed)
			(copperpour not_allowed)
			(footprints allowed)
		)
		(placement
			(enabled no)
			(sheetname "")
		)
		(fill
			(thermal_gap 0.5)
			(thermal_bridge_width 0.5)
			(island_removal_mode 0)
		)
		(polygon
			(pts
				(arc
					(start 18.8468 -54.487572)
					(mid 18.33626 -54.998112)
					(end 18.8468 -55.508652)
				)
				(xy 19.016472 -55.508652) (xy 19.016472 -55.259986)
				(arc
					(start 18.983706 -55.226966)
					(mid 18.580122 -54.998112)
					(end 18.983706 -54.769258)
				)
				(xy 19.016472 -54.736238) (xy 19.016472 -54.487572)
			)
		)
	)
	(zone
		(net "GND")
		(layer "F.Cu")
		(hatch none 0.5)
		(connect_pads
			(clearance 0.5)
		)
		(min_thickness 0.25)
		(fill yes
			(thermal_gap 0.5)
			(thermal_bridge_width 0.5)
			(island_removal_mode 0)
		)
		(polygon
			(pts
				(xy 337.558126 -47.759874) (xy 337.185 -48.133) (xy 310.0324 -48.133) (xy 306.5018 -51.6636) (xy 296.9514 -51.6636)
				(xy 295.656 -52.959) (xy 295.656 -56.6928) (xy 295.91 -56.9468) (xy 308.5846 -56.9468) (xy 311.1754 -54.356)
				(xy 321.437 -54.356) (xy 321.4497 -54.3433) (xy 321.5132 -54.4068) (xy 336.3722 -54.4068) (xy 336.7532 -54.7878)
				(xy 336.7532 -58.2422) (xy 337.018376 -58.507376) (xy 337.018376 -62.912244) (xy 337.947 -63.840868)
				(xy 337.947 -70.739) (xy 338.328 -71.12) (xy 340.741 -71.12) (xy 341.122 -70.739) (xy 341.122 -60.452)
				(xy 340.106 -59.436) (xy 340.106 -48.028098) (xy 339.837776 -47.759874)
			)
		)
		(polygon
			(pts
				(xy 340.3346 -62.9412) (xy 340.1314 -62.9412) (xy 340.1314 -63.1444) (xy 340.3346 -63.1444)
			)
		)
		(polygon
			(pts
				(xy 340.3346 -62.0776) (xy 340.1314 -62.0776) (xy 340.1314 -62.2808) (xy 340.3346 -62.2808)
			)
		)
	)
	(zone
		(layer "F.Cu")
		(hatch none 0.5)
		(connect_pads
			(clearance 0)
		)
		(min_thickness 0.25)
		(keepout
			(tracks not_allowed)
			(vias allowed)
			(pads allowed)
			(copperpour not_allowed)
			(footprints allowed)
		)
		(placement
			(enabled no)
			(sheetname "")
		)
		(fill
			(thermal_gap 0.5)
			(thermal_bridge_width 0.5)
			(island_removal_mode 0)
		)
		(polygon
			(pts
				(arc
					(start 267.693902 -210.385914)
					(mid 267.183108 -210.896327)
					(end 267.693648 -211.406994)
				)
				(xy 267.860272 -211.406994)
				(arc
					(start 267.860272 -211.304886)
					(mid 267.847392 -211.217023)
					(end 267.80998 -211.136484)
				)
				(arc
					(start 267.80998 -211.136484)
					(mid 267.50872 -210.704405)
					(end 267.928344 -211.022946)
				)
				(arc
					(start 267.928344 -211.022946)
					(mid 267.992443 -211.139994)
					(end 268.021054 -211.270342)
				)
				(xy 268.022324 -211.271612) (xy 268.022324 -211.406994) (xy 268.165072 -211.406994) (xy 268.165072 -211.281518)
				(arc
					(start 268.166342 -211.280248)
					(mid 268.198478 -211.142503)
					(end 268.270736 -211.020914)
				)
				(arc
					(start 268.270736 -211.020914)
					(mid 268.693442 -210.706353)
					(end 268.387068 -211.13496)
				)
				(arc
					(start 268.387068 -211.13496)
					(mid 268.342505 -211.220151)
					(end 268.327124 -211.315046)
				)
				(xy 268.327124 -211.406994)
				(arc
					(start 268.506448 -211.406994)
					(mid 269.016988 -210.896454)
					(end 268.506448 -210.385914)
				)
			)
		)
	)
	(zone
		(layer "F.Cu")
		(hatch none 0.5)
		(connect_pads
			(clearance 0)
		)
		(min_thickness 0.25)
		(keepout
			(tracks allowed)
			(vias allowed)
			(pads allowed)
			(copperpour allowed)
			(footprints not_allowed)
		)
		(placement
			(enabled no)
			(sheetname "")
		)
		(fill
			(thermal_gap 0.5)
			(thermal_bridge_width 0.5)
			(island_removal_mode 0)
		)
		(polygon
			(pts
				(arc
					(start 341.600028 -203.499974)
					(mid 345.60002 -199.499982)
					(end 349.600012 -203.499974)
				)
				(arc
					(start 349.600012 -203.499974)
					(mid 345.60002 -207.499966)
					(end 341.600028 -203.499974)
				)
			)
		)
	)
	(zone
		(layer "F.Cu")
		(hatch none 0.5)
		(connect_pads
			(clearance 0)
		)
		(min_thickness 0.25)
		(keepout
			(tracks not_allowed)
			(vias allowed)
			(pads allowed)
			(copperpour not_allowed)
			(footprints allowed)
		)
		(placement
			(enabled no)
			(sheetname "")
		)
		(fill
			(thermal_gap 0.5)
			(thermal_bridge_width 0.5)
			(island_removal_mode 0)
		)
		(polygon
			(pts
				(arc
					(start 184.093866 -210.385914)
					(mid 183.583072 -210.896327)
					(end 184.093612 -211.406994)
				)
				(xy 184.260236 -211.406994)
				(arc
					(start 184.260236 -211.284058)
					(mid 184.248066 -211.205823)
					(end 184.212738 -211.13496)
				)
				(arc
					(start 184.212738 -211.13496)
					(mid 183.907614 -210.705289)
					(end 184.329578 -211.020914)
				)
				(arc
					(start 184.329578 -211.020914)
					(mid 184.392231 -211.128268)
					(end 184.420764 -211.24926)
				)
				(xy 184.422288 -211.250784) (xy 184.422288 -211.406994) (xy 184.565036 -211.406994) (xy 184.565036 -211.251038)
				(arc
					(start 184.56656 -211.249514)
					(mid 184.594735 -211.135702)
					(end 184.65546 -211.035392)
				)
				(xy 184.65546 -211.033106)
				(arc
					(start 184.66943 -211.018882)
					(mid 185.094823 -210.707641)
					(end 184.784492 -211.13369)
				)
				(arc
					(start 184.784492 -211.13369)
					(mid 184.741989 -211.203868)
					(end 184.727088 -211.284566)
				)
				(xy 184.727088 -211.406994)
				(arc
					(start 184.906412 -211.406994)
					(mid 185.416952 -210.896454)
					(end 184.906412 -210.385914)
				)
			)
		)
	)
	(zone
		(net "GND")
		(layer "F.Cu")
		(hatch none 0.5)
		(connect_pads
			(clearance 0.5)
		)
		(min_thickness 0.25)
		(fill yes
			(thermal_gap 0.5)
			(thermal_bridge_width 0.5)
			(island_removal_mode 0)
		)
		(polygon
			(pts
				(xy 40.513 -50.292) (xy 40.132 -50.673) (xy 40.132 -53.848) (xy 40.513 -54.229) (xy 43.815 -54.229)
				(xy 44.069 -53.975) (xy 44.069 -50.673) (xy 43.688 -50.292)
			)
		)
	)
	(zone
		(layer "F.Cu")
		(hatch none 0.5)
		(connect_pads
			(clearance 0)
		)
		(min_thickness 0.25)
		(keepout
			(tracks allowed)
			(vias allowed)
			(pads allowed)
			(copperpour allowed)
			(footprints allowed)
		)
		(placement
			(enabled no)
			(sheetname "")
		)
		(fill
			(thermal_gap 0.5)
			(thermal_bridge_width 0.5)
			(island_removal_mode 0)
		)
		(polygon
			(pts
				(xy 216.535 -5.461) (xy 216.535 -7.874) (xy 214.376 -7.874) (xy 214.376 -5.461)
			)
		)
	)
	(zone
		(layer "F.Cu")
		(hatch none 0.5)
		(connect_pads
			(clearance 0)
		)
		(min_thickness 0.25)
		(keepout
			(tracks not_allowed)
			(vias allowed)
			(pads allowed)
			(copperpour not_allowed)
			(footprints allowed)
		)
		(placement
			(enabled no)
			(sheetname "")
		)
		(fill
			(thermal_gap 0.5)
			(thermal_bridge_width 0.5)
			(island_removal_mode 0)
		)
		(polygon
			(pts
				(arc
					(start 171.518072 -21.209)
					(mid 171.486991 -21.164523)
					(end 171.458128 -21.118576)
				)
				(arc
					(start 171.458128 -21.118576)
					(mid 171.34742 -20.863175)
					(end 171.30395 -20.588224)
				)
				(xy 171.303442 -20.587716)
				(arc
					(start 171.303442 -20.502372)
					(mid 171.384468 -19.74893)
					(end 171.465494 -20.502372)
				)
				(arc
					(start 171.465494 -20.554696)
					(mid 171.499097 -20.804083)
					(end 171.59732 -21.035772)
				)
				(xy 171.604432 -21.04771) (xy 171.937426 -20.426426) (xy 171.937172 -20.426172)
				(arc
					(start 171.93514 -20.425156)
					(mid 171.679464 -19.579255)
					(end 170.833542 -19.835114)
				)
				(xy 170.83151 -19.833844) (xy 170.081448 -21.233892)
				(arc
					(start 170.08348 -21.235162)
					(mid 170.339512 -22.080982)
					(end 171.185332 -21.82495)
				)
				(xy 171.187364 -21.82622) (xy 171.361354 -21.501608) (xy 171.339002 -21.479256) (xy 171.326302 -21.468588)
				(xy 171.313602 -21.461984) (xy 171.311824 -21.461222)
				(arc
					(start 171.107354 -21.376386)
					(mid 171.044044 -21.361623)
					(end 170.979338 -21.368004)
				)
				(arc
					(start 170.979338 -21.368004)
					(mid 170.333552 -21.763992)
					(end 170.876468 -21.23567)
				)
				(xy 170.906694 -21.215604)
				(arc
					(start 170.917108 -21.217636)
					(mid 171.026347 -21.199097)
					(end 171.136056 -21.214588)
				)
				(xy 171.138342 -21.213826) (xy 171.373546 -21.311362) (xy 171.376086 -21.312378) (xy 171.404788 -21.324316)
				(xy 171.406312 -21.327618) (xy 171.415964 -21.333714) (xy 171.416726 -21.334222) (xy 171.426124 -21.340826)
				(xy 171.42968 -21.340826) (xy 171.441364 -21.352256)
			)
		)
	)
	(zone
		(layer "F.Cu")
		(hatch none 0.5)
		(connect_pads
			(clearance 0)
		)
		(min_thickness 0.25)
		(keepout
			(tracks allowed)
			(vias allowed)
			(pads allowed)
			(copperpour allowed)
			(footprints allowed)
		)
		(placement
			(enabled no)
			(sheetname "")
		)
		(fill
			(thermal_gap 0.5)
			(thermal_bridge_width 0.5)
			(island_removal_mode 0)
		)
		(polygon
			(pts
				(xy 135.9408 -22.9362) (xy 135.9408 -20.7264) (xy 138.049 -20.7264) (xy 138.049 -22.206966) (xy 138.44524 -22.206966)
				(xy 139.601194 -23.36292) (xy 139.601194 -23.781766) (xy 139.225528 -24.157432) (xy 137.116058 -24.157432)
				(xy 137.014966 -24.05634) (xy 137.014966 -23.976584) (xy 135.974582 -22.9362)
			)
		)
	)
	(zone
		(layer "F.Cu")
		(hatch none 0.5)
		(connect_pads
			(clearance 0)
		)
		(min_thickness 0.25)
		(keepout
			(tracks not_allowed)
			(vias allowed)
			(pads allowed)
			(copperpour not_allowed)
			(footprints allowed)
		)
		(placement
			(enabled no)
			(sheetname "")
		)
		(fill
			(thermal_gap 0.5)
			(thermal_bridge_width 0.5)
			(island_removal_mode 0)
		)
		(polygon
			(pts
				(arc
					(start 176.093882 -210.385914)
					(mid 175.583088 -210.896327)
					(end 176.093628 -211.406994)
				)
				(xy 176.260252 -211.406994)
				(arc
					(start 176.260252 -211.286598)
					(mid 176.248024 -211.207235)
					(end 176.2125 -211.135214)
				)
				(arc
					(start 176.2125 -211.135214)
					(mid 175.907376 -210.705543)
					(end 176.32934 -211.021168)
				)
				(arc
					(start 176.32934 -211.021168)
					(mid 176.392218 -211.12968)
					(end 176.42078 -211.2518)
				)
				(xy 176.422304 -211.253324) (xy 176.422304 -211.406994) (xy 176.565052 -211.406994) (xy 176.565052 -211.253578)
				(arc
					(start 176.566576 -211.252054)
					(mid 176.595238 -211.135919)
					(end 176.657254 -211.033614)
				)
				(xy 176.657254 -211.031328)
				(arc
					(start 176.669446 -211.019136)
					(mid 177.094189 -210.706981)
					(end 176.784762 -211.13369)
				)
				(arc
					(start 176.784762 -211.13369)
					(mid 176.742005 -211.205168)
					(end 176.727104 -211.287106)
				)
				(xy 176.727104 -211.406994)
				(arc
					(start 176.906428 -211.406994)
					(mid 177.416968 -210.896454)
					(end 176.906428 -210.385914)
				)
			)
		)
	)
	(zone
		(layer "F.Cu")
		(hatch none 0.5)
		(connect_pads
			(clearance 0)
		)
		(min_thickness 0.25)
		(keepout
			(tracks allowed)
			(vias allowed)
			(pads allowed)
			(copperpour allowed)
			(footprints allowed)
		)
		(placement
			(enabled no)
			(sheetname "")
		)
		(fill
			(thermal_gap 0.5)
			(thermal_bridge_width 0.5)
			(island_removal_mode 0)
		)
		(polygon
			(pts
				(xy 219.520008 -69.1388) (xy 219.520008 -26.67) (xy 261.049008 -26.67) (xy 261.049008 -69.1388)
			)
		)
	)
	(zone
		(layer "F.Cu")
		(hatch none 0.5)
		(connect_pads
			(clearance 0)
		)
		(min_thickness 0.25)
		(keepout
			(tracks not_allowed)
			(vias allowed)
			(pads allowed)
			(copperpour not_allowed)
			(footprints allowed)
		)
		(placement
			(enabled no)
			(sheetname "")
		)
		(fill
			(thermal_gap 0.5)
			(thermal_bridge_width 0.5)
			(island_removal_mode 0)
		)
		(polygon
			(pts
				(arc
					(start 70.09384 -210.385914)
					(mid 69.583046 -210.896327)
					(end 70.093586 -211.406994)
				)
				(xy 70.26021 -211.406994)
				(arc
					(start 70.26021 -211.298028)
					(mid 70.24751 -211.213316)
					(end 70.21068 -211.135976)
				)
				(arc
					(start 70.21068 -211.135976)
					(mid 69.908631 -210.70443)
					(end 70.328536 -211.022438)
				)
				(arc
					(start 70.328536 -211.022438)
					(mid 70.392238 -211.135989)
					(end 70.420992 -211.262976)
				)
				(xy 70.422262 -211.2645) (xy 70.422262 -211.406994) (xy 70.56501 -211.406994) (xy 70.56501 -211.280248)
				(arc
					(start 70.56628 -211.278978)
					(mid 70.598336 -211.141751)
					(end 70.67042 -211.02066)
				)
				(arc
					(start 70.67042 -211.02066)
					(mid 71.093126 -210.706099)
					(end 70.786752 -211.134706)
				)
				(arc
					(start 70.786752 -211.134706)
					(mid 70.742375 -211.219393)
					(end 70.727062 -211.313776)
				)
				(xy 70.727062 -211.406994)
				(arc
					(start 70.906386 -211.406994)
					(mid 71.416926 -210.896454)
					(end 70.906386 -210.385914)
				)
			)
		)
	)
	(zone
		(layer "F.Cu")
		(hatch none 0.5)
		(connect_pads
			(clearance 0)
		)
		(min_thickness 0.25)
		(keepout
			(tracks not_allowed)
			(vias allowed)
			(pads allowed)
			(copperpour not_allowed)
			(footprints allowed)
		)
		(placement
			(enabled no)
			(sheetname "")
		)
		(fill
			(thermal_gap 0.5)
			(thermal_bridge_width 0.5)
			(island_removal_mode 0)
		)
		(polygon
			(pts
				(arc
					(start 319.72123 -36.51504)
					(mid 319.210436 -37.025453)
					(end 319.720976 -37.53612)
				)
				(arc
					(start 320.533776 -37.53612)
					(mid 321.044316 -37.02558)
					(end 320.533776 -36.51504)
				)
				(xy 320.373502 -36.51504)
				(arc
					(start 320.373502 -36.593526)
					(mid 320.386389 -36.691327)
					(end 320.424048 -36.782502)
				)
				(arc
					(start 320.424048 -36.782502)
					(mid 320.713273 -37.222831)
					(end 320.302128 -36.8935)
				)
				(arc
					(start 320.302128 -36.8935)
					(mid 320.239862 -36.766806)
					(end 320.212466 -36.628324)
				)
				(xy 320.21145 -36.627054) (xy 320.21145 -36.51504) (xy 320.068702 -36.51504) (xy 320.068702 -36.627054)
				(arc
					(start 320.067432 -36.628324)
					(mid 320.033822 -36.773658)
					(end 319.957196 -36.901628)
				)
				(arc
					(start 319.957196 -36.901628)
					(mid 319.533957 -37.215812)
					(end 319.840864 -36.787328)
				)
				(arc
					(start 319.840864 -36.787328)
					(mid 319.889729 -36.695981)
					(end 319.90665 -36.59378)
				)
				(xy 319.90665 -36.51504)
			)
		)
	)
	(zone
		(layer "F.Cu")
		(hatch none 0.5)
		(connect_pads
			(clearance 0)
		)
		(min_thickness 0.25)
		(keepout
			(tracks not_allowed)
			(vias allowed)
			(pads allowed)
			(copperpour not_allowed)
			(footprints allowed)
		)
		(placement
			(enabled no)
			(sheetname "")
		)
		(fill
			(thermal_gap 0.5)
			(thermal_bridge_width 0.5)
			(island_removal_mode 0)
		)
		(polygon
			(pts
				(arc
					(start 324.31228 -24.999696)
					(mid 324.375852 -25.094651)
					(end 324.414642 -25.202134)
				)
				(arc
					(start 324.504812 -25.033478)
					(mid 324.453648 -24.948669)
					(end 324.389496 -24.873204)
				)
				(arc
					(start 324.389496 -24.873204)
					(mid 324.333136 -24.79399)
					(end 324.305676 -24.700738)
				)
				(xy 324.30339 -24.698452)
				(arc
					(start 324.30339 -24.302466)
					(mid 324.384416 -23.549024)
					(end 324.465442 -24.302466)
				)
				(arc
					(start 324.465442 -24.664924)
					(mid 324.475598 -24.715512)
					(end 324.504304 -24.758396)
				)
				(arc
					(start 324.504304 -24.758396)
					(mid 324.551723 -24.810453)
					(end 324.59422 -24.8666)
				)
				(xy 324.937374 -24.226266)
				(arc
					(start 324.935342 -24.224996)
					(mid 324.67931 -23.379176)
					(end 323.83349 -23.635208)
				)
				(xy 323.831458 -23.633938) (xy 323.081396 -25.033732) (xy 323.08165 -25.033986)
				(arc
					(start 323.083682 -25.035002)
					(mid 323.339358 -25.880903)
					(end 324.18528 -25.625044)
				)
				(xy 324.187312 -25.626314) (xy 324.264274 -25.48255)
				(arc
					(start 324.264274 -25.306782)
					(mid 324.240719 -25.188833)
					(end 324.17385 -25.08885)
				)
				(arc
					(start 323.994272 -24.909018)
					(mid 323.937078 -24.871732)
					(end 323.870066 -24.858726)
				)
				(arc
					(start 323.820282 -24.858726)
					(mid 323.784954 -24.865847)
					(end 323.755004 -24.885904)
				)
				(arc
					(start 323.755004 -24.885904)
					(mid 323.730582 -24.919181)
					(end 323.717412 -24.958294)
				)
				(arc
					(start 323.717412 -24.958294)
					(mid 323.632805 -25.711222)
					(end 323.553328 -24.957786)
				)
				(xy 323.553328 -24.947626)
				(arc
					(start 323.55536 -24.94534)
					(mid 323.583172 -24.851107)
					(end 323.640196 -24.771096)
				)
				(arc
					(start 323.640196 -24.771096)
					(mid 323.706373 -24.72347)
					(end 323.784214 -24.699214)
				)
				(xy 323.786754 -24.696674) (xy 323.903594 -24.696674)
				(arc
					(start 323.905372 -24.698452)
					(mid 324.000302 -24.722514)
					(end 324.084442 -24.77262)
				)
				(xy 324.086982 -24.77262) (xy 324.108318 -24.793956) (xy 324.110858 -24.796496) (xy 324.31228 -24.997918)
			)
		)
	)
	(zone
		(net "P3V3_STBY")
		(layer "F.Cu")
		(hatch none 0.5)
		(connect_pads
			(clearance 0.5)
		)
		(min_thickness 0.25)
		(fill yes
			(thermal_gap 0.5)
			(thermal_bridge_width 0.5)
			(island_removal_mode 0)
		)
		(polygon
			(pts
				(xy 256.9718 -12.827) (xy 256.5908 -13.208) (xy 256.5908 -16.9418) (xy 256.667 -17.018) (xy 261.62 -17.018)
				(xy 261.747 -16.891) (xy 261.747 -12.954) (xy 261.62 -12.827)
			)
		)
		(polygon
			(pts
				(xy 260.9088 -16.0274) (xy 260.7056 -16.0274) (xy 260.7056 -16.2306) (xy 260.9088 -16.2306)
			)
		)
	)
	(zone
		(layer "F.Cu")
		(hatch none 0.5)
		(connect_pads
			(clearance 0)
		)
		(min_thickness 0.25)
		(keepout
			(tracks not_allowed)
			(vias allowed)
			(pads allowed)
			(copperpour not_allowed)
			(footprints allowed)
		)
		(placement
			(enabled no)
			(sheetname "")
		)
		(fill
			(thermal_gap 0.5)
			(thermal_bridge_width 0.5)
			(island_removal_mode 0)
		)
		(polygon
			(pts
				(arc
					(start 338.893658 -210.385914)
					(mid 338.383118 -210.896454)
					(end 338.893658 -211.406994)
				)
				(xy 339.060282 -211.406994)
				(arc
					(start 339.060282 -211.339176)
					(mid 339.046148 -211.23523)
					(end 339.00491 -211.13877)
				)
				(arc
					(start 339.00491 -211.13877)
					(mid 338.713531 -210.699672)
					(end 339.126068 -211.027518)
				)
				(arc
					(start 339.126068 -211.027518)
					(mid 339.192436 -211.159898)
					(end 339.221318 -211.30514)
				)
				(xy 339.222334 -211.306156) (xy 339.222334 -211.406994) (xy 339.365082 -211.406994) (xy 339.365082 -211.30641)
				(arc
					(start 339.366098 -211.30514)
					(mid 339.398157 -211.15638)
					(end 339.471762 -211.0232)
				)
				(arc
					(start 339.471762 -211.0232)
					(mid 339.891005 -210.704289)
					(end 339.589872 -211.136484)
				)
				(arc
					(start 339.589872 -211.136484)
					(mid 339.543174 -211.233351)
					(end 339.527134 -211.339684)
				)
				(xy 339.527134 -211.406994)
				(arc
					(start 339.706204 -211.406994)
					(mid 340.216998 -210.896581)
					(end 339.706458 -210.385914)
				)
			)
		)
	)
	(zone
		(layer "F.Cu")
		(hatch none 0.5)
		(connect_pads
			(clearance 0)
		)
		(min_thickness 0.25)
		(keepout
			(tracks allowed)
			(vias allowed)
			(pads allowed)
			(copperpour allowed)
			(footprints not_allowed)
		)
		(placement
			(enabled no)
			(sheetname "")
		)
		(fill
			(thermal_gap 0.5)
			(thermal_bridge_width 0.5)
			(island_removal_mode 0)
		)
		(polygon
			(pts
				(xy 191.622172 -52.999894) (xy 191.622172 -77.0001) (xy 207.62214 -77.0001) (xy 207.62214 -52.999894)
			)
		)
	)
	(zone
		(layer "F.Cu")
		(hatch none 0.5)
		(connect_pads
			(clearance 0)
		)
		(min_thickness 0.25)
		(keepout
			(tracks not_allowed)
			(vias allowed)
			(pads allowed)
			(copperpour not_allowed)
			(footprints allowed)
		)
		(placement
			(enabled no)
			(sheetname "")
		)
		(fill
			(thermal_gap 0.5)
			(thermal_bridge_width 0.5)
			(island_removal_mode 0)
		)
		(polygon
			(pts
				(arc
					(start 138.557254 -38.14826)
					(mid 138.04646 -38.658673)
					(end 138.557 -39.16934)
				)
				(arc
					(start 139.3698 -39.16934)
					(mid 139.88034 -38.6588)
					(end 139.3698 -38.14826)
				)
				(xy 139.172188 -38.14826)
				(arc
					(start 139.172188 -38.33876)
					(mid 139.179408 -38.397407)
					(end 139.200636 -38.452552)
				)
				(arc
					(start 139.200636 -38.452552)
					(mid 139.597694 -38.797432)
					(end 139.108942 -38.603428)
				)
				(arc
					(start 139.108942 -38.603428)
					(mid 139.042173 -38.496305)
					(end 139.01166 -38.373812)
				)
				(xy 139.010136 -38.372288) (xy 139.010136 -38.14826) (xy 138.867388 -38.14826) (xy 138.867388 -38.372288)
				(arc
					(start 138.865864 -38.373812)
					(mid 138.846225 -38.470264)
					(end 138.80465 -38.559486)
				)
				(arc
					(start 138.80465 -38.559486)
					(mid 138.35627 -38.834337)
					(end 138.689588 -38.427406)
				)
				(arc
					(start 138.689588 -38.427406)
					(mid 138.701383 -38.383779)
					(end 138.705336 -38.33876)
				)
				(xy 138.705336 -38.14826)
			)
		)
	)
	(zone
		(layer "F.Cu")
		(hatch none 0.5)
		(connect_pads
			(clearance 0)
		)
		(min_thickness 0.25)
		(keepout
			(tracks allowed)
			(vias allowed)
			(pads allowed)
			(copperpour allowed)
			(footprints allowed)
		)
		(placement
			(enabled no)
			(sheetname "")
		)
		(fill
			(thermal_gap 0.5)
			(thermal_bridge_width 0.5)
			(island_removal_mode 0)
		)
		(polygon
			(pts
				(xy 19.13763 -79.357474) (xy 16.85925 -79.357474) (xy 16.662654 -79.55407) (xy 16.662654 -81.809336)
				(xy 16.662654 -82.271108) (xy 16.662654 -82.465672) (xy 16.6116 -82.516726) (xy 16.6116 -84.6836)
				(xy 16.6116 -85.072982) (xy 16.801338 -85.26272) (xy 17.35328 -85.26272) (xy 17.9324 -84.6836) (xy 18.1864 -84.4296)
				(xy 18.1864 -83.103466) (xy 18.719546 -82.57032) (xy 18.969482 -82.320384) (xy 19.31924 -81.970626)
				(xy 19.31924 -81.953354) (xy 20.765008 -81.953354) (xy 21.543518 -81.953354) (xy 21.829522 -82.239358)
				(xy 22.310344 -82.239358) (xy 22.438614 -82.111088) (xy 22.438614 -81.315814) (xy 22.1996 -81.0768)
				(xy 21.01469 -79.89189) (xy 21.01469 -79.463138) (xy 20.909026 -79.357474)
			)
		)
	)
	(zone
		(layer "F.Cu")
		(hatch none 0.5)
		(connect_pads
			(clearance 0)
		)
		(min_thickness 0.25)
		(keepout
			(tracks not_allowed)
			(vias allowed)
			(pads allowed)
			(copperpour not_allowed)
			(footprints allowed)
		)
		(placement
			(enabled no)
			(sheetname "")
		)
		(fill
			(thermal_gap 0.5)
			(thermal_bridge_width 0.5)
			(island_removal_mode 0)
		)
		(polygon
			(pts
				(xy 147.171918 -25.183592) (xy 147.248626 -25.040336) (xy 147.15109 -24.892)
				(arc
					(start 147.154392 -24.875998)
					(mid 147.102524 -24.592132)
					(end 147.069048 -24.305514)
				)
				(arc
					(start 147.069048 -24.305514)
					(mid 147.118209 -23.549398)
					(end 147.2311 -24.298656)
				)
				(arc
					(start 147.2311 -24.298656)
					(mid 147.263421 -24.572381)
					(end 147.313142 -24.843486)
				)
				(xy 147.335748 -24.877776)
				(arc
					(start 147.685252 -24.224996)
					(mid 147.42922 -23.379176)
					(end 146.5834 -23.635208)
				)
				(arc
					(start 145.837656 -25.027636)
					(mid 146.08579 -25.879089)
					(end 146.935444 -25.625044)
				)
				(xy 147.084796 -25.346152)
				(arc
					(start 146.839432 -24.973026)
					(mid 146.744611 -24.896564)
					(end 146.623024 -24.889206)
				)
				(xy 146.520154 -24.95677)
				(arc
					(start 146.503898 -24.968454)
					(mid 146.364893 -25.710532)
					(end 146.302984 -24.95804)
				)
				(arc
					(start 146.302984 -24.95804)
					(mid 146.347257 -24.895035)
					(end 146.402806 -24.841708)
				)
				(xy 146.40306 -24.839676) (xy 146.431 -24.821388) (xy 146.431254 -24.821134) (xy 146.572478 -24.728424)
				(arc
					(start 146.586448 -24.731218)
					(mid 146.788105 -24.740053)
					(end 146.953732 -24.855424)
				)
				(xy 146.956272 -24.855932)
			)
		)
	)
	(zone
		(layer "F.Cu")
		(hatch none 0.5)
		(connect_pads
			(clearance 0)
		)
		(min_thickness 0.25)
		(keepout
			(tracks allowed)
			(vias allowed)
			(pads allowed)
			(copperpour allowed)
			(footprints allowed)
		)
		(placement
			(enabled no)
			(sheetname "")
		)
		(fill
			(thermal_gap 0.5)
			(thermal_bridge_width 0.5)
			(island_removal_mode 0)
		)
		(polygon
			(pts
				(xy 12.317222 -51.496976) (xy 11.872214 -51.496976) (xy 11.868404 -51.500786) (xy 11.053318 -51.500786)
				(xy 10.6045 -51.051968) (xy 10.6045 -50.498756) (xy 10.939272 -50.163984) (xy 12.267946 -50.163984)
				(xy 12.496038 -50.392076) (xy 12.496038 -51.31816)
			)
		)
	)
	(zone
		(layer "F.Cu")
		(hatch none 0.5)
		(connect_pads
			(clearance 0)
		)
		(min_thickness 0.25)
		(keepout
			(tracks not_allowed)
			(vias allowed)
			(pads allowed)
			(copperpour not_allowed)
			(footprints allowed)
		)
		(placement
			(enabled no)
			(sheetname "")
		)
		(fill
			(thermal_gap 0.5)
			(thermal_bridge_width 0.5)
			(island_removal_mode 0)
		)
		(polygon
			(pts
				(arc
					(start 303.8348 -35.773614)
					(mid 303.32426 -36.284154)
					(end 303.8348 -36.794694)
				)
				(arc
					(start 304.647346 -36.794694)
					(mid 305.15814 -36.284281)
					(end 304.6476 -35.773614)
				)
				(xy 304.487326 -35.773614)
				(arc
					(start 304.487326 -35.8521)
					(mid 304.500213 -35.949901)
					(end 304.537872 -36.041076)
				)
				(arc
					(start 304.537872 -36.041076)
					(mid 304.827097 -36.481405)
					(end 304.415952 -36.152074)
				)
				(arc
					(start 304.415952 -36.152074)
					(mid 304.353686 -36.02538)
					(end 304.32629 -35.886898)
				)
				(xy 304.325274 -35.885628) (xy 304.325274 -35.773614) (xy 304.182526 -35.773614) (xy 304.182526 -35.885628)
				(arc
					(start 304.181256 -35.886898)
					(mid 304.147646 -36.032232)
					(end 304.07102 -36.160202)
				)
				(arc
					(start 304.07102 -36.160202)
					(mid 303.647781 -36.474386)
					(end 303.954688 -36.045902)
				)
				(arc
					(start 303.954688 -36.045902)
					(mid 304.003553 -35.954555)
					(end 304.020474 -35.852354)
				)
				(xy 304.020474 -35.773614)
			)
		)
	)
	(zone
		(layer "F.Cu")
		(hatch none 0.5)
		(connect_pads
			(clearance 0)
		)
		(min_thickness 0.25)
		(keepout
			(tracks not_allowed)
			(vias allowed)
			(pads allowed)
			(copperpour not_allowed)
			(footprints allowed)
		)
		(placement
			(enabled no)
			(sheetname "")
		)
		(fill
			(thermal_gap 0.5)
			(thermal_bridge_width 0.5)
			(island_removal_mode 0)
		)
		(polygon
			(pts
				(arc
					(start 305.762914 -39.29888)
					(mid 305.252374 -39.80942)
					(end 305.762914 -40.31996)
				)
				(arc
					(start 306.57546 -40.31996)
					(mid 307.086254 -39.809547)
					(end 306.575714 -39.29888)
				)
				(xy 306.40274 -39.29888) (xy 306.40274 -39.521892)
				(arc
					(start 306.453286 -39.572438)
					(mid 306.764326 -39.998032)
					(end 306.338732 -39.686992)
				)
				(xy 306.240688 -39.588948) (xy 306.240688 -39.29888) (xy 306.09794 -39.29888) (xy 306.09794 -39.588948)
				(arc
					(start 305.999896 -39.686992)
					(mid 305.574302 -39.998032)
					(end 305.885342 -39.572438)
				)
				(xy 305.935888 -39.521892) (xy 305.935888 -39.29888)
			)
		)
	)
	(zone
		(layer "F.Cu")
		(hatch none 0.5)
		(connect_pads
			(clearance 0)
		)
		(min_thickness 0.25)
		(keepout
			(tracks allowed)
			(vias allowed)
			(pads allowed)
			(copperpour allowed)
			(footprints not_allowed)
		)
		(placement
			(enabled no)
			(sheetname "")
		)
		(fill
			(thermal_gap 0.5)
			(thermal_bridge_width 0.5)
			(island_removal_mode 0)
		)
		(polygon
			(pts
				(arc
					(start 343.7001 -203.499974)
					(mid 345.60002 -201.600054)
					(end 347.49994 -203.499974)
				)
				(arc
					(start 347.49994 -203.499974)
					(mid 345.60002 -205.399894)
					(end 343.7001 -203.499974)
				)
			)
		)
	)
	(zone
		(layer "F.Cu")
		(hatch none 0.5)
		(connect_pads
			(clearance 0)
		)
		(min_thickness 0.25)
		(keepout
			(tracks allowed)
			(vias allowed)
			(pads allowed)
			(copperpour allowed)
			(footprints not_allowed)
		)
		(placement
			(enabled no)
			(sheetname "")
		)
		(fill
			(thermal_gap 0.5)
			(thermal_bridge_width 0.5)
			(island_removal_mode 0)
		)
		(polygon
			(pts
				(arc
					(start 349.600012 -203.499974)
					(mid 345.60002 -207.499966)
					(end 341.600028 -203.499974)
				)
				(arc
					(start 341.600028 -203.499974)
					(mid 345.60002 -199.499982)
					(end 349.600012 -203.499974)
				)
			)
		)
	)
	(zone
		(layer "F.Cu")
		(hatch none 0.5)
		(connect_pads
			(clearance 0)
		)
		(min_thickness 0.25)
		(keepout
			(tracks allowed)
			(vias allowed)
			(pads allowed)
			(copperpour allowed)
			(footprints not_allowed)
		)
		(placement
			(enabled no)
			(sheetname "")
		)
		(fill
			(thermal_gap 0.5)
			(thermal_bridge_width 0.5)
			(island_removal_mode 0)
		)
		(polygon
			(pts
				(arc
					(start 343.7001 -34.500058)
					(mid 345.60002 -32.600138)
					(end 347.49994 -34.500058)
				)
				(arc
					(start 347.49994 -34.500058)
					(mid 345.60002 -36.399978)
					(end 343.7001 -34.500058)
				)
			)
		)
	)
	(zone
		(layer "F.Cu")
		(hatch none 0.5)
		(connect_pads
			(clearance 0)
		)
		(min_thickness 0.25)
		(keepout
			(tracks not_allowed)
			(vias allowed)
			(pads allowed)
			(copperpour not_allowed)
			(footprints allowed)
		)
		(placement
			(enabled no)
			(sheetname "")
		)
		(fill
			(thermal_gap 0.5)
			(thermal_bridge_width 0.5)
			(island_removal_mode 0)
		)
		(polygon
			(pts
				(arc
					(start 349.600012 -34.500058)
					(mid 345.60002 -38.50005)
					(end 341.600028 -34.500058)
				)
				(arc
					(start 341.600028 -34.500058)
					(mid 345.60002 -30.500066)
					(end 349.600012 -34.500058)
				)
			)
		)
	)
	(zone
		(layer "F.Cu")
		(hatch none 0.5)
		(connect_pads
			(clearance 0)
		)
		(min_thickness 0.25)
		(keepout
			(tracks allowed)
			(vias allowed)
			(pads allowed)
			(copperpour allowed)
			(footprints not_allowed)
		)
		(placement
			(enabled no)
			(sheetname "")
		)
		(fill
			(thermal_gap 0.5)
			(thermal_bridge_width 0.5)
			(island_removal_mode 0)
		)
		(polygon
			(pts
				(xy 351.600008 -213.499954) (xy 351.600008 -77.0001) (xy 355.6 -77.0001)
				(arc
					(start 355.6 -212.499956)
					(mid 355.307107 -213.207061)
					(end 354.600002 -213.499954)
				)
			)
		)
	)
	(zone
		(layer "F.Cu")
		(hatch none 0.5)
		(connect_pads
			(clearance 0)
		)
		(min_thickness 0.25)
		(keepout
			(tracks allowed)
			(vias allowed)
			(pads allowed)
			(copperpour allowed)
			(footprints not_allowed)
		)
		(placement
			(enabled no)
			(sheetname "")
		)
		(fill
			(thermal_gap 0.5)
			(thermal_bridge_width 0.5)
			(island_removal_mode 0)
		)
		(polygon
			(pts
				(xy 115.24742 -77.0001) (xy 115.24742 -25.80005) (xy 121.637552 -25.80005) (xy 121.637552 -15.80007)
				(xy 121.637552 0)
				(arc
					(start 119.637556 0)
					(mid 121.051767 0.585785)
					(end 121.637552 1.999996)
				)
				(arc
					(start 121.637552 2.999994)
					(mid 122.223337 4.414205)
					(end 123.637548 4.99999)
				)
				(arc
					(start 330.74991 4.99999)
					(mid 331.457015 4.707097)
					(end 331.749908 3.999992)
				)
				(xy 331.749908 -29.99994) (xy 350.60001 -29.99994) (xy 350.60001 -34.99993) (xy 355.6 -34.99993)
				(xy 355.6 -77.0001) (xy 351.600008 -77.0001) (xy 269.599918 -77.0001) (xy 269.599918 -50.939954)
				(xy 277.599902 -50.939954) (xy 277.599902 -18.940018) (xy 211.600034 -18.940018) (xy 211.600034 -44.99991)
				(xy 204.099922 -44.99991) (xy 204.099922 -52.999894) (xy 191.622172 -52.999894) (xy 191.622172 -77.0001)
			)
		)
	)
	(zone
		(net "GND")
		(layer "F.Cu")
		(hatch none 0.5)
		(connect_pads
			(clearance 0.5)
		)
		(min_thickness 0.25)
		(fill yes
			(thermal_gap 0.5)
			(thermal_bridge_width 0.5)
			(island_removal_mode 0)
		)
		(polygon
			(pts
				(xy 38.1254 -77.851) (xy 37.973 -78.0034) (xy 37.973 -80.137) (xy 39.2176 -81.3816) (xy 41.1988 -81.3816)
				(xy 42.2402 -80.3402) (xy 42.2402 -78.105) (xy 41.9862 -77.851)
			)
		)
	)
	(zone
		(layer "F.Cu")
		(hatch none 0.5)
		(connect_pads
			(clearance 0)
		)
		(min_thickness 0.25)
		(keepout
			(tracks not_allowed)
			(vias allowed)
			(pads allowed)
			(copperpour not_allowed)
			(footprints allowed)
		)
		(placement
			(enabled no)
			(sheetname "")
		)
		(fill
			(thermal_gap 0.5)
			(thermal_bridge_width 0.5)
			(island_removal_mode 0)
		)
		(polygon
			(pts
				(arc
					(start 325.969122 -35.451034)
					(mid 325.458582 -35.961574)
					(end 325.969122 -36.472114)
				)
				(arc
					(start 326.781668 -36.472114)
					(mid 327.292462 -35.961701)
					(end 326.781922 -35.451034)
				)
				(xy 326.621648 -35.451034)
				(arc
					(start 326.621648 -35.52952)
					(mid 326.634535 -35.627321)
					(end 326.672194 -35.718496)
				)
				(arc
					(start 326.672194 -35.718496)
					(mid 326.961419 -36.158825)
					(end 326.550274 -35.829494)
				)
				(arc
					(start 326.550274 -35.829494)
					(mid 326.488008 -35.7028)
					(end 326.460612 -35.564318)
				)
				(xy 326.459596 -35.563048) (xy 326.459596 -35.451034) (xy 326.316848 -35.451034) (xy 326.316848 -35.563048)
				(arc
					(start 326.315578 -35.564318)
					(mid 326.281968 -35.709652)
					(end 326.205342 -35.837622)
				)
				(arc
					(start 326.205342 -35.837622)
					(mid 325.782103 -36.151806)
					(end 326.08901 -35.723322)
				)
				(arc
					(start 326.08901 -35.723322)
					(mid 326.137875 -35.631975)
					(end 326.154796 -35.529774)
				)
				(xy 326.154796 -35.451034)
			)
		)
	)
	(zone
		(layer "F.Cu")
		(hatch none 0.5)
		(connect_pads
			(clearance 0)
		)
		(min_thickness 0.25)
		(keepout
			(tracks not_allowed)
			(vias allowed)
			(pads allowed)
			(copperpour not_allowed)
			(footprints allowed)
		)
		(placement
			(enabled no)
			(sheetname "")
		)
		(fill
			(thermal_gap 0.5)
			(thermal_bridge_width 0.5)
			(island_removal_mode 0)
		)
		(polygon
			(pts
				(arc
					(start 171.532042 -24.982932)
					(mid 171.37108 -24.658632)
					(end 171.304712 -24.30272)
				)
				(arc
					(start 171.304712 -24.30272)
					(mid 171.38252 -23.549101)
					(end 171.467018 -24.301958)
				)
				(arc
					(start 171.467018 -24.301958)
					(mid 171.512867 -24.569332)
					(end 171.619926 -24.818594)
				)
				(xy 171.937426 -24.226266)
				(arc
					(start 171.935394 -24.224996)
					(mid 171.679362 -23.379176)
					(end 170.833542 -23.635208)
				)
				(xy 170.83151 -23.633938) (xy 170.081448 -25.033732) (xy 170.081702 -25.033986)
				(arc
					(start 170.083734 -25.035002)
					(mid 170.33941 -25.880903)
					(end 171.185332 -25.625044)
				)
				(xy 171.187364 -25.626314)
				(arc
					(start 171.363132 -25.298146)
					(mid 171.241013 -25.24514)
					(end 171.109132 -25.227026)
				)
				(arc
					(start 171.078906 -25.227026)
					(mid 171.040713 -25.22836)
					(end 171.002706 -25.23236)
				)
				(arc
					(start 171.002706 -25.23236)
					(mid 170.297158 -25.507947)
					(end 170.923712 -25.082246)
				)
				(arc
					(start 170.923712 -25.082246)
					(mid 170.983808 -25.071377)
					(end 171.044616 -25.065736)
				)
				(xy 171.045378 -25.064974) (xy 171.14266 -25.064974)
				(arc
					(start 171.143676 -25.06599)
					(mid 171.297134 -25.092719)
					(end 171.43984 -25.155144)
				)
			)
		)
	)
	(zone
		(layer "F.Cu")
		(hatch none 0.5)
		(connect_pads
			(clearance 0)
		)
		(min_thickness 0.25)
		(keepout
			(tracks not_allowed)
			(vias allowed)
			(pads allowed)
			(copperpour not_allowed)
			(footprints allowed)
		)
		(placement
			(enabled no)
			(sheetname "")
		)
		(fill
			(thermal_gap 0.5)
			(thermal_bridge_width 0.5)
			(island_removal_mode 0)
		)
		(polygon
			(pts
				(arc
					(start 293.2938 -210.385914)
					(mid 292.783006 -210.896327)
					(end 293.293546 -211.406994)
				)
				(xy 293.46017 -211.406994)
				(arc
					(start 293.46017 -211.297012)
					(mid 293.447635 -211.212851)
					(end 293.411148 -211.135976)
				)
				(arc
					(start 293.411148 -211.135976)
					(mid 293.107728 -210.705122)
					(end 293.52875 -211.022184)
				)
				(arc
					(start 293.52875 -211.022184)
					(mid 293.592387 -211.135602)
					(end 293.620952 -211.262468)
				)
				(xy 293.622222 -211.263738) (xy 293.622222 -211.406994) (xy 293.76497 -211.406994) (xy 293.76497 -211.281264)
				(arc
					(start 293.76624 -211.279994)
					(mid 293.798273 -211.142398)
					(end 293.87038 -211.020914)
				)
				(arc
					(start 293.87038 -211.020914)
					(mid 294.292967 -210.705816)
					(end 293.986966 -211.13496)
				)
				(arc
					(start 293.986966 -211.13496)
					(mid 293.942405 -211.220017)
					(end 293.927022 -211.314792)
				)
				(xy 293.927022 -211.406994)
				(arc
					(start 294.106346 -211.406994)
					(mid 294.616886 -210.896454)
					(end 294.106346 -210.385914)
				)
			)
		)
	)
	(zone
		(layer "F.Cu")
		(hatch none 0.5)
		(connect_pads
			(clearance 0)
		)
		(min_thickness 0.25)
		(keepout
			(tracks not_allowed)
			(vias allowed)
			(pads allowed)
			(copperpour not_allowed)
			(footprints allowed)
		)
		(placement
			(enabled no)
			(sheetname "")
		)
		(fill
			(thermal_gap 0.5)
			(thermal_bridge_width 0.5)
			(island_removal_mode 0)
		)
		(polygon
			(pts
				(arc
					(start 289.2298 -34.503614)
					(mid 288.71926 -35.014154)
					(end 289.2298 -35.524694)
				)
				(arc
					(start 290.042346 -35.524694)
					(mid 290.55314 -35.014281)
					(end 290.0426 -34.503614)
				)
				(xy 289.882326 -34.503614)
				(arc
					(start 289.882326 -34.5821)
					(mid 289.895213 -34.679901)
					(end 289.932872 -34.771076)
				)
				(arc
					(start 289.932872 -34.771076)
					(mid 290.222097 -35.211405)
					(end 289.810952 -34.882074)
				)
				(arc
					(start 289.810952 -34.882074)
					(mid 289.748686 -34.75538)
					(end 289.72129 -34.616898)
				)
				(xy 289.720274 -34.615628) (xy 289.720274 -34.503614) (xy 289.577526 -34.503614) (xy 289.577526 -34.615628)
				(arc
					(start 289.576256 -34.616898)
					(mid 289.542646 -34.762232)
					(end 289.46602 -34.890202)
				)
				(arc
					(start 289.46602 -34.890202)
					(mid 289.042781 -35.204386)
					(end 289.349688 -34.775902)
				)
				(arc
					(start 289.349688 -34.775902)
					(mid 289.398553 -34.684555)
					(end 289.415474 -34.582354)
				)
				(xy 289.415474 -34.503614)
			)
		)
	)
	(zone
		(layer "F.Cu")
		(hatch none 0.5)
		(connect_pads
			(clearance 0)
		)
		(min_thickness 0.25)
		(keepout
			(tracks not_allowed)
			(vias allowed)
			(pads allowed)
			(copperpour not_allowed)
			(footprints allowed)
		)
		(placement
			(enabled no)
			(sheetname "")
		)
		(fill
			(thermal_gap 0.5)
			(thermal_bridge_width 0.5)
			(island_removal_mode 0)
		)
		(polygon
			(pts
				(arc
					(start 343.7001 -34.500058)
					(mid 345.60002 -32.600138)
					(end 347.49994 -34.500058)
				)
				(arc
					(start 347.49994 -34.500058)
					(mid 345.60002 -36.399978)
					(end 343.7001 -34.500058)
				)
			)
		)
	)
	(zone
		(layer "F.Cu")
		(hatch none 0.5)
		(connect_pads
			(clearance 0)
		)
		(min_thickness 0.25)
		(keepout
			(tracks not_allowed)
			(vias allowed)
			(pads allowed)
			(copperpour not_allowed)
			(footprints allowed)
		)
		(placement
			(enabled no)
			(sheetname "")
		)
		(fill
			(thermal_gap 0.5)
			(thermal_bridge_width 0.5)
			(island_removal_mode 0)
		)
		(polygon
			(pts
				(arc
					(start 20.396454 -86.91626)
					(mid 19.88566 -87.426673)
					(end 20.3962 -87.93734)
				)
				(arc
					(start 21.209 -87.93734)
					(mid 21.71954 -87.4268)
					(end 21.209 -86.91626)
				)
				(xy 21.030184 -86.91626)
				(arc
					(start 21.030184 -86.995)
					(mid 21.043155 -87.09705)
					(end 21.081238 -87.192612)
				)
				(arc
					(start 21.081238 -87.192612)
					(mid 21.403953 -87.6089)
					(end 20.966684 -87.315294)
				)
				(arc
					(start 20.966684 -87.315294)
					(mid 20.898655 -87.178995)
					(end 20.869148 -87.029544)
				)
				(xy 20.868132 -87.028528) (xy 20.868132 -86.91626) (xy 20.725384 -86.91626) (xy 20.725384 -87.028528)
				(arc
					(start 20.724368 -87.029544)
					(mid 20.697068 -87.173947)
					(end 20.634452 -87.306912)
				)
				(arc
					(start 20.634452 -87.306912)
					(mid 20.207724 -87.615932)
					(end 20.515834 -87.188548)
				)
				(arc
					(start 20.515834 -87.188548)
					(mid 20.551299 -87.094645)
					(end 20.563332 -86.995)
				)
				(xy 20.563332 -86.91626)
			)
		)
	)
	(zone
		(layer "F.Cu")
		(hatch none 0.5)
		(connect_pads
			(clearance 0)
		)
		(min_thickness 0.25)
		(keepout
			(tracks not_allowed)
			(vias allowed)
			(pads allowed)
			(copperpour not_allowed)
			(footprints allowed)
		)
		(placement
			(enabled no)
			(sheetname "")
		)
		(fill
			(thermal_gap 0.5)
			(thermal_bridge_width 0.5)
			(island_removal_mode 0)
		)
		(polygon
			(pts
				(arc
					(start 158.68523 -20.425156)
					(mid 158.429554 -19.579255)
					(end 157.583632 -19.835114)
				)
				(xy 157.5816 -19.833844) (xy 156.831538 -21.233892)
				(arc
					(start 156.83357 -21.235162)
					(mid 157.089602 -22.080982)
					(end 157.935422 -21.82495)
				)
				(xy 157.937454 -21.82622) (xy 158.112968 -21.498814) (xy 157.829504 -21.21535) (xy 157.734508 -21.120608)
				(arc
					(start 157.734254 -21.120354)
					(mid 157.597514 -21.076422)
					(end 157.482032 -21.161756)
				)
				(arc
					(start 157.482032 -21.161756)
					(mid 157.37134 -21.910825)
					(end 157.312614 -21.155914)
				)
				(arc
					(start 157.312614 -21.155914)
					(mid 157.519916 -20.929401)
					(end 157.822392 -20.982178)
				)
				(xy 157.825186 -20.982178) (xy 157.848554 -21.005546) (xy 157.848808 -21.0058) (xy 157.920182 -21.07692)
				(xy 157.943804 -21.100542) (xy 157.96387 -21.120608) (xy 157.96768 -21.124164) (xy 157.96768 -21.124418)
				(xy 158.192978 -21.349462)
				(arc
					(start 158.271718 -21.202396)
					(mid 158.190128 -21.069508)
					(end 158.126684 -20.92706)
				)
				(arc
					(start 158.126684 -20.92706)
					(mid 158.113052 -20.888296)
					(end 158.100776 -20.849082)
				)
				(xy 158.100522 -20.848574)
				(arc
					(start 158.090616 -20.810982)
					(mid 158.065123 -20.682203)
					(end 158.05404 -20.551394)
				)
				(xy 158.053532 -20.550886)
				(arc
					(start 158.053532 -20.502372)
					(mid 158.134558 -19.74893)
					(end 158.215584 -20.502372)
				)
				(arc
					(start 158.215584 -20.517358)
					(mid 158.223609 -20.645238)
					(end 158.247588 -20.771104)
				)
				(xy 158.247588 -20.771358)
				(arc
					(start 158.256224 -20.803616)
					(mid 158.266821 -20.837337)
					(end 158.278576 -20.870672)
				)
				(arc
					(start 158.278576 -20.870926)
					(mid 158.314984 -20.957092)
					(end 158.359094 -21.039582)
				)
				(xy 158.687516 -20.426426) (xy 158.687262 -20.426172)
			)
		)
	)
	(zone
		(layer "F.Cu")
		(hatch none 0.5)
		(connect_pads
			(clearance 0)
		)
		(min_thickness 0.25)
		(keepout
			(tracks not_allowed)
			(vias allowed)
			(pads allowed)
			(copperpour not_allowed)
			(footprints allowed)
		)
		(placement
			(enabled no)
			(sheetname "")
		)
		(fill
			(thermal_gap 0.5)
			(thermal_bridge_width 0.5)
			(island_removal_mode 0)
		)
		(polygon
			(pts
				(arc
					(start 286.893762 -210.385914)
					(mid 286.383222 -210.896454)
					(end 286.893762 -211.406994)
				)
				(xy 287.060386 -211.406994)
				(arc
					(start 287.060386 -211.299552)
					(mid 287.047647 -211.21418)
					(end 287.010602 -211.13623)
				)
				(arc
					(start 287.010602 -211.13623)
					(mid 286.708929 -210.70415)
					(end 287.128712 -211.022692)
				)
				(arc
					(start 287.128712 -211.022692)
					(mid 287.192481 -211.137023)
					(end 287.221168 -211.264754)
				)
				(xy 287.222438 -211.266024) (xy 287.222438 -211.406994) (xy 287.365186 -211.406994) (xy 287.365186 -211.26577)
				(arc
					(start 287.365948 -211.265008)
					(mid 287.393505 -211.140822)
					(end 287.458658 -211.031582)
				)
				(xy 287.458658 -211.02955)
				(arc
					(start 287.46958 -211.018628)
					(mid 287.895505 -210.707765)
					(end 287.584642 -211.13369)
				)
				(arc
					(start 287.584642 -211.13369)
					(mid 287.542052 -211.20615)
					(end 287.527238 -211.288884)
				)
				(xy 287.527238 -211.299552) (xy 287.527238 -211.406994)
				(arc
					(start 287.706308 -211.406994)
					(mid 288.217102 -210.896581)
					(end 287.706562 -210.385914)
				)
			)
		)
	)
	(zone
		(layer "F.Cu")
		(hatch none 0.5)
		(connect_pads
			(clearance 0)
		)
		(min_thickness 0.25)
		(keepout
			(tracks not_allowed)
			(vias allowed)
			(pads allowed)
			(copperpour not_allowed)
			(footprints allowed)
		)
		(placement
			(enabled no)
			(sheetname "")
		)
		(fill
			(thermal_gap 0.5)
			(thermal_bridge_width 0.5)
			(island_removal_mode 0)
		)
		(polygon
			(pts
				(arc
					(start 144.464532 -13.74013)
					(mid 144.492485 -13.449372)
					(end 144.244314 -13.295376)
				)
				(xy 143.773144 -13.295376) (xy 143.76273 -13.295376) (xy 143.581374 -13.633704) (xy 143.581628 -13.633958)
				(arc
					(start 143.58366 -13.634974)
					(mid 143.839336 -14.480875)
					(end 144.685258 -14.225016)
				)
				(xy 144.68729 -14.226286) (xy 145.437352 -12.826238)
				(arc
					(start 145.43532 -12.824968)
					(mid 145.179288 -11.979148)
					(end 144.333468 -12.23518)
				)
				(xy 144.331436 -12.23391) (xy 144.01292 -12.828524)
				(arc
					(start 144.0688 -12.828524)
					(mid 144.214607 -12.817446)
					(end 144.35709 -12.784582)
				)
				(arc
					(start 144.35709 -12.784582)
					(mid 144.453337 -12.749041)
					(end 144.545304 -12.703556)
				)
				(arc
					(start 144.545304 -12.703556)
					(mid 145.178068 -12.287517)
					(end 144.649952 -12.830302)
				)
				(arc
					(start 144.649952 -12.830302)
					(mid 144.530887 -12.89216)
					(end 144.40535 -12.939522)
				)
				(arc
					(start 144.40535 -12.939522)
					(mid 144.255809 -12.975057)
					(end 144.102836 -12.990068)
				)
				(xy 144.102328 -12.990576) (xy 143.926052 -12.990576) (xy 143.849598 -13.133324) (xy 144.277842 -13.133324)
				(arc
					(start 144.279366 -13.134594)
					(mid 144.664717 -13.445665)
					(end 144.515078 -13.917676)
				)
				(arc
					(start 144.515078 -13.917676)
					(mid 143.767946 -14.034447)
					(end 144.464532 -13.74013)
				)
			)
		)
	)
	(zone
		(layer "F.Cu")
		(hatch none 0.5)
		(connect_pads
			(clearance 0)
		)
		(min_thickness 0.25)
		(keepout
			(tracks not_allowed)
			(vias allowed)
			(pads allowed)
			(copperpour not_allowed)
			(footprints allowed)
		)
		(placement
			(enabled no)
			(sheetname "")
		)
		(fill
			(thermal_gap 0.5)
			(thermal_bridge_width 0.5)
			(island_removal_mode 0)
		)
		(polygon
			(pts
				(arc
					(start 324.31228 -21.199602)
					(mid 324.375852 -21.294557)
					(end 324.414642 -21.40204)
				)
				(arc
					(start 324.505066 -21.233384)
					(mid 324.453779 -21.148561)
					(end 324.389496 -21.07311)
				)
				(arc
					(start 324.389496 -21.07311)
					(mid 324.333136 -20.993896)
					(end 324.305676 -20.900644)
				)
				(xy 324.30339 -20.898358)
				(arc
					(start 324.30339 -20.502372)
					(mid 324.384416 -19.74893)
					(end 324.465442 -20.502372)
				)
				(arc
					(start 324.465442 -20.86483)
					(mid 324.475598 -20.915418)
					(end 324.504304 -20.958302)
				)
				(arc
					(start 324.504304 -20.958302)
					(mid 324.551738 -21.010479)
					(end 324.59422 -21.06676)
				)
				(xy 324.937374 -20.426426) (xy 324.93712 -20.426172)
				(arc
					(start 324.935088 -20.425156)
					(mid 324.679412 -19.579255)
					(end 323.83349 -19.835114)
				)
				(xy 323.831458 -19.833844) (xy 323.081396 -21.233892)
				(arc
					(start 323.083428 -21.235162)
					(mid 323.33946 -22.080982)
					(end 324.18528 -21.82495)
				)
				(xy 324.187312 -21.82622) (xy 324.264274 -21.68271)
				(arc
					(start 324.264274 -21.506688)
					(mid 324.240719 -21.388739)
					(end 324.17385 -21.288756)
				)
				(arc
					(start 323.994272 -21.108924)
					(mid 323.937078 -21.071638)
					(end 323.870066 -21.058632)
				)
				(arc
					(start 323.820282 -21.058632)
					(mid 323.784954 -21.065753)
					(end 323.755004 -21.08581)
				)
				(arc
					(start 323.755004 -21.08581)
					(mid 323.730582 -21.119087)
					(end 323.717412 -21.1582)
				)
				(arc
					(start 323.717412 -21.1582)
					(mid 323.632805 -21.911128)
					(end 323.553328 -21.157692)
				)
				(xy 323.553328 -21.147532)
				(arc
					(start 323.55536 -21.145246)
					(mid 323.583172 -21.051013)
					(end 323.640196 -20.971002)
				)
				(arc
					(start 323.640196 -20.971002)
					(mid 323.706373 -20.923376)
					(end 323.784214 -20.89912)
				)
				(xy 323.786754 -20.89658) (xy 323.903594 -20.89658)
				(arc
					(start 323.905372 -20.898358)
					(mid 324.000302 -20.92242)
					(end 324.084442 -20.972526)
				)
				(xy 324.086982 -20.972526) (xy 324.108318 -20.993862) (xy 324.110858 -20.996402) (xy 324.31228 -21.197824)
			)
		)
	)
	(zone
		(layer "F.Cu")
		(hatch none 0.5)
		(connect_pads
			(clearance 0)
		)
		(min_thickness 0.25)
		(keepout
			(tracks not_allowed)
			(vias allowed)
			(pads allowed)
			(copperpour not_allowed)
			(footprints allowed)
		)
		(placement
			(enabled no)
			(sheetname "")
		)
		(fill
			(thermal_gap 0.5)
			(thermal_bridge_width 0.5)
			(island_removal_mode 0)
		)
		(polygon
			(pts
				(arc
					(start 203.29398 -210.385914)
					(mid 202.783186 -210.896327)
					(end 203.293726 -211.406994)
				)
				(xy 203.46035 -211.406994)
				(arc
					(start 203.46035 -211.278724)
					(mid 203.448301 -211.202982)
					(end 203.41336 -211.134706)
				)
				(arc
					(start 203.41336 -211.134706)
					(mid 203.107026 -210.70614)
					(end 203.529692 -211.02066)
				)
				(arc
					(start 203.529692 -211.02066)
					(mid 203.592243 -211.125237)
					(end 203.620878 -211.243672)
				)
				(xy 203.622402 -211.245196) (xy 203.622402 -211.406994) (xy 203.76515 -211.406994) (xy 203.76515 -211.255102)
				(arc
					(start 203.766674 -211.253578)
					(mid 203.795534 -211.135807)
					(end 203.858368 -211.03209)
				)
				(xy 203.858368 -211.030058)
				(arc
					(start 203.869544 -211.018882)
					(mid 204.294284 -210.707143)
					(end 203.98486 -211.13369)
				)
				(arc
					(start 203.98486 -211.13369)
					(mid 203.942079 -211.205969)
					(end 203.927202 -211.28863)
				)
				(xy 203.927202 -211.406994)
				(arc
					(start 204.106526 -211.406994)
					(mid 204.617066 -210.896454)
					(end 204.106526 -210.385914)
				)
			)
		)
	)
	(zone
		(layer "F.Cu")
		(hatch none 0.5)
		(connect_pads
			(clearance 0)
		)
		(min_thickness 0.25)
		(keepout
			(tracks not_allowed)
			(vias allowed)
			(pads allowed)
			(copperpour not_allowed)
			(footprints allowed)
		)
		(placement
			(enabled no)
			(sheetname "")
		)
		(fill
			(thermal_gap 0.5)
			(thermal_bridge_width 0.5)
			(island_removal_mode 0)
		)
		(polygon
			(pts
				(arc
					(start 183.59374 -28.994354)
					(mid 183.083327 -28.48356)
					(end 182.57266 -28.9941)
				)
				(xy 182.57266 -29.167074)
				(arc
					(start 182.660544 -29.167074)
					(mid 182.756199 -29.152731)
					(end 182.843424 -29.11094)
				)
				(arc
					(start 182.843424 -29.11094)
					(mid 183.275583 -28.808934)
					(end 182.956708 -29.228796)
				)
				(arc
					(start 182.956708 -29.228796)
					(mid 182.833264 -29.297422)
					(end 182.695342 -29.327856)
				)
				(xy 182.694072 -29.329126) (xy 182.57266 -29.329126) (xy 182.57266 -29.471874) (xy 182.673752 -29.471874)
				(arc
					(start 182.675022 -29.47289)
					(mid 182.821792 -29.503369)
					(end 182.954422 -29.57322)
				)
				(arc
					(start 182.954422 -29.57322)
					(mid 183.278017 -29.989081)
					(end 182.842154 -29.692854)
				)
				(arc
					(start 182.842154 -29.692854)
					(mid 182.745401 -29.648955)
					(end 182.640224 -29.633926)
				)
				(xy 182.57266 -29.633926)
				(arc
					(start 182.57266 -29.8069)
					(mid 183.0832 -30.31744)
					(end 183.59374 -29.8069)
				)
			)
		)
	)
	(zone
		(layer "F.Cu")
		(hatch none 0.5)
		(connect_pads
			(clearance 0)
		)
		(min_thickness 0.25)
		(keepout
			(tracks allowed)
			(vias allowed)
			(pads allowed)
			(copperpour allowed)
			(footprints allowed)
		)
		(placement
			(enabled no)
			(sheetname "")
		)
		(fill
			(thermal_gap 0.5)
			(thermal_bridge_width 0.5)
			(island_removal_mode 0)
		)
		(polygon
			(pts
				(xy 21.849588 -123.79579) (xy 21.849588 -125.82779) (xy 19.309588 -125.82779) (xy 19.309588 -123.79579)
			)
		)
	)
	(zone
		(layer "F.Cu")
		(hatch none 0.5)
		(connect_pads
			(clearance 0)
		)
		(min_thickness 0.25)
		(keepout
			(tracks not_allowed)
			(vias allowed)
			(pads allowed)
			(copperpour not_allowed)
			(footprints allowed)
		)
		(placement
			(enabled no)
			(sheetname "")
		)
		(fill
			(thermal_gap 0.5)
			(thermal_bridge_width 0.5)
			(island_removal_mode 0)
		)
		(polygon
			(pts
				(xy 158.118048 -25.289002) (xy 158.113984 -25.284684) (xy 158.112968 -25.283668)
				(arc
					(start 157.749494 -24.91994)
					(mid 157.695771 -24.884043)
					(end 157.6324 -24.871426)
				)
				(arc
					(start 157.6324 -24.871426)
					(mid 157.581921 -24.877559)
					(end 157.534356 -24.895556)
				)
				(arc
					(start 157.534356 -24.895556)
					(mid 157.509029 -24.92792)
					(end 157.489144 -24.963882)
				)
				(arc
					(start 157.489144 -24.963882)
					(mid 157.363915 -25.710518)
					(end 157.31998 -24.954738)
				)
				(arc
					(start 157.31998 -24.954738)
					(mid 157.361955 -24.857284)
					(end 157.426914 -24.773382)
				)
				(arc
					(start 157.426914 -24.773382)
					(mid 157.434642 -24.766635)
					(end 157.44317 -24.760936)
				)
				(arc
					(start 157.44317 -24.760936)
					(mid 157.534333 -24.722481)
					(end 157.6324 -24.709374)
				)
				(arc
					(start 157.632908 -24.709374)
					(mid 157.741397 -24.728034)
					(end 157.837632 -24.78151)
				)
				(xy 157.840426 -24.78151) (xy 157.864302 -24.805386) (xy 158.198058 -25.13965)
				(arc
					(start 158.270702 -25.004268)
					(mid 158.115427 -24.738881)
					(end 158.05404 -24.437594)
				)
				(xy 158.053532 -24.436832)
				(arc
					(start 158.053532 -24.302466)
					(mid 158.134558 -23.549024)
					(end 158.215584 -24.302466)
				)
				(arc
					(start 158.215584 -24.403304)
					(mid 158.251245 -24.635935)
					(end 158.354776 -24.847296)
				)
				(xy 158.687516 -24.226266)
				(arc
					(start 158.685484 -24.224996)
					(mid 158.429452 -23.379176)
					(end 157.583632 -23.635208)
				)
				(xy 157.5816 -23.633938) (xy 156.831538 -25.033732) (xy 156.831792 -25.033986)
				(arc
					(start 156.833824 -25.035002)
					(mid 157.0895 -25.880903)
					(end 157.935422 -25.625044)
				)
				(xy 157.937454 -25.626314)
			)
		)
	)
	(zone
		(layer "F.Cu")
		(hatch none 0.5)
		(connect_pads
			(clearance 0)
		)
		(min_thickness 0.25)
		(keepout
			(tracks allowed)
			(vias allowed)
			(pads allowed)
			(copperpour allowed)
			(footprints allowed)
		)
		(placement
			(enabled no)
			(sheetname "")
		)
		(fill
			(thermal_gap 0.5)
			(thermal_bridge_width 0.5)
			(island_removal_mode 0)
		)
		(polygon
			(pts
				(xy 21.142198 -50.880772) (xy 20.69719 -50.880772) (xy 20.69338 -50.884582) (xy 19.878294 -50.884582)
				(xy 19.429476 -50.435764) (xy 19.429476 -49.882552) (xy 19.764248 -49.54778) (xy 21.092922 -49.54778)
				(xy 21.321014 -49.775872) (xy 21.321014 -50.701956)
			)
		)
	)
	(zone
		(layer "F.Cu")
		(hatch none 0.5)
		(connect_pads
			(clearance 0)
		)
		(min_thickness 0.25)
		(keepout
			(tracks not_allowed)
			(vias allowed)
			(pads allowed)
			(copperpour not_allowed)
			(footprints allowed)
		)
		(placement
			(enabled no)
			(sheetname "")
		)
		(fill
			(thermal_gap 0.5)
			(thermal_bridge_width 0.5)
			(island_removal_mode 0)
		)
		(polygon
			(pts
				(arc
					(start 9.6647 -54.538372)
					(mid 9.15416 -55.048912)
					(end 9.6647 -55.559452)
				)
				(arc
					(start 10.477246 -55.559452)
					(mid 10.98804 -55.049039)
					(end 10.4775 -54.538372)
				)
				(xy 10.307828 -54.538372) (xy 10.307828 -54.787038)
				(arc
					(start 10.340594 -54.820058)
					(mid 10.66607 -55.237482)
					(end 10.248646 -54.912006)
				)
				(xy 10.177526 -54.840886) (xy 10.177272 -54.840886) (xy 10.177272 -54.538372) (xy 9.964928 -54.538372)
				(xy 9.964928 -54.840886) (xy 9.964674 -54.840886)
				(arc
					(start 9.893554 -54.912006)
					(mid 9.47613 -55.237482)
					(end 9.801606 -54.820058)
				)
				(xy 9.834372 -54.787038) (xy 9.834372 -54.538372)
			)
		)
	)
	(zone
		(net "P3V3_STBY")
		(layer "F.Cu")
		(hatch none 0.5)
		(connect_pads
			(clearance 0.5)
		)
		(min_thickness 0.25)
		(fill yes
			(thermal_gap 0.5)
			(thermal_bridge_width 0.5)
			(island_removal_mode 0)
		)
		(polygon
			(pts
				(xy 72.9234 -158.5468) (xy 72.7964 -158.6738) (xy 72.7964 -161.2392) (xy 73.0504 -161.4932) (xy 74.6252 -161.4932)
				(xy 74.7522 -161.3662) (xy 74.7522 -158.6738) (xy 74.6252 -158.5468)
			)
		)
		(polygon
			(pts
				(xy 73.8124 -160.401) (xy 73.6092 -160.401) (xy 73.6092 -160.6042) (xy 73.8124 -160.6042)
			)
		)
		(polygon
			(pts
				(xy 73.8124 -159.5374) (xy 73.6092 -159.5374) (xy 73.6092 -159.7406) (xy 73.8124 -159.7406)
			)
		)
	)
	(zone
		(net "GND")
		(layer "F.Cu")
		(hatch none 0.5)
		(connect_pads
			(clearance 0.5)
		)
		(min_thickness 0.25)
		(fill yes
			(thermal_gap 0.5)
			(thermal_bridge_width 0.5)
			(island_removal_mode 0)
		)
		(polygon
			(pts
				(xy 253.276862 -7.095998) (xy 253.112016 -7.260844) (xy 253.112016 -9.470898) (xy 253.117604 -9.476486)
				(xy 254.113538 -9.476486) (xy 254.124714 -9.46531) (xy 254.124714 -7.828788) (xy 254.127508 -7.828788)
				(xy 254.228092 -7.728204) (xy 254.446278 -7.728204) (xy 254.561086 -7.613396) (xy 254.561086 -7.188454)
				(xy 254.46863 -7.095998)
			)
		)
	)
	(zone
		(layer "F.Cu")
		(hatch none 0.5)
		(connect_pads
			(clearance 0)
		)
		(min_thickness 0.25)
		(keepout
			(tracks allowed)
			(vias allowed)
			(pads allowed)
			(copperpour allowed)
			(footprints not_allowed)
		)
		(placement
			(enabled no)
			(sheetname "")
		)
		(fill
			(thermal_gap 0.5)
			(thermal_bridge_width 0.5)
			(island_removal_mode 0)
		)
		(polygon
			(pts
				(arc
					(start 76.049886 -14.200124)
					(mid 74.44994 -15.80007)
					(end 72.849994 -14.200124)
				)
				(arc
					(start 72.849994 -14.200124)
					(mid 74.44994 -12.600178)
					(end 76.049886 -14.200124)
				)
			)
		)
	)
	(zone
		(layer "F.Cu")
		(hatch none 0.5)
		(connect_pads
			(clearance 0)
		)
		(min_thickness 0.25)
		(keepout
			(tracks not_allowed)
			(vias allowed)
			(pads allowed)
			(copperpour not_allowed)
			(footprints allowed)
		)
		(placement
			(enabled no)
			(sheetname "")
		)
		(fill
			(thermal_gap 0.5)
			(thermal_bridge_width 0.5)
			(island_removal_mode 0)
		)
		(polygon
			(pts
				(arc
					(start 299.430948 -35.678872)
					(mid 298.920154 -36.189285)
					(end 299.430694 -36.699952)
				)
				(arc
					(start 300.243494 -36.699952)
					(mid 300.754034 -36.189412)
					(end 300.243494 -35.678872)
				)
				(xy 300.08322 -35.678872)
				(arc
					(start 300.08322 -35.757358)
					(mid 300.096107 -35.855159)
					(end 300.133766 -35.946334)
				)
				(arc
					(start 300.133766 -35.946334)
					(mid 300.422991 -36.386663)
					(end 300.011846 -36.057332)
				)
				(arc
					(start 300.011846 -36.057332)
					(mid 299.94958 -35.930638)
					(end 299.922184 -35.792156)
				)
				(xy 299.921168 -35.790886) (xy 299.921168 -35.678872) (xy 299.77842 -35.678872) (xy 299.77842 -35.790886)
				(arc
					(start 299.77715 -35.792156)
					(mid 299.74354 -35.93749)
					(end 299.666914 -36.06546)
				)
				(arc
					(start 299.666914 -36.06546)
					(mid 299.243675 -36.379644)
					(end 299.550582 -35.95116)
				)
				(arc
					(start 299.550582 -35.95116)
					(mid 299.599447 -35.859813)
					(end 299.616368 -35.757612)
				)
				(xy 299.616368 -35.678872)
			)
		)
	)
	(zone
		(layer "F.Cu")
		(hatch none 0.5)
		(connect_pads
			(clearance 0)
		)
		(min_thickness 0.25)
		(keepout
			(tracks allowed)
			(vias allowed)
			(pads allowed)
			(copperpour allowed)
			(footprints not_allowed)
		)
		(placement
			(enabled no)
			(sheetname "")
		)
		(fill
			(thermal_gap 0.5)
			(thermal_bridge_width 0.5)
			(island_removal_mode 0)
		)
		(polygon
			(pts
				(xy 3.999992 -77.0001) (xy 3.999992 -213.499954) (xy 90.950034 -213.499954) (xy 90.950034 -77.0001)
			)
		)
	)
	(zone
		(layer "F.Cu")
		(hatch none 0.5)
		(connect_pads
			(clearance 0)
		)
		(min_thickness 0.25)
		(keepout
			(tracks not_allowed)
			(vias allowed)
			(pads allowed)
			(copperpour not_allowed)
			(footprints allowed)
		)
		(placement
			(enabled no)
			(sheetname "")
		)
		(fill
			(thermal_gap 0.5)
			(thermal_bridge_width 0.5)
			(island_removal_mode 0)
		)
		(polygon
			(pts
				(arc
					(start 98.094038 -210.385914)
					(mid 97.583244 -210.896327)
					(end 98.093784 -211.406994)
				)
				(xy 98.260408 -211.406994)
				(arc
					(start 98.260408 -211.2772)
					(mid 98.248317 -211.202193)
					(end 98.213418 -211.134706)
				)
				(arc
					(start 98.213418 -211.134706)
					(mid 97.907084 -210.70614)
					(end 98.32975 -211.02066)
				)
				(arc
					(start 98.32975 -211.02066)
					(mid 98.392259 -211.124447)
					(end 98.420936 -211.242148)
				)
				(xy 98.42246 -211.243672) (xy 98.42246 -211.406994) (xy 98.565208 -211.406994) (xy 98.565208 -211.255864)
				(arc
					(start 98.566732 -211.25434)
					(mid 98.595734 -211.13589)
					(end 98.658934 -211.031582)
				)
				(xy 98.658934 -211.02955)
				(arc
					(start 98.669602 -211.018882)
					(mid 99.094342 -210.707143)
					(end 98.784918 -211.13369)
				)
				(arc
					(start 98.784918 -211.13369)
					(mid 98.742129 -211.206373)
					(end 98.72726 -211.289392)
				)
				(xy 98.72726 -211.406994)
				(arc
					(start 98.906584 -211.406994)
					(mid 99.417124 -210.896454)
					(end 98.906584 -210.385914)
				)
			)
		)
	)
	(zone
		(layer "F.Cu")
		(hatch none 0.5)
		(connect_pads
			(clearance 0)
		)
		(min_thickness 0.25)
		(keepout
			(tracks allowed)
			(vias allowed)
			(pads allowed)
			(copperpour allowed)
			(footprints not_allowed)
		)
		(placement
			(enabled no)
			(sheetname "")
		)
		(fill
			(thermal_gap 0.5)
			(thermal_bridge_width 0.5)
			(island_removal_mode 0)
		)
		(polygon
			(pts
				(arc
					(start 340.350094 -14.200124)
					(mid 338.750148 -15.80007)
					(end 337.149948 -14.200124)
				)
				(arc
					(start 337.149948 -14.200124)
					(mid 338.750148 -12.599924)
					(end 340.350094 -14.200124)
				)
			)
		)
	)
	(zone
		(layer "F.Cu")
		(hatch none 0.5)
		(connect_pads
			(clearance 0)
		)
		(min_thickness 0.25)
		(keepout
			(tracks not_allowed)
			(vias allowed)
			(pads allowed)
			(copperpour not_allowed)
			(footprints allowed)
		)
		(placement
			(enabled no)
			(sheetname "")
		)
		(fill
			(thermal_gap 0.5)
			(thermal_bridge_width 0.5)
			(island_removal_mode 0)
		)
		(polygon
			(pts
				(arc
					(start 169.693844 -210.385914)
					(mid 169.18305 -210.896327)
					(end 169.69359 -211.406994)
				)
				(xy 169.860214 -211.406994)
				(arc
					(start 169.860214 -211.288376)
					(mid 169.847917 -211.208131)
					(end 169.812208 -211.135214)
				)
				(arc
					(start 169.812208 -211.135214)
					(mid 169.507998 -210.704891)
					(end 169.929302 -211.021422)
				)
				(arc
					(start 169.929302 -211.021422)
					(mid 169.992227 -211.130724)
					(end 170.020742 -211.253578)
				)
				(xy 170.022266 -211.255102) (xy 170.022266 -211.406994) (xy 170.165014 -211.406994) (xy 170.165014 -211.255356)
				(arc
					(start 170.166284 -211.254086)
					(mid 170.19385 -211.137568)
					(end 170.255438 -211.034884)
				)
				(xy 170.255438 -211.032598)
				(arc
					(start 170.269408 -211.018628)
					(mid 170.69492 -210.707924)
					(end 170.384216 -211.133436)
				)
				(arc
					(start 170.384216 -211.133436)
					(mid 170.341774 -211.203765)
					(end 170.327066 -211.284566)
				)
				(xy 170.327066 -211.28482) (xy 170.327066 -211.288884) (xy 170.327066 -211.406994)
				(arc
					(start 170.50639 -211.406994)
					(mid 171.01693 -210.896454)
					(end 170.50639 -210.385914)
				)
			)
		)
	)
	(zone
		(layer "F.Cu")
		(hatch none 0.5)
		(connect_pads
			(clearance 0)
		)
		(min_thickness 0.25)
		(keepout
			(tracks allowed)
			(vias allowed)
			(pads allowed)
			(copperpour allowed)
			(footprints not_allowed)
		)
		(placement
			(enabled no)
			(sheetname "")
		)
		(fill
			(thermal_gap 0.5)
			(thermal_bridge_width 0.5)
			(island_removal_mode 0)
		)
		(polygon
			(pts
				(xy 44.500038 -47.500032) (xy 44.500038 -49.9999) (xy 56.500014 -49.9999) (xy 56.500014 -47.500032)
			)
		)
	)
	(zone
		(layer "F.Cu")
		(hatch none 0.5)
		(connect_pads
			(clearance 0)
		)
		(min_thickness 0.25)
		(keepout
			(tracks allowed)
			(vias allowed)
			(pads allowed)
			(copperpour allowed)
			(footprints not_allowed)
		)
		(placement
			(enabled no)
			(sheetname "")
		)
		(fill
			(thermal_gap 0.5)
			(thermal_bridge_width 0.5)
			(island_removal_mode 0)
		)
		(polygon
			(pts
				(arc
					(start 11.712194 -60.300108)
					(mid 13.812266 -58.200036)
					(end 15.912084 -60.300108)
				)
				(arc
					(start 15.912084 -60.300108)
					(mid 13.812266 -62.399926)
					(end 11.712194 -60.300108)
				)
			)
		)
	)
	(zone
		(layer "F.Cu")
		(hatch none 0.5)
		(connect_pads
			(clearance 0)
		)
		(min_thickness 0.25)
		(keepout
			(tracks not_allowed)
			(vias allowed)
			(pads allowed)
			(copperpour not_allowed)
			(footprints allowed)
		)
		(placement
			(enabled no)
			(sheetname "")
		)
		(fill
			(thermal_gap 0.5)
			(thermal_bridge_width 0.5)
			(island_removal_mode 0)
		)
		(polygon
			(pts
				(arc
					(start 322.062348 -24.999696)
					(mid 322.12592 -25.094651)
					(end 322.16471 -25.202134)
				)
				(arc
					(start 322.25488 -25.033478)
					(mid 322.203716 -24.948669)
					(end 322.139564 -24.873204)
				)
				(arc
					(start 322.139564 -24.873204)
					(mid 322.083204 -24.79399)
					(end 322.055744 -24.700738)
				)
				(xy 322.053458 -24.698452)
				(arc
					(start 322.053458 -24.302466)
					(mid 322.134484 -23.549024)
					(end 322.21551 -24.302466)
				)
				(arc
					(start 322.21551 -24.664924)
					(mid 322.225666 -24.715512)
					(end 322.254372 -24.758396)
				)
				(arc
					(start 322.254372 -24.758396)
					(mid 322.301791 -24.810453)
					(end 322.344288 -24.8666)
				)
				(xy 322.687442 -24.226266)
				(arc
					(start 322.68541 -24.224996)
					(mid 322.429378 -23.379176)
					(end 321.583558 -23.635208)
				)
				(xy 321.581526 -23.633938) (xy 320.831464 -25.033732) (xy 320.831718 -25.033986)
				(arc
					(start 320.83375 -25.035002)
					(mid 321.089426 -25.880903)
					(end 321.935348 -25.625044)
				)
				(xy 321.93738 -25.626314) (xy 322.014342 -25.48255)
				(arc
					(start 322.014342 -25.306782)
					(mid 321.990787 -25.188833)
					(end 321.923918 -25.08885)
				)
				(arc
					(start 321.74434 -24.909018)
					(mid 321.687146 -24.871732)
					(end 321.620134 -24.858726)
				)
				(arc
					(start 321.57035 -24.858726)
					(mid 321.535022 -24.865847)
					(end 321.505072 -24.885904)
				)
				(arc
					(start 321.505072 -24.885904)
					(mid 321.48065 -24.919181)
					(end 321.46748 -24.958294)
				)
				(arc
					(start 321.46748 -24.958294)
					(mid 321.382873 -25.711222)
					(end 321.303396 -24.957786)
				)
				(xy 321.303396 -24.947626)
				(arc
					(start 321.305428 -24.94534)
					(mid 321.33324 -24.851107)
					(end 321.390264 -24.771096)
				)
				(arc
					(start 321.390264 -24.771096)
					(mid 321.456441 -24.72347)
					(end 321.534282 -24.699214)
				)
				(xy 321.536822 -24.696674) (xy 321.653662 -24.696674)
				(arc
					(start 321.65544 -24.698452)
					(mid 321.75037 -24.722514)
					(end 321.83451 -24.77262)
				)
				(xy 321.83705 -24.77262) (xy 321.858386 -24.793956) (xy 321.860926 -24.796496) (xy 322.062348 -24.997918)
			)
		)
	)
	(zone
		(layer "F.Cu")
		(hatch none 0.5)
		(connect_pads
			(clearance 0)
		)
		(min_thickness 0.25)
		(keepout
			(tracks not_allowed)
			(vias allowed)
			(pads allowed)
			(copperpour not_allowed)
			(footprints allowed)
		)
		(placement
			(enabled no)
			(sheetname "")
		)
		(fill
			(thermal_gap 0.5)
			(thermal_bridge_width 0.5)
			(island_removal_mode 0)
		)
		(polygon
			(pts
				(arc
					(start 216.093802 -210.385914)
					(mid 215.583008 -210.896327)
					(end 216.093548 -211.406994)
				)
				(xy 216.260172 -211.406994)
				(arc
					(start 216.260172 -211.274406)
					(mid 216.248089 -211.200785)
					(end 216.213436 -211.134706)
				)
				(arc
					(start 216.213436 -211.134706)
					(mid 215.906282 -210.706537)
					(end 216.330022 -211.019644)
				)
				(arc
					(start 216.330022 -211.020914)
					(mid 216.392125 -211.123183)
					(end 216.4207 -211.239354)
				)
				(xy 216.422224 -211.240878) (xy 216.422224 -211.406994) (xy 216.564972 -211.406994) (xy 216.564972 -211.240878)
				(arc
					(start 216.56675 -211.2391)
					(mid 216.592701 -211.134606)
					(end 216.64803 -211.04225)
				)
				(xy 216.64803 -211.039964)
				(arc
					(start 216.669366 -211.018628)
					(mid 217.095531 -210.708423)
					(end 216.78392 -211.133436)
				)
				(arc
					(start 216.78392 -211.133436)
					(mid 216.741803 -211.198271)
					(end 216.727024 -211.274152)
				)
				(xy 216.727024 -211.406994)
				(arc
					(start 216.906348 -211.406994)
					(mid 217.416888 -210.896454)
					(end 216.906348 -210.385914)
				)
			)
		)
	)
	(zone
		(layer "F.Cu")
		(hatch none 0.5)
		(connect_pads
			(clearance 0)
		)
		(min_thickness 0.25)
		(keepout
			(tracks not_allowed)
			(vias allowed)
			(pads allowed)
			(copperpour not_allowed)
			(footprints allowed)
		)
		(placement
			(enabled no)
			(sheetname "")
		)
		(fill
			(thermal_gap 0.5)
			(thermal_bridge_width 0.5)
			(island_removal_mode 0)
		)
		(polygon
			(pts
				(arc
					(start 168.212516 -88.646254)
					(mid 167.702103 -88.13546)
					(end 167.191436 -88.646)
				)
				(xy 167.191436 -88.826594) (xy 167.406828 -88.826594)
				(arc
					(start 167.464994 -88.768428)
					(mid 167.890588 -88.457388)
					(end 167.579548 -88.882982)
				)
				(xy 167.473884 -88.988646) (xy 167.191436 -88.988646) (xy 167.191436 -89.131394) (xy 167.489124 -89.131394)
				(arc
					(start 167.579548 -89.221818)
					(mid 167.890588 -89.647412)
					(end 167.464994 -89.336372)
				)
				(xy 167.422068 -89.293446) (xy 167.191436 -89.293446)
				(arc
					(start 167.191436 -89.4588)
					(mid 167.701976 -89.96934)
					(end 168.212516 -89.4588)
				)
			)
		)
	)
	(zone
		(layer "F.Cu")
		(hatch none 0.5)
		(connect_pads
			(clearance 0)
		)
		(min_thickness 0.25)
		(keepout
			(tracks not_allowed)
			(vias allowed)
			(pads allowed)
			(copperpour not_allowed)
			(footprints allowed)
		)
		(placement
			(enabled no)
			(sheetname "")
		)
		(fill
			(thermal_gap 0.5)
			(thermal_bridge_width 0.5)
			(island_removal_mode 0)
		)
		(polygon
			(pts
				(arc
					(start 302.093884 -210.385914)
					(mid 301.58309 -210.896327)
					(end 302.09363 -211.406994)
				)
				(xy 302.260254 -211.406994)
				(arc
					(start 302.260254 -211.28228)
					(mid 302.248097 -211.204879)
					(end 302.212756 -211.13496)
				)
				(arc
					(start 302.212756 -211.13496)
					(mid 301.907256 -210.705822)
					(end 302.329342 -211.020914)
				)
				(arc
					(start 302.329342 -211.020914)
					(mid 302.392115 -211.127184)
					(end 302.420782 -211.247228)
				)
				(xy 302.422306 -211.248752) (xy 302.422306 -211.406994) (xy 302.565054 -211.406994) (xy 302.565054 -211.248752)
				(arc
					(start 302.566578 -211.247228)
					(mid 302.594187 -211.135349)
					(end 302.6537 -211.036662)
				)
				(xy 302.6537 -211.034376)
				(arc
					(start 302.669448 -211.018628)
					(mid 303.09496 -210.707924)
					(end 302.784256 -211.133436)
				)
				(arc
					(start 302.784256 -211.133436)
					(mid 302.741934 -211.202437)
					(end 302.727106 -211.282026)
				)
				(xy 302.727106 -211.406994)
				(arc
					(start 302.90643 -211.406994)
					(mid 303.41697 -210.896454)
					(end 302.90643 -210.385914)
				)
			)
		)
	)
	(zone
		(net "P1V8_STBY")
		(layer "F.Cu")
		(hatch none 0.5)
		(connect_pads
			(clearance 0.5)
		)
		(min_thickness 0.25)
		(fill yes
			(thermal_gap 0.5)
			(thermal_bridge_width 0.5)
			(island_removal_mode 0)
		)
		(polygon
			(pts
				(xy 151.76754 -83.06308) (xy 150.67788 -84.15274) (xy 150.67788 -86.96706) (xy 150.84044 -87.12962)
				(xy 152.27554 -87.12962) (xy 152.77973 -86.62543) (xy 152.77973 -84.49945) (xy 153.02484 -84.25434)
				(xy 154.84348 -84.25434) (xy 155.08732 -84.49818) (xy 155.08732 -85.60308) (xy 155.15082 -85.66658)
				(xy 156.30652 -85.66658) (xy 156.37256 -85.60054) (xy 156.37256 -83.93176) (xy 155.50388 -83.06308)
			)
		)
		(polygon
			(pts
				(xy 156.19222 -84.7725) (xy 155.98902 -84.7725) (xy 155.98902 -84.9757) (xy 156.19222 -84.9757)
			)
		)
		(polygon
			(pts
				(xy 154.83586 -83.60664) (xy 154.63266 -83.60664) (xy 154.63266 -83.80984) (xy 154.83586 -83.80984)
			)
		)
		(polygon
			(pts
				(xy 154.27706 -83.60664) (xy 154.07386 -83.60664) (xy 154.07386 -83.80984) (xy 154.27706 -83.80984)
			)
		)
		(polygon
			(pts
				(xy 153.86558 -83.55076) (xy 153.66238 -83.55076) (xy 153.66238 -83.75396) (xy 153.86558 -83.75396)
			)
		)
		(polygon
			(pts
				(xy 153.25598 -83.55076) (xy 153.05278 -83.55076) (xy 153.05278 -83.75396) (xy 153.25598 -83.75396)
			)
		)
	)
	(zone
		(net "VR_P1V538_STBY_IN")
		(layer "F.Cu")
		(hatch none 0.5)
		(connect_pads
			(clearance 0.5)
		)
		(min_thickness 0.25)
		(fill yes
			(thermal_gap 0.5)
			(thermal_bridge_width 0.5)
			(island_removal_mode 0)
		)
		(polygon
			(pts
				(xy 67.6148 -158.9532) (xy 66.9798 -159.5882) (xy 66.9798 -161.163) (xy 68.6054 -161.163) (xy 69.2912 -160.4772)
				(xy 72.1614 -160.4772) (xy 72.2376 -160.401) (xy 72.2376 -159.1564) (xy 72.0344 -158.9532)
			)
		)
		(polygon
			(pts
				(xy 71.5264 -159.5374) (xy 71.3232 -159.5374) (xy 71.3232 -159.7406) (xy 71.5264 -159.7406)
			)
		)
	)
	(zone
		(layer "F.Cu")
		(hatch none 0.5)
		(connect_pads
			(clearance 0)
		)
		(min_thickness 0.25)
		(keepout
			(tracks not_allowed)
			(vias allowed)
			(pads allowed)
			(copperpour not_allowed)
			(footprints allowed)
		)
		(placement
			(enabled no)
			(sheetname "")
		)
		(fill
			(thermal_gap 0.5)
			(thermal_bridge_width 0.5)
			(island_removal_mode 0)
		)
		(polygon
			(pts
				(arc
					(start 183.59374 -19.850354)
					(mid 183.083327 -19.33956)
					(end 182.57266 -19.8501)
				)
				(xy 182.57266 -20.023074)
				(arc
					(start 182.72252 -20.023074)
					(mid 182.79165 -20.015115)
					(end 182.85714 -19.991578)
				)
				(arc
					(start 182.85714 -19.991578)
					(mid 183.251683 -19.643382)
					(end 182.990236 -20.100036)
				)
				(arc
					(start 182.990236 -20.100036)
					(mid 182.879471 -20.157773)
					(end 182.757318 -20.183856)
				)
				(xy 182.756048 -20.185126) (xy 182.57266 -20.185126) (xy 182.57266 -20.327874) (xy 182.755794 -20.327874)
				(arc
					(start 182.757064 -20.329144)
					(mid 182.879352 -20.355201)
					(end 182.990236 -20.412964)
				)
				(arc
					(start 182.990236 -20.412964)
					(mid 183.251808 -20.869495)
					(end 182.856886 -20.521676)
				)
				(arc
					(start 182.856886 -20.521676)
					(mid 182.791417 -20.497993)
					(end 182.722266 -20.489926)
				)
				(xy 182.57266 -20.489926)
				(arc
					(start 182.57266 -20.6629)
					(mid 183.0832 -21.17344)
					(end 183.59374 -20.6629)
				)
			)
		)
	)
	(zone
		(layer "F.Cu")
		(hatch none 0.5)
		(connect_pads
			(clearance 0)
		)
		(min_thickness 0.25)
		(keepout
			(tracks not_allowed)
			(vias allowed)
			(pads allowed)
			(copperpour not_allowed)
			(footprints allowed)
		)
		(placement
			(enabled no)
			(sheetname "")
		)
		(fill
			(thermal_gap 0.5)
			(thermal_bridge_width 0.5)
			(island_removal_mode 0)
		)
		(polygon
			(pts
				(arc
					(start 132.358384 -41.605454)
					(mid 131.746371 -40.99306)
					(end 131.134104 -41.6052)
				)
				(arc
					(start 131.134104 -42.7228)
					(mid 131.746244 -43.33494)
					(end 132.358384 -42.7228)
				)
				(xy 132.358384 -42.366184) (xy 132.31114 -42.37101) (xy 132.310124 -42.372026)
				(arc
					(start 132.139944 -42.372026)
					(mid 131.999703 -42.405211)
					(end 131.889246 -42.497756)
				)
				(arc
					(start 131.889246 -42.497756)
					(mid 131.682833 -42.981785)
					(end 131.723384 -42.457116)
				)
				(arc
					(start 131.723384 -42.457116)
					(mid 131.882969 -42.2856)
					(end 132.105146 -42.211244)
				)
				(xy 132.106416 -42.209974)
				(arc
					(start 132.276596 -42.209974)
					(mid 132.317702 -42.207848)
					(end 132.358384 -42.201592)
				)
				(arc
					(start 132.358384 -42.054272)
					(mid 132.335753 -42.060483)
					(end 132.312664 -42.064686)
				)
				(xy 132.310124 -42.067226) (xy 132.093716 -42.067226)
				(arc
					(start 132.092446 -42.065956)
					(mid 131.899514 -42.007252)
					(end 131.750054 -41.8719)
				)
				(arc
					(start 131.750054 -41.8719)
					(mid 131.657133 -41.353893)
					(end 131.912106 -41.814242)
				)
				(arc
					(start 131.912106 -41.814242)
					(mid 132.010462 -41.881506)
					(end 132.127244 -41.905174)
				)
				(arc
					(start 132.276596 -41.905174)
					(mid 132.31602 -41.897256)
					(end 132.349494 -41.874948)
				)
				(xy 132.349748 -41.874694) (xy 132.358384 -41.864788)
			)
		)
	)
	(zone
		(layer "F.Cu")
		(hatch none 0.5)
		(connect_pads
			(clearance 0)
		)
		(min_thickness 0.25)
		(keepout
			(tracks allowed)
			(vias allowed)
			(pads allowed)
			(copperpour allowed)
			(footprints allowed)
		)
		(placement
			(enabled no)
			(sheetname "")
		)
		(fill
			(thermal_gap 0.5)
			(thermal_bridge_width 0.5)
			(island_removal_mode 0)
		)
		(polygon
			(pts
				(xy 57.440322 -19.202908) (xy 61.22162 -19.202908) (xy 61.570616 -18.853912) (xy 61.570616 -18.271998)
				(xy 61.202316 -17.903698) (xy 57.45988 -17.903698) (xy 57.130188 -18.23339) (xy 57.130188 -18.892774)
			)
		)
	)
	(zone
		(net "DUT_VDD")
		(layer "F.Cu")
		(hatch none 0.5)
		(connect_pads
			(clearance 0.5)
		)
		(min_thickness 0.25)
		(fill yes
			(thermal_gap 0.5)
			(thermal_bridge_width 0.5)
			(island_removal_mode 0)
		)
		(polygon
			(pts
				(xy 309.2704 -56.6928) (xy 309.1942 -56.769) (xy 309.1942 -57.023) (xy 308.9021 -57.3151) (xy 308.5719 -57.3151)
				(xy 308.5592 -57.3278) (xy 296.037 -57.3278) (xy 295.656 -57.7088) (xy 295.656 -68.2752) (xy 296.1132 -68.7324)
				(xy 309.5244 -68.7324) (xy 309.6514 -68.6054) (xy 309.6514 -67.9196) (xy 309.753 -67.818) (xy 309.753 -56.8452)
				(xy 309.6006 -56.6928)
			)
		)
	)
	(zone
		(layer "F.Cu")
		(hatch none 0.5)
		(connect_pads
			(clearance 0)
		)
		(min_thickness 0.25)
		(keepout
			(tracks allowed)
			(vias allowed)
			(pads allowed)
			(copperpour allowed)
			(footprints allowed)
		)
		(placement
			(enabled no)
			(sheetname "")
		)
		(fill
			(thermal_gap 0.5)
			(thermal_bridge_width 0.5)
			(island_removal_mode 0)
		)
		(polygon
			(pts
				(xy 162.7124 -224.3836) (xy 162.7124 -222.123) (xy 164.8714 -222.123) (xy 164.8714 -224.3836)
			)
		)
	)
	(zone
		(net "GND")
		(layer "F.Cu")
		(hatch none 0.5)
		(connect_pads
			(clearance 0.5)
		)
		(min_thickness 0.25)
		(fill yes
			(thermal_gap 0.5)
			(thermal_bridge_width 0.5)
			(island_removal_mode 0)
		)
		(polygon
			(pts
				(xy 33.655 -145.669) (xy 33.528 -145.796) (xy 33.528 -146.264884) (xy 33.597342 -146.334226) (xy 40.860472 -146.334226)
				(xy 40.906954 -146.287744) (xy 40.906954 -145.796) (xy 40.779954 -145.669)
			)
		)
	)
	(zone
		(net "GND")
		(layer "F.Cu")
		(hatch none 0.5)
		(connect_pads
			(clearance 0.5)
		)
		(min_thickness 0.25)
		(fill yes
			(thermal_gap 0.5)
			(thermal_bridge_width 0.5)
			(island_removal_mode 0)
		)
		(polygon
			(pts
				(xy 309.88 -169.926) (xy 307.848 -171.958) (xy 307.848 -208.056226) (xy 308.471824 -208.68005) (xy 327.323704 -208.68005)
				(xy 327.787 -208.216754) (xy 327.787 -175.387) (xy 322.326 -169.926)
			)
		)
	)
	(zone
		(layer "F.Cu")
		(hatch none 0.5)
		(connect_pads
			(clearance 0)
		)
		(min_thickness 0.25)
		(keepout
			(tracks not_allowed)
			(vias allowed)
			(pads allowed)
			(copperpour not_allowed)
			(footprints allowed)
		)
		(placement
			(enabled no)
			(sheetname "")
		)
		(fill
			(thermal_gap 0.5)
			(thermal_bridge_width 0.5)
			(island_removal_mode 0)
		)
		(polygon
			(pts
				(arc
					(start 290.093908 -210.385914)
					(mid 289.583114 -210.896327)
					(end 290.093654 -211.406994)
				)
				(xy 290.260278 -211.406994)
				(arc
					(start 290.260278 -211.3026)
					(mid 290.247494 -211.215736)
					(end 290.21024 -211.13623)
				)
				(arc
					(start 290.21024 -211.13623)
					(mid 289.909104 -210.704032)
					(end 290.32835 -211.022946)
				)
				(arc
					(start 290.32835 -211.022946)
					(mid 290.392349 -211.138693)
					(end 290.42106 -211.267802)
				)
				(xy 290.42233 -211.269072) (xy 290.42233 -211.406994) (xy 290.565078 -211.406994) (xy 290.565078 -211.269072)
				(arc
					(start 290.566602 -211.267548)
					(mid 290.598145 -211.136896)
					(end 290.668202 -211.022184)
				)
				(xy 290.668202 -211.020152)
				(arc
					(start 290.669472 -211.018882)
					(mid 291.093809 -210.706743)
					(end 290.785804 -211.134198)
				)
				(arc
					(start 290.785804 -211.134198)
					(mid 290.742221 -211.213435)
					(end 290.72713 -211.3026)
				)
				(xy 290.72713 -211.406994)
				(arc
					(start 290.906454 -211.406994)
					(mid 291.416994 -210.896454)
					(end 290.906454 -210.385914)
				)
			)
		)
	)
	(zone
		(net "P3V3_STBY_LL")
		(layer "F.Cu")
		(hatch none 0.5)
		(connect_pads
			(clearance 0.5)
		)
		(min_thickness 0.25)
		(fill yes
			(thermal_gap 0.5)
			(thermal_bridge_width 0.5)
			(island_removal_mode 0)
		)
		(polygon
			(pts
				(xy 68.072 -38.481) (xy 67.945 -38.608) (xy 67.945 -44.196) (xy 68.453 -44.704) (xy 72.771 -44.704)
				(xy 73.025 -44.45) (xy 73.025 -38.989) (xy 72.898 -38.862) (xy 69.85 -38.862) (xy 69.469 -38.481)
			)
		)
	)
	(zone
		(layer "F.Cu")
		(hatch none 0.5)
		(connect_pads
			(clearance 0)
		)
		(min_thickness 0.25)
		(keepout
			(tracks not_allowed)
			(vias allowed)
			(pads allowed)
			(copperpour not_allowed)
			(footprints allowed)
		)
		(placement
			(enabled no)
			(sheetname "")
		)
		(fill
			(thermal_gap 0.5)
			(thermal_bridge_width 0.5)
			(island_removal_mode 0)
		)
		(polygon
			(pts
				(arc
					(start 160.364678 -25.295606)
					(mid 160.3276 -25.242866)
					(end 160.284668 -25.194768)
				)
				(xy 160.077404 -24.98725)
				(arc
					(start 159.991298 -24.901652)
					(mid 159.95784 -24.879299)
					(end 159.9184 -24.871426)
				)
				(arc
					(start 159.917892 -24.871426)
					(mid 159.845066 -24.880591)
					(end 159.776668 -24.90724)
				)
				(arc
					(start 159.776668 -24.90724)
					(mid 159.755429 -24.93403)
					(end 159.738314 -24.963628)
				)
				(arc
					(start 159.738314 -24.963628)
					(mid 159.614241 -25.710658)
					(end 159.568896 -24.954738)
				)
				(arc
					(start 159.568896 -24.954738)
					(mid 159.608186 -24.863563)
					(end 159.668972 -24.785066)
				)
				(arc
					(start 159.668972 -24.785066)
					(mid 159.676826 -24.778311)
					(end 159.685482 -24.77262)
				)
				(arc
					(start 159.685482 -24.77262)
					(mid 159.797347 -24.725514)
					(end 159.917638 -24.709374)
				)
				(arc
					(start 159.9184 -24.709374)
					(mid 160.003263 -24.723349)
					(end 160.079182 -24.76373)
				)
				(xy 160.082738 -24.76373) (xy 160.105598 -24.78659) (xy 160.10636 -24.787352) (xy 160.168082 -24.84882)
				(xy 160.191704 -24.872442) (xy 160.21558 -24.896064) (xy 160.21558 -24.896318) (xy 160.423098 -25.103836)
				(xy 160.423098 -25.105106) (xy 160.450022 -25.136348) (xy 160.522158 -25.001474)
				(arc
					(start 160.500314 -24.979122)
					(mid 160.393966 -24.840746)
					(end 160.326832 -24.679656)
				)
				(arc
					(start 160.326832 -24.679402)
					(mid 160.311767 -24.609392)
					(end 160.304226 -24.538178)
				)
				(xy 160.303464 -24.537162)
				(arc
					(start 160.303464 -24.302466)
					(mid 160.38449 -23.549024)
					(end 160.465516 -24.302466)
				)
				(arc
					(start 160.465516 -24.503634)
					(mid 160.469985 -24.571024)
					(end 160.483296 -24.637238)
				)
				(arc
					(start 160.483296 -24.637238)
					(mid 160.529828 -24.751547)
					(end 160.602422 -24.85136)
				)
				(xy 160.937448 -24.226266)
				(arc
					(start 160.935416 -24.224996)
					(mid 160.679384 -23.379176)
					(end 159.833564 -23.635208)
				)
				(xy 159.831532 -23.633938) (xy 159.08147 -25.033732) (xy 159.081724 -25.033986)
				(arc
					(start 159.083756 -25.035002)
					(mid 159.339432 -25.880903)
					(end 160.185354 -25.625044)
				)
				(xy 160.187386 -25.626314)
			)
		)
	)
	(zone
		(layer "F.Cu")
		(hatch none 0.5)
		(connect_pads
			(clearance 0)
		)
		(min_thickness 0.25)
		(keepout
			(tracks allowed)
			(vias allowed)
			(pads allowed)
			(copperpour allowed)
			(footprints allowed)
		)
		(placement
			(enabled no)
			(sheetname "")
		)
		(fill
			(thermal_gap 0.5)
			(thermal_bridge_width 0.5)
			(island_removal_mode 0)
		)
		(polygon
			(pts
				(xy 319.462912 -34.683446) (xy 320.96583 -34.683446) (xy 321.117468 -34.531808) (xy 321.117468 -32.588454)
				(xy 320.922396 -32.393382) (xy 319.513712 -32.393382) (xy 319.354708 -32.552386) (xy 319.354708 -34.575242)
			)
		)
	)
	(zone
		(layer "F.Cu")
		(hatch none 0.5)
		(connect_pads
			(clearance 0)
		)
		(min_thickness 0.25)
		(keepout
			(tracks not_allowed)
			(vias allowed)
			(pads allowed)
			(copperpour not_allowed)
			(footprints allowed)
		)
		(placement
			(enabled no)
			(sheetname "")
		)
		(fill
			(thermal_gap 0.5)
			(thermal_bridge_width 0.5)
			(island_removal_mode 0)
		)
		(polygon
			(pts
				(arc
					(start 58.051954 -195.75526)
					(mid 57.54116 -196.265673)
					(end 58.0517 -196.77634)
				)
				(xy 58.211974 -196.77634)
				(arc
					(start 58.211974 -196.75475)
					(mid 58.196801 -196.630176)
					(end 58.15203 -196.512942)
				)
				(arc
					(start 58.15203 -196.512942)
					(mid 57.879477 -196.061783)
					(end 58.278014 -196.40677)
				)
				(arc
					(start 58.278014 -196.40677)
					(mid 58.344824 -196.557657)
					(end 58.373264 -196.720206)
				)
				(xy 58.374026 -196.721222) (xy 58.374026 -196.77634)
				(arc
					(start 58.525664 -196.77634)
					(mid 58.568995 -196.592103)
					(end 58.646568 -196.41947)
				)
				(arc
					(start 58.646568 -196.41947)
					(mid 59.024863 -196.052745)
					(end 58.777124 -196.517768)
				)
				(arc
					(start 58.777124 -196.517768)
					(mid 58.722606 -196.643426)
					(end 58.689494 -196.77634)
				)
				(arc
					(start 58.8645 -196.77634)
					(mid 59.37504 -196.2658)
					(end 58.8645 -195.75526)
				)
			)
		)
	)
	(zone
		(layer "F.Cu")
		(hatch none 0.5)
		(connect_pads
			(clearance 0)
		)
		(min_thickness 0.25)
		(keepout
			(tracks not_allowed)
			(vias allowed)
			(pads allowed)
			(copperpour not_allowed)
			(footprints allowed)
		)
		(placement
			(enabled no)
			(sheetname "")
		)
		(fill
			(thermal_gap 0.5)
			(thermal_bridge_width 0.5)
			(island_removal_mode 0)
		)
		(polygon
			(pts
				(arc
					(start 26.74112 -142.580614)
					(mid 26.129107 -141.96822)
					(end 25.51684 -142.58036)
				)
				(arc
					(start 25.51684 -143.69796)
					(mid 26.12898 -144.3101)
					(end 26.74112 -143.69796)
				)
				(xy 26.74112 -143.362426) (xy 26.579068 -143.362426)
				(arc
					(start 26.365962 -143.575532)
					(mid 25.940368 -143.886572)
					(end 26.251408 -143.460978)
				)
				(xy 26.512012 -143.200374) (xy 26.74112 -143.200374) (xy 26.74112 -143.057626) (xy 26.491692 -143.057626)
				(arc
					(start 26.251408 -142.817342)
					(mid 25.940368 -142.391748)
					(end 26.365962 -142.702788)
				)
				(xy 26.558748 -142.895574) (xy 26.74112 -142.895574)
			)
		)
	)
	(zone
		(layer "F.Cu")
		(hatch none 0.5)
		(connect_pads
			(clearance 0)
		)
		(min_thickness 0.25)
		(keepout
			(tracks not_allowed)
			(vias allowed)
			(pads allowed)
			(copperpour not_allowed)
			(footprints allowed)
		)
		(placement
			(enabled no)
			(sheetname "")
		)
		(fill
			(thermal_gap 0.5)
			(thermal_bridge_width 0.5)
			(island_removal_mode 0)
		)
		(polygon
			(pts
				(arc
					(start 186.56554 -24.999188)
					(mid 186.055127 -24.488394)
					(end 185.54446 -24.998934)
				)
				(xy 185.54446 -25.183338)
				(arc
					(start 185.78957 -25.183338)
					(mid 185.821416 -25.180612)
					(end 185.852308 -25.172416)
				)
				(arc
					(start 185.852308 -25.172416)
					(mid 186.184758 -24.765818)
					(end 186.01436 -25.262586)
				)
				(arc
					(start 186.01436 -25.262586)
					(mid 185.92578 -25.317508)
					(end 185.824876 -25.343612)
				)
				(xy 185.823098 -25.34539) (xy 185.54446 -25.34539) (xy 185.54446 -25.488138) (xy 185.845958 -25.488138)
				(arc
					(start 185.84799 -25.49017)
					(mid 185.929378 -25.510018)
					(end 186.00293 -25.550114)
				)
				(arc
					(start 186.00293 -25.550114)
					(mid 186.197656 -26.037135)
					(end 185.840878 -25.65273)
				)
				(arc
					(start 185.840878 -25.65273)
					(mid 185.82671 -25.650838)
					(end 185.81243 -25.65019)
				)
				(xy 185.54446 -25.65019)
				(arc
					(start 185.54446 -25.811734)
					(mid 186.055 -26.322274)
					(end 186.56554 -25.811734)
				)
			)
		)
	)
	(zone
		(net "P12V")
		(layer "F.Cu")
		(hatch none 0.5)
		(connect_pads
			(clearance 0.5)
		)
		(min_thickness 0.25)
		(fill yes
			(thermal_gap 0.5)
			(thermal_bridge_width 0.5)
			(island_removal_mode 0)
		)
		(polygon
			(pts
				(xy 139.433046 -76.862432) (xy 139.23137 -77.064108) (xy 139.23137 -77.089) (xy 138.811 -77.50937)
				(xy 138.811 -80.813656) (xy 139.234672 -81.237328) (xy 139.558522 -81.561432) (xy 142.560802 -81.561432)
				(xy 142.891002 -81.231232) (xy 142.891002 -78.336648) (xy 142.628874 -78.07452) (xy 141.877288 -78.07452)
				(xy 140.6652 -76.862432)
			)
		)
	)
	(zone
		(layer "F.Cu")
		(hatch none 0.5)
		(connect_pads
			(clearance 0)
		)
		(min_thickness 0.25)
		(keepout
			(tracks not_allowed)
			(vias allowed)
			(pads allowed)
			(copperpour not_allowed)
			(footprints allowed)
		)
		(placement
			(enabled no)
			(sheetname "")
		)
		(fill
			(thermal_gap 0.5)
			(thermal_bridge_width 0.5)
			(island_removal_mode 0)
		)
		(polygon
			(pts
				(xy 22.836124 -53.045614) (xy 22.836124 -53.367178)
				(arc
					(start 22.784054 -53.419248)
					(mid 22.821878 -53.556154)
					(end 22.784054 -53.69306)
				)
				(xy 22.855174 -53.76418) (xy 22.855428 -53.76418) (xy 22.855428 -54.066694) (xy 23.067772 -54.066694)
				(xy 23.067772 -53.76418) (xy 23.068026 -53.76418)
				(arc
					(start 23.139146 -53.69306)
					(mid 23.101322 -53.556154)
					(end 23.139146 -53.419248)
				)
				(xy 23.048976 -53.329078) (xy 23.048976 -53.045614)
			)
		)
	)
	(zone
		(layer "F.Cu")
		(hatch none 0.5)
		(connect_pads
			(clearance 0)
		)
		(min_thickness 0.25)
		(keepout
			(tracks allowed)
			(vias allowed)
			(pads allowed)
			(copperpour allowed)
			(footprints allowed)
		)
		(placement
			(enabled no)
			(sheetname "")
		)
		(fill
			(thermal_gap 0.5)
			(thermal_bridge_width 0.5)
			(island_removal_mode 0)
		)
		(polygon
			(pts
				(xy 126.585726 -34.763202) (xy 128.290574 -34.763202) (xy 128.630172 -34.423604) (xy 128.630172 -32.646366)
				(xy 128.312418 -32.328612) (xy 126.74473 -32.328612) (xy 126.463044 -32.610298) (xy 126.463044 -34.64052)
			)
		)
	)
	(zone
		(net "P12V")
		(layer "F.Cu")
		(hatch none 0.5)
		(connect_pads
			(clearance 0.5)
		)
		(min_thickness 0.25)
		(fill yes
			(thermal_gap 0.5)
			(thermal_bridge_width 0.5)
			(island_removal_mode 0)
		)
		(polygon
			(pts
				(xy 55.88 -46.355) (xy 55.245 -46.99) (xy 55.245 -49.657) (xy 55.626 -50.038) (xy 58.674 -50.038)
				(xy 58.928 -49.784) (xy 58.928 -46.609) (xy 58.674 -46.355)
			)
		)
		(polygon
			(pts
				(xy 57.7469 -47.8409) (xy 57.5437 -47.8409) (xy 57.5437 -48.0441) (xy 57.7469 -48.0441)
			)
		)
	)
	(zone
		(net "GND")
		(layer "F.Cu")
		(hatch none 0.5)
		(connect_pads
			(clearance 0.5)
		)
		(min_thickness 0.25)
		(fill yes
			(thermal_gap 0.5)
			(thermal_bridge_width 0.5)
			(island_removal_mode 0)
		)
		(polygon
			(pts
				(xy 264.795 -154.686) (xy 263.017 -156.464) (xy 263.017 -208.715864) (xy 263.378696 -209.07756)
				(xy 263.378696 -209.09026) (xy 294.704516 -209.09026) (xy 295.275 -208.519776) (xy 295.275 -178.943)
				(xy 271.018 -154.686)
			)
		)
	)
	(zone
		(net "P1V8_CLKGEN")
		(layer "F.Cu")
		(hatch none 0.5)
		(connect_pads
			(clearance 0.5)
		)
		(min_thickness 0.25)
		(fill yes
			(thermal_gap 0.5)
			(thermal_bridge_width 0.5)
			(island_removal_mode 0)
		)
		(polygon
			(pts
				(xy 155.067 -85.979) (xy 154.94 -86.106) (xy 154.94 -87.249) (xy 155.067 -87.376) (xy 157.607 -87.376)
				(xy 158.75 -88.519) (xy 159.004 -88.519) (xy 159.131 -88.392) (xy 159.131 -87.122) (xy 157.988 -85.979)
			)
		)
		(polygon
			(pts
				(xy 156.19222 -86.1949) (xy 155.98902 -86.1949) (xy 155.98902 -86.3981) (xy 156.19222 -86.3981)
			)
		)
	)
	(zone
		(layer "F.Cu")
		(hatch none 0.5)
		(connect_pads
			(clearance 0)
		)
		(min_thickness 0.25)
		(keepout
			(tracks not_allowed)
			(vias allowed)
			(pads allowed)
			(copperpour not_allowed)
			(footprints allowed)
		)
		(placement
			(enabled no)
			(sheetname "")
		)
		(fill
			(thermal_gap 0.5)
			(thermal_bridge_width 0.5)
			(island_removal_mode 0)
		)
		(polygon
			(pts
				(arc
					(start 294.159432 -34.66973)
					(mid 293.648638 -35.180143)
					(end 294.159178 -35.69081)
				)
				(arc
					(start 294.971978 -35.69081)
					(mid 295.482518 -35.18027)
					(end 294.971978 -34.66973)
				)
				(xy 294.811704 -34.66973)
				(arc
					(start 294.811704 -34.748216)
					(mid 294.824591 -34.846017)
					(end 294.86225 -34.937192)
				)
				(arc
					(start 294.86225 -34.937192)
					(mid 295.151475 -35.377521)
					(end 294.74033 -35.04819)
				)
				(arc
					(start 294.74033 -35.04819)
					(mid 294.678064 -34.921496)
					(end 294.650668 -34.783014)
				)
				(xy 294.649652 -34.781744) (xy 294.649652 -34.66973) (xy 294.506904 -34.66973) (xy 294.506904 -34.781744)
				(arc
					(start 294.505634 -34.783014)
					(mid 294.472024 -34.928348)
					(end 294.395398 -35.056318)
				)
				(arc
					(start 294.395398 -35.056318)
					(mid 293.972159 -35.370502)
					(end 294.279066 -34.942018)
				)
				(arc
					(start 294.279066 -34.942018)
					(mid 294.327931 -34.850671)
					(end 294.344852 -34.74847)
				)
				(xy 294.344852 -34.66973)
			)
		)
	)
	(zone
		(layer "F.Cu")
		(hatch none 0.5)
		(connect_pads
			(clearance 0)
		)
		(min_thickness 0.25)
		(keepout
			(tracks not_allowed)
			(vias allowed)
			(pads allowed)
			(copperpour not_allowed)
			(footprints allowed)
		)
		(placement
			(enabled no)
			(sheetname "")
		)
		(fill
			(thermal_gap 0.5)
			(thermal_bridge_width 0.5)
			(island_removal_mode 0)
		)
		(polygon
			(pts
				(arc
					(start 148.093938 -210.385914)
					(mid 147.583144 -210.896327)
					(end 148.093684 -211.406994)
				)
				(xy 148.260308 -211.406994)
				(arc
					(start 148.260308 -211.28228)
					(mid 148.248205 -211.204927)
					(end 148.213064 -211.13496)
				)
				(arc
					(start 148.213064 -211.13496)
					(mid 147.907026 -210.70594)
					(end 148.32965 -211.02066)
				)
				(arc
					(start 148.32965 -211.02066)
					(mid 148.392263 -211.127222)
					(end 148.420836 -211.247482)
				)
				(xy 148.42236 -211.249006) (xy 148.42236 -211.406994) (xy 148.565108 -211.406994) (xy 148.565108 -211.24926)
				(arc
					(start 148.566632 -211.247482)
					(mid 148.594488 -211.135444)
					(end 148.654262 -211.036662)
				)
				(xy 148.654262 -211.034376)
				(arc
					(start 148.669502 -211.018882)
					(mid 149.094895 -210.707641)
					(end 148.784564 -211.13369)
				)
				(arc
					(start 148.784564 -211.13369)
					(mid 148.742055 -211.202922)
					(end 148.72716 -211.282788)
				)
				(xy 148.72716 -211.406994)
				(arc
					(start 148.906484 -211.406994)
					(mid 149.417024 -210.896454)
					(end 148.906484 -210.385914)
				)
			)
		)
	)
	(zone
		(layer "F.Cu")
		(hatch none 0.5)
		(connect_pads
			(clearance 0)
		)
		(min_thickness 0.25)
		(keepout
			(tracks allowed)
			(vias allowed)
			(pads allowed)
			(copperpour allowed)
			(footprints not_allowed)
		)
		(placement
			(enabled no)
			(sheetname "")
		)
		(fill
			(thermal_gap 0.5)
			(thermal_bridge_width 0.5)
			(island_removal_mode 0)
		)
		(polygon
			(pts
				(xy 9.212072 -55.79999) (xy 9.212072 -70.79996) (xy 44.511976 -70.79996) (xy 44.511976 -55.79999)
			)
		)
	)
	(zone
		(layer "F.Cu")
		(hatch none 0.5)
		(connect_pads
			(clearance 0)
		)
		(min_thickness 0.25)
		(keepout
			(tracks not_allowed)
			(vias allowed)
			(pads allowed)
			(copperpour not_allowed)
			(footprints allowed)
		)
		(placement
			(enabled no)
			(sheetname "")
		)
		(fill
			(thermal_gap 0.5)
			(thermal_bridge_width 0.5)
			(island_removal_mode 0)
		)
		(polygon
			(pts
				(arc
					(start 103.2383 -81.000854)
					(mid 102.626287 -80.38846)
					(end 102.01402 -81.0006)
				)
				(xy 102.01402 -81.325974)
				(arc
					(start 102.21976 -81.325974)
					(mid 102.354906 -81.29658)
					(end 102.465632 -81.213706)
				)
				(arc
					(start 102.465632 -81.213706)
					(mid 102.709553 -80.74741)
					(end 102.627684 -81.2673)
				)
				(arc
					(start 102.627684 -81.2673)
					(mid 102.466817 -81.420711)
					(end 102.254558 -81.486756)
				)
				(xy 102.253288 -81.488026) (xy 102.01402 -81.488026) (xy 102.01402 -81.630774) (xy 102.305104 -81.630774)
				(arc
					(start 102.306628 -81.632044)
					(mid 102.507254 -81.699398)
					(end 102.653084 -81.85277)
				)
				(arc
					(start 102.653084 -81.85277)
					(mid 102.687013 -82.377959)
					(end 102.484174 -81.892394)
				)
				(arc
					(start 102.484174 -81.892394)
					(mid 102.388947 -81.818978)
					(end 102.271576 -81.792826)
				)
				(xy 102.01402 -81.792826)
				(arc
					(start 102.01402 -82.1182)
					(mid 102.62616 -82.73034)
					(end 103.2383 -82.1182)
				)
			)
		)
	)
	(zone
		(layer "F.Cu")
		(hatch none 0.5)
		(connect_pads
			(clearance 0)
		)
		(min_thickness 0.25)
		(keepout
			(tracks not_allowed)
			(vias allowed)
			(pads allowed)
			(copperpour not_allowed)
			(footprints allowed)
		)
		(placement
			(enabled no)
			(sheetname "")
		)
		(fill
			(thermal_gap 0.5)
			(thermal_bridge_width 0.5)
			(island_removal_mode 0)
		)
		(polygon
			(pts
				(xy 91.864688 -185.92165) (xy 91.96578 -186.022742) (xy 92.066872 -185.921396) (xy 92.067126 -185.921396)
				(xy 92.090748 -185.897774)
				(arc
					(start 92.09278 -185.897774)
					(mid 92.185101 -185.837997)
					(end 92.28963 -185.803794)
				)
				(arc
					(start 92.28963 -185.803794)
					(mid 92.812413 -185.868096)
					(end 92.295472 -185.968894)
				)
				(arc
					(start 92.295472 -185.968894)
					(mid 92.23434 -185.99523)
					(end 92.18168 -186.03595)
				)
				(xy 92.080334 -186.137296) (xy 92.18295 -186.240166) (xy 92.183204 -186.240166)
				(arc
					(start 92.184982 -186.238388)
					(mid 92.90685 -186.238388)
					(end 92.90685 -185.51652)
				)
				(xy 92.908628 -185.514742) (xy 92.333826 -184.93994)
				(arc
					(start 92.332048 -184.941718)
					(mid 91.61018 -184.941718)
					(end 91.61018 -185.663586)
				)
				(xy 91.608402 -185.665364) (xy 91.750134 -185.807096)
				(arc
					(start 91.851226 -185.70575)
					(mid 91.879964 -185.66288)
					(end 91.890088 -185.612278)
				)
				(arc
					(start 91.890088 -185.556652)
					(mid 91.971114 -185.036041)
					(end 92.05214 -185.556652)
				)
				(xy 92.05214 -185.645806)
				(arc
					(start 92.049854 -185.648092)
					(mid 92.029682 -185.72497)
					(end 91.989656 -185.793634)
				)
				(xy 91.989656 -185.796682)
			)
		)
	)
	(zone
		(layer "F.Cu")
		(hatch none 0.5)
		(connect_pads
			(clearance 0)
		)
		(min_thickness 0.25)
		(keepout
			(tracks not_allowed)
			(vias allowed)
			(pads allowed)
			(copperpour not_allowed)
			(footprints allowed)
		)
		(placement
			(enabled no)
			(sheetname "")
		)
		(fill
			(thermal_gap 0.5)
			(thermal_bridge_width 0.5)
			(island_removal_mode 0)
		)
		(polygon
			(pts
				(arc
					(start 183.59374 -23.6601)
					(mid 183.0832 -23.14956)
					(end 182.57266 -23.6601)
				)
				(xy 182.57266 -23.833074)
				(arc
					(start 182.671466 -23.833074)
					(mid 182.762054 -23.819137)
					(end 182.844186 -23.778464)
				)
				(arc
					(start 182.844186 -23.778464)
					(mid 183.274509 -23.474254)
					(end 182.957978 -23.895558)
				)
				(arc
					(start 182.957978 -23.895558)
					(mid 182.839472 -23.963534)
					(end 182.706264 -23.993856)
				)
				(xy 182.704994 -23.995126) (xy 182.57266 -23.995126) (xy 182.57266 -24.172164) (xy 182.715662 -24.172164)
				(arc
					(start 182.716932 -24.173434)
					(mid 182.835642 -24.195435)
					(end 182.94604 -24.2443)
				)
				(arc
					(start 182.94604 -24.2443)
					(mid 183.284718 -24.647431)
					(end 182.837328 -24.369776)
				)
				(arc
					(start 182.837328 -24.369776)
					(mid 182.761737 -24.343252)
					(end 182.682134 -24.334216)
				)
				(xy 182.57266 -24.334216)
				(arc
					(start 182.57266 -24.472646)
					(mid 183.083073 -24.98344)
					(end 183.59374 -24.4729)
				)
			)
		)
	)
	(zone
		(layer "F.Cu")
		(hatch none 0.5)
		(connect_pads
			(clearance 0)
		)
		(min_thickness 0.25)
		(keepout
			(tracks allowed)
			(vias allowed)
			(pads allowed)
			(copperpour allowed)
			(footprints allowed)
		)
		(placement
			(enabled no)
			(sheetname "")
		)
		(fill
			(thermal_gap 0.5)
			(thermal_bridge_width 0.5)
			(island_removal_mode 0)
		)
		(polygon
			(pts
				(xy 159.0294 -88.2904) (xy 159.0294 -84.3534) (xy 163.5252 -84.3534) (xy 163.5252 -88.2904)
			)
		)
	)
	(zone
		(net "P5V_STBY")
		(layer "F.Cu")
		(hatch none 0.5)
		(connect_pads
			(clearance 0.5)
		)
		(min_thickness 0.25)
		(fill yes
			(thermal_gap 0.5)
			(thermal_bridge_width 0.5)
			(island_removal_mode 0)
		)
		(polygon
			(pts
				(xy 37.7952 -66.802) (xy 37.6428 -66.9544) (xy 37.6428 -68.58) (xy 37.7444 -68.6816) (xy 40.9194 -68.6816)
				(xy 40.9575 -68.6435) (xy 40.9194 -68.6054) (xy 40.9194 -66.929) (xy 40.7924 -66.802)
			)
		)
		(polygon
			(pts
				(xy 38.9255 -68.1863) (xy 38.7223 -68.1863) (xy 38.7223 -68.3895) (xy 38.9255 -68.3895)
			)
		)
	)
	(zone
		(layer "F.Cu")
		(hatch none 0.5)
		(connect_pads
			(clearance 0)
		)
		(min_thickness 0.25)
		(keepout
			(tracks not_allowed)
			(vias allowed)
			(pads allowed)
			(copperpour not_allowed)
			(footprints allowed)
		)
		(placement
			(enabled no)
			(sheetname "")
		)
		(fill
			(thermal_gap 0.5)
			(thermal_bridge_width 0.5)
			(island_removal_mode 0)
		)
		(polygon
			(pts
				(arc
					(start 65.330832 -127.168656)
					(mid 64.822918 -127.625046)
					(end 65.223136 -128.178306)
				)
				(xy 65.310766 -128.178306) (xy 65.503806 -127.985266) (xy 65.503806 -127.966978)
				(arc
					(start 65.453006 -127.916178)
					(mid 65.141966 -127.490584)
					(end 65.56756 -127.801624)
				)
				(xy 65.665858 -127.899922) (xy 65.665858 -128.052322) (xy 65.528444 -128.189736) (xy 65.730628 -128.189736)
				(xy 65.808606 -128.111758) (xy 65.808606 -127.899414)
				(arc
					(start 65.906396 -127.801624)
					(mid 66.33199 -127.490584)
					(end 66.02095 -127.916178)
				)
				(xy 65.970658 -127.96647) (xy 65.970658 -128.178814) (xy 65.959736 -128.189736)
				(arc
					(start 66.143378 -128.189736)
					(mid 66.653918 -127.679196)
					(end 66.143378 -127.168656)
				)
			)
		)
	)
	(zone
		(layer "F.Cu")
		(hatch none 0.5)
		(connect_pads
			(clearance 0)
		)
		(min_thickness 0.25)
		(keepout
			(tracks allowed)
			(vias allowed)
			(pads allowed)
			(copperpour allowed)
			(footprints allowed)
		)
		(placement
			(enabled no)
			(sheetname "")
		)
		(fill
			(thermal_gap 0.5)
			(thermal_bridge_width 0.5)
			(island_removal_mode 0)
		)
		(polygon
			(pts
				(xy 108.3056 -226.9744) (xy 108.3056 -222.25) (xy 112.6236 -222.25) (xy 112.6236 -226.9744)
			)
		)
	)
	(zone
		(layer "F.Cu")
		(hatch none 0.5)
		(connect_pads
			(clearance 0)
		)
		(min_thickness 0.25)
		(keepout
			(tracks not_allowed)
			(vias allowed)
			(pads allowed)
			(copperpour not_allowed)
			(footprints allowed)
		)
		(placement
			(enabled no)
			(sheetname "")
		)
		(fill
			(thermal_gap 0.5)
			(thermal_bridge_width 0.5)
			(island_removal_mode 0)
		)
		(polygon
			(pts
				(xy 147.11172 -21.495766)
				(arc
					(start 146.79295 -21.17725)
					(mid 146.641441 -21.110181)
					(end 146.484086 -21.162264)
				)
				(arc
					(start 146.484086 -21.162264)
					(mid 146.386891 -21.91108)
					(end 146.280378 -21.163534)
				)
				(arc
					(start 146.280378 -21.163534)
					(mid 146.55085 -20.956072)
					(end 146.881596 -21.03882)
				)
				(xy 146.883882 -21.03882) (xy 147.19173 -21.346414)
				(arc
					(start 147.269454 -21.201126)
					(mid 147.174342 -21.043629)
					(end 147.105624 -20.872958)
				)
				(xy 147.10537 -20.872958) (xy 147.097496 -20.846542) (xy 147.097496 -20.846034) (xy 147.09521 -20.83816)
				(xy 147.09521 -20.837906) (xy 147.094194 -20.834096)
				(arc
					(start 147.087844 -20.809204)
					(mid 147.064219 -20.687694)
					(end 147.053808 -20.564348)
				)
				(xy 147.0533 -20.56384)
				(arc
					(start 147.0533 -20.502372)
					(mid 147.134326 -19.74893)
					(end 147.215352 -20.502372)
				)
				(arc
					(start 147.215352 -20.530312)
					(mid 147.222728 -20.650978)
					(end 147.244816 -20.769834)
				)
				(xy 147.24507 -20.770088) (xy 147.250658 -20.791678) (xy 147.250658 -20.792186) (xy 147.251674 -20.795742)
				(xy 147.253452 -20.802092)
				(arc
					(start 147.260056 -20.824698)
					(mid 147.301799 -20.934631)
					(end 147.356322 -21.03882)
				)
				(arc
					(start 147.681188 -20.432522)
					(mid 147.433054 -19.581069)
					(end 146.5834 -19.835114)
				)
				(arc
					(start 145.833592 -21.235162)
					(mid 146.089624 -22.080982)
					(end 146.935444 -21.82495)
				)
			)
		)
	)
	(zone
		(net "P3V3_GPIO")
		(layer "F.Cu")
		(hatch none 0.5)
		(connect_pads
			(clearance 0.5)
		)
		(min_thickness 0.25)
		(fill yes
			(thermal_gap 0.5)
			(thermal_bridge_width 0.5)
			(island_removal_mode 0)
		)
		(polygon
			(pts
				(xy 251.911866 -18.217134) (xy 251.46 -18.669) (xy 243.459 -18.669) (xy 243.16563 -18.37563) (xy 243.16563 -18.221706)
				(xy 243.043964 -18.10004) (xy 242.37696 -18.10004) (xy 242.316 -18.161) (xy 242.316 -18.536158)
				(xy 242.512342 -18.7325) (xy 242.512342 -19.246342) (xy 243.351558 -20.085558) (xy 251.225558 -20.085558)
				(xy 257.265678 -26.125678) (xy 267.117322 -26.125678) (xy 267.208 -26.035) (xy 267.208 -24.13) (xy 266.7 -23.622)
				(xy 260.477 -23.622) (xy 255.905 -19.05) (xy 255.905 -13.716) (xy 255.651 -13.462) (xy 253.609856 -13.462)
				(xy 253.458726 -13.61313) (xy 253.458726 -14.070838) (xy 253.19482 -14.334744) (xy 251.956062 -14.334744)
				(xy 251.911866 -14.37894)
			)
		)
		(polygon
			(pts
				(xy 266.6492 -25.4762) (xy 266.446 -25.4762) (xy 266.446 -25.6794) (xy 266.6492 -25.6794)
			)
		)
		(polygon
			(pts
				(xy 266.065 -25.4762) (xy 265.8618 -25.4762) (xy 265.8618 -25.6794) (xy 266.065 -25.6794)
			)
		)
		(polygon
			(pts
				(xy 265.5062 -25.4762) (xy 265.303 -25.4762) (xy 265.303 -25.6794) (xy 265.5062 -25.6794)
			)
		)
		(polygon
			(pts
				(xy 264.922 -25.4762) (xy 264.7188 -25.4762) (xy 264.7188 -25.6794) (xy 264.922 -25.6794)
			)
		)
		(polygon
			(pts
				(xy 264.3632 -25.4762) (xy 264.16 -25.4762) (xy 264.16 -25.6794) (xy 264.3632 -25.6794)
			)
		)
		(polygon
			(pts
				(xy 263.779 -25.4762) (xy 263.5758 -25.4762) (xy 263.5758 -25.6794) (xy 263.779 -25.6794)
			)
		)
		(polygon
			(pts
				(xy 263.2202 -25.4762) (xy 263.017 -25.4762) (xy 263.017 -25.6794) (xy 263.2202 -25.6794)
			)
		)
		(polygon
			(pts
				(xy 262.636 -25.4762) (xy 262.4328 -25.4762) (xy 262.4328 -25.6794) (xy 262.636 -25.6794)
			)
		)
		(polygon
			(pts
				(xy 262.0772 -25.4762) (xy 261.874 -25.4762) (xy 261.874 -25.6794) (xy 262.0772 -25.6794)
			)
		)
		(polygon
			(pts
				(xy 261.493 -25.4762) (xy 261.2898 -25.4762) (xy 261.2898 -25.6794) (xy 261.493 -25.6794)
			)
		)
		(polygon
			(pts
				(xy 260.9342 -25.4762) (xy 260.731 -25.4762) (xy 260.731 -25.6794) (xy 260.9342 -25.6794)
			)
		)
		(polygon
			(pts
				(xy 260.477 -25.4762) (xy 260.2738 -25.4762) (xy 260.2738 -25.6794) (xy 260.477 -25.6794)
			)
		)
		(polygon
			(pts
				(xy 259.9182 -25.4762) (xy 259.715 -25.4762) (xy 259.715 -25.6794) (xy 259.9182 -25.6794)
			)
		)
		(polygon
			(pts
				(xy 259.461 -25.4762) (xy 259.2578 -25.4762) (xy 259.2578 -25.6794) (xy 259.461 -25.6794)
			)
		)
		(polygon
			(pts
				(xy 258.9022 -25.4762) (xy 258.699 -25.4762) (xy 258.699 -25.6794) (xy 258.9022 -25.6794)
			)
		)
		(polygon
			(pts
				(xy 258.431792 -25.4762) (xy 258.228592 -25.4762) (xy 258.228592 -25.6794) (xy 258.431792 -25.6794)
			)
		)
		(polygon
			(pts
				(xy 257.872992 -25.4762) (xy 257.669792 -25.4762) (xy 257.669792 -25.6794) (xy 257.872992 -25.6794)
			)
		)
		(polygon
			(pts
				(xy 243.0526 -18.5674) (xy 242.8494 -18.5674) (xy 242.8494 -18.7706) (xy 243.0526 -18.7706)
			)
		)
	)
	(zone
		(net "AGND_CURRENT_MON")
		(layer "F.Cu")
		(hatch none 0.5)
		(connect_pads
			(clearance 0.5)
		)
		(min_thickness 0.25)
		(fill yes
			(thermal_gap 0.5)
			(thermal_bridge_width 0.5)
			(island_removal_mode 0)
		)
		(polygon
			(pts
				(xy 12.05611 -188.399674) (xy 12.05611 -184.94121) (xy 15.51432 -184.94121) (xy 15.51432 -188.399674)
			)
		)
	)
	(zone
		(layer "F.Cu")
		(hatch none 0.5)
		(connect_pads
			(clearance 0)
		)
		(min_thickness 0.25)
		(keepout
			(tracks not_allowed)
			(vias allowed)
			(pads allowed)
			(copperpour not_allowed)
			(footprints allowed)
		)
		(placement
			(enabled no)
			(sheetname "")
		)
		(fill
			(thermal_gap 0.5)
			(thermal_bridge_width 0.5)
			(island_removal_mode 0)
		)
		(polygon
			(pts
				(arc
					(start 8.10006 -203.499974)
					(mid 9.99998 -201.600054)
					(end 11.8999 -203.499974)
				)
				(arc
					(start 11.8999 -203.499974)
					(mid 9.99998 -205.399894)
					(end 8.10006 -203.499974)
				)
			)
		)
	)
	(zone
		(layer "F.Cu")
		(hatch none 0.5)
		(connect_pads
			(clearance 0)
		)
		(min_thickness 0.25)
		(keepout
			(tracks not_allowed)
			(vias allowed)
			(pads allowed)
			(copperpour not_allowed)
			(footprints allowed)
		)
		(placement
			(enabled no)
			(sheetname "")
		)
		(fill
			(thermal_gap 0.5)
			(thermal_bridge_width 0.5)
			(island_removal_mode 0)
		)
		(polygon
			(pts
				(arc
					(start 15.8496 -86.43366)
					(mid 15.23746 -87.0458)
					(end 15.8496 -87.65794)
				)
				(arc
					(start 16.9672 -87.65794)
					(mid 17.57934 -87.0458)
					(end 16.9672 -86.43366)
				)
				(xy 16.667226 -86.43366) (xy 16.667226 -86.631272)
				(arc
					(start 16.844772 -86.808818)
					(mid 17.155812 -87.234412)
					(end 16.730218 -86.923372)
				)
				(xy 16.505174 -86.698328) (xy 16.505174 -86.43366) (xy 16.362426 -86.43366) (xy 16.362426 -86.647528)
				(arc
					(start 16.086582 -86.923372)
					(mid 15.660988 -87.234412)
					(end 15.972028 -86.808818)
				)
				(xy 16.200374 -86.580472) (xy 16.200374 -86.43366)
			)
		)
	)
	(zone
		(layer "F.Cu")
		(hatch none 0.5)
		(connect_pads
			(clearance 0)
		)
		(min_thickness 0.25)
		(keepout
			(tracks not_allowed)
			(vias allowed)
			(pads allowed)
			(copperpour not_allowed)
			(footprints allowed)
		)
		(placement
			(enabled no)
			(sheetname "")
		)
		(fill
			(thermal_gap 0.5)
			(thermal_bridge_width 0.5)
			(island_removal_mode 0)
		)
		(polygon
			(pts
				(arc
					(start 158.655258 -34.51098)
					(mid 158.144464 -35.021393)
					(end 158.655004 -35.53206)
				)
				(arc
					(start 159.467804 -35.53206)
					(mid 159.978344 -35.02152)
					(end 159.467804 -34.51098)
				)
				(xy 159.26181 -34.51098)
				(arc
					(start 159.26181 -34.60496)
					(mid 159.276327 -34.706801)
					(end 159.318706 -34.80054)
				)
				(arc
					(start 159.318706 -34.80054)
					(mid 159.678892 -35.184357)
					(end 159.215582 -34.934652)
				)
				(arc
					(start 159.215582 -34.934652)
					(mid 159.135651 -34.796005)
					(end 159.101028 -34.639758)
				)
				(xy 159.099758 -34.638488) (xy 159.099758 -34.51098) (xy 158.95701 -34.51098) (xy 158.95701 -34.638488)
				(arc
					(start 158.955994 -34.639504)
					(mid 158.934158 -34.76678)
					(end 158.884874 -34.886138)
				)
				(arc
					(start 158.884874 -34.886138)
					(mid 158.479229 -35.222198)
					(end 158.75889 -34.775902)
				)
				(arc
					(start 158.75889 -34.775902)
					(mid 158.785854 -34.692316)
					(end 158.794958 -34.60496)
				)
				(xy 158.794958 -34.51098)
			)
		)
	)
	(zone
		(layer "F.Cu")
		(hatch none 0.5)
		(connect_pads
			(clearance 0)
		)
		(min_thickness 0.25)
		(keepout
			(tracks allowed)
			(vias allowed)
			(pads allowed)
			(copperpour allowed)
			(footprints not_allowed)
		)
		(placement
			(enabled no)
			(sheetname "")
		)
		(fill
			(thermal_gap 0.5)
			(thermal_bridge_width 0.5)
			(island_removal_mode 0)
		)
		(polygon
			(pts
				(arc
					(start 351.350072 -22.999954)
					(mid 349.750126 -24.5999)
					(end 348.149926 -22.999954)
				)
				(arc
					(start 348.149926 -22.999954)
					(mid 349.750126 -21.399754)
					(end 351.350072 -22.999954)
				)
			)
		)
	)
	(zone
		(net "GND")
		(layer "F.Cu")
		(hatch none 0.5)
		(connect_pads
			(clearance 0.5)
		)
		(min_thickness 0.25)
		(fill yes
			(thermal_gap 0.5)
			(thermal_bridge_width 0.5)
			(island_removal_mode 0)
		)
		(polygon
			(pts
				(xy 16.3576 -73.8632) (xy 16.3576 -77.47) (xy 19.9644 -77.47) (xy 19.9644 -73.8632)
			)
		)
	)
	(zone
		(net "P3V3_STBY_VIN")
		(layer "F.Cu")
		(hatch none 0.5)
		(connect_pads
			(clearance 0.5)
		)
		(min_thickness 0.25)
		(fill yes
			(thermal_gap 0.5)
			(thermal_bridge_width 0.5)
			(island_removal_mode 0)
		)
		(polygon
			(pts
				(xy 62.738 -38.481) (xy 62.357 -38.862) (xy 60.325 -38.862) (xy 59.563 -39.624) (xy 59.563 -48.26)
				(xy 59.944 -48.641) (xy 63.246 -48.641) (xy 63.754 -48.133) (xy 63.754 -43.053) (xy 63.5 -42.799)
				(xy 63.5 -41.656) (xy 64.008 -41.148) (xy 64.008 -38.608) (xy 63.881 -38.481)
			)
		)
		(polygon
			(pts
				(xy 60.8203 -47.8409) (xy 60.6171 -47.8409) (xy 60.6171 -48.0441) (xy 60.8203 -48.0441)
			)
		)
		(polygon
			(pts
				(xy 60.8203 -46.4439) (xy 60.6171 -46.4439) (xy 60.6171 -46.6471) (xy 60.8203 -46.6471)
			)
		)
	)
	(zone
		(layer "F.Cu")
		(hatch none 0.5)
		(connect_pads
			(clearance 0)
		)
		(min_thickness 0.25)
		(keepout
			(tracks allowed)
			(vias allowed)
			(pads allowed)
			(copperpour allowed)
			(footprints allowed)
		)
		(placement
			(enabled no)
			(sheetname "")
		)
		(fill
			(thermal_gap 0.5)
			(thermal_bridge_width 0.5)
			(island_removal_mode 0)
		)
		(polygon
			(pts
				(xy 84.535772 -83.998562) (xy 86.092792 -83.998562) (xy 86.164928 -83.926426) (xy 86.164928 -83.08848)
				(xy 86.110826 -83.034378) (xy 84.607908 -83.034378) (xy 84.398612 -83.243674) (xy 84.398612 -83.861402)
			)
		)
	)
	(zone
		(layer "F.Cu")
		(hatch none 0.5)
		(connect_pads
			(clearance 0)
		)
		(min_thickness 0.25)
		(keepout
			(tracks not_allowed)
			(vias allowed)
			(pads allowed)
			(copperpour not_allowed)
			(footprints allowed)
		)
		(placement
			(enabled no)
			(sheetname "")
		)
		(fill
			(thermal_gap 0.5)
			(thermal_bridge_width 0.5)
			(island_removal_mode 0)
		)
		(polygon
			(pts
				(arc
					(start 342.09355 -210.385914)
					(mid 341.58301 -210.896454)
					(end 342.09355 -211.406994)
				)
				(xy 342.260174 -211.406994)
				(arc
					(start 342.260174 -211.2772)
					(mid 342.248083 -211.202193)
					(end 342.213184 -211.134706)
				)
				(arc
					(start 342.213184 -211.134706)
					(mid 341.90685 -210.70614)
					(end 342.329516 -211.02066)
				)
				(arc
					(start 342.329516 -211.02066)
					(mid 342.392025 -211.124447)
					(end 342.420702 -211.242148)
				)
				(xy 342.422226 -211.243672) (xy 342.422226 -211.406994) (xy 342.564974 -211.406994) (xy 342.564974 -211.243672)
				(arc
					(start 342.566752 -211.241894)
					(mid 342.593294 -211.134928)
					(end 342.650064 -211.040472)
				)
				(xy 342.650064 -211.038186)
				(arc
					(start 342.669368 -211.018882)
					(mid 343.094309 -210.707343)
					(end 342.784176 -211.133436)
				)
				(arc
					(start 342.784176 -211.133436)
					(mid 342.741817 -211.199841)
					(end 342.727026 -211.2772)
				)
				(xy 342.727026 -211.406994)
				(arc
					(start 342.906096 -211.406994)
					(mid 343.41689 -210.896581)
					(end 342.90635 -210.385914)
				)
			)
		)
	)
	(zone
		(net "GND")
		(layer "F.Cu")
		(hatch none 0.5)
		(connect_pads
			(clearance 0.5)
		)
		(min_thickness 0.25)
		(fill yes
			(thermal_gap 0.5)
			(thermal_bridge_width 0.5)
			(island_removal_mode 0)
		)
		(polygon
			(pts
				(xy 140.335 -88.9) (xy 140.208 -89.027) (xy 140.208 -91.567) (xy 140.462 -91.821) (xy 144.78 -91.821)
				(xy 145.161 -92.202) (xy 150.114 -92.202) (xy 150.368 -91.948) (xy 150.368 -91.144344) (xy 150.436326 -91.076018)
				(xy 150.436326 -89.921842) (xy 150.42515 -89.910666) (xy 150.246334 -89.910666) (xy 150.241 -89.916)
				(xy 145.034 -89.916) (xy 144.907 -90.043) (xy 141.605 -90.043) (xy 141.478 -89.916) (xy 141.478 -89.027)
				(xy 141.351 -88.9)
			)
		)
	)
	(zone
		(layer "F.Cu")
		(hatch none 0.5)
		(connect_pads
			(clearance 0)
		)
		(min_thickness 0.25)
		(keepout
			(tracks allowed)
			(vias allowed)
			(pads allowed)
			(copperpour allowed)
			(footprints not_allowed)
		)
		(placement
			(enabled no)
			(sheetname "")
		)
		(fill
			(thermal_gap 0.5)
			(thermal_bridge_width 0.5)
			(island_removal_mode 0)
		)
		(polygon
			(pts
				(xy 269.599918 -77.0001) (xy 207.62214 -77.0001) (xy 207.62214 -52.999894) (xy 204.099922 -52.999894)
				(xy 204.099922 -44.99991) (xy 211.600034 -44.99991) (xy 211.600034 -18.940018) (xy 277.599902 -18.940018)
				(xy 277.599902 -50.939954) (xy 269.599918 -50.939954)
			)
		)
	)
	(zone
		(net "GND")
		(layer "F.Cu")
		(hatch none 0.5)
		(connect_pads
			(clearance 0.5)
		)
		(min_thickness 0.25)
		(fill yes
			(thermal_gap 0.5)
			(thermal_bridge_width 0.5)
			(island_removal_mode 0)
		)
		(polygon
			(pts
				(xy 246.253 -6.35) (xy 245.999 -6.604) (xy 245.999 -8.636) (xy 246.126 -8.763) (xy 249.555 -8.763)
				(xy 249.682 -8.636) (xy 249.682 -6.477) (xy 249.555 -6.35)
			)
		)
	)
	(zone
		(layer "F.Cu")
		(hatch none 0.5)
		(connect_pads
			(clearance 0)
		)
		(min_thickness 0.25)
		(keepout
			(tracks not_allowed)
			(vias allowed)
			(pads allowed)
			(copperpour not_allowed)
			(footprints allowed)
		)
		(placement
			(enabled no)
			(sheetname "")
		)
		(fill
			(thermal_gap 0.5)
			(thermal_bridge_width 0.5)
			(island_removal_mode 0)
		)
		(polygon
			(pts
				(arc
					(start 298.893992 -210.385914)
					(mid 298.383198 -210.896327)
					(end 298.893738 -211.406994)
				)
				(xy 299.060362 -211.406994)
				(arc
					(start 299.060362 -211.2518)
					(mid 299.048757 -211.188683)
					(end 299.015658 -211.13369)
				)
				(arc
					(start 299.015658 -211.13369)
					(mid 298.705332 -210.707646)
					(end 299.13072 -211.018882)
				)
				(xy 299.146214 -211.034376)
				(arc
					(start 299.146214 -211.036916)
					(mid 299.196492 -211.121289)
					(end 299.220636 -211.216494)
				)
				(xy 299.222414 -211.218272) (xy 299.222414 -211.406994) (xy 299.365162 -211.406994) (xy 299.365162 -211.218272)
				(arc
					(start 299.36694 -211.216494)
					(mid 299.387521 -211.134707)
					(end 299.429932 -211.061808)
				)
				(xy 299.429932 -211.05876) (xy 299.453046 -211.035646) (xy 299.453554 -211.034884)
				(arc
					(start 299.469556 -211.018882)
					(mid 299.894497 -210.707343)
					(end 299.584364 -211.133436)
				)
				(arc
					(start 299.567854 -211.149946)
					(mid 299.537797 -211.195073)
					(end 299.527214 -211.248244)
				)
				(xy 299.527214 -211.2518) (xy 299.527214 -211.406994)
				(arc
					(start 299.706538 -211.406994)
					(mid 300.217078 -210.896454)
					(end 299.706538 -210.385914)
				)
			)
		)
	)
	(zone
		(layer "F.Cu")
		(hatch none 0.5)
		(connect_pads
			(clearance 0)
		)
		(min_thickness 0.25)
		(keepout
			(tracks not_allowed)
			(vias allowed)
			(pads allowed)
			(copperpour not_allowed)
			(footprints allowed)
		)
		(placement
			(enabled no)
			(sheetname "")
		)
		(fill
			(thermal_gap 0.5)
			(thermal_bridge_width 0.5)
			(island_removal_mode 0)
		)
		(polygon
			(pts
				(arc
					(start 190.493904 -210.385914)
					(mid 189.98311 -210.896327)
					(end 190.49365 -211.406994)
				)
				(xy 190.660274 -211.406994)
				(arc
					(start 190.660274 -211.28228)
					(mid 190.648171 -211.204927)
					(end 190.61303 -211.13496)
				)
				(arc
					(start 190.61303 -211.13496)
					(mid 190.306992 -210.70594)
					(end 190.729616 -211.02066)
				)
				(arc
					(start 190.729616 -211.02066)
					(mid 190.792229 -211.127222)
					(end 190.820802 -211.247482)
				)
				(xy 190.822326 -211.249006) (xy 190.822326 -211.406994) (xy 190.965074 -211.406994) (xy 190.965074 -211.259166)
				(arc
					(start 190.966598 -211.257642)
					(mid 190.996169 -211.136038)
					(end 191.061086 -211.029042)
				)
				(xy 191.061086 -211.02701)
				(arc
					(start 191.069468 -211.018628)
					(mid 191.494779 -210.707724)
					(end 191.184784 -211.13369)
				)
				(arc
					(start 191.184784 -211.13369)
					(mid 191.141948 -211.207983)
					(end 191.127126 -211.29244)
				)
				(xy 191.127126 -211.406994)
				(arc
					(start 191.30645 -211.406994)
					(mid 191.81699 -210.896454)
					(end 191.30645 -210.385914)
				)
			)
		)
	)
	(zone
		(layer "F.Cu")
		(hatch none 0.5)
		(connect_pads
			(clearance 0)
		)
		(min_thickness 0.25)
		(keepout
			(tracks not_allowed)
			(vias allowed)
			(pads allowed)
			(copperpour not_allowed)
			(footprints allowed)
		)
		(placement
			(enabled no)
			(sheetname "")
		)
		(fill
			(thermal_gap 0.5)
			(thermal_bridge_width 0.5)
			(island_removal_mode 0)
		)
		(polygon
			(pts
				(arc
					(start 66.893948 -210.385914)
					(mid 66.383154 -210.896327)
					(end 66.893694 -211.406994)
				)
				(xy 67.060318 -211.406994)
				(arc
					(start 67.060318 -211.299298)
					(mid 67.047648 -211.213975)
					(end 67.010788 -211.135976)
				)
				(arc
					(start 67.010788 -211.135976)
					(mid 66.708739 -210.70443)
					(end 67.128644 -211.022438)
				)
				(arc
					(start 67.128644 -211.022438)
					(mid 67.192419 -211.136764)
					(end 67.2211 -211.2645)
				)
				(xy 67.22237 -211.26577) (xy 67.22237 -211.406994) (xy 67.365118 -211.406994) (xy 67.365118 -211.26577)
				(arc
					(start 67.366388 -211.2645)
					(mid 67.396561 -211.137809)
					(end 67.464178 -211.026502)
				)
				(xy 67.464178 -211.02447)
				(arc
					(start 67.469512 -211.019136)
					(mid 67.894585 -210.707158)
					(end 67.585336 -211.134198)
				)
				(arc
					(start 67.585336 -211.134198)
					(mid 67.542165 -211.21044)
					(end 67.52717 -211.296758)
				)
				(xy 67.52717 -211.299298) (xy 67.52717 -211.406994)
				(arc
					(start 67.706494 -211.406994)
					(mid 68.217034 -210.896454)
					(end 67.706494 -210.385914)
				)
			)
		)
	)
	(zone
		(layer "F.Cu")
		(hatch none 0.5)
		(connect_pads
			(clearance 0)
		)
		(min_thickness 0.25)
		(keepout
			(tracks not_allowed)
			(vias allowed)
			(pads allowed)
			(copperpour not_allowed)
			(footprints allowed)
		)
		(placement
			(enabled no)
			(sheetname "")
		)
		(fill
			(thermal_gap 0.5)
			(thermal_bridge_width 0.5)
			(island_removal_mode 0)
		)
		(polygon
			(pts
				(arc
					(start 198.429118 -45.590714)
					(mid 197.817105 -44.97832)
					(end 197.204838 -45.59046)
				)
				(arc
					(start 197.204838 -46.70806)
					(mid 197.816978 -47.3202)
					(end 198.429118 -46.70806)
				)
				(xy 198.429118 -46.378114)
				(arc
					(start 198.275956 -46.378114)
					(mid 198.119856 -46.411584)
					(end 197.991222 -46.50613)
				)
				(arc
					(start 197.991222 -46.50613)
					(mid 197.714988 -46.954789)
					(end 197.835266 -46.441868)
				)
				(arc
					(start 197.835266 -46.441868)
					(mid 198.013104 -46.283886)
					(end 198.241412 -46.217078)
				)
				(xy 198.242428 -46.216062) (xy 198.429118 -46.216062) (xy 198.429118 -46.073314) (xy 198.146162 -46.073314)
				(arc
					(start 198.144638 -46.072044)
					(mid 197.945321 -46.00633)
					(end 197.798436 -45.856398)
				)
				(arc
					(start 197.798436 -45.856398)
					(mid 197.748921 -45.332759)
					(end 197.965314 -45.812202)
				)
				(arc
					(start 197.965314 -45.812202)
					(mid 198.061607 -45.885316)
					(end 198.17969 -45.911262)
				)
				(xy 198.429118 -45.911262)
			)
		)
	)
	(zone
		(layer "F.Cu")
		(hatch none 0.5)
		(connect_pads
			(clearance 0)
		)
		(min_thickness 0.25)
		(keepout
			(tracks not_allowed)
			(vias allowed)
			(pads allowed)
			(copperpour not_allowed)
			(footprints allowed)
		)
		(placement
			(enabled no)
			(sheetname "")
		)
		(fill
			(thermal_gap 0.5)
			(thermal_bridge_width 0.5)
			(island_removal_mode 0)
		)
		(polygon
			(pts
				(arc
					(start 310.093868 -210.385914)
					(mid 309.583328 -210.896454)
					(end 310.093868 -211.406994)
				)
				(xy 310.260492 -211.406994)
				(arc
					(start 310.260492 -211.281518)
					(mid 310.248285 -211.204497)
					(end 310.212994 -211.13496)
				)
				(arc
					(start 310.212994 -211.13496)
					(mid 309.90787 -210.705289)
					(end 310.329834 -211.020914)
				)
				(arc
					(start 310.329834 -211.020914)
					(mid 310.392427 -211.126818)
					(end 310.42102 -211.246466)
				)
				(xy 310.422544 -211.24799) (xy 310.422544 -211.406994) (xy 310.565292 -211.406994) (xy 310.565292 -211.24799)
				(arc
					(start 310.566816 -211.246212)
					(mid 310.594351 -211.135279)
					(end 310.65343 -211.037424)
				)
				(xy 310.65343 -211.035138)
				(arc
					(start 310.669686 -211.018882)
					(mid 311.094627 -210.707343)
					(end 310.784494 -211.133436)
				)
				(arc
					(start 310.784494 -211.133436)
					(mid 310.742089 -211.202145)
					(end 310.727344 -211.281518)
				)
				(xy 310.727344 -211.406994)
				(arc
					(start 310.906414 -211.406994)
					(mid 311.417208 -210.896581)
					(end 310.906668 -210.385914)
				)
			)
		)
	)
	(zone
		(net "MB0_P12V_MAIN_R")
		(layer "F.Cu")
		(hatch none 0.5)
		(connect_pads
			(clearance 0.5)
		)
		(min_thickness 0.25)
		(fill yes
			(thermal_gap 0.5)
			(thermal_bridge_width 0.5)
			(island_removal_mode 0)
		)
		(polygon
			(pts
				(xy 26.8478 -199.8472) (xy 26.797 -199.898) (xy 24.892 -199.898) (xy 24.511 -200.279) (xy 24.511 -205.105)
				(xy 25.146 -205.74) (xy 25.1714 -205.74) (xy 25.5016 -206.0702) (xy 25.5016 -207.0608) (xy 25.6159 -207.1751)
				(xy 31.1404 -207.1751) (xy 32.258 -206.0575) (xy 32.258 -200.787) (xy 31.3182 -199.8472)
			)
		)
	)
	(zone
		(layer "F.Cu")
		(hatch none 0.5)
		(connect_pads
			(clearance 0)
		)
		(min_thickness 0.25)
		(keepout
			(tracks allowed)
			(vias allowed)
			(pads allowed)
			(copperpour allowed)
			(footprints allowed)
		)
		(placement
			(enabled no)
			(sheetname "")
		)
		(fill
			(thermal_gap 0.5)
			(thermal_bridge_width 0.5)
			(island_removal_mode 0)
		)
		(polygon
			(pts
				(xy 56.261 -125.984) (xy 56.261 -128.016) (xy 53.721 -128.016) (xy 53.721 -125.984)
			)
		)
	)
	(zone
		(layer "F.Cu")
		(hatch none 0.5)
		(connect_pads
			(clearance 0)
		)
		(min_thickness 0.25)
		(keepout
			(tracks not_allowed)
			(vias allowed)
			(pads allowed)
			(copperpour not_allowed)
			(footprints allowed)
		)
		(placement
			(enabled no)
			(sheetname "")
		)
		(fill
			(thermal_gap 0.5)
			(thermal_bridge_width 0.5)
			(island_removal_mode 0)
		)
		(polygon
			(pts
				(arc
					(start 138.494008 -210.385914)
					(mid 137.983214 -210.896327)
					(end 138.493754 -211.406994)
				)
				(xy 138.660378 -211.406994)
				(arc
					(start 138.660378 -211.3534)
					(mid 138.645666 -211.242908)
					(end 138.60272 -211.14004)
				)
				(arc
					(start 138.60272 -211.14004)
					(mid 138.314489 -210.698985)
					(end 138.724894 -211.02955)
				)
				(arc
					(start 138.724894 -211.02955)
					(mid 138.79231 -211.167814)
					(end 138.821414 -211.318856)
				)
				(xy 138.82243 -211.319872) (xy 138.82243 -211.406994) (xy 138.965178 -211.406994) (xy 138.965178 -211.250276)
				(arc
					(start 138.966702 -211.248498)
					(mid 138.994761 -211.135493)
					(end 139.055094 -211.0359)
				)
				(xy 139.055094 -211.033614)
				(arc
					(start 139.069572 -211.018882)
					(mid 139.494965 -210.707641)
					(end 139.184634 -211.13369)
				)
				(arc
					(start 139.184634 -211.13369)
					(mid 139.142097 -211.203459)
					(end 139.12723 -211.283804)
				)
				(xy 139.12723 -211.406994)
				(arc
					(start 139.306554 -211.406994)
					(mid 139.817094 -210.896454)
					(end 139.306554 -210.385914)
				)
			)
		)
	)
	(zone
		(layer "F.Cu")
		(hatch none 0.5)
		(connect_pads
			(clearance 0)
		)
		(min_thickness 0.25)
		(keepout
			(tracks not_allowed)
			(vias allowed)
			(pads allowed)
			(copperpour not_allowed)
			(footprints allowed)
		)
		(placement
			(enabled no)
			(sheetname "")
		)
		(fill
			(thermal_gap 0.5)
			(thermal_bridge_width 0.5)
			(island_removal_mode 0)
		)
		(polygon
			(pts
				(arc
					(start 308.812438 -24.999696)
					(mid 308.875077 -25.093039)
					(end 308.913784 -25.198578)
				)
				(arc
					(start 309.0037 -25.030684)
					(mid 308.95296 -24.947394)
					(end 308.889654 -24.873204)
				)
				(arc
					(start 308.889654 -24.873204)
					(mid 308.833294 -24.79399)
					(end 308.805834 -24.700738)
				)
				(xy 308.803548 -24.698452)
				(arc
					(start 308.803548 -24.302466)
					(mid 308.883543 -23.549132)
					(end 308.9656 -24.302212)
				)
				(arc
					(start 308.9656 -24.664924)
					(mid 308.975756 -24.715512)
					(end 309.004462 -24.758396)
				)
				(arc
					(start 309.004462 -24.758396)
					(mid 309.051028 -24.809378)
					(end 309.092854 -24.864314)
				)
				(arc
					(start 309.431182 -24.232616)
					(mid 309.183048 -23.381163)
					(end 308.333394 -23.635208)
				)
				(arc
					(start 307.583586 -25.035256)
					(mid 307.839618 -25.881076)
					(end 308.685438 -25.625044)
				)
				(xy 308.764432 -25.47747)
				(arc
					(start 308.764432 -25.306782)
					(mid 308.740877 -25.188833)
					(end 308.674008 -25.08885)
				)
				(arc
					(start 308.49443 -24.909018)
					(mid 308.437236 -24.871732)
					(end 308.370224 -24.858726)
				)
				(arc
					(start 308.32044 -24.858726)
					(mid 308.285112 -24.865847)
					(end 308.255162 -24.885904)
				)
				(arc
					(start 308.255162 -24.885904)
					(mid 308.23074 -24.919181)
					(end 308.21757 -24.958294)
				)
				(arc
					(start 308.21757 -24.958294)
					(mid 308.132963 -25.711222)
					(end 308.053486 -24.957786)
				)
				(xy 308.053486 -24.947626)
				(arc
					(start 308.055518 -24.94534)
					(mid 308.08333 -24.851107)
					(end 308.140354 -24.771096)
				)
				(arc
					(start 308.140354 -24.771096)
					(mid 308.206531 -24.72347)
					(end 308.284372 -24.699214)
				)
				(xy 308.286912 -24.696674) (xy 308.403752 -24.696674)
				(arc
					(start 308.40553 -24.698452)
					(mid 308.50046 -24.722514)
					(end 308.5846 -24.77262)
				)
				(xy 308.58714 -24.77262) (xy 308.608476 -24.793956) (xy 308.611016 -24.796496) (xy 308.812438 -24.997918)
			)
		)
	)
	(zone
		(layer "F.Cu")
		(hatch none 0.5)
		(connect_pads
			(clearance 0)
		)
		(min_thickness 0.25)
		(keepout
			(tracks not_allowed)
			(vias allowed)
			(pads allowed)
			(copperpour not_allowed)
			(footprints allowed)
		)
		(placement
			(enabled no)
			(sheetname "")
		)
		(fill
			(thermal_gap 0.5)
			(thermal_bridge_width 0.5)
			(island_removal_mode 0)
		)
		(polygon
			(pts
				(arc
					(start 314.8838 -34.503614)
					(mid 314.37326 -35.014154)
					(end 314.8838 -35.524694)
				)
				(arc
					(start 315.696346 -35.524694)
					(mid 316.20714 -35.014281)
					(end 315.6966 -34.503614)
				)
				(xy 315.536326 -34.503614)
				(arc
					(start 315.536326 -34.5821)
					(mid 315.549213 -34.679901)
					(end 315.586872 -34.771076)
				)
				(arc
					(start 315.586872 -34.771076)
					(mid 315.876097 -35.211405)
					(end 315.464952 -34.882074)
				)
				(arc
					(start 315.464952 -34.882074)
					(mid 315.402686 -34.75538)
					(end 315.37529 -34.616898)
				)
				(xy 315.374274 -34.615628) (xy 315.374274 -34.503614) (xy 315.231526 -34.503614) (xy 315.231526 -34.615628)
				(arc
					(start 315.230256 -34.616898)
					(mid 315.196646 -34.762232)
					(end 315.12002 -34.890202)
				)
				(arc
					(start 315.12002 -34.890202)
					(mid 314.696781 -35.204386)
					(end 315.003688 -34.775902)
				)
				(arc
					(start 315.003688 -34.775902)
					(mid 315.052553 -34.684555)
					(end 315.069474 -34.582354)
				)
				(xy 315.069474 -34.503614)
			)
		)
	)
	(zone
		(layer "F.Cu")
		(hatch none 0.5)
		(connect_pads
			(clearance 0)
		)
		(min_thickness 0.25)
		(keepout
			(tracks not_allowed)
			(vias allowed)
			(pads allowed)
			(copperpour not_allowed)
			(footprints allowed)
		)
		(placement
			(enabled no)
			(sheetname "")
		)
		(fill
			(thermal_gap 0.5)
			(thermal_bridge_width 0.5)
			(island_removal_mode 0)
		)
		(polygon
			(pts
				(arc
					(start 272.57883 -14.52245)
					(mid 272.06829 -14.01191)
					(end 271.55775 -14.52245)
				)
				(arc
					(start 271.55775 -15.334996)
					(mid 272.068163 -15.84579)
					(end 272.57883 -15.33525)
				)
				(xy 272.57883 -15.168626)
				(arc
					(start 272.5166 -15.168626)
					(mid 272.40949 -15.181539)
					(end 272.308574 -15.21968)
				)
				(arc
					(start 272.308574 -15.21968)
					(mid 271.876173 -15.520139)
					(end 272.193004 -15.099538)
				)
				(arc
					(start 272.193004 -15.099538)
					(mid 272.331728 -15.035322)
					(end 272.482056 -15.00759)
				)
				(xy 272.483072 -15.006574) (xy 272.57883 -15.006574) (xy 272.57883 -14.863826) (xy 272.483072 -14.863826)
				(arc
					(start 272.482056 -14.86281)
					(mid 272.326392 -14.832706)
					(end 272.184114 -14.762734)
				)
				(arc
					(start 272.184114 -14.762734)
					(mid 271.88254 -14.331184)
					(end 272.304256 -14.646402)
				)
				(arc
					(start 272.304256 -14.646402)
					(mid 272.406878 -14.687703)
					(end 272.5166 -14.701774)
				)
				(xy 272.57883 -14.701774)
			)
		)
	)
	(zone
		(layer "F.Cu")
		(hatch none 0.5)
		(connect_pads
			(clearance 0)
		)
		(min_thickness 0.25)
		(keepout
			(tracks not_allowed)
			(vias allowed)
			(pads allowed)
			(copperpour not_allowed)
			(footprints allowed)
		)
		(placement
			(enabled no)
			(sheetname "")
		)
		(fill
			(thermal_gap 0.5)
			(thermal_bridge_width 0.5)
			(island_removal_mode 0)
		)
		(polygon
			(pts
				(arc
					(start 24.23668 -112.398556)
					(mid 24.058576 -112.289097)
					(end 23.861014 -112.220756)
				)
				(arc
					(start 23.861014 -112.521746)
					(mid 24.473027 -113.13414)
					(end 25.085294 -112.522)
				)
				(arc
					(start 25.085294 -111.4044)
					(mid 24.473154 -110.79226)
					(end 23.861014 -111.4044)
				)
				(arc
					(start 23.861014 -111.705644)
					(mid 24.058569 -111.637287)
					(end 24.23668 -111.527844)
				)
				(arc
					(start 24.23668 -111.527844)
					(mid 24.659916 -111.214077)
					(end 24.353012 -111.642398)
				)
				(arc
					(start 24.353012 -111.642398)
					(mid 24.121039 -111.786975)
					(end 23.861014 -111.871252)
				)
				(arc
					(start 23.861014 -112.055148)
					(mid 24.121047 -112.139407)
					(end 24.353012 -112.284002)
				)
				(arc
					(start 24.353012 -112.284002)
					(mid 24.659963 -112.712371)
					(end 24.23668 -112.398556)
				)
			)
		)
	)
	(zone
		(layer "F.Cu")
		(hatch none 0.5)
		(connect_pads
			(clearance 0)
		)
		(min_thickness 0.25)
		(keepout
			(tracks not_allowed)
			(vias allowed)
			(pads allowed)
			(copperpour not_allowed)
			(footprints allowed)
		)
		(placement
			(enabled no)
			(sheetname "")
		)
		(fill
			(thermal_gap 0.5)
			(thermal_bridge_width 0.5)
			(island_removal_mode 0)
		)
		(polygon
			(pts
				(arc
					(start 313.312302 -21.199602)
					(mid 313.375874 -21.294557)
					(end 313.414664 -21.40204)
				)
				(arc
					(start 313.505088 -21.233384)
					(mid 313.453801 -21.148561)
					(end 313.389518 -21.07311)
				)
				(arc
					(start 313.389518 -21.07311)
					(mid 313.333158 -20.993896)
					(end 313.305698 -20.900644)
				)
				(xy 313.303412 -20.898358)
				(arc
					(start 313.303412 -20.502372)
					(mid 313.384438 -19.74893)
					(end 313.465464 -20.502372)
				)
				(arc
					(start 313.465464 -20.86483)
					(mid 313.47562 -20.915418)
					(end 313.504326 -20.958302)
				)
				(arc
					(start 313.504326 -20.958302)
					(mid 313.55176 -21.010479)
					(end 313.594242 -21.06676)
				)
				(xy 313.937396 -20.426426) (xy 313.937142 -20.426172)
				(arc
					(start 313.93511 -20.425156)
					(mid 313.679434 -19.579255)
					(end 312.833512 -19.835114)
				)
				(xy 312.83148 -19.833844) (xy 312.081418 -21.233892)
				(arc
					(start 312.08345 -21.235162)
					(mid 312.339482 -22.080982)
					(end 313.185302 -21.82495)
				)
				(xy 313.187334 -21.82622) (xy 313.264296 -21.68271)
				(arc
					(start 313.264296 -21.506688)
					(mid 313.240741 -21.388739)
					(end 313.173872 -21.288756)
				)
				(arc
					(start 312.994294 -21.108924)
					(mid 312.9371 -21.071638)
					(end 312.870088 -21.058632)
				)
				(arc
					(start 312.820304 -21.058632)
					(mid 312.784976 -21.065753)
					(end 312.755026 -21.08581)
				)
				(arc
					(start 312.755026 -21.08581)
					(mid 312.730604 -21.119087)
					(end 312.717434 -21.1582)
				)
				(arc
					(start 312.717434 -21.1582)
					(mid 312.632827 -21.911128)
					(end 312.55335 -21.157692)
				)
				(xy 312.55335 -21.147532)
				(arc
					(start 312.555382 -21.145246)
					(mid 312.583194 -21.051013)
					(end 312.640218 -20.971002)
				)
				(arc
					(start 312.640218 -20.971002)
					(mid 312.706395 -20.923376)
					(end 312.784236 -20.89912)
				)
				(xy 312.786776 -20.89658) (xy 312.903616 -20.89658)
				(arc
					(start 312.905394 -20.898358)
					(mid 313.000324 -20.92242)
					(end 313.084464 -20.972526)
				)
				(xy 313.087004 -20.972526) (xy 313.10834 -20.993862) (xy 313.11088 -20.996402) (xy 313.312302 -21.197824)
			)
		)
	)
	(zone
		(net "P0V9_LX")
		(layer "F.Cu")
		(hatch none 0.5)
		(connect_pads
			(clearance 0.5)
		)
		(min_thickness 0.25)
		(fill yes
			(thermal_gap 0.5)
			(thermal_bridge_width 0.5)
			(island_removal_mode 0)
		)
		(polygon
			(pts
				(xy 155.210002 -61.114432) (xy 155.210002 -66.956432) (xy 155.718002 -67.464432) (xy 160.417002 -67.464432)
				(xy 160.671002 -67.210432) (xy 160.671002 -61.495432) (xy 160.290002 -61.114432)
			)
		)
	)
	(zone
		(net "P5V_USB")
		(layer "F.Cu")
		(hatch none 0.5)
		(connect_pads
			(clearance 0.5)
		)
		(min_thickness 0.25)
		(fill yes
			(thermal_gap 0.5)
			(thermal_bridge_width 0.5)
			(island_removal_mode 0)
		)
		(polygon
			(pts
				(xy 33.26384 -37.54374) (xy 31.79572 -39.01186) (xy 31.79572 -43.20794) (xy 31.623 -43.38066) (xy 31.623 -55.372)
				(xy 32.766 -56.515) (xy 37.846 -56.515) (xy 38.227 -56.134) (xy 38.227 -50.8) (xy 35.433 -48.006)
				(xy 35.433 -45.10151) (xy 35.420808 -45.089572) (xy 35.420808 -38.14064) (xy 34.823908 -37.54374)
			)
		)
		(polygon
			(pts
				(xy 32.2326 -48.2092) (xy 32.0294 -48.2092) (xy 32.0294 -48.4124) (xy 32.2326 -48.4124)
			)
		)
		(polygon
			(pts
				(xy 32.2326 -47.5996) (xy 32.0294 -47.5996) (xy 32.0294 -47.8028) (xy 32.2326 -47.8028)
			)
		)
		(polygon
			(pts
				(xy 32.2326 -47.1932) (xy 32.0294 -47.1932) (xy 32.0294 -47.3964) (xy 32.2326 -47.3964)
			)
		)
		(polygon
			(pts
				(xy 32.2326 -46.5836) (xy 32.0294 -46.5836) (xy 32.0294 -46.7868) (xy 32.2326 -46.7868)
			)
		)
		(polygon
			(pts
				(xy 32.2326 -46.1772) (xy 32.0294 -46.1772) (xy 32.0294 -46.3804) (xy 32.2326 -46.3804)
			)
		)
		(polygon
			(pts
				(xy 32.2326 -45.5676) (xy 32.0294 -45.5676) (xy 32.0294 -45.7708) (xy 32.2326 -45.7708)
			)
		)
		(polygon
			(pts
				(xy 32.2326 -45.1612) (xy 32.0294 -45.1612) (xy 32.0294 -45.3644) (xy 32.2326 -45.3644)
			)
		)
		(polygon
			(pts
				(xy 32.2326 -44.5516) (xy 32.0294 -44.5516) (xy 32.0294 -44.7548) (xy 32.2326 -44.7548)
			)
		)
		(polygon
			(pts
				(xy 32.2326 -44.1452) (xy 32.0294 -44.1452) (xy 32.0294 -44.3484) (xy 32.2326 -44.3484)
			)
		)
		(polygon
			(pts
				(xy 32.2326 -43.5356) (xy 32.0294 -43.5356) (xy 32.0294 -43.7388) (xy 32.2326 -43.7388)
			)
		)
	)
	(zone
		(layer "F.Cu")
		(hatch none 0.5)
		(connect_pads
			(clearance 0)
		)
		(min_thickness 0.25)
		(keepout
			(tracks not_allowed)
			(vias allowed)
			(pads allowed)
			(copperpour not_allowed)
			(footprints allowed)
		)
		(placement
			(enabled no)
			(sheetname "")
		)
		(fill
			(thermal_gap 0.5)
			(thermal_bridge_width 0.5)
			(island_removal_mode 0)
		)
		(polygon
			(pts
				(arc
					(start 311.254902 -25.033478)
					(mid 311.203738 -24.948669)
					(end 311.139586 -24.873204)
				)
				(arc
					(start 311.139586 -24.873204)
					(mid 311.083226 -24.79399)
					(end 311.055766 -24.700738)
				)
				(xy 311.05348 -24.698452)
				(arc
					(start 311.05348 -24.302466)
					(mid 311.134506 -23.549024)
					(end 311.215532 -24.302466)
				)
				(arc
					(start 311.215532 -24.664924)
					(mid 311.225688 -24.715512)
					(end 311.254394 -24.758396)
				)
				(arc
					(start 311.254394 -24.758396)
					(mid 311.301813 -24.810453)
					(end 311.34431 -24.8666)
				)
				(xy 311.687464 -24.226266)
				(arc
					(start 311.685432 -24.224996)
					(mid 311.4294 -23.379176)
					(end 310.58358 -23.635208)
				)
				(xy 310.581548 -23.633938) (xy 309.831486 -25.033732) (xy 309.83174 -25.033986)
				(arc
					(start 309.833772 -25.035002)
					(mid 310.089448 -25.880903)
					(end 310.93537 -25.625044)
				)
				(xy 310.937402 -25.626314) (xy 311.014364 -25.48255)
				(arc
					(start 311.014364 -25.306782)
					(mid 310.990809 -25.188833)
					(end 310.92394 -25.08885)
				)
				(arc
					(start 310.744362 -24.909018)
					(mid 310.687168 -24.871732)
					(end 310.620156 -24.858726)
				)
				(arc
					(start 310.570372 -24.858726)
					(mid 310.535044 -24.865847)
					(end 310.505094 -24.885904)
				)
				(arc
					(start 310.505094 -24.885904)
					(mid 310.480672 -24.919181)
					(end 310.467502 -24.958294)
				)
				(arc
					(start 310.467502 -24.958294)
					(mid 310.382895 -25.711222)
					(end 310.303418 -24.957786)
				)
				(xy 310.303418 -24.947626)
				(arc
					(start 310.30545 -24.94534)
					(mid 310.333262 -24.851107)
					(end 310.390286 -24.771096)
				)
				(arc
					(start 310.390286 -24.771096)
					(mid 310.456463 -24.72347)
					(end 310.534304 -24.699214)
				)
				(xy 310.536844 -24.696674) (xy 310.653684 -24.696674)
				(arc
					(start 310.655462 -24.698452)
					(mid 310.750392 -24.722514)
					(end 310.834532 -24.77262)
				)
				(xy 310.837072 -24.77262) (xy 310.858408 -24.793956) (xy 310.860948 -24.796496) (xy 311.06237 -24.997918)
				(arc
					(start 311.06237 -24.999696)
					(mid 311.125942 -25.094651)
					(end 311.164732 -25.202134)
				)
			)
		)
	)
	(zone
		(layer "F.Cu")
		(hatch none 0.5)
		(connect_pads
			(clearance 0)
		)
		(min_thickness 0.25)
		(keepout
			(tracks not_allowed)
			(vias allowed)
			(pads allowed)
			(copperpour not_allowed)
			(footprints allowed)
		)
		(placement
			(enabled no)
			(sheetname "")
		)
		(fill
			(thermal_gap 0.5)
			(thermal_bridge_width 0.5)
			(island_removal_mode 0)
		)
		(polygon
			(pts
				(arc
					(start 187.294012 -210.385914)
					(mid 186.783218 -210.896327)
					(end 187.293758 -211.406994)
				)
				(xy 187.460382 -211.406994)
				(arc
					(start 187.460382 -211.283804)
					(mid 187.448224 -211.205802)
					(end 187.412884 -211.135214)
				)
				(arc
					(start 187.412884 -211.135214)
					(mid 187.106846 -210.706194)
					(end 187.52947 -211.020914)
				)
				(arc
					(start 187.52947 -211.020914)
					(mid 187.592291 -211.127971)
					(end 187.62091 -211.248752)
				)
				(xy 187.622434 -211.250276) (xy 187.622434 -211.406994) (xy 187.765182 -211.406994) (xy 187.765182 -211.250276)
				(arc
					(start 187.766706 -211.248498)
					(mid 187.794765 -211.135493)
					(end 187.855098 -211.0359)
				)
				(xy 187.855098 -211.033614)
				(arc
					(start 187.869576 -211.018882)
					(mid 188.294969 -210.707641)
					(end 187.984638 -211.13369)
				)
				(arc
					(start 187.984638 -211.13369)
					(mid 187.942101 -211.203459)
					(end 187.927234 -211.283804)
				)
				(xy 187.927234 -211.406994)
				(arc
					(start 188.106558 -211.406994)
					(mid 188.617098 -210.896454)
					(end 188.106558 -210.385914)
				)
			)
		)
	)
	(zone
		(layer "F.Cu")
		(hatch none 0.5)
		(connect_pads
			(clearance 0)
		)
		(min_thickness 0.25)
		(keepout
			(tracks not_allowed)
			(vias allowed)
			(pads allowed)
			(copperpour not_allowed)
			(footprints allowed)
		)
		(placement
			(enabled no)
			(sheetname "")
		)
		(fill
			(thermal_gap 0.5)
			(thermal_bridge_width 0.5)
			(island_removal_mode 0)
		)
		(polygon
			(pts
				(xy 19.489928 -54.487572) (xy 19.489928 -54.736238)
				(arc
					(start 19.522694 -54.769258)
					(mid 19.926278 -54.998112)
					(end 19.522694 -55.226966)
				)
				(xy 19.489928 -55.259986) (xy 19.489928 -55.508652)
				(arc
					(start 19.659346 -55.508652)
					(mid 20.17014 -54.998239)
					(end 19.6596 -54.487572)
				)
			)
		)
	)
	(zone
		(layer "F.Cu")
		(hatch none 0.5)
		(connect_pads
			(clearance 0)
		)
		(min_thickness 0.25)
		(keepout
			(tracks allowed)
			(vias allowed)
			(pads allowed)
			(copperpour allowed)
			(footprints not_allowed)
		)
		(placement
			(enabled no)
			(sheetname "")
		)
		(fill
			(thermal_gap 0.5)
			(thermal_bridge_width 0.5)
			(island_removal_mode 0)
		)
		(polygon
			(pts
				(arc
					(start 349.600012 -34.500058)
					(mid 345.60002 -38.50005)
					(end 341.600028 -34.500058)
				)
				(arc
					(start 341.600028 -34.500058)
					(mid 345.60002 -30.500066)
					(end 349.600012 -34.500058)
				)
			)
		)
	)
	(zone
		(layer "F.Cu")
		(hatch none 0.5)
		(connect_pads
			(clearance 0)
		)
		(min_thickness 0.25)
		(keepout
			(tracks allowed)
			(vias allowed)
			(pads allowed)
			(copperpour allowed)
			(footprints allowed)
		)
		(placement
			(enabled no)
			(sheetname "")
		)
		(fill
			(thermal_gap 0.5)
			(thermal_bridge_width 0.5)
			(island_removal_mode 0)
		)
		(polygon
			(pts
				(xy 143.256 -34.2138) (xy 143.256 -33.6042) (xy 145.0086 -33.6042) (xy 145.0086 -34.2138)
			)
		)
	)
	(zone
		(layer "F.Cu")
		(hatch none 0.5)
		(connect_pads
			(clearance 0)
		)
		(min_thickness 0.25)
		(keepout
			(tracks allowed)
			(vias allowed)
			(pads allowed)
			(copperpour allowed)
			(footprints not_allowed)
		)
		(placement
			(enabled no)
			(sheetname "")
		)
		(fill
			(thermal_gap 0.5)
			(thermal_bridge_width 0.5)
			(island_removal_mode 0)
		)
		(polygon
			(pts
				(arc
					(start 83.849972 -5.40004)
					(mid 85.450172 -3.79984)
					(end 87.050118 -5.40004)
				)
				(arc
					(start 87.050118 -5.40004)
					(mid 85.450172 -6.999986)
					(end 83.849972 -5.40004)
				)
			)
		)
	)
	(zone
		(layer "F.Cu")
		(hatch none 0.5)
		(connect_pads
			(clearance 0)
		)
		(min_thickness 0.25)
		(keepout
			(tracks allowed)
			(vias allowed)
			(pads allowed)
			(copperpour allowed)
			(footprints allowed)
		)
		(placement
			(enabled no)
			(sheetname "")
		)
		(fill
			(thermal_gap 0.5)
			(thermal_bridge_width 0.5)
			(island_removal_mode 0)
		)
		(polygon
			(pts
				(xy 54.864 -113.6142) (xy 56.1848 -113.6142) (xy 56.3372 -113.4618) (xy 56.3372 -112.7252) (xy 55.6514 -112.0394)
				(xy 54.9656 -112.0394) (xy 54.7878 -112.2172) (xy 54.7878 -113.538)
			)
		)
	)
	(zone
		(layer "F.Cu")
		(hatch none 0.5)
		(connect_pads
			(clearance 0)
		)
		(min_thickness 0.25)
		(keepout
			(tracks not_allowed)
			(vias allowed)
			(pads allowed)
			(copperpour not_allowed)
			(footprints allowed)
		)
		(placement
			(enabled no)
			(sheetname "")
		)
		(fill
			(thermal_gap 0.5)
			(thermal_bridge_width 0.5)
			(island_removal_mode 0)
		)
		(polygon
			(pts
				(arc
					(start 11.712194 -60.300108)
					(mid 13.812266 -58.200036)
					(end 15.912084 -60.300108)
				)
				(arc
					(start 15.912084 -60.300108)
					(mid 13.812266 -62.399926)
					(end 11.712194 -60.300108)
				)
			)
		)
	)
	(zone
		(layer "F.Cu")
		(hatch none 0.5)
		(connect_pads
			(clearance 0)
		)
		(min_thickness 0.25)
		(keepout
			(tracks not_allowed)
			(vias allowed)
			(pads allowed)
			(copperpour not_allowed)
			(footprints allowed)
		)
		(placement
			(enabled no)
			(sheetname "")
		)
		(fill
			(thermal_gap 0.5)
			(thermal_bridge_width 0.5)
			(island_removal_mode 0)
		)
		(polygon
			(pts
				(arc
					(start 17.562068 -60.300108)
					(mid 13.812012 -64.050164)
					(end 10.061956 -60.300108)
				)
				(arc
					(start 10.061956 -60.300108)
					(mid 13.812012 -56.550052)
					(end 17.562068 -60.300108)
				)
			)
		)
	)
	(zone
		(layer "F.Cu")
		(hatch none 0.5)
		(connect_pads
			(clearance 0)
		)
		(min_thickness 0.25)
		(keepout
			(tracks not_allowed)
			(vias allowed)
			(pads allowed)
			(copperpour not_allowed)
			(footprints allowed)
		)
		(placement
			(enabled no)
			(sheetname "")
		)
		(fill
			(thermal_gap 0.5)
			(thermal_bridge_width 0.5)
			(island_removal_mode 0)
		)
		(polygon
			(pts
				(arc
					(start 169.265346 -21.21408)
					(mid 169.231642 -21.168388)
					(end 169.200576 -21.120862)
				)
				(xy 169.200576 -21.120608)
				(arc
					(start 169.177716 -21.081238)
					(mid 169.089404 -20.864124)
					(end 169.054018 -20.63242)
				)
				(xy 169.05351 -20.631912)
				(arc
					(start 169.05351 -20.502372)
					(mid 169.134536 -19.74893)
					(end 169.215562 -20.502372)
				)
				(arc
					(start 169.215562 -20.598892)
					(mid 169.241942 -20.807523)
					(end 169.319448 -21.003006)
				)
				(xy 169.338752 -21.036026) (xy 169.35069 -21.055076) (xy 169.687494 -20.426426) (xy 169.68724 -20.426172)
				(arc
					(start 169.685208 -20.425156)
					(mid 169.429532 -19.579255)
					(end 168.58361 -19.835114)
				)
				(xy 168.581578 -19.833844) (xy 167.831516 -21.233892)
				(arc
					(start 167.833548 -21.235162)
					(mid 168.08958 -22.080982)
					(end 168.9354 -21.82495)
				)
				(xy 168.937432 -21.82622) (xy 169.111168 -21.501862) (xy 169.055034 -21.445474)
				(arc
					(start 169.041064 -21.431758)
					(mid 168.980462 -21.393387)
					(end 168.91 -21.379942)
				)
				(arc
					(start 168.783 -21.379942)
					(mid 168.759444 -21.380728)
					(end 168.73601 -21.383244)
				)
				(arc
					(start 168.73601 -21.383244)
					(mid 168.075475 -21.753212)
					(end 168.633394 -21.241512)
				)
				(arc
					(start 168.633394 -21.241512)
					(mid 168.690123 -21.226873)
					(end 168.748202 -21.21916)
				)
				(xy 168.749472 -21.21789) (xy 168.943528 -21.21789)
				(arc
					(start 168.945306 -21.219668)
					(mid 169.044986 -21.244742)
					(end 169.133266 -21.297392)
				)
				(xy 169.135298 -21.297392) (xy 169.14495 -21.30679) (xy 169.145458 -21.30679) (xy 169.168826 -21.330158)
				(xy 169.191432 -21.352256)
			)
		)
	)
	(zone
		(net "GND")
		(layer "F.Cu")
		(hatch none 0.5)
		(connect_pads
			(clearance 0.5)
		)
		(min_thickness 0.25)
		(fill yes
			(thermal_gap 0.5)
			(thermal_bridge_width 0.5)
			(island_removal_mode 0)
		)
		(polygon
			(pts
				(arc
					(start 123.637548 4.236974)
					(mid 122.762871 3.874671)
					(end 122.400568 2.999994)
				)
				(arc
					(start 122.400568 1.999996)
					(mid 121.591301 0.046251)
					(end 119.637556 -0.763016)
				)
				(arc
					(start 53.950108 -0.763016)
					(mid 53.075431 -1.125319)
					(end 52.713128 -1.999996)
				)
				(arc
					(start 52.713128 -24.010112)
					(mid 51.903861 -25.963857)
					(end 49.950116 -26.773124)
				)
				(arc
					(start 1.999996 -26.773124)
					(mid 1.125319 -27.135427)
					(end 0.763016 -28.010104)
				)
				(arc
					(start 0.763016 -212.499956)
					(mid 0.832426 -212.667528)
					(end 0.999998 -212.736938)
				)
				(xy 23.905972 -212.736938) (xy 23.905972 -211.467954) (xy 2.032 -211.467954) (xy 2.032 -28.042108)
				(arc
					(start 49.950116 -28.042108)
					(mid 50.312133 -28.025823)
					(end 50.671222 -27.977084)
				)
				(xy 53.219096 -27.977084) (xy 54.82336 -26.37282) (xy 54.82336 -17.11452) (xy 57.24906 -14.68882)
				(xy 65.62852 -14.68882) (xy 66.86296 -15.92326) (xy 66.86296 -26.478484) (xy 68.36156 -27.977084)
				(xy 106.447082 -27.977084) (xy 113.504472 -20.919694) (xy 113.504472 -15.478506) (xy 118.752874 -10.230104)
				(xy 118.752874 -4.459986)
				(arc
					(start 121.828306 -1.384554)
					(mid 123.179354 0.073579)
					(end 123.669552 1.999996)
				)
				(xy 123.669552 2.96799) (xy 329.717908 2.96799)
				(arc
					(start 329.717908 0.999998)
					(mid 330.28371 -0.763773)
					(end 331.769974 -1.869186)
				)
				(xy 332.552548 -1.869186) (xy 333.745332 -3.06197) (xy 333.745332 -28.010104) (xy 353.035616 -28.010104)
				(xy 353.568 -28.542488) (xy 353.568 -211.467954)
				(arc
					(start 347.600016 -211.467954)
					(mid 345.243956 -212.443866)
					(end 344.268044 -214.799926)
				)
				(arc
					(start 344.268044 -219.976192)
					(mid 342.980143 -220.873089)
					(end 342.4682 -222.35668)
				)
				(xy 342.4682 -223.231202) (xy 342.719152 -223.482154) (xy 343.459562 -223.482154) (xy 343.737692 -223.204024)
				(arc
					(start 343.737692 -222.35668)
					(mid 344.122306 -221.49181)
					(end 344.999818 -221.136972)
				)
				(xy 345.537028 -221.136972)
				(arc
					(start 345.537028 -214.799926)
					(mid 346.141263 -213.341173)
					(end 347.600016 -212.736938)
				)
				(arc
					(start 354.600002 -212.736938)
					(mid 354.767574 -212.667528)
					(end 354.836984 -212.499956)
				)
				(xy 354.836984 -20.939506) (xy 354.76942 -20.871942) (xy 354.836984 -20.871942)
				(arc
					(start 354.836984 -19.459956)
					(mid 353.888159 -19.123385)
					(end 353.486974 -18.200116)
				)
				(arc
					(start 353.486974 -10.199878)
					(mid 353.888305 -9.276765)
					(end 354.836984 -8.940038)
				)
				(arc
					(start 354.836984 -0.999998)
					(mid 354.767574 -0.832426)
					(end 354.600002 -0.763016)
				)
				(arc
					(start 332.749906 -0.763016)
					(mid 331.503267 -0.246641)
					(end 330.986892 0.999998)
				)
				(arc
					(start 330.986892 3.999992)
					(mid 330.917482 4.167564)
					(end 330.74991 4.236974)
				)
			)
		)
	)
	(zone
		(layer "F.Cu")
		(hatch none 0.5)
		(connect_pads
			(clearance 0)
		)
		(min_thickness 0.25)
		(keepout
			(tracks not_allowed)
			(vias allowed)
			(pads allowed)
			(copperpour not_allowed)
			(footprints allowed)
		)
		(placement
			(enabled no)
			(sheetname "")
		)
		(fill
			(thermal_gap 0.5)
			(thermal_bridge_width 0.5)
			(island_removal_mode 0)
		)
		(polygon
			(pts
				(arc
					(start 18.574004 -72.700134)
					(mid 18.06321 -73.210547)
					(end 18.57375 -73.721214)
				)
				(arc
					(start 19.38655 -73.721214)
					(mid 19.89709 -73.210674)
					(end 19.38655 -72.700134)
				)
				(xy 19.219672 -72.700134) (xy 19.219672 -72.951848)
				(arc
					(start 19.249644 -72.98182)
					(mid 19.57512 -73.399244)
					(end 19.157696 -73.073768)
				)
				(xy 19.089624 -73.005696) (xy 19.089624 -72.700134) (xy 18.82775 -72.700134) (xy 18.876772 -72.74941)
				(xy 18.876772 -72.9996)
				(arc
					(start 18.802604 -73.073768)
					(mid 18.38518 -73.399244)
					(end 18.710656 -72.98182)
				)
				(xy 18.746724 -72.945752) (xy 18.746724 -72.803258) (xy 18.643346 -72.700134)
			)
		)
	)
	(zone
		(layer "F.Cu")
		(hatch none 0.5)
		(connect_pads
			(clearance 0)
		)
		(min_thickness 0.25)
		(keepout
			(tracks not_allowed)
			(vias allowed)
			(pads allowed)
			(copperpour not_allowed)
			(footprints allowed)
		)
		(placement
			(enabled no)
			(sheetname "")
		)
		(fill
			(thermal_gap 0.5)
			(thermal_bridge_width 0.5)
			(island_removal_mode 0)
		)
		(polygon
			(pts
				(arc
					(start 141.694154 -210.385914)
					(mid 141.18336 -210.896327)
					(end 141.6939 -211.406994)
				)
				(xy 141.860524 -211.406994)
				(arc
					(start 141.860524 -211.2518)
					(mid 141.848919 -211.188683)
					(end 141.81582 -211.13369)
				)
				(arc
					(start 141.81582 -211.13369)
					(mid 141.505494 -210.707646)
					(end 141.930882 -211.018882)
				)
				(xy 141.946376 -211.034376)
				(arc
					(start 141.946376 -211.036916)
					(mid 141.996654 -211.121289)
					(end 142.020798 -211.216494)
				)
				(xy 142.022576 -211.218272) (xy 142.022576 -211.406994) (xy 142.165324 -211.406994) (xy 142.165324 -211.230464)
				(arc
					(start 142.167102 -211.228686)
					(mid 142.191064 -211.133906)
					(end 142.241016 -211.04987)
				)
				(xy 142.241016 -211.04733)
				(arc
					(start 142.269718 -211.018628)
					(mid 142.695883 -210.708423)
					(end 142.384272 -211.133436)
				)
				(arc
					(start 142.379446 -211.138262)
					(mid 142.34095 -211.19583)
					(end 142.327376 -211.263738)
				)
				(xy 142.327376 -211.406994)
				(arc
					(start 142.5067 -211.406994)
					(mid 143.01724 -210.896454)
					(end 142.5067 -210.385914)
				)
			)
		)
	)
	(zone
		(layer "F.Cu")
		(hatch none 0.5)
		(connect_pads
			(clearance 0)
		)
		(min_thickness 0.25)
		(keepout
			(tracks not_allowed)
			(vias allowed)
			(pads allowed)
			(copperpour not_allowed)
			(footprints allowed)
		)
		(placement
			(enabled no)
			(sheetname "")
		)
		(fill
			(thermal_gap 0.5)
			(thermal_bridge_width 0.5)
			(island_removal_mode 0)
		)
		(polygon
			(pts
				(arc
					(start 23.77694 -113.995454)
					(mid 23.164927 -113.38306)
					(end 22.55266 -113.9952)
				)
				(xy 22.55266 -114.329718) (xy 22.570948 -114.327432) (xy 22.571456 -114.32667) (xy 22.60473 -114.321844)
				(xy 22.627844 -114.318542)
				(arc
					(start 22.62886 -114.318542)
					(mid 22.637346 -114.316431)
					(end 22.64537 -114.312954)
				)
				(arc
					(start 22.73554 -114.264948)
					(mid 22.828375 -114.206031)
					(end 22.911562 -114.134138)
				)
				(arc
					(start 22.927818 -114.117628)
					(mid 23.352759 -113.806089)
					(end 23.042626 -114.232182)
				)
				(xy 23.002494 -114.272314)
				(arc
					(start 23.001732 -114.272314)
					(mid 22.924154 -114.33674)
					(end 22.839934 -114.392202)
				)
				(xy 22.83968 -114.392964) (xy 22.811994 -114.407696) (xy 22.809962 -114.408712) (xy 22.692106 -114.471958)
				(xy 22.687534 -114.470434) (xy 22.686518 -114.470942) (xy 22.683978 -114.474244) (xy 22.652228 -114.478816)
				(xy 22.65045 -114.47907)
				(arc
					(start 22.629622 -114.482118)
					(mid 22.591288 -114.488312)
					(end 22.55266 -114.492278)
				)
				(xy 22.55266 -114.636804) (xy 22.61489 -114.636804)
				(arc
					(start 22.616668 -114.638328)
					(mid 22.654128 -114.643801)
					(end 22.690836 -114.65306)
				)
				(xy 22.693122 -114.652298) (xy 22.72411 -114.665252) (xy 22.781768 -114.689128) (xy 22.784054 -114.690144)
				(xy 22.81301 -114.702082)
				(arc
					(start 22.813264 -114.703352)
					(mid 22.900644 -114.752886)
					(end 22.979888 -114.814604)
				)
				(xy 22.981158 -114.814604)
				(arc
					(start 23.042372 -114.875818)
					(mid 23.353412 -115.301412)
					(end 22.927818 -114.990372)
				)
				(arc
					(start 22.890226 -114.953034)
					(mid 22.811419 -114.888171)
					(end 22.72157 -114.83975)
				)
				(xy 22.719538 -114.838734)
				(arc
					(start 22.66188 -114.814858)
					(mid 22.622659 -114.80293)
					(end 22.58187 -114.798856)
				)
				(xy 22.55266 -114.798856)
				(arc
					(start 22.55266 -115.1128)
					(mid 23.1648 -115.72494)
					(end 23.77694 -115.1128)
				)
			)
		)
	)
	(zone
		(layer "F.Cu")
		(hatch none 0.5)
		(connect_pads
			(clearance 0)
		)
		(min_thickness 0.25)
		(keepout
			(tracks not_allowed)
			(vias allowed)
			(pads allowed)
			(copperpour not_allowed)
			(footprints allowed)
		)
		(placement
			(enabled no)
			(sheetname "")
		)
		(fill
			(thermal_gap 0.5)
			(thermal_bridge_width 0.5)
			(island_removal_mode 0)
		)
		(polygon
			(pts
				(arc
					(start 302.312324 -21.199602)
					(mid 302.375896 -21.294557)
					(end 302.414686 -21.40204)
				)
				(arc
					(start 302.50511 -21.233384)
					(mid 302.453823 -21.148561)
					(end 302.38954 -21.07311)
				)
				(arc
					(start 302.38954 -21.07311)
					(mid 302.337186 -21.002057)
					(end 302.30826 -20.918678)
				)
				(xy 302.30699 -20.912836) (xy 302.306482 -20.909788) (xy 302.305466 -20.90039) (xy 302.303434 -20.898358)
				(xy 302.303434 -20.86864) (xy 302.303434 -20.864576)
				(arc
					(start 302.303434 -20.502372)
					(mid 302.38446 -19.74893)
					(end 302.465486 -20.502372)
				)
				(xy 302.465486 -20.868132) (xy 302.466756 -20.884388) (xy 302.46701 -20.886166)
				(arc
					(start 302.467518 -20.888452)
					(mid 302.480462 -20.92618)
					(end 302.504094 -20.958302)
				)
				(arc
					(start 302.504348 -20.958302)
					(mid 302.551782 -21.010479)
					(end 302.594264 -21.06676)
				)
				(xy 302.937418 -20.426426) (xy 302.937164 -20.426172)
				(arc
					(start 302.935132 -20.425156)
					(mid 302.679456 -19.579255)
					(end 301.833534 -19.835114)
				)
				(xy 301.831502 -19.833844) (xy 301.08144 -21.233892)
				(arc
					(start 301.083472 -21.235162)
					(mid 301.339504 -22.080982)
					(end 302.185324 -21.82495)
				)
				(xy 302.187356 -21.82622) (xy 302.264318 -21.68271)
				(arc
					(start 302.264318 -21.506688)
					(mid 302.240763 -21.388739)
					(end 302.173894 -21.288756)
				)
				(arc
					(start 301.994316 -21.108924)
					(mid 301.937122 -21.071638)
					(end 301.87011 -21.058632)
				)
				(arc
					(start 301.820326 -21.058632)
					(mid 301.784998 -21.065753)
					(end 301.755048 -21.08581)
				)
				(arc
					(start 301.755048 -21.08581)
					(mid 301.730626 -21.119087)
					(end 301.717456 -21.1582)
				)
				(arc
					(start 301.717456 -21.1582)
					(mid 301.632849 -21.911128)
					(end 301.553372 -21.157692)
				)
				(xy 301.553372 -21.147532)
				(arc
					(start 301.555404 -21.145246)
					(mid 301.583216 -21.051013)
					(end 301.64024 -20.971002)
				)
				(arc
					(start 301.64024 -20.971002)
					(mid 301.706417 -20.923376)
					(end 301.784258 -20.89912)
				)
				(xy 301.786798 -20.89658) (xy 301.903638 -20.89658)
				(arc
					(start 301.905416 -20.898358)
					(mid 302.000346 -20.92242)
					(end 302.084486 -20.972526)
				)
				(xy 302.087026 -20.972526) (xy 302.108362 -20.993862) (xy 302.110902 -20.996402) (xy 302.312324 -21.197824)
			)
		)
	)
	(zone
		(net "GND")
		(layer "F.Cu")
		(hatch none 0.5)
		(connect_pads
			(clearance 0.5)
		)
		(min_thickness 0.25)
		(fill yes
			(thermal_gap 0.5)
			(thermal_bridge_width 0.5)
			(island_removal_mode 0)
		)
		(polygon
			(pts
				(arc
					(start 115.599972 -211.467954)
					(mid 113.243912 -212.443866)
					(end 112.268 -214.799926)
				)
				(arc
					(start 112.268 -219.976192)
					(mid 111.045459 -220.790287)
					(end 110.480602 -222.146114)
				)
				(arc
					(start 111.762794 -222.146114)
					(mid 112.201601 -221.421264)
					(end 112.999774 -221.136972)
				)
				(xy 113.536984 -221.136972)
				(arc
					(start 113.536984 -214.799926)
					(mid 114.141219 -213.341173)
					(end 115.599972 -212.736938)
				)
				(arc
					(start 131.400042 -212.736938)
					(mid 132.858795 -213.341173)
					(end 133.46303 -214.799926)
				)
				(xy 133.46303 -221.136972)
				(arc
					(start 134.00024 -221.136972)
					(mid 134.877763 -221.491799)
					(end 135.262366 -222.35668)
				)
				(arc
					(start 136.531858 -222.35668)
					(mid 136.019928 -220.873079)
					(end 134.732014 -219.976192)
				)
				(arc
					(start 134.732014 -214.799926)
					(mid 133.756102 -212.443866)
					(end 131.400042 -211.467954)
				)
			)
		)
	)
	(zone
		(layer "F.Cu")
		(hatch none 0.5)
		(connect_pads
			(clearance 0)
		)
		(min_thickness 0.25)
		(keepout
			(tracks not_allowed)
			(vias allowed)
			(pads allowed)
			(copperpour not_allowed)
			(footprints allowed)
		)
		(placement
			(enabled no)
			(sheetname "")
		)
		(fill
			(thermal_gap 0.5)
			(thermal_bridge_width 0.5)
			(island_removal_mode 0)
		)
		(polygon
			(pts
				(arc
					(start 157.694122 -210.385914)
					(mid 157.183328 -210.896327)
					(end 157.693868 -211.406994)
				)
				(xy 157.860492 -211.406994)
				(arc
					(start 157.860492 -211.2518)
					(mid 157.848887 -211.188683)
					(end 157.815788 -211.13369)
				)
				(arc
					(start 157.815788 -211.13369)
					(mid 157.505462 -210.707646)
					(end 157.93085 -211.018882)
				)
				(xy 157.946344 -211.034376)
				(arc
					(start 157.946344 -211.036916)
					(mid 157.996622 -211.121289)
					(end 158.020766 -211.216494)
				)
				(xy 158.022544 -211.218272) (xy 158.022544 -211.406994) (xy 158.165292 -211.406994) (xy 158.165292 -211.218272)
				(arc
					(start 158.167324 -211.21624)
					(mid 158.188838 -211.132961)
					(end 158.232348 -211.05876)
				)
				(xy 158.232348 -211.055966)
				(arc
					(start 158.269686 -211.018628)
					(mid 158.695851 -210.708423)
					(end 158.38424 -211.133436)
				)
				(arc
					(start 158.370778 -211.146898)
					(mid 158.338668 -211.19491)
					(end 158.327344 -211.251546)
				)
				(xy 158.327344 -211.406994)
				(arc
					(start 158.506668 -211.406994)
					(mid 159.017208 -210.896454)
					(end 158.506668 -210.385914)
				)
			)
		)
	)
	(zone
		(layer "F.Cu")
		(hatch none 0.5)
		(connect_pads
			(clearance 0)
		)
		(min_thickness 0.25)
		(keepout
			(tracks not_allowed)
			(vias allowed)
			(pads allowed)
			(copperpour not_allowed)
			(footprints allowed)
		)
		(placement
			(enabled no)
			(sheetname "")
		)
		(fill
			(thermal_gap 0.5)
			(thermal_bridge_width 0.5)
			(island_removal_mode 0)
		)
		(polygon
			(pts
				(arc
					(start 136.685274 -20.424902)
					(mid 136.429242 -19.579082)
					(end 135.583422 -19.835114)
				)
				(arc
					(start 134.837678 -21.227542)
					(mid 135.085812 -22.078995)
					(end 135.935466 -21.82495)
				)
				(arc
					(start 136.12241 -21.475954)
					(mid 136.050111 -21.389083)
					(end 135.984742 -21.296884)
				)
				(xy 135.984488 -21.29663)
				(arc
					(start 135.973058 -21.278596)
					(mid 135.946011 -21.246826)
					(end 135.92048 -21.213826)
				)
				(arc
					(start 135.92048 -21.213826)
					(mid 135.888283 -21.175162)
					(end 135.851646 -21.140674)
				)
				(arc
					(start 135.82904 -21.123148)
					(mid 135.777878 -21.100237)
					(end 135.724138 -21.084286)
				)
				(arc
					(start 135.724138 -21.084286)
					(mid 135.683854 -21.08515)
					(end 135.64362 -21.087334)
				)
				(arc
					(start 135.637778 -21.087588)
					(mid 135.555352 -21.108013)
					(end 135.491982 -21.16455)
				)
				(arc
					(start 135.491982 -21.16455)
					(mid 135.363283 -21.910433)
					(end 135.3185 -21.154898)
				)
				(xy 135.323072 -21.139404)
				(arc
					(start 135.325612 -21.132546)
					(mid 135.44922 -20.98282)
					(end 135.63473 -20.925536)
				)
				(arc
					(start 135.63473 -20.925536)
					(mid 135.683723 -20.923026)
					(end 135.732774 -20.922234)
				)
				(arc
					(start 135.749284 -20.924012)
					(mid 135.830082 -20.946917)
					(end 135.906764 -20.981162)
				)
				(xy 135.910574 -20.983194) (xy 135.918702 -20.98802)
				(arc
					(start 135.955278 -21.016214)
					(mid 136.006239 -21.064109)
					(end 136.051036 -21.117814)
				)
				(arc
					(start 136.051036 -21.117814)
					(mid 136.073795 -21.147243)
					(end 136.098026 -21.175472)
				)
				(xy 136.106916 -21.187156)
				(arc
					(start 136.120632 -21.208492)
					(mid 136.160975 -21.266915)
					(end 136.204452 -21.323046)
				)
				(xy 136.278112 -21.185124) (xy 136.24052 -21.130768) (xy 136.240266 -21.130768)
				(arc
					(start 136.216644 -21.092414)
					(mid 136.152756 -21.002398)
					(end 136.109964 -20.900644)
				)
				(xy 136.108186 -20.895818) (xy 136.106154 -20.888452) (xy 136.105138 -20.884642) (xy 136.10336 -20.876514)
				(arc
					(start 136.102852 -20.873212)
					(mid 136.093051 -20.818213)
					(end 136.08939 -20.762468)
				)
				(arc
					(start 136.08939 -20.762468)
					(mid 136.076212 -20.633826)
					(end 136.066022 -20.504912)
				)
				(arc
					(start 136.066022 -20.504912)
					(mid 136.120843 -19.749205)
					(end 136.228074 -20.499324)
				)
				(arc
					(start 136.228074 -20.499324)
					(mid 136.238063 -20.623916)
					(end 136.250934 -20.748244)
				)
				(arc
					(start 136.251442 -20.757642)
					(mid 136.253853 -20.798442)
					(end 136.261094 -20.838668)
				)
				(xy 136.262364 -20.845018) (xy 136.262618 -20.845526)
				(arc
					(start 136.264396 -20.851114)
					(mid 136.29504 -20.924735)
					(end 136.341866 -20.98929)
				)
				(xy 136.352026 -21.00326) (xy 136.364472 -21.023834)
			)
		)
	)
	(zone
		(net "P1V53_STBY")
		(layer "F.Cu")
		(hatch none 0.5)
		(connect_pads
			(clearance 0.5)
		)
		(min_thickness 0.25)
		(fill yes
			(thermal_gap 0.5)
			(thermal_bridge_width 0.5)
			(island_removal_mode 0)
		)
		(polygon
			(pts
				(xy 60.071 -151.765) (xy 59.944 -151.892) (xy 59.944 -154.94) (xy 60.198 -155.194) (xy 61.833506 -155.194)
				(xy 61.966602 -155.060904) (xy 61.966602 -152.777698) (xy 62.103 -152.6413) (xy 62.103 -151.892)
				(xy 61.976 -151.765)
			)
		)
	)
	(zone
		(net "P12V")
		(layer "F.Cu")
		(hatch none 0.5)
		(connect_pads
			(clearance 0.5)
		)
		(min_thickness 0.25)
		(fill yes
			(thermal_gap 0.5)
			(thermal_bridge_width 0.5)
			(island_removal_mode 0)
		)
		(polygon
			(pts
				(xy 24.6888 -193.7512) (xy 24.384 -194.056) (xy 24.384 -199.39) (xy 24.511 -199.517) (xy 28.702 -199.517)
				(xy 29.083 -199.136) (xy 29.083 -194.183) (xy 28.6512 -193.7512)
			)
		)
	)
	(zone
		(net "GND")
		(layer "F.Cu")
		(hatch none 0.5)
		(connect_pads
			(clearance 0.5)
		)
		(min_thickness 0.25)
		(fill yes
			(thermal_gap 0.5)
			(thermal_bridge_width 0.5)
			(island_removal_mode 0)
		)
		(polygon
			(pts
				(xy 56.261 -41.91) (xy 56.134 -42.037) (xy 56.134 -45.847) (xy 56.261 -45.974) (xy 58.801 -45.974)
				(xy 58.928 -45.847) (xy 58.928 -42.291) (xy 58.547 -41.91)
			)
		)
	)
	(zone
		(net "GND")
		(layer "F.Cu")
		(hatch none 0.5)
		(connect_pads
			(clearance 0.5)
		)
		(min_thickness 0.25)
		(fill yes
			(thermal_gap 0.5)
			(thermal_bridge_width 0.5)
			(island_removal_mode 0)
		)
		(polygon
			(pts
				(xy 17.755362 -112.761014) (xy 17.755362 -110.721648) (xy 19.189954 -110.721648) (xy 19.189954 -112.081056)
				(xy 18.41119 -112.85982) (xy 17.854168 -112.85982)
			)
		)
	)
	(zone
		(layer "F.Cu")
		(hatch none 0.5)
		(connect_pads
			(clearance 0)
		)
		(min_thickness 0.25)
		(keepout
			(tracks not_allowed)
			(vias allowed)
			(pads allowed)
			(copperpour not_allowed)
			(footprints allowed)
		)
		(placement
			(enabled no)
			(sheetname "")
		)
		(fill
			(thermal_gap 0.5)
			(thermal_bridge_width 0.5)
			(island_removal_mode 0)
		)
		(polygon
			(pts
				(arc
					(start 319.812416 -24.999696)
					(mid 319.875055 -25.093039)
					(end 319.913762 -25.198578)
				)
				(arc
					(start 320.003678 -25.030684)
					(mid 319.952938 -24.947394)
					(end 319.889632 -24.873204)
				)
				(arc
					(start 319.889632 -24.873204)
					(mid 319.833272 -24.79399)
					(end 319.805812 -24.700738)
				)
				(xy 319.803526 -24.698452)
				(arc
					(start 319.803526 -24.302466)
					(mid 319.883521 -23.549132)
					(end 319.965578 -24.302212)
				)
				(arc
					(start 319.965578 -24.664924)
					(mid 319.975734 -24.715512)
					(end 320.00444 -24.758396)
				)
				(arc
					(start 320.00444 -24.758396)
					(mid 320.051006 -24.809378)
					(end 320.092832 -24.864314)
				)
				(arc
					(start 320.43116 -24.232616)
					(mid 320.183026 -23.381163)
					(end 319.333372 -23.635208)
				)
				(arc
					(start 318.583564 -25.035256)
					(mid 318.839596 -25.881076)
					(end 319.685416 -25.625044)
				)
				(xy 319.76441 -25.47747)
				(arc
					(start 319.76441 -25.306782)
					(mid 319.740855 -25.188833)
					(end 319.673986 -25.08885)
				)
				(arc
					(start 319.494408 -24.909018)
					(mid 319.437214 -24.871732)
					(end 319.370202 -24.858726)
				)
				(arc
					(start 319.320418 -24.858726)
					(mid 319.28509 -24.865847)
					(end 319.25514 -24.885904)
				)
				(arc
					(start 319.25514 -24.885904)
					(mid 319.230718 -24.919181)
					(end 319.217548 -24.958294)
				)
				(arc
					(start 319.217548 -24.958294)
					(mid 319.132941 -25.711222)
					(end 319.053464 -24.957786)
				)
				(xy 319.053464 -24.947626)
				(arc
					(start 319.055496 -24.94534)
					(mid 319.083308 -24.851107)
					(end 319.140332 -24.771096)
				)
				(arc
					(start 319.140332 -24.771096)
					(mid 319.206509 -24.72347)
					(end 319.28435 -24.699214)
				)
				(xy 319.28689 -24.696674) (xy 319.40373 -24.696674)
				(arc
					(start 319.405508 -24.698452)
					(mid 319.500438 -24.722514)
					(end 319.584578 -24.77262)
				)
				(xy 319.587118 -24.77262) (xy 319.608454 -24.793956) (xy 319.610994 -24.796496) (xy 319.812416 -24.997918)
			)
		)
	)
	(zone
		(layer "F.Cu")
		(hatch none 0.5)
		(connect_pads
			(clearance 0)
		)
		(min_thickness 0.25)
		(keepout
			(tracks not_allowed)
			(vias allowed)
			(pads allowed)
			(copperpour not_allowed)
			(footprints allowed)
		)
		(placement
			(enabled no)
			(sheetname "")
		)
		(fill
			(thermal_gap 0.5)
			(thermal_bridge_width 0.5)
			(island_removal_mode 0)
		)
		(polygon
			(pts
				(arc
					(start 22.417786 -56.076596)
					(mid 21.805646 -56.688736)
					(end 22.417786 -57.300876)
				)
				(arc
					(start 23.535386 -57.300876)
					(mid 24.147526 -56.688736)
					(end 23.535386 -56.076596)
				)
				(xy 23.211028 -56.076596) (xy 23.211028 -56.27243)
				(arc
					(start 23.39848 -56.459882)
					(mid 23.723956 -56.877306)
					(end 23.306532 -56.55183)
				)
				(xy 23.08098 -56.326278) (xy 23.08098 -56.076596) (xy 22.868128 -56.076596) (xy 22.868128 -56.330342)
				(arc
					(start 22.64664 -56.55183)
					(mid 22.229216 -56.877306)
					(end 22.554692 -56.459882)
				)
				(xy 22.737826 -56.276494) (xy 22.737826 -56.076596)
			)
		)
	)
	(zone
		(layer "F.Cu")
		(hatch none 0.5)
		(connect_pads
			(clearance 0)
		)
		(min_thickness 0.25)
		(keepout
			(tracks not_allowed)
			(vias allowed)
			(pads allowed)
			(copperpour not_allowed)
			(footprints allowed)
		)
		(placement
			(enabled no)
			(sheetname "")
		)
		(fill
			(thermal_gap 0.5)
			(thermal_bridge_width 0.5)
			(island_removal_mode 0)
		)
		(polygon
			(pts
				(arc
					(start 89.293954 -210.385914)
					(mid 88.78316 -210.896327)
					(end 89.2937 -211.406994)
				)
				(xy 89.460324 -211.406994)
				(arc
					(start 89.460324 -211.33435)
					(mid 89.446327 -211.232665)
					(end 89.40546 -211.138516)
				)
				(arc
					(start 89.40546 -211.138516)
					(mid 89.113168 -210.70007)
					(end 89.526364 -211.02701)
				)
				(arc
					(start 89.526364 -211.02701)
					(mid 89.592406 -211.156818)
					(end 89.62136 -211.299552)
				)
				(xy 89.622376 -211.300822) (xy 89.622376 -211.406994) (xy 89.765124 -211.406994) (xy 89.765124 -211.300822)
				(arc
					(start 89.766394 -211.299552)
					(mid 89.798392 -211.153185)
					(end 89.87155 -211.022438)
				)
				(arc
					(start 89.87155 -211.022438)
					(mid 90.292099 -210.704937)
					(end 89.989152 -211.135976)
				)
				(arc
					(start 89.989152 -211.135976)
					(mid 89.943041 -211.230304)
					(end 89.927176 -211.334096)
				)
				(xy 89.927176 -211.406994)
				(arc
					(start 90.1065 -211.406994)
					(mid 90.61704 -210.896454)
					(end 90.1065 -210.385914)
				)
			)
		)
	)
	(zone
		(net "DUT_AVD_PCIE_Q")
		(layer "F.Cu")
		(hatch none 0.5)
		(connect_pads
			(clearance 0.5)
		)
		(min_thickness 0.25)
		(fill yes
			(thermal_gap 0.5)
			(thermal_bridge_width 0.5)
			(island_removal_mode 0)
		)
		(polygon
			(pts
				(xy 186.521598 -51.610768) (xy 186.140598 -51.991768) (xy 186.140598 -55.547768) (xy 186.242198 -55.649368)
				(xy 190.283592 -55.649368) (xy 191.423798 -54.509162) (xy 191.423798 -51.712368) (xy 191.322198 -51.610768)
			)
		)
	)
	(zone
		(layer "F.Cu")
		(hatch none 0.5)
		(connect_pads
			(clearance 0)
		)
		(min_thickness 0.25)
		(keepout
			(tracks not_allowed)
			(vias allowed)
			(pads allowed)
			(copperpour not_allowed)
			(footprints allowed)
		)
		(placement
			(enabled no)
			(sheetname "")
		)
		(fill
			(thermal_gap 0.5)
			(thermal_bridge_width 0.5)
			(island_removal_mode 0)
		)
		(polygon
			(pts
				(xy 136.092438 -25.332182) (xy 136.08177 -25.310592) (xy 136.08431 -25.302718)
				(arc
					(start 136.074658 -25.27681)
					(mid 136.059732 -25.245918)
					(end 136.041892 -25.216612)
				)
				(arc
					(start 136.041892 -25.216612)
					(mid 135.956932 -25.114117)
					(end 135.885174 -25.001982)
				)
				(arc
					(start 135.840978 -24.957532)
					(mid 135.771626 -24.904437)
					(end 135.690864 -24.871172)
				)
				(arc
					(start 135.690864 -24.871172)
					(mid 135.653703 -24.863708)
					(end 135.615934 -24.860504)
				)
				(arc
					(start 135.615934 -24.860504)
					(mid 135.542739 -24.89977)
					(end 135.490204 -24.964136)
				)
				(arc
					(start 135.490204 -24.964136)
					(mid 135.36356 -25.710533)
					(end 135.31977 -24.954738)
				)
				(arc
					(start 135.31977 -24.954738)
					(mid 135.419323 -24.792749)
					(end 135.585708 -24.700738)
				)
				(arc
					(start 135.585708 -24.700738)
					(mid 135.595536 -24.698863)
					(end 135.60552 -24.698198)
				)
				(arc
					(start 135.606028 -24.698198)
					(mid 135.669553 -24.702389)
					(end 135.732012 -24.714708)
				)
				(arc
					(start 135.732012 -24.714708)
					(mid 135.83721 -24.75564)
					(end 135.930386 -24.819356)
				)
				(xy 135.932164 -24.819356) (xy 136.031732 -24.919686)
				(arc
					(start 136.031732 -24.932132)
					(mid 136.092422 -25.024885)
					(end 136.163812 -25.109678)
				)
				(xy 136.171432 -25.119076) (xy 136.190736 -25.14854)
				(arc
					(start 136.265412 -25.00884)
					(mid 136.185615 -24.90915)
					(end 136.123172 -24.797766)
				)
				(arc
					(start 136.123172 -24.797512)
					(mid 136.100772 -24.743161)
					(end 136.082532 -24.687276)
				)
				(xy 136.082532 -24.686768)
				(arc
					(start 136.075928 -24.661876)
					(mid 136.061201 -24.585965)
					(end 136.054084 -24.508968)
				)
				(xy 136.053322 -24.508206) (xy 136.053322 -24.476202) (xy 136.053322 -24.474678)
				(arc
					(start 136.053322 -24.302466)
					(mid 136.134348 -23.549024)
					(end 136.215374 -24.302466)
				)
				(arc
					(start 136.215374 -24.475948)
					(mid 136.219945 -24.550152)
					(end 136.233408 -24.623268)
				)
				(xy 136.233408 -24.623522)
				(arc
					(start 136.238488 -24.643334)
					(mid 136.252852 -24.687497)
					(end 136.270492 -24.730456)
				)
				(arc
					(start 136.270492 -24.730456)
					(mid 136.305088 -24.795613)
					(end 136.3472 -24.856186)
				)
				(arc
					(start 136.685274 -24.224996)
					(mid 136.429242 -23.379176)
					(end 135.583422 -23.635208)
				)
				(arc
					(start 134.837678 -25.027636)
					(mid 135.085812 -25.879089)
					(end 135.935466 -25.625044)
				)
			)
		)
	)
	(zone
		(layer "F.Cu")
		(hatch none 0.5)
		(connect_pads
			(clearance 0)
		)
		(min_thickness 0.25)
		(keepout
			(tracks not_allowed)
			(vias allowed)
			(pads allowed)
			(copperpour not_allowed)
			(footprints allowed)
		)
		(placement
			(enabled no)
			(sheetname "")
		)
		(fill
			(thermal_gap 0.5)
			(thermal_bridge_width 0.5)
			(island_removal_mode 0)
		)
		(polygon
			(pts
				(arc
					(start 280.493978 -210.385914)
					(mid 279.983184 -210.896327)
					(end 280.493724 -211.406994)
				)
				(xy 280.660348 -211.406994)
				(arc
					(start 280.660348 -211.2772)
					(mid 280.648257 -211.202193)
					(end 280.613358 -211.134706)
				)
				(arc
					(start 280.613358 -211.134706)
					(mid 280.307024 -210.70614)
					(end 280.72969 -211.02066)
				)
				(arc
					(start 280.72969 -211.02066)
					(mid 280.792199 -211.124447)
					(end 280.820876 -211.242148)
				)
				(xy 280.8224 -211.243672) (xy 280.8224 -211.406994) (xy 280.965148 -211.406994) (xy 280.965148 -211.243418)
				(arc
					(start 280.966926 -211.24164)
					(mid 280.993366 -211.134823)
					(end 281.049984 -211.040472)
				)
				(xy 281.049984 -211.038186)
				(arc
					(start 281.069542 -211.018628)
					(mid 281.495707 -210.708423)
					(end 281.184096 -211.133436)
				)
				(arc
					(start 281.184096 -211.133436)
					(mid 281.14204 -211.199516)
					(end 281.1272 -211.276438)
				)
				(xy 281.1272 -211.406994)
				(arc
					(start 281.306524 -211.406994)
					(mid 281.817064 -210.896454)
					(end 281.306524 -210.385914)
				)
			)
		)
	)
	(zone
		(layer "F.Cu")
		(hatch none 0.5)
		(connect_pads
			(clearance 0)
		)
		(min_thickness 0.25)
		(keepout
			(tracks not_allowed)
			(vias allowed)
			(pads allowed)
			(copperpour not_allowed)
			(footprints allowed)
		)
		(placement
			(enabled no)
			(sheetname "")
		)
		(fill
			(thermal_gap 0.5)
			(thermal_bridge_width 0.5)
			(island_removal_mode 0)
		)
		(polygon
			(pts
				(arc
					(start 58.093864 -210.385914)
					(mid 57.58307 -210.896327)
					(end 58.09361 -211.406994)
				)
				(xy 58.260234 -211.406994)
				(arc
					(start 58.260234 -211.281518)
					(mid 58.248027 -211.204497)
					(end 58.212736 -211.13496)
				)
				(arc
					(start 58.212736 -211.13496)
					(mid 57.907612 -210.705289)
					(end 58.329576 -211.020914)
				)
				(arc
					(start 58.329576 -211.020914)
					(mid 58.392169 -211.126818)
					(end 58.420762 -211.246466)
				)
				(xy 58.422286 -211.24799) (xy 58.422286 -211.406994) (xy 58.565034 -211.406994) (xy 58.565034 -211.256118)
				(arc
					(start 58.566558 -211.254594)
					(mid 58.59562 -211.135855)
					(end 58.659014 -211.031328)
				)
				(xy 58.659014 -211.029296)
				(arc
					(start 58.669428 -211.018882)
					(mid 59.094168 -210.707143)
					(end 58.784744 -211.13369)
				)
				(arc
					(start 58.784744 -211.13369)
					(mid 58.741967 -211.206511)
					(end 58.727086 -211.289646)
				)
				(xy 58.727086 -211.406994)
				(arc
					(start 58.90641 -211.406994)
					(mid 59.41695 -210.896454)
					(end 58.90641 -210.385914)
				)
			)
		)
	)
	(zone
		(layer "F.Cu")
		(hatch none 0.5)
		(connect_pads
			(clearance 0)
		)
		(min_thickness 0.25)
		(keepout
			(tracks not_allowed)
			(vias allowed)
			(pads allowed)
			(copperpour not_allowed)
			(footprints allowed)
		)
		(placement
			(enabled no)
			(sheetname "")
		)
		(fill
			(thermal_gap 0.5)
			(thermal_bridge_width 0.5)
			(island_removal_mode 0)
		)
		(polygon
			(pts
				(arc
					(start 152.7175 -34.48558)
					(mid 152.20696 -34.99612)
					(end 152.7175 -35.50666)
				)
				(arc
					(start 153.530046 -35.50666)
					(mid 154.04084 -34.996247)
					(end 153.5303 -34.48558)
				)
				(xy 153.324306 -34.48558)
				(arc
					(start 153.324306 -34.57956)
					(mid 153.338823 -34.681401)
					(end 153.381202 -34.77514)
				)
				(arc
					(start 153.381202 -34.77514)
					(mid 153.741388 -35.158957)
					(end 153.278078 -34.909252)
				)
				(arc
					(start 153.278078 -34.909252)
					(mid 153.198147 -34.770605)
					(end 153.163524 -34.614358)
				)
				(xy 153.162254 -34.613088) (xy 153.162254 -34.48558) (xy 153.019506 -34.48558) (xy 153.019506 -34.613088)
				(arc
					(start 153.01849 -34.614104)
					(mid 152.996654 -34.74138)
					(end 152.94737 -34.860738)
				)
				(arc
					(start 152.94737 -34.860738)
					(mid 152.541725 -35.196798)
					(end 152.821386 -34.750502)
				)
				(arc
					(start 152.821386 -34.750502)
					(mid 152.84835 -34.666916)
					(end 152.857454 -34.57956)
				)
				(xy 152.857454 -34.48558)
			)
		)
	)
	(zone
		(layer "F.Cu")
		(hatch none 0.5)
		(connect_pads
			(clearance 0)
		)
		(min_thickness 0.25)
		(keepout
			(tracks not_allowed)
			(vias allowed)
			(pads allowed)
			(copperpour not_allowed)
			(footprints allowed)
		)
		(placement
			(enabled no)
			(sheetname "")
		)
		(fill
			(thermal_gap 0.5)
			(thermal_bridge_width 0.5)
			(island_removal_mode 0)
		)
		(polygon
			(pts
				(arc
					(start 144.894046 -210.385914)
					(mid 144.383252 -210.896327)
					(end 144.893792 -211.406994)
				)
				(xy 145.060416 -211.406994)
				(arc
					(start 145.060416 -211.307934)
					(mid 145.047383 -211.218665)
					(end 145.009616 -211.136738)
				)
				(arc
					(start 145.009616 -211.136738)
					(mid 144.709232 -210.703473)
					(end 145.128234 -211.023454)
				)
				(arc
					(start 145.128234 -211.023454)
					(mid 145.192568 -211.14192)
					(end 145.221198 -211.273644)
				)
				(xy 145.222468 -211.274914) (xy 145.222468 -211.406994) (xy 145.365216 -211.406994) (xy 145.365216 -211.275168)
				(arc
					(start 145.366486 -211.273644)
					(mid 145.39864 -211.138915)
					(end 145.470372 -211.020406)
				)
				(arc
					(start 145.470372 -211.020406)
					(mid 145.893159 -210.705924)
					(end 145.58645 -211.134452)
				)
				(arc
					(start 145.58645 -211.134452)
					(mid 145.542488 -211.216686)
					(end 145.527268 -211.308696)
				)
				(xy 145.527268 -211.406994)
				(arc
					(start 145.706592 -211.406994)
					(mid 146.217132 -210.896454)
					(end 145.706592 -210.385914)
				)
			)
		)
	)
	(zone
		(layer "F.Cu")
		(hatch none 0.5)
		(connect_pads
			(clearance 0)
		)
		(min_thickness 0.25)
		(keepout
			(tracks not_allowed)
			(vias allowed)
			(pads allowed)
			(copperpour not_allowed)
			(footprints allowed)
		)
		(placement
			(enabled no)
			(sheetname "")
		)
		(fill
			(thermal_gap 0.5)
			(thermal_bridge_width 0.5)
			(island_removal_mode 0)
		)
		(polygon
			(pts
				(arc
					(start 291.312346 -21.199602)
					(mid 291.375918 -21.294557)
					(end 291.414708 -21.40204)
				)
				(arc
					(start 291.504878 -21.233384)
					(mid 291.453836 -21.148589)
					(end 291.389816 -21.07311)
				)
				(arc
					(start 291.389816 -21.07311)
					(mid 291.33459 -20.996818)
					(end 291.30625 -20.906994)
				)
				(xy 291.30625 -20.906486) (xy 291.305488 -20.90039) (xy 291.303456 -20.898358) (xy 291.303456 -20.867116)
				(xy 291.303456 -20.864576)
				(arc
					(start 291.303456 -20.502372)
					(mid 291.384482 -19.74893)
					(end 291.465508 -20.502372)
				)
				(xy 291.465508 -20.866862)
				(arc
					(start 291.466778 -20.88388)
					(mid 291.479415 -20.924124)
					(end 291.504116 -20.958302)
				)
				(arc
					(start 291.50437 -20.958302)
					(mid 291.551789 -21.010359)
					(end 291.594286 -21.066506)
				)
				(xy 291.93744 -20.426172)
				(arc
					(start 291.935408 -20.424902)
					(mid 291.679376 -19.579082)
					(end 290.833556 -19.835114)
				)
				(xy 290.831524 -19.833844) (xy 290.081462 -21.233638) (xy 290.081716 -21.233892)
				(arc
					(start 290.083748 -21.234908)
					(mid 290.339424 -22.080809)
					(end 291.185346 -21.82495)
				)
				(xy 291.187378 -21.82622) (xy 291.26434 -21.682456)
				(arc
					(start 291.26434 -21.506434)
					(mid 291.240736 -21.388622)
					(end 291.173916 -21.288756)
				)
				(xy 290.994338 -21.108924)
				(arc
					(start 290.987734 -21.102828)
					(mid 290.932959 -21.07)
					(end 290.870132 -21.058632)
				)
				(arc
					(start 290.820348 -21.058632)
					(mid 290.78502 -21.065753)
					(end 290.75507 -21.08581)
				)
				(arc
					(start 290.75507 -21.08581)
					(mid 290.730648 -21.119087)
					(end 290.717478 -21.1582)
				)
				(arc
					(start 290.717478 -21.1582)
					(mid 290.632871 -21.911128)
					(end 290.553394 -21.157692)
				)
				(xy 290.553394 -21.147532)
				(arc
					(start 290.555426 -21.145246)
					(mid 290.583238 -21.051013)
					(end 290.640262 -20.971002)
				)
				(arc
					(start 290.640262 -20.971002)
					(mid 290.706439 -20.923376)
					(end 290.78428 -20.89912)
				)
				(xy 290.78682 -20.89658) (xy 290.90366 -20.89658)
				(arc
					(start 290.905438 -20.898358)
					(mid 291.000368 -20.92242)
					(end 291.084508 -20.972526)
				)
				(xy 291.087048 -20.972526) (xy 291.108384 -20.993862) (xy 291.110924 -20.996402) (xy 291.312346 -21.197824)
			)
		)
	)
	(zone
		(layer "F.Cu")
		(hatch none 0.5)
		(connect_pads
			(clearance 0)
		)
		(min_thickness 0.25)
		(keepout
			(tracks not_allowed)
			(vias allowed)
			(pads allowed)
			(copperpour not_allowed)
			(footprints allowed)
		)
		(placement
			(enabled no)
			(sheetname "")
		)
		(fill
			(thermal_gap 0.5)
			(thermal_bridge_width 0.5)
			(island_removal_mode 0)
		)
		(polygon
			(pts
				(xy 23.183088 -53.045614) (xy 23.179024 -53.049424) (xy 23.179024 -53.27523)
				(arc
					(start 23.231094 -53.3273)
					(mid 23.634678 -53.556154)
					(end 23.231094 -53.785008)
				)
				(xy 23.198328 -53.818028) (xy 23.198328 -54.066694)
				(arc
					(start 23.368 -54.066694)
					(mid 23.87854 -53.556154)
					(end 23.368 -53.045614)
				)
			)
		)
	)
	(zone
		(net "GND")
		(layer "F.Cu")
		(hatch none 0.5)
		(connect_pads
			(clearance 0.5)
		)
		(min_thickness 0.25)
		(fill yes
			(thermal_gap 0.5)
			(thermal_bridge_width 0.5)
			(island_removal_mode 0)
		)
		(polygon
			(pts
				(xy 178.374802 -71.8312) (xy 178.197002 -72.009) (xy 178.197002 -76.216002) (xy 178.2826 -76.3016)
				(xy 187.518802 -76.3016) (xy 187.976002 -75.8444) (xy 187.976002 -72.050402) (xy 187.7568 -71.8312)
			)
		)
	)
	(zone
		(layer "F.Cu")
		(hatch none 0.5)
		(connect_pads
			(clearance 0)
		)
		(min_thickness 0.25)
		(keepout
			(tracks not_allowed)
			(vias allowed)
			(pads allowed)
			(copperpour not_allowed)
			(footprints allowed)
		)
		(placement
			(enabled no)
			(sheetname "")
		)
		(fill
			(thermal_gap 0.5)
			(thermal_bridge_width 0.5)
			(island_removal_mode 0)
		)
		(polygon
			(pts
				(arc
					(start 322.062348 -21.199602)
					(mid 322.12592 -21.294557)
					(end 322.16471 -21.40204)
				)
				(arc
					(start 322.255134 -21.233384)
					(mid 322.203847 -21.148561)
					(end 322.139564 -21.07311)
				)
				(arc
					(start 322.139564 -21.07311)
					(mid 322.083204 -20.993896)
					(end 322.055744 -20.900644)
				)
				(xy 322.053458 -20.898358)
				(arc
					(start 322.053458 -20.502372)
					(mid 322.134484 -19.74893)
					(end 322.21551 -20.502372)
				)
				(arc
					(start 322.21551 -20.86483)
					(mid 322.225666 -20.915418)
					(end 322.254372 -20.958302)
				)
				(arc
					(start 322.254372 -20.958302)
					(mid 322.301793 -21.010489)
					(end 322.344288 -21.06676)
				)
				(xy 322.687442 -20.426426) (xy 322.687188 -20.426172)
				(arc
					(start 322.685156 -20.425156)
					(mid 322.42948 -19.579255)
					(end 321.583558 -19.835114)
				)
				(xy 321.581526 -19.833844) (xy 320.831464 -21.233892)
				(arc
					(start 320.833496 -21.235162)
					(mid 321.089528 -22.080982)
					(end 321.935348 -21.82495)
				)
				(xy 321.93738 -21.82622) (xy 322.014342 -21.68271)
				(arc
					(start 322.014342 -21.506688)
					(mid 321.990787 -21.388739)
					(end 321.923918 -21.288756)
				)
				(arc
					(start 321.74434 -21.108924)
					(mid 321.687146 -21.071638)
					(end 321.620134 -21.058632)
				)
				(arc
					(start 321.57035 -21.058632)
					(mid 321.535022 -21.065753)
					(end 321.505072 -21.08581)
				)
				(arc
					(start 321.505072 -21.08581)
					(mid 321.48065 -21.119087)
					(end 321.46748 -21.1582)
				)
				(arc
					(start 321.46748 -21.1582)
					(mid 321.382873 -21.911128)
					(end 321.303396 -21.157692)
				)
				(xy 321.303396 -21.147532)
				(arc
					(start 321.305428 -21.145246)
					(mid 321.33324 -21.051013)
					(end 321.390264 -20.971002)
				)
				(arc
					(start 321.390264 -20.971002)
					(mid 321.456441 -20.923376)
					(end 321.534282 -20.89912)
				)
				(xy 321.536822 -20.89658) (xy 321.653662 -20.89658)
				(arc
					(start 321.65544 -20.898358)
					(mid 321.75037 -20.92242)
					(end 321.83451 -20.972526)
				)
				(xy 321.83705 -20.972526) (xy 321.858386 -20.993862) (xy 321.860926 -20.996402) (xy 322.062348 -21.197824)
			)
		)
	)
	(zone
		(net "GND")
		(layer "F.Cu")
		(hatch none 0.5)
		(connect_pads
			(clearance 0.5)
		)
		(min_thickness 0.25)
		(fill yes
			(thermal_gap 0.5)
			(thermal_bridge_width 0.5)
			(island_removal_mode 0)
		)
		(polygon
			(pts
				(xy 166.894002 -55.145432) (xy 166.386002 -55.653432) (xy 166.386002 -58.320432) (xy 166.894002 -58.828432)
				(xy 168.672002 -58.828432) (xy 170.831002 -60.987432) (xy 178.7906 -60.987432) (xy 179.118768 -61.3156)
				(xy 186.8678 -61.3156) (xy 187.7568 -60.4266) (xy 187.7568 -57.8612) (xy 186.8424 -56.9468) (xy 176.8856 -56.9468)
				(xy 175.1584 -55.2196) (xy 175.1584 -55.145432)
			)
		)
	)
	(zone
		(layer "F.Cu")
		(hatch none 0.5)
		(connect_pads
			(clearance 0)
		)
		(min_thickness 0.25)
		(keepout
			(tracks allowed)
			(vias allowed)
			(pads allowed)
			(copperpour allowed)
			(footprints not_allowed)
		)
		(placement
			(enabled no)
			(sheetname "")
		)
		(fill
			(thermal_gap 0.5)
			(thermal_bridge_width 0.5)
			(island_removal_mode 0)
		)
		(polygon
			(pts
				(xy 256.141982 -213.499954) (xy 256.141982 -158.999936) (xy 229.142036 -158.999936) (xy 229.142036 -213.499954)
				(xy 115.24996 -213.499954) (xy 115.24996 -77.0001) (xy 351.600008 -77.0001) (xy 351.600008 -213.499954)
			)
		)
	)
	(zone
		(layer "F.Cu")
		(hatch none 0.5)
		(connect_pads
			(clearance 0)
		)
		(min_thickness 0.25)
		(keepout
			(tracks not_allowed)
			(vias allowed)
			(pads allowed)
			(copperpour not_allowed)
			(footprints allowed)
		)
		(placement
			(enabled no)
			(sheetname "")
		)
		(fill
			(thermal_gap 0.5)
			(thermal_bridge_width 0.5)
			(island_removal_mode 0)
		)
		(polygon
			(pts
				(arc
					(start 131.089654 -34.762694)
					(mid 130.57886 -35.273107)
					(end 131.0894 -35.783774)
				)
				(arc
					(start 131.9022 -35.783774)
					(mid 132.41274 -35.273234)
					(end 131.9022 -34.762694)
				)
				(xy 131.729226 -34.762694)
				(arc
					(start 131.729226 -35.019234)
					(mid 131.730719 -35.042428)
					(end 131.735322 -35.065208)
				)
				(arc
					(start 131.735322 -35.065208)
					(mid 132.13176 -35.408975)
					(end 131.639564 -35.22726)
				)
				(arc
					(start 131.639564 -35.22726)
					(mid 131.592015 -35.146037)
					(end 131.568952 -35.054794)
				)
				(xy 131.567174 -35.052762) (xy 131.567174 -34.762694) (xy 131.424426 -34.762694) (xy 131.424426 -35.052762)
				(arc
					(start 131.422648 -35.054794)
					(mid 131.399555 -35.146025)
					(end 131.352036 -35.22726)
				)
				(arc
					(start 131.352036 -35.22726)
					(mid 130.859892 -35.408944)
					(end 131.256278 -35.065208)
				)
				(arc
					(start 131.256278 -35.065208)
					(mid 131.260867 -35.042426)
					(end 131.262374 -35.019234)
				)
				(xy 131.262374 -34.762694)
			)
		)
	)
	(zone
		(layer "F.Cu")
		(hatch none 0.5)
		(connect_pads
			(clearance 0)
		)
		(min_thickness 0.25)
		(keepout
			(tracks allowed)
			(vias allowed)
			(pads allowed)
			(copperpour allowed)
			(footprints allowed)
		)
		(placement
			(enabled no)
			(sheetname "")
		)
		(fill
			(thermal_gap 0.5)
			(thermal_bridge_width 0.5)
			(island_removal_mode 0)
		)
		(polygon
			(pts
				(xy 44.196 -226.7966) (xy 44.196 -222.0722) (xy 48.514 -222.0722) (xy 48.514 -226.7966)
			)
		)
	)
	(zone
		(layer "F.Cu")
		(hatch none 0.5)
		(connect_pads
			(clearance 0)
		)
		(min_thickness 0.25)
		(keepout
			(tracks not_allowed)
			(vias allowed)
			(pads allowed)
			(copperpour not_allowed)
			(footprints allowed)
		)
		(placement
			(enabled no)
			(sheetname "")
		)
		(fill
			(thermal_gap 0.5)
			(thermal_bridge_width 0.5)
			(island_removal_mode 0)
		)
		(polygon
			(pts
				(arc
					(start 328.375518 -34.408872)
					(mid 327.864978 -34.919412)
					(end 328.375518 -35.429952)
				)
				(arc
					(start 329.188064 -35.429952)
					(mid 329.698858 -34.919539)
					(end 329.188318 -34.408872)
				)
				(xy 329.028044 -34.408872)
				(arc
					(start 329.028044 -34.487358)
					(mid 329.040931 -34.585159)
					(end 329.07859 -34.676334)
				)
				(arc
					(start 329.07859 -34.676334)
					(mid 329.367815 -35.116663)
					(end 328.95667 -34.787332)
				)
				(arc
					(start 328.95667 -34.787332)
					(mid 328.894404 -34.660638)
					(end 328.867008 -34.522156)
				)
				(xy 328.865992 -34.520886) (xy 328.865992 -34.408872) (xy 328.723244 -34.408872) (xy 328.723244 -34.520886)
				(arc
					(start 328.721974 -34.522156)
					(mid 328.688364 -34.66749)
					(end 328.611738 -34.79546)
				)
				(arc
					(start 328.611738 -34.79546)
					(mid 328.188499 -35.109644)
					(end 328.495406 -34.68116)
				)
				(arc
					(start 328.495406 -34.68116)
					(mid 328.544271 -34.589813)
					(end 328.561192 -34.487612)
				)
				(xy 328.561192 -34.408872)
			)
		)
	)
	(zone
		(layer "F.Cu")
		(hatch none 0.5)
		(connect_pads
			(clearance 0)
		)
		(min_thickness 0.25)
		(keepout
			(tracks allowed)
			(vias allowed)
			(pads allowed)
			(copperpour allowed)
			(footprints allowed)
		)
		(placement
			(enabled no)
			(sheetname "")
		)
		(fill
			(thermal_gap 0.5)
			(thermal_bridge_width 0.5)
			(island_removal_mode 0)
		)
		(polygon
			(pts
				(xy 322.961 -99.568) (xy 322.961 -101.346) (xy 321.437 -101.346) (xy 321.437 -99.568)
			)
		)
	)
	(zone
		(layer "F.Cu")
		(hatch none 0.5)
		(connect_pads
			(clearance 0)
		)
		(min_thickness 0.25)
		(keepout
			(tracks not_allowed)
			(vias allowed)
			(pads allowed)
			(copperpour not_allowed)
			(footprints allowed)
		)
		(placement
			(enabled no)
			(sheetname "")
		)
		(fill
			(thermal_gap 0.5)
			(thermal_bridge_width 0.5)
			(island_removal_mode 0)
		)
		(polygon
			(pts
				(arc
					(start 206.493872 -210.385914)
					(mid 205.983078 -210.896327)
					(end 206.493618 -211.406994)
				)
				(xy 206.660242 -211.406994)
				(arc
					(start 206.660242 -211.302854)
					(mid 206.647465 -211.215865)
					(end 206.610204 -211.13623)
				)
				(arc
					(start 206.610204 -211.13623)
					(mid 206.309068 -210.704032)
					(end 206.728314 -211.022946)
				)
				(arc
					(start 206.728314 -211.022946)
					(mid 206.792318 -211.138825)
					(end 206.821024 -211.268056)
				)
				(xy 206.822294 -211.269326) (xy 206.822294 -211.406994) (xy 206.965042 -211.406994) (xy 206.965042 -211.283042)
				(arc
					(start 206.966312 -211.281772)
					(mid 206.998271 -211.143309)
					(end 207.070452 -211.020914)
				)
				(arc
					(start 207.070452 -211.020914)
					(mid 207.493039 -210.705816)
					(end 207.187038 -211.13496)
				)
				(arc
					(start 207.187038 -211.13496)
					(mid 207.142427 -211.220938)
					(end 207.127094 -211.31657)
				)
				(xy 207.127094 -211.406994)
				(arc
					(start 207.306418 -211.406994)
					(mid 207.816958 -210.896454)
					(end 207.306418 -210.385914)
				)
			)
		)
	)
	(zone
		(net "DUT_VDDO_REF")
		(layer "F.Cu")
		(hatch none 0.5)
		(connect_pads
			(clearance 0.5)
		)
		(min_thickness 0.25)
		(fill yes
			(thermal_gap 0.5)
			(thermal_bridge_width 0.5)
			(island_removal_mode 0)
		)
		(polygon
			(pts
				(xy 234.083606 -9.525) (xy 234.03179 -9.576816) (xy 234.03179 -10.627106) (xy 233.72826 -10.930636)
				(xy 233.045 -10.930636) (xy 231.773222 -12.202414) (xy 231.773222 -14.233144) (xy 231.469438 -14.536928)
				(xy 231.3432 -14.536928) (xy 231.3432 -18.7706) (xy 231.5972 -19.0246) (xy 231.6226 -19.0246) (xy 232.3338 -19.7358)
				(xy 234.2134 -19.7358) (xy 234.6706 -19.2786) (xy 234.6706 -18.3896) (xy 233.5022 -17.2212) (xy 233.5022 -13.2588)
				(xy 233.934 -12.827) (xy 239.776 -12.827) (xy 240.03 -12.573) (xy 240.03 -9.779) (xy 239.776 -9.525)
			)
		)
	)
	(zone
		(layer "F.Cu")
		(hatch none 0.5)
		(connect_pads
			(clearance 0)
		)
		(min_thickness 0.25)
		(keepout
			(tracks allowed)
			(vias allowed)
			(pads allowed)
			(copperpour allowed)
			(footprints allowed)
		)
		(placement
			(enabled no)
			(sheetname "")
		)
		(fill
			(thermal_gap 0.5)
			(thermal_bridge_width 0.5)
			(island_removal_mode 0)
		)
		(polygon
			(pts
				(xy 86.905338 -84.009484) (xy 88.740234 -84.009484) (xy 88.819736 -83.929982) (xy 88.819736 -83.30184)
				(xy 88.631776 -83.11388) (xy 86.948518 -83.11388) (xy 86.905338 -83.15706)
			)
		)
	)
	(zone
		(net "DUT_AVD_TX")
		(layer "F.Cu")
		(hatch none 0.5)
		(connect_pads
			(clearance 0.5)
		)
		(min_thickness 0.25)
		(fill yes
			(thermal_gap 0.5)
			(thermal_bridge_width 0.5)
			(island_removal_mode 0)
		)
		(polygon
			(pts
				(xy 174.996602 -71.325232) (xy 174.615602 -71.706232) (xy 174.615602 -77.091032) (xy 174.818802 -77.294232)
				(xy 177.391568 -77.294232) (xy 177.874168 -76.811632) (xy 177.874168 -71.4756) (xy 177.7238 -71.325232)
			)
		)
	)
	(zone
		(layer "F.Cu")
		(hatch none 0.5)
		(connect_pads
			(clearance 0)
		)
		(min_thickness 0.25)
		(keepout
			(tracks allowed)
			(vias allowed)
			(pads allowed)
			(copperpour allowed)
			(footprints allowed)
		)
		(placement
			(enabled no)
			(sheetname "")
		)
		(fill
			(thermal_gap 0.5)
			(thermal_bridge_width 0.5)
			(island_removal_mode 0)
		)
		(polygon
			(pts
				(xy 220.65996 -1.31191) (xy 222.498158 -1.31191) (xy 222.570548 -1.23952) (xy 222.570548 -0.076454)
				(xy 222.433388 0.060706) (xy 220.739208 0.060706) (xy 220.576648 -0.101854) (xy 220.576648 -1.228598)
			)
		)
	)
	(zone
		(layer "F.Cu")
		(hatch none 0.5)
		(connect_pads
			(clearance 0)
		)
		(min_thickness 0.25)
		(keepout
			(tracks not_allowed)
			(vias allowed)
			(pads allowed)
			(copperpour not_allowed)
			(footprints allowed)
		)
		(placement
			(enabled no)
			(sheetname "")
		)
		(fill
			(thermal_gap 0.5)
			(thermal_bridge_width 0.5)
			(island_removal_mode 0)
		)
		(polygon
			(pts
				(xy 149.35835 -21.507196) (xy 149.013672 -21.162518) (xy 149.013418 -21.162518) (xy 148.99005 -21.138896)
				(xy 148.966428 -21.115274) (xy 148.966428 -21.11502)
				(arc
					(start 148.961094 -21.109686)
					(mid 148.907342 -21.073926)
					(end 148.844 -21.061426)
				)
				(arc
					(start 148.844 -21.061426)
					(mid 148.809523 -21.068173)
					(end 148.780246 -21.087588)
				)
				(xy 148.737574 -21.130514)
				(arc
					(start 148.72716 -21.160486)
					(mid 148.624814 -21.910887)
					(end 148.561552 -21.156168)
				)
				(arc
					(start 148.561552 -21.156168)
					(mid 148.572811 -21.110756)
					(end 148.58873 -21.06676)
				)
				(xy 148.58873 -21.050504) (xy 148.68906 -20.949412)
				(arc
					(start 148.69287 -20.949412)
					(mid 148.764139 -20.912212)
					(end 148.843492 -20.899374)
				)
				(xy 148.844 -20.899374)
				(arc
					(start 148.844508 -20.899374)
					(mid 148.953165 -20.918093)
					(end 149.049486 -20.971764)
				)
				(xy 149.052534 -20.971764) (xy 149.104858 -21.024596) (xy 149.141688 -21.061426) (xy 149.43836 -21.358098)
				(arc
					(start 149.51202 -21.22043)
					(mid 149.40325 -21.048171)
					(end 149.33295 -20.856956)
				)
				(arc
					(start 149.33295 -20.856956)
					(mid 149.313114 -20.756631)
					(end 149.303994 -20.654772)
				)
				(xy 149.303486 -20.65401)
				(arc
					(start 149.303486 -20.502372)
					(mid 149.384512 -19.74893)
					(end 149.465538 -20.502372)
				)
				(arc
					(start 149.465538 -20.620482)
					(mid 149.471638 -20.719662)
					(end 149.489922 -20.817332)
				)
				(arc
					(start 149.489922 -20.817332)
					(mid 149.533328 -20.943975)
					(end 149.59711 -21.06168)
				)
				(xy 149.93747 -20.426426) (xy 149.937216 -20.426172)
				(arc
					(start 149.935184 -20.425156)
					(mid 149.679508 -19.579255)
					(end 148.833586 -19.835114)
				)
				(xy 148.831554 -19.833844) (xy 148.081492 -21.233892)
				(arc
					(start 148.083524 -21.235162)
					(mid 148.339556 -22.080982)
					(end 149.185376 -21.82495)
				)
				(xy 149.187408 -21.82622)
			)
		)
	)
	(zone
		(layer "F.Cu")
		(hatch none 0.5)
		(connect_pads
			(clearance 0)
		)
		(min_thickness 0.25)
		(keepout
			(tracks not_allowed)
			(vias allowed)
			(pads allowed)
			(copperpour not_allowed)
			(footprints allowed)
		)
		(placement
			(enabled no)
			(sheetname "")
		)
		(fill
			(thermal_gap 0.5)
			(thermal_bridge_width 0.5)
			(island_removal_mode 0)
		)
		(polygon
			(pts
				(arc
					(start 201.97318 -44.714922)
					(mid 201.36104 -44.102782)
					(end 200.7489 -44.714922)
				)
				(arc
					(start 200.7489 -45.832268)
					(mid 201.360913 -46.444662)
					(end 201.97318 -45.832522)
				)
				(xy 201.97318 -45.532548)
				(arc
					(start 201.76744 -45.532548)
					(mid 201.641292 -45.557911)
					(end 201.534776 -45.630084)
				)
				(arc
					(start 201.534776 -45.630084)
					(mid 201.261699 -46.079823)
					(end 201.376534 -45.56633)
				)
				(arc
					(start 201.376534 -45.56633)
					(mid 201.533416 -45.430302)
					(end 201.732642 -45.371766)
				)
				(xy 201.733912 -45.370496) (xy 201.97318 -45.370496) (xy 201.97318 -45.227748) (xy 201.733912 -45.227748)
				(arc
					(start 201.732642 -45.226478)
					(mid 201.507211 -45.152574)
					(end 201.34326 -44.981114)
				)
				(arc
					(start 201.34326 -44.981114)
					(mid 201.292797 -44.457013)
					(end 201.508106 -44.937426)
				)
				(arc
					(start 201.508106 -44.937426)
					(mid 201.622787 -45.031849)
					(end 201.76744 -45.065696)
				)
				(xy 201.97318 -45.065696)
			)
		)
	)
	(zone
		(layer "F.Cu")
		(hatch none 0.5)
		(connect_pads
			(clearance 0)
		)
		(min_thickness 0.25)
		(keepout
			(tracks not_allowed)
			(vias allowed)
			(pads allowed)
			(copperpour not_allowed)
			(footprints allowed)
		)
		(placement
			(enabled no)
			(sheetname "")
		)
		(fill
			(thermal_gap 0.5)
			(thermal_bridge_width 0.5)
			(island_removal_mode 0)
		)
		(polygon
			(pts
				(arc
					(start 200.25233 -49.559972)
					(mid 200.352757 -49.425789)
					(end 200.388474 -49.26203)
				)
				(xy 200.388474 -49.120044)
				(arc
					(start 200.046844 -49.122076)
					(mid 199.43826 -49.737772)
					(end 200.053956 -50.346356)
				)
				(arc
					(start 201.171302 -50.339752)
					(mid 201.780139 -49.724183)
					(end 201.164444 -49.115472)
				)
				(xy 200.855326 -49.11725)
				(arc
					(start 200.855326 -49.247806)
					(mid 200.894652 -49.40223)
					(end 200.985628 -49.533048)
				)
				(arc
					(start 200.985628 -49.533048)
					(mid 201.402111 -49.855309)
					(end 200.905618 -49.679606)
				)
				(arc
					(start 200.905618 -49.679606)
					(mid 200.763926 -49.503152)
					(end 200.696322 -49.287176)
				)
				(xy 200.693274 -49.284128) (xy 200.693274 -49.118266) (xy 200.550526 -49.119028) (xy 200.550526 -49.295558)
				(arc
					(start 200.54951 -49.296574)
					(mid 200.480352 -49.53251)
					(end 200.316338 -49.715674)
				)
				(arc
					(start 200.316338 -49.715674)
					(mid 199.803844 -49.835291)
					(end 200.25233 -49.559972)
				)
			)
		)
	)
	(zone
		(net "P12V")
		(layer "F.Cu")
		(hatch none 0.5)
		(connect_pads
			(clearance 0.5)
		)
		(min_thickness 0.25)
		(fill yes
			(thermal_gap 0.5)
			(thermal_bridge_width 0.5)
			(island_removal_mode 0)
		)
		(polygon
			(pts
				(xy 347.218 -47.371) (xy 346.964 -47.625) (xy 346.964 -49.7586) (xy 348.3102 -49.7586) (xy 348.8182 -50.2666)
				(xy 349.424498 -50.2666) (xy 349.991172 -50.833274) (xy 351.554034 -50.833274) (xy 351.779586 -50.607722)
				(xy 351.779586 -47.733458) (xy 351.417128 -47.371)
			)
		)
	)
	(zone
		(net "GND")
		(layer "F.Cu")
		(hatch none 0.5)
		(connect_pads
			(clearance 0.5)
		)
		(min_thickness 0.25)
		(fill yes
			(thermal_gap 0.5)
			(thermal_bridge_width 0.5)
			(island_removal_mode 0)
		)
		(polygon
			(pts
				(xy 64.643 -34.163) (xy 64.262 -34.544) (xy 64.262 -41.783) (xy 63.881 -42.164) (xy 63.881 -42.418)
				(xy 64.262 -42.799) (xy 64.262 -48.641) (xy 66.421 -50.8) (xy 87.249 -50.8) (xy 88.011 -50.038)
				(xy 88.011 -47.371) (xy 87.757 -47.117) (xy 69.85 -47.117) (xy 67.437 -44.704) (xy 67.437 -34.417)
				(xy 67.183 -34.163)
			)
		)
	)
	(zone
		(net "AGND_USB")
		(layer "F.Cu")
		(hatch none 0.5)
		(connect_pads
			(clearance 0.5)
		)
		(min_thickness 0.25)
		(fill yes
			(thermal_gap 0.5)
			(thermal_bridge_width 0.5)
			(island_removal_mode 0)
		)
		(polygon
			(pts
				(xy 28.57754 -32.94126) (xy 28.4353 -33.0835) (xy 28.4353 -37.1983) (xy 29.66466 -38.42766) (xy 31.93542 -38.42766)
				(xy 32.97174 -37.39134) (xy 41.6814 -37.39134) (xy 42.71772 -38.42766) (xy 45.5549 -38.42766) (xy 46.31436 -37.6682)
				(xy 46.31436 -33.02254) (xy 46.23308 -32.94126)
			)
		)
		(polygon
			(pts
				(xy 29.581856 -33.883346) (xy 29.378656 -33.883346) (xy 29.378656 -34.086546) (xy 29.581856 -34.086546)
			)
		)
		(polygon
			(pts
				(xy 45.856652 -33.860994) (xy 45.653452 -33.860994) (xy 45.653452 -34.064194) (xy 45.856652 -34.064194)
			)
		)
	)
	(zone
		(net "DUT_AVD_PCIE")
		(layer "F.Cu")
		(hatch none 0.5)
		(connect_pads
			(clearance 0.5)
		)
		(min_thickness 0.25)
		(fill yes
			(thermal_gap 0.5)
			(thermal_bridge_width 0.5)
			(island_removal_mode 0)
		)
		(polygon
			(pts
				(xy 179.0192 -61.976) (xy 178.2572 -62.738) (xy 178.2572 -71.446644) (xy 178.48834 -71.677784) (xy 187.816998 -71.677784)
				(xy 188.096398 -71.398384) (xy 188.096398 -62.671198) (xy 187.4012 -61.976)
			)
		)
	)
	(zone
		(layer "F.Cu")
		(hatch none 0.5)
		(connect_pads
			(clearance 0)
		)
		(min_thickness 0.25)
		(keepout
			(tracks not_allowed)
			(vias allowed)
			(pads allowed)
			(copperpour not_allowed)
			(footprints allowed)
		)
		(placement
			(enabled no)
			(sheetname "")
		)
		(fill
			(thermal_gap 0.5)
			(thermal_bridge_width 0.5)
			(island_removal_mode 0)
		)
		(polygon
			(pts
				(arc
					(start 145.910554 -34.48558)
					(mid 145.39976 -34.995993)
					(end 145.9103 -35.50666)
				)
				(arc
					(start 146.7231 -35.50666)
					(mid 147.23364 -34.99612)
					(end 146.7231 -34.48558)
				)
				(xy 146.550126 -34.48558)
				(arc
					(start 146.550126 -34.588704)
					(mid 146.563938 -34.677281)
					(end 146.604228 -34.75736)
				)
				(arc
					(start 146.604228 -34.75736)
					(mid 146.909271 -35.18711)
					(end 146.487388 -34.871152)
				)
				(arc
					(start 146.487388 -34.871152)
					(mid 146.419662 -34.754728)
					(end 146.389344 -34.623502)
				)
				(xy 146.388074 -34.622232) (xy 146.388074 -34.48558) (xy 146.245326 -34.48558) (xy 146.245326 -34.622232)
				(arc
					(start 146.244056 -34.623502)
					(mid 146.213689 -34.754708)
					(end 146.146012 -34.871152)
				)
				(arc
					(start 146.146012 -34.871152)
					(mid 145.724076 -35.187164)
					(end 146.029172 -34.75736)
				)
				(arc
					(start 146.029172 -34.75736)
					(mid 146.069433 -34.677272)
					(end 146.083274 -34.588704)
				)
				(xy 146.083274 -34.48558)
			)
		)
	)
	(zone
		(layer "F.Cu")
		(hatch none 0.5)
		(connect_pads
			(clearance 0)
		)
		(min_thickness 0.25)
		(keepout
			(tracks not_allowed)
			(vias allowed)
			(pads allowed)
			(copperpour not_allowed)
			(footprints allowed)
		)
		(placement
			(enabled no)
			(sheetname "")
		)
		(fill
			(thermal_gap 0.5)
			(thermal_bridge_width 0.5)
			(island_removal_mode 0)
		)
		(polygon
			(pts
				(arc
					(start 156.431234 -24.232616)
					(mid 156.1831 -23.381163)
					(end 155.333446 -23.635208)
				)
				(arc
					(start 154.583638 -25.035256)
					(mid 154.83967 -25.881076)
					(end 155.68549 -25.625044)
				)
				(arc
					(start 155.857956 -25.302972)
					(mid 155.836055 -25.270581)
					(end 155.810204 -25.24125)
				)
				(arc
					(start 155.507436 -24.938736)
					(mid 155.468761 -24.912801)
					(end 155.423108 -24.903684)
				)
				(arc
					(start 155.346146 -24.903684)
					(mid 155.317552 -24.912966)
					(end 155.290012 -24.92502)
				)
				(arc
					(start 155.290012 -24.92502)
					(mid 155.272284 -24.946297)
					(end 155.256738 -24.969216)
				)
				(arc
					(start 155.256738 -24.969216)
					(mid 155.097532 -25.709397)
					(end 155.084526 -24.952452)
				)
				(arc
					(start 155.084526 -24.952452)
					(mid 155.126193 -24.872065)
					(end 155.183332 -24.80183)
				)
				(arc
					(start 155.183332 -24.80183)
					(mid 155.192118 -24.794318)
					(end 155.201874 -24.788114)
				)
				(arc
					(start 155.201874 -24.788114)
					(mid 155.246957 -24.766602)
					(end 155.294076 -24.750014)
				)
				(xy 155.302458 -24.741632) (xy 155.456636 -24.741632)
				(arc
					(start 155.458922 -24.743918)
					(mid 155.530757 -24.763032)
					(end 155.595066 -24.800306)
				)
				(xy 155.598368 -24.800306) (xy 155.924758 -25.126442) (xy 155.924758 -25.126696) (xy 155.942792 -25.14473)
				(arc
					(start 156.013404 -25.01265)
					(mid 155.863156 -24.749222)
					(end 155.803854 -24.451818)
				)
				(xy 155.803346 -24.451056)
				(arc
					(start 155.803346 -24.302466)
					(mid 155.884372 -23.549024)
					(end 155.965398 -24.302466)
				)
				(arc
					(start 155.965398 -24.417528)
					(mid 155.999389 -24.645825)
					(end 156.09824 -24.854408)
				)
			)
		)
	)
	(zone
		(layer "F.Cu")
		(hatch none 0.5)
		(connect_pads
			(clearance 0)
		)
		(min_thickness 0.25)
		(keepout
			(tracks not_allowed)
			(vias allowed)
			(pads allowed)
			(copperpour not_allowed)
			(footprints allowed)
		)
		(placement
			(enabled no)
			(sheetname "")
		)
		(fill
			(thermal_gap 0.5)
			(thermal_bridge_width 0.5)
			(island_removal_mode 0)
		)
		(polygon
			(pts
				(xy 160.446466 -21.342604) (xy 160.517078 -21.211032) (xy 160.414208 -21.108416) (xy 160.414208 -21.108162)
				(xy 160.390586 -21.08454)
				(arc
					(start 160.390586 -21.083524)
					(mid 160.250483 -20.863171)
					(end 160.193736 -20.60829)
				)
				(xy 160.192974 -20.607528)
				(arc
					(start 160.192974 -20.459446)
					(mid 160.497824 -19.766191)
					(end 160.355026 -20.509992)
				)
				(arc
					(start 160.355026 -20.574)
					(mid 160.400177 -20.801077)
					(end 160.528762 -20.993608)
				)
				(xy 160.597088 -21.06168) (xy 160.937448 -20.426426) (xy 160.937194 -20.426172)
				(arc
					(start 160.935162 -20.425156)
					(mid 160.679486 -19.579255)
					(end 159.833564 -19.835114)
				)
				(xy 159.831532 -19.833844) (xy 159.08147 -21.233892)
				(arc
					(start 159.083502 -21.235162)
					(mid 159.339534 -22.080982)
					(end 160.185354 -21.82495)
				)
				(xy 160.187386 -21.82622) (xy 160.36671 -21.491702)
				(arc
					(start 160.19399 -21.318982)
					(mid 160.074119 -21.286299)
					(end 159.9565 -21.326348)
				)
				(arc
					(start 159.9565 -21.326348)
					(mid 159.364196 -21.7982)
					(end 159.841184 -21.210016)
				)
				(arc
					(start 159.8422 -21.210016)
					(mid 160.049881 -21.125417)
					(end 160.268666 -21.17471)
				)
				(xy 160.278826 -21.17471)
			)
		)
	)
	(zone
		(layer "F.Cu")
		(hatch none 0.5)
		(connect_pads
			(clearance 0)
		)
		(min_thickness 0.25)
		(keepout
			(tracks not_allowed)
			(vias allowed)
			(pads allowed)
			(copperpour not_allowed)
			(footprints allowed)
		)
		(placement
			(enabled no)
			(sheetname "")
		)
		(fill
			(thermal_gap 0.5)
			(thermal_bridge_width 0.5)
			(island_removal_mode 0)
		)
		(polygon
			(pts
				(arc
					(start 28.47594 -105.502202)
					(mid 27.610308 -105.502202)
					(end 27.610308 -106.367834)
				)
				(xy 27.60853 -106.369612)
				(arc
					(start 27.898344 -106.659426)
					(mid 27.939784 -106.568941)
					(end 27.997658 -106.487976)
				)
				(xy 27.997658 -106.486198)
				(arc
					(start 28.092146 -106.391456)
					(mid 28.147029 -106.29397)
					(end 28.1432 -106.18216)
				)
				(arc
					(start 28.1432 -106.18216)
					(mid 27.870186 -105.73185)
					(end 28.271978 -106.072178)
				)
				(arc
					(start 28.271978 -106.072178)
					(mid 28.313124 -106.282419)
					(end 28.230576 -106.480102)
				)
				(xy 28.230576 -106.482388)
				(arc
					(start 28.136088 -106.576876)
					(mid 28.065952 -106.676735)
					(end 28.033218 -106.7943)
				)
				(xy 28.174188 -106.93527) (xy 28.174188 -106.797348)
				(arc
					(start 28.177236 -106.7943)
					(mid 28.190598 -106.748186)
					(end 28.213812 -106.706162)
				)
				(xy 28.213812 -106.70159) (xy 28.23718 -106.678222) (xy 28.237434 -106.677968) (xy 28.331414 -106.58348)
				(arc
					(start 28.333954 -106.58348)
					(mid 28.494083 -106.506722)
					(end 28.67152 -106.51363)
				)
				(arc
					(start 28.67152 -106.51363)
					(mid 29.056584 -106.871757)
					(end 28.574746 -106.661204)
				)
				(arc
					(start 28.574746 -106.661204)
					(mid 28.492443 -106.675753)
					(end 28.4226 -106.721656)
				)
				(arc
					(start 28.351988 -106.792522)
					(mid 28.340337 -106.810147)
					(end 28.33624 -106.830876)
				)
				(xy 28.33624 -107.097322) (xy 28.398978 -107.16006)
				(arc
					(start 28.400756 -107.158282)
					(mid 29.266388 -107.158282)
					(end 29.266388 -106.29265)
				)
				(xy 29.268166 -106.290872) (xy 28.477972 -105.500678) (xy 28.477464 -105.500678)
			)
		)
	)
	(zone
		(net "P1V26_STBY")
		(layer "F.Cu")
		(hatch none 0.5)
		(connect_pads
			(clearance 0.5)
		)
		(min_thickness 0.25)
		(fill yes
			(thermal_gap 0.5)
			(thermal_bridge_width 0.5)
			(island_removal_mode 0)
		)
		(polygon
			(pts
				(xy 13.95476 -113.55324) (xy 13.8176 -113.6904) (xy 13.8176 -115.2906) (xy 15.781274 -117.254274)
				(xy 16.832326 -117.254274) (xy 16.9799 -117.1067) (xy 16.9799 -114.4397) (xy 16.09344 -113.55324)
			)
		)
	)
	(zone
		(layer "F.Cu")
		(hatch none 0.5)
		(connect_pads
			(clearance 0)
		)
		(min_thickness 0.25)
		(keepout
			(tracks not_allowed)
			(vias allowed)
			(pads allowed)
			(copperpour not_allowed)
			(footprints allowed)
		)
		(placement
			(enabled no)
			(sheetname "")
		)
		(fill
			(thermal_gap 0.5)
			(thermal_bridge_width 0.5)
			(island_removal_mode 0)
		)
		(polygon
			(pts
				(arc
					(start 167.012112 -25.01519)
					(mid 166.862081 -24.718335)
					(end 166.803832 -24.390858)
				)
				(xy 166.803324 -24.39035)
				(arc
					(start 166.803324 -24.302466)
					(mid 166.88435 -23.549024)
					(end 166.965376 -24.302466)
				)
				(arc
					(start 166.965376 -24.356822)
					(mid 166.999483 -24.613276)
					(end 167.099488 -24.851868)
				)
				(arc
					(start 167.431212 -24.232616)
					(mid 167.183078 -23.381163)
					(end 166.333424 -23.635208)
				)
				(arc
					(start 165.583616 -25.035256)
					(mid 165.839648 -25.881076)
					(end 166.685468 -25.625044)
				)
				(xy 166.853362 -25.311608)
				(arc
					(start 166.78402 -25.242266)
					(mid 166.71072 -25.193258)
					(end 166.624254 -25.175972)
				)
				(arc
					(start 166.5478 -25.175972)
					(mid 166.516433 -25.177363)
					(end 166.485316 -25.18156)
				)
				(arc
					(start 166.485316 -25.18156)
					(mid 165.826852 -25.554756)
					(end 166.382954 -25.041352)
				)
				(arc
					(start 166.382954 -25.041352)
					(mid 166.447126 -25.024037)
					(end 166.513002 -25.01519)
				)
				(xy 166.514272 -25.01392) (xy 166.657528 -25.01392)
				(arc
					(start 166.659052 -25.015444)
					(mid 166.772576 -25.043398)
					(end 166.872666 -25.103836)
				)
				(xy 166.874952 -25.103836) (xy 166.898828 -25.127712) (xy 166.933372 -25.162256)
			)
		)
	)
	(zone
		(layer "F.Cu")
		(hatch none 0.5)
		(connect_pads
			(clearance 0)
		)
		(min_thickness 0.25)
		(keepout
			(tracks not_allowed)
			(vias allowed)
			(pads allowed)
			(copperpour not_allowed)
			(footprints allowed)
		)
		(placement
			(enabled no)
			(sheetname "")
		)
		(fill
			(thermal_gap 0.5)
			(thermal_bridge_width 0.5)
			(island_removal_mode 0)
		)
		(polygon
			(pts
				(arc
					(start 300.062392 -21.199602)
					(mid 300.125031 -21.292945)
					(end 300.163738 -21.398484)
				)
				(arc
					(start 300.253654 -21.23059)
					(mid 300.202914 -21.1473)
					(end 300.139608 -21.07311)
				)
				(arc
					(start 300.139608 -21.07311)
					(mid 300.083248 -20.993896)
					(end 300.055788 -20.900644)
				)
				(xy 300.053502 -20.898358)
				(arc
					(start 300.053502 -20.502372)
					(mid 300.133497 -19.749038)
					(end 300.215554 -20.502118)
				)
				(arc
					(start 300.215554 -20.86483)
					(mid 300.22571 -20.915418)
					(end 300.254416 -20.958302)
				)
				(arc
					(start 300.254416 -20.958302)
					(mid 300.300982 -21.009284)
					(end 300.342808 -21.06422)
				)
				(arc
					(start 300.681136 -20.432522)
					(mid 300.433002 -19.581069)
					(end 299.583348 -19.835114)
				)
				(arc
					(start 298.83354 -21.235162)
					(mid 299.089572 -22.080982)
					(end 299.935392 -21.82495)
				)
				(xy 300.014386 -21.677376)
				(arc
					(start 300.014386 -21.506688)
					(mid 299.990831 -21.388739)
					(end 299.923962 -21.288756)
				)
				(xy 299.744384 -21.108924)
				(arc
					(start 299.726858 -21.094192)
					(mid 299.676398 -21.067758)
					(end 299.620178 -21.058632)
				)
				(arc
					(start 299.570394 -21.058632)
					(mid 299.535066 -21.065753)
					(end 299.505116 -21.08581)
				)
				(arc
					(start 299.505116 -21.08581)
					(mid 299.480694 -21.119087)
					(end 299.467524 -21.1582)
				)
				(arc
					(start 299.467524 -21.1582)
					(mid 299.382917 -21.911128)
					(end 299.30344 -21.157692)
				)
				(xy 299.30344 -21.147532)
				(arc
					(start 299.305472 -21.145246)
					(mid 299.333284 -21.051013)
					(end 299.390308 -20.971002)
				)
				(arc
					(start 299.390308 -20.971002)
					(mid 299.456485 -20.923376)
					(end 299.534326 -20.89912)
				)
				(xy 299.536866 -20.89658) (xy 299.653706 -20.89658)
				(arc
					(start 299.655484 -20.898358)
					(mid 299.744121 -20.919887)
					(end 299.823886 -20.964144)
				)
				(xy 299.834554 -20.972526) (xy 299.837094 -20.972526) (xy 299.85843 -20.993862) (xy 299.86097 -20.996402)
				(xy 300.062392 -21.197824)
			)
		)
	)
	(zone
		(net "GND")
		(layer "F.Cu")
		(hatch none 0.5)
		(connect_pads
			(clearance 0.5)
		)
		(min_thickness 0.25)
		(fill yes
			(thermal_gap 0.5)
			(thermal_bridge_width 0.5)
			(island_removal_mode 0)
		)
		(polygon
			(pts
				(xy 295.8338 -69.1642) (xy 295.529 -69.469) (xy 295.529 -75.057) (xy 296.037 -75.565) (xy 320.548 -75.565)
				(xy 321.183 -74.93) (xy 321.183 -69.469) (xy 320.8782 -69.1642)
			)
		)
	)
	(zone
		(layer "F.Cu")
		(hatch none 0.5)
		(connect_pads
			(clearance 0)
		)
		(min_thickness 0.25)
		(keepout
			(tracks allowed)
			(vias allowed)
			(pads allowed)
			(copperpour allowed)
			(footprints allowed)
		)
		(placement
			(enabled no)
			(sheetname "")
		)
		(fill
			(thermal_gap 0.5)
			(thermal_bridge_width 0.5)
			(island_removal_mode 0)
		)
		(polygon
			(pts
				(xy 22.27707 -78.409038) (xy 22.27707 -80.687418) (xy 22.473666 -80.884014) (xy 24.728932 -80.884014)
				(xy 25.190704 -80.884014) (xy 25.385268 -80.884014) (xy 25.489916 -80.779366) (xy 25.489916 -78.827122)
				(xy 25.23998 -78.577186) (xy 24.890222 -78.227428) (xy 24.87295 -78.227428) (xy 24.87295 -76.78166)
				(xy 24.623268 -76.531978) (xy 22.382734 -76.531978) (xy 22.27707 -76.637642)
			)
		)
	)
	(zone
		(net "P3V3_PWR")
		(layer "F.Cu")
		(hatch none 0.5)
		(connect_pads
			(clearance 0.5)
		)
		(min_thickness 0.25)
		(fill yes
			(thermal_gap 0.5)
			(thermal_bridge_width 0.5)
			(island_removal_mode 0)
		)
		(polygon
			(pts
				(xy 75.819 -40.005) (xy 75.438 -40.386) (xy 75.438 -46.101) (xy 75.692 -46.355) (xy 88.519 -46.355)
				(xy 88.773 -46.101) (xy 88.773 -40.132) (xy 88.646 -40.005)
			)
		)
	)
	(zone
		(layer "F.Cu")
		(hatch none 0.5)
		(connect_pads
			(clearance 0)
		)
		(min_thickness 0.25)
		(keepout
			(tracks allowed)
			(vias allowed)
			(pads allowed)
			(copperpour allowed)
			(footprints allowed)
		)
		(placement
			(enabled no)
			(sheetname "")
		)
		(fill
			(thermal_gap 0.5)
			(thermal_bridge_width 0.5)
			(island_removal_mode 0)
		)
		(polygon
			(pts
				(xy 162.9664 -92.3036) (xy 162.9664 -88.265) (xy 164.9222 -88.265) (xy 164.9222 -92.3036)
			)
		)
	)
	(zone
		(net "P0V9_E_VIN")
		(layer "F.Cu")
		(hatch none 0.5)
		(connect_pads
			(clearance 0.5)
		)
		(min_thickness 0.25)
		(fill yes
			(thermal_gap 0.5)
			(thermal_bridge_width 0.5)
			(island_removal_mode 0)
		)
		(polygon
			(pts
				(xy 340.868 -47.879) (xy 340.614 -48.133) (xy 340.614 -59.436) (xy 341.503 -60.325) (xy 341.503 -66.929)
				(xy 341.63 -67.056) (xy 342.773 -67.056) (xy 343.281 -66.548) (xy 345.313 -66.548) (xy 346.075 -65.786)
				(xy 346.075 -48.387) (xy 345.567 -47.879)
			)
		)
		(polygon
			(pts
				(xy 342.6206 -62.9412) (xy 342.4174 -62.9412) (xy 342.4174 -63.1444) (xy 342.6206 -63.1444)
			)
		)
		(polygon
			(pts
				(xy 342.6206 -62.0776) (xy 342.4174 -62.0776) (xy 342.4174 -62.2808) (xy 342.6206 -62.2808)
			)
		)
	)
	(zone
		(net "GND")
		(layer "F.Cu")
		(hatch none 0.5)
		(connect_pads
			(clearance 0.5)
		)
		(min_thickness 0.25)
		(fill yes
			(thermal_gap 0.5)
			(thermal_bridge_width 0.5)
			(island_removal_mode 0)
		)
		(polygon
			(pts
				(xy 196.986144 -52.060856) (xy 194.4116 -54.6354) (xy 193.3194 -54.6354) (xy 192.786 -55.1688) (xy 192.786 -79.375)
				(xy 195.199 -81.788) (xy 211.963 -81.788) (xy 218.313 -75.438) (xy 228.092 -75.438) (xy 233.172 -80.518)
				(xy 233.172 -96.139) (xy 230.632 -98.679) (xy 184.658 -98.679) (xy 177.292 -106.045) (xy 93.726 -106.045)
				(xy 90.551 -109.22) (xy 90.551 -125.095) (xy 83.439 -132.207) (xy 83.439 -140.716) (xy 78.994 -145.161)
				(xy 78.994 -168.656) (xy 84.455 -174.117) (xy 99.06 -174.117) (xy 112.776 -187.833) (xy 191.135 -187.833)
				(xy 201.549 -177.419) (xy 219.329 -177.419) (xy 223.393 -173.355) (xy 223.393 -158.115) (xy 233.553 -147.955)
				(xy 275.59 -147.955) (xy 282.702 -155.067) (xy 327.787 -155.067) (xy 330.454 -152.4) (xy 330.454 -117.221)
				(xy 324.358 -111.125) (xy 303.022 -111.125) (xy 259.461 -67.564) (xy 229.87 -67.564) (xy 229.743 -67.437)
				(xy 220.726 -67.437) (xy 219.202 -65.913) (xy 219.202 -55.245) (xy 219.329 -55.118) (xy 216.271856 -52.060856)
			)
		)
	)
	(zone
		(layer "F.Cu")
		(hatch none 0.5)
		(connect_pads
			(clearance 0)
		)
		(min_thickness 0.25)
		(keepout
			(tracks allowed)
			(vias allowed)
			(pads allowed)
			(copperpour allowed)
			(footprints not_allowed)
		)
		(placement
			(enabled no)
			(sheetname "")
		)
		(fill
			(thermal_gap 0.5)
			(thermal_bridge_width 0.5)
			(island_removal_mode 0)
		)
		(polygon
			(pts
				(arc
					(start 348.149926 -5.40004)
					(mid 349.750126 -3.79984)
					(end 351.350072 -5.40004)
				)
				(arc
					(start 351.350072 -5.40004)
					(mid 349.750126 -6.999986)
					(end 348.149926 -5.40004)
				)
			)
		)
	)
	(zone
		(layer "F.Cu")
		(hatch none 0.5)
		(connect_pads
			(clearance 0)
		)
		(min_thickness 0.25)
		(keepout
			(tracks not_allowed)
			(vias allowed)
			(pads allowed)
			(copperpour not_allowed)
			(footprints allowed)
		)
		(placement
			(enabled no)
			(sheetname "")
		)
		(fill
			(thermal_gap 0.5)
			(thermal_bridge_width 0.5)
			(island_removal_mode 0)
		)
		(polygon
			(pts
				(arc
					(start 18.6944 -57.627266)
					(mid 18.08226 -58.239406)
					(end 18.6944 -58.851546)
				)
				(arc
					(start 19.812 -58.851546)
					(mid 20.42414 -58.239406)
					(end 19.812 -57.627266)
				)
				(xy 19.489928 -57.627266) (xy 19.489928 -57.825132)
				(arc
					(start 19.675094 -58.010552)
					(mid 20.00057 -58.427976)
					(end 19.583146 -58.1025)
				)
				(xy 19.359626 -57.87898) (xy 19.359372 -57.87898) (xy 19.359372 -57.627266) (xy 19.147028 -57.627266)
				(xy 19.147028 -57.87898) (xy 19.146774 -57.87898)
				(arc
					(start 18.923254 -58.1025)
					(mid 18.50583 -58.427976)
					(end 18.831306 -58.010552)
				)
				(xy 19.016472 -57.825132) (xy 19.016472 -57.627266)
			)
		)
	)
	(zone
		(layer "F.Cu")
		(hatch none 0.5)
		(connect_pads
			(clearance 0)
		)
		(min_thickness 0.25)
		(keepout
			(tracks not_allowed)
			(vias allowed)
			(pads allowed)
			(copperpour not_allowed)
			(footprints allowed)
		)
		(placement
			(enabled no)
			(sheetname "")
		)
		(fill
			(thermal_gap 0.5)
			(thermal_bridge_width 0.5)
			(island_removal_mode 0)
		)
		(polygon
			(pts
				(arc
					(start 326.093836 -210.385914)
					(mid 325.583042 -210.896327)
					(end 326.093582 -211.406994)
				)
				(xy 326.260206 -211.406994)
				(arc
					(start 326.260206 -211.2772)
					(mid 326.248115 -211.202193)
					(end 326.213216 -211.134706)
				)
				(arc
					(start 326.213216 -211.134706)
					(mid 325.906882 -210.70614)
					(end 326.329548 -211.02066)
				)
				(arc
					(start 326.329548 -211.02066)
					(mid 326.392057 -211.124447)
					(end 326.420734 -211.242148)
				)
				(xy 326.422258 -211.243672) (xy 326.422258 -211.406994) (xy 326.565006 -211.406994) (xy 326.565006 -211.243418)
				(arc
					(start 326.565768 -211.242656)
					(mid 326.588188 -211.14041)
					(end 326.640698 -211.04987)
				)
				(xy 326.640698 -211.04733) (xy 326.664574 -211.023454)
				(arc
					(start 326.6694 -211.018628)
					(mid 327.095565 -210.708423)
					(end 326.783954 -211.133436)
				)
				(arc
					(start 326.779128 -211.138262)
					(mid 326.740681 -211.195713)
					(end 326.727058 -211.263484)
				)
				(xy 326.727058 -211.277454) (xy 326.727058 -211.406994)
				(arc
					(start 326.906382 -211.406994)
					(mid 327.416922 -210.896454)
					(end 326.906382 -210.385914)
				)
			)
		)
	)
	(zone
		(layer "F.Cu")
		(hatch none 0.5)
		(connect_pads
			(clearance 0)
		)
		(min_thickness 0.25)
		(keepout
			(tracks not_allowed)
			(vias allowed)
			(pads allowed)
			(copperpour not_allowed)
			(footprints allowed)
		)
		(placement
			(enabled no)
			(sheetname "")
		)
		(fill
			(thermal_gap 0.5)
			(thermal_bridge_width 0.5)
			(island_removal_mode 0)
		)
		(polygon
			(pts
				(arc
					(start 296.921936 -12.997942)
					(mid 297.087155 -13.25962)
					(end 297.186604 -13.552678)
				)
				(arc
					(start 297.186604 -13.552678)
					(mid 297.164702 -14.309945)
					(end 297.023536 -13.565632)
				)
				(arc
					(start 297.023536 -13.565632)
					(mid 296.950978 -13.351105)
					(end 296.837862 -13.154914)
				)
				(xy 296.581322 -13.633704) (xy 296.581576 -13.633958)
				(arc
					(start 296.583608 -13.634974)
					(mid 296.839284 -14.480875)
					(end 297.685206 -14.225016)
				)
				(xy 297.687238 -14.226286) (xy 298.4373 -12.826238)
				(arc
					(start 298.435268 -12.824968)
					(mid 298.179236 -11.979148)
					(end 297.333416 -12.23518)
				)
				(xy 297.331384 -12.23391) (xy 297.216068 -12.449048)
				(arc
					(start 297.511978 -12.449048)
					(mid 298.26542 -12.530074)
					(end 297.511978 -12.6111)
				)
				(xy 297.1292 -12.6111)
			)
		)
	)
	(zone
		(layer "F.Cu")
		(hatch none 0.5)
		(connect_pads
			(clearance 0)
		)
		(min_thickness 0.25)
		(keepout
			(tracks not_allowed)
			(vias allowed)
			(pads allowed)
			(copperpour not_allowed)
			(footprints allowed)
		)
		(placement
			(enabled no)
			(sheetname "")
		)
		(fill
			(thermal_gap 0.5)
			(thermal_bridge_width 0.5)
			(island_removal_mode 0)
		)
		(polygon
			(pts
				(arc
					(start 22.555454 -53.045614)
					(mid 22.04466 -53.556027)
					(end 22.5552 -54.066694)
				)
				(xy 22.724872 -54.066694) (xy 22.724872 -53.818028)
				(arc
					(start 22.692106 -53.785008)
					(mid 22.288522 -53.556154)
					(end 22.692106 -53.3273)
				)
				(xy 22.705822 -53.31333) (xy 22.705822 -53.045614)
			)
		)
	)
	(zone
		(net "GND")
		(layer "F.Cu")
		(hatch none 0.5)
		(connect_pads
			(clearance 0.5)
		)
		(min_thickness 0.25)
		(fill yes
			(thermal_gap 0.5)
			(thermal_bridge_width 0.5)
			(island_removal_mode 0)
		)
		(polygon
			(pts
				(xy 221.996 -23.368) (xy 221.869 -23.495) (xy 221.869 -25.146) (xy 222.123 -25.4) (xy 238.125 -25.4)
				(xy 238.506 -25.019) (xy 238.506 -23.495) (xy 238.379 -23.368)
			)
		)
		(polygon
			(pts
				(xy 238.0742 -23.8506) (xy 237.871 -23.8506) (xy 237.871 -24.0538) (xy 238.0742 -24.0538)
			)
		)
		(polygon
			(pts
				(xy 237.49 -23.8506) (xy 237.2868 -23.8506) (xy 237.2868 -24.0538) (xy 237.49 -24.0538)
			)
		)
		(polygon
			(pts
				(xy 236.9312 -23.8506) (xy 236.728 -23.8506) (xy 236.728 -24.0538) (xy 236.9312 -24.0538)
			)
		)
		(polygon
			(pts
				(xy 236.347 -23.8506) (xy 236.1438 -23.8506) (xy 236.1438 -24.0538) (xy 236.347 -24.0538)
			)
		)
		(polygon
			(pts
				(xy 235.7882 -23.8506) (xy 235.585 -23.8506) (xy 235.585 -24.0538) (xy 235.7882 -24.0538)
			)
		)
		(polygon
			(pts
				(xy 235.204 -23.8506) (xy 235.0008 -23.8506) (xy 235.0008 -24.0538) (xy 235.204 -24.0538)
			)
		)
		(polygon
			(pts
				(xy 234.6452 -23.8506) (xy 234.442 -23.8506) (xy 234.442 -24.0538) (xy 234.6452 -24.0538)
			)
		)
		(polygon
			(pts
				(xy 234.061 -23.8506) (xy 233.8578 -23.8506) (xy 233.8578 -24.0538) (xy 234.061 -24.0538)
			)
		)
		(polygon
			(pts
				(xy 233.5022 -23.8506) (xy 233.299 -23.8506) (xy 233.299 -24.0538) (xy 233.5022 -24.0538)
			)
		)
		(polygon
			(pts
				(xy 232.918 -23.8506) (xy 232.7148 -23.8506) (xy 232.7148 -24.0538) (xy 232.918 -24.0538)
			)
		)
		(polygon
			(pts
				(xy 232.3592 -23.8506) (xy 232.156 -23.8506) (xy 232.156 -24.0538) (xy 232.3592 -24.0538)
			)
		)
		(polygon
			(pts
				(xy 231.775 -23.8506) (xy 231.5718 -23.8506) (xy 231.5718 -24.0538) (xy 231.775 -24.0538)
			)
		)
		(polygon
			(pts
				(xy 231.2162 -23.8506) (xy 231.013 -23.8506) (xy 231.013 -24.0538) (xy 231.2162 -24.0538)
			)
		)
		(polygon
			(pts
				(xy 230.632 -23.8506) (xy 230.4288 -23.8506) (xy 230.4288 -24.0538) (xy 230.632 -24.0538)
			)
		)
		(polygon
			(pts
				(xy 230.0732 -23.8506) (xy 229.87 -23.8506) (xy 229.87 -24.0538) (xy 230.0732 -24.0538)
			)
		)
		(polygon
			(pts
				(xy 229.489 -23.8506) (xy 229.2858 -23.8506) (xy 229.2858 -24.0538) (xy 229.489 -24.0538)
			)
		)
		(polygon
			(pts
				(xy 228.9302 -23.8506) (xy 228.727 -23.8506) (xy 228.727 -24.0538) (xy 228.9302 -24.0538)
			)
		)
		(polygon
			(pts
				(xy 228.346 -23.8506) (xy 228.1428 -23.8506) (xy 228.1428 -24.0538) (xy 228.346 -24.0538)
			)
		)
		(polygon
			(pts
				(xy 227.7872 -23.8506) (xy 227.584 -23.8506) (xy 227.584 -24.0538) (xy 227.7872 -24.0538)
			)
		)
		(polygon
			(pts
				(xy 227.203 -23.8506) (xy 226.9998 -23.8506) (xy 226.9998 -24.0538) (xy 227.203 -24.0538)
			)
		)
		(polygon
			(pts
				(xy 226.6442 -23.8506) (xy 226.441 -23.8506) (xy 226.441 -24.0538) (xy 226.6442 -24.0538)
			)
		)
		(polygon
			(pts
				(xy 226.06 -23.8506) (xy 225.8568 -23.8506) (xy 225.8568 -24.0538) (xy 226.06 -24.0538)
			)
		)
		(polygon
			(pts
				(xy 225.5012 -23.8506) (xy 225.298 -23.8506) (xy 225.298 -24.0538) (xy 225.5012 -24.0538)
			)
		)
		(polygon
			(pts
				(xy 224.917 -23.8506) (xy 224.7138 -23.8506) (xy 224.7138 -24.0538) (xy 224.917 -24.0538)
			)
		)
		(polygon
			(pts
				(xy 224.3582 -23.8506) (xy 224.155 -23.8506) (xy 224.155 -24.0538) (xy 224.3582 -24.0538)
			)
		)
		(polygon
			(pts
				(xy 223.774 -23.8506) (xy 223.5708 -23.8506) (xy 223.5708 -24.0538) (xy 223.774 -24.0538)
			)
		)
		(polygon
			(pts
				(xy 223.2152 -23.8506) (xy 223.012 -23.8506) (xy 223.012 -24.0538) (xy 223.2152 -24.0538)
			)
		)
		(polygon
			(pts
				(xy 222.631 -23.8506) (xy 222.4278 -23.8506) (xy 222.4278 -24.0538) (xy 222.631 -24.0538)
			)
		)
	)
	(zone
		(layer "F.Cu")
		(hatch none 0.5)
		(connect_pads
			(clearance 0)
		)
		(min_thickness 0.25)
		(keepout
			(tracks not_allowed)
			(vias allowed)
			(pads allowed)
			(copperpour not_allowed)
			(footprints allowed)
		)
		(placement
			(enabled no)
			(sheetname "")
		)
		(fill
			(thermal_gap 0.5)
			(thermal_bridge_width 0.5)
			(island_removal_mode 0)
		)
		(polygon
			(pts
				(arc
					(start 288.85388 -20.387818)
					(mid 289.341953 -19.810669)
					(end 289.012376 -20.490942)
				)
				(arc
					(start 289.012376 -20.490942)
					(mid 288.740338 -20.561876)
					(end 288.479992 -20.45589)
				)
				(xy 288.478214 -20.45589) (xy 288.330132 -20.307808) (xy 288.25952 -20.439634) (xy 288.514028 -20.694142)
				(arc
					(start 288.514028 -20.695412)
					(mid 288.653517 -20.959967)
					(end 288.652458 -21.259038)
				)
				(arc
					(start 288.652458 -21.259038)
					(mid 288.185493 -21.854744)
					(end 288.505138 -21.168614)
				)
				(arc
					(start 288.505138 -21.168614)
					(mid 288.485239 -20.961696)
					(end 288.375598 -20.785074)
				)
				(xy 288.179764 -20.588986)
				(arc
					(start 287.837626 -21.227542)
					(mid 288.08576 -22.078995)
					(end 288.935414 -21.82495)
				)
				(arc
					(start 289.685222 -20.424902)
					(mid 289.42919 -19.579082)
					(end 288.58337 -19.835114)
				)
				(xy 288.410142 -20.15871)
				(arc
					(start 288.569146 -20.31746)
					(mid 288.701718 -20.392287)
					(end 288.85388 -20.387818)
				)
			)
		)
	)
	(zone
		(layer "F.Cu")
		(hatch none 0.5)
		(connect_pads
			(clearance 0)
		)
		(min_thickness 0.25)
		(keepout
			(tracks not_allowed)
			(vias allowed)
			(pads allowed)
			(copperpour not_allowed)
			(footprints allowed)
		)
		(placement
			(enabled no)
			(sheetname "")
		)
		(fill
			(thermal_gap 0.5)
			(thermal_bridge_width 0.5)
			(island_removal_mode 0)
		)
		(polygon
			(pts
				(arc
					(start 107.693968 -210.385914)
					(mid 107.183174 -210.896327)
					(end 107.693714 -211.406994)
				)
				(xy 107.860338 -211.406994)
				(arc
					(start 107.860338 -211.323428)
					(mid 107.84676 -211.226888)
					(end 107.807252 -211.137754)
				)
				(arc
					(start 107.807252 -211.137754)
					(mid 107.511389 -210.701841)
					(end 107.92714 -211.025486)
				)
				(arc
					(start 107.92714 -211.025486)
					(mid 107.992354 -211.150549)
					(end 108.02112 -211.28863)
				)
				(xy 108.02239 -211.2899) (xy 108.02239 -211.406994) (xy 108.165138 -211.406994) (xy 108.165138 -211.306156)
				(arc
					(start 108.166408 -211.304886)
					(mid 108.198404 -211.156292)
					(end 108.271818 -211.0232)
				)
				(arc
					(start 108.271818 -211.0232)
					(mid 108.691061 -210.704289)
					(end 108.389928 -211.136484)
				)
				(arc
					(start 108.389928 -211.136484)
					(mid 108.34323 -211.233351)
					(end 108.32719 -211.339684)
				)
				(xy 108.32719 -211.406994)
				(arc
					(start 108.506514 -211.406994)
					(mid 109.017054 -210.896454)
					(end 108.506514 -210.385914)
				)
			)
		)
	)
	(zone
		(net "P12V_PCIE")
		(layer "F.Cu")
		(hatch none 0.5)
		(connect_pads
			(clearance 0.5)
		)
		(min_thickness 0.25)
		(fill yes
			(thermal_gap 0.5)
			(thermal_bridge_width 0.5)
			(island_removal_mode 0)
		)
		(polygon
			(pts
				(xy 25.6286 -207.899) (xy 25.4254 -208.1022) (xy 25.4254 -211.455) (xy 27.559 -213.5886) (xy 27.559 -220.091)
				(xy 28.702 -221.234)
				(arc
					(start 28.702 -221.35084)
					(mid 29.113387 -221.805242)
					(end 29.262324 -222.39986)
				)
				(xy 29.262324 -223.9772) (xy 33.528 -223.9772) (xy 33.528 -214.0204) (xy 32.4104 -212.9028) (xy 32.4104 -209.677)
				(xy 30.6324 -207.899)
			)
		)
		(polygon
			(pts
				(xy 32.0548 -212.4202) (xy 31.8516 -212.4202) (xy 31.8516 -212.6234) (xy 32.0548 -212.6234)
			)
		)
		(polygon
			(pts
				(xy 32.0548 -211.5566) (xy 31.8516 -211.5566) (xy 31.8516 -211.7598) (xy 32.0548 -211.7598)
			)
		)
	)
	(zone
		(layer "F.Cu")
		(hatch none 0.5)
		(connect_pads
			(clearance 0)
		)
		(min_thickness 0.25)
		(keepout
			(tracks not_allowed)
			(vias allowed)
			(pads allowed)
			(copperpour not_allowed)
			(footprints allowed)
		)
		(placement
			(enabled no)
			(sheetname "")
		)
		(fill
			(thermal_gap 0.5)
			(thermal_bridge_width 0.5)
			(island_removal_mode 0)
		)
		(polygon
			(pts
				(arc
					(start 154.493976 -210.385914)
					(mid 153.983182 -210.896327)
					(end 154.493722 -211.406994)
				)
				(xy 154.660346 -211.406994)
				(arc
					(start 154.660346 -211.2772)
					(mid 154.648255 -211.202193)
					(end 154.613356 -211.134706)
				)
				(arc
					(start 154.613356 -211.134706)
					(mid 154.307022 -210.70614)
					(end 154.729688 -211.02066)
				)
				(arc
					(start 154.729688 -211.02066)
					(mid 154.792197 -211.124447)
					(end 154.820874 -211.242148)
				)
				(xy 154.822398 -211.243672) (xy 154.822398 -211.406994) (xy 154.965146 -211.406994) (xy 154.965146 -211.218272)
				(arc
					(start 154.967178 -211.21624)
					(mid 154.988692 -211.132961)
					(end 155.032202 -211.05876)
				)
				(xy 155.032202 -211.055966)
				(arc
					(start 155.06954 -211.018628)
					(mid 155.495705 -210.708423)
					(end 155.184094 -211.133436)
				)
				(arc
					(start 155.170632 -211.146898)
					(mid 155.138522 -211.19491)
					(end 155.127198 -211.251546)
				)
				(xy 155.127198 -211.406994)
				(arc
					(start 155.306522 -211.406994)
					(mid 155.817062 -210.896454)
					(end 155.306522 -210.385914)
				)
			)
		)
	)
	(zone
		(net "P3V3_STBY")
		(layer "F.Cu")
		(hatch none 0.5)
		(connect_pads
			(clearance 0.5)
		)
		(min_thickness 0.25)
		(fill yes
			(thermal_gap 0.5)
			(thermal_bridge_width 0.5)
			(island_removal_mode 0)
		)
		(polygon
			(pts
				(xy 89.417906 -39.89959) (xy 89.154 -40.163496) (xy 89.154 -46.482) (xy 89.408 -46.736) (xy 92.329 -46.736)
				(xy 92.583 -46.482) (xy 92.583 -41.148) (xy 92.575888 -41.140888) (xy 92.575888 -40.411908) (xy 92.06357 -39.89959)
			)
		)
	)
	(zone
		(layer "F.Cu")
		(hatch none 0.5)
		(connect_pads
			(clearance 0)
		)
		(min_thickness 0.25)
		(keepout
			(tracks not_allowed)
			(vias allowed)
			(pads allowed)
			(copperpour not_allowed)
			(footprints allowed)
		)
		(placement
			(enabled no)
			(sheetname "")
		)
		(fill
			(thermal_gap 0.5)
			(thermal_bridge_width 0.5)
			(island_removal_mode 0)
		)
		(polygon
			(pts
				(arc
					(start 92.493846 -210.385914)
					(mid 91.983052 -210.896327)
					(end 92.493592 -211.406994)
				)
				(xy 92.660216 -211.406994)
				(arc
					(start 92.660216 -211.307934)
					(mid 92.647183 -211.218665)
					(end 92.609416 -211.136738)
				)
				(arc
					(start 92.609416 -211.136738)
					(mid 92.309032 -210.703473)
					(end 92.728034 -211.023454)
				)
				(arc
					(start 92.728034 -211.023454)
					(mid 92.792368 -211.14192)
					(end 92.820998 -211.273644)
				)
				(xy 92.822268 -211.274914) (xy 92.822268 -211.406994) (xy 92.965016 -211.406994) (xy 92.965016 -211.275168)
				(arc
					(start 92.966286 -211.273644)
					(mid 92.99844 -211.138915)
					(end 93.070172 -211.020406)
				)
				(arc
					(start 93.070172 -211.020406)
					(mid 93.492959 -210.705924)
					(end 93.18625 -211.134452)
				)
				(arc
					(start 93.18625 -211.134452)
					(mid 93.142288 -211.216686)
					(end 93.127068 -211.308696)
				)
				(xy 93.127068 -211.406994)
				(arc
					(start 93.306392 -211.406994)
					(mid 93.816932 -210.896454)
					(end 93.306392 -210.385914)
				)
			)
		)
	)
	(zone
		(layer "F.Cu")
		(hatch none 0.5)
		(connect_pads
			(clearance 0)
		)
		(min_thickness 0.25)
		(keepout
			(tracks not_allowed)
			(vias allowed)
			(pads allowed)
			(copperpour not_allowed)
			(footprints allowed)
		)
		(placement
			(enabled no)
			(sheetname "")
		)
		(fill
			(thermal_gap 0.5)
			(thermal_bridge_width 0.5)
			(island_removal_mode 0)
		)
		(polygon
			(pts
				(arc
					(start 104.494076 -210.385914)
					(mid 103.983282 -210.896327)
					(end 104.493822 -211.406994)
				)
				(xy 104.660446 -211.406994)
				(arc
					(start 104.660446 -211.293456)
					(mid 104.647973 -211.210907)
					(end 104.611678 -211.135722)
				)
				(arc
					(start 104.611678 -211.135722)
					(mid 104.308258 -210.704868)
					(end 104.72928 -211.02193)
				)
				(arc
					(start 104.72928 -211.02193)
					(mid 104.792606 -211.13342)
					(end 104.821228 -211.258404)
				)
				(xy 104.822498 -211.259928) (xy 104.822498 -211.406994) (xy 104.965246 -211.406994) (xy 104.965246 -211.259928)
				(arc
					(start 104.966516 -211.258658)
					(mid 104.995458 -211.137206)
					(end 105.059988 -211.030312)
				)
				(xy 105.059988 -211.02828)
				(arc
					(start 105.06964 -211.018628)
					(mid 105.494951 -210.707724)
					(end 105.184956 -211.13369)
				)
				(arc
					(start 105.184956 -211.13369)
					(mid 105.142147 -211.207049)
					(end 105.127298 -211.290662)
				)
				(xy 105.127298 -211.290916) (xy 105.127298 -211.293456) (xy 105.127298 -211.406994)
				(arc
					(start 105.306622 -211.406994)
					(mid 105.817162 -210.896454)
					(end 105.306622 -210.385914)
				)
			)
		)
	)
	(zone
		(layer "F.Cu")
		(hatch none 0.5)
		(connect_pads
			(clearance 0)
		)
		(min_thickness 0.25)
		(keepout
			(tracks not_allowed)
			(vias allowed)
			(pads allowed)
			(copperpour not_allowed)
			(footprints allowed)
		)
		(placement
			(enabled no)
			(sheetname "")
		)
		(fill
			(thermal_gap 0.5)
			(thermal_bridge_width 0.5)
			(island_removal_mode 0)
		)
		(polygon
			(pts
				(arc
					(start 148.5011 -34.49066)
					(mid 147.99056 -35.0012)
					(end 148.5011 -35.51174)
				)
				(arc
					(start 149.313646 -35.51174)
					(mid 149.82444 -35.001327)
					(end 149.3139 -34.49066)
				)
				(xy 149.140926 -34.49066)
				(arc
					(start 149.140926 -34.593784)
					(mid 149.154738 -34.682361)
					(end 149.195028 -34.76244)
				)
				(arc
					(start 149.195028 -34.76244)
					(mid 149.500071 -35.19219)
					(end 149.078188 -34.876232)
				)
				(arc
					(start 149.078188 -34.876232)
					(mid 149.010462 -34.759808)
					(end 148.980144 -34.628582)
				)
				(xy 148.978874 -34.627312) (xy 148.978874 -34.49066) (xy 148.836126 -34.49066) (xy 148.836126 -34.627312)
				(arc
					(start 148.834856 -34.628582)
					(mid 148.804489 -34.759788)
					(end 148.736812 -34.876232)
				)
				(arc
					(start 148.736812 -34.876232)
					(mid 148.314876 -35.192244)
					(end 148.619972 -34.76244)
				)
				(arc
					(start 148.619972 -34.76244)
					(mid 148.660233 -34.682352)
					(end 148.674074 -34.593784)
				)
				(xy 148.674074 -34.49066)
			)
		)
	)
	(zone
		(layer "F.Cu")
		(hatch none 0.5)
		(connect_pads
			(clearance 0)
		)
		(min_thickness 0.25)
		(keepout
			(tracks not_allowed)
			(vias allowed)
			(pads allowed)
			(copperpour not_allowed)
			(footprints allowed)
		)
		(placement
			(enabled no)
			(sheetname "")
		)
		(fill
			(thermal_gap 0.5)
			(thermal_bridge_width 0.5)
			(island_removal_mode 0)
		)
		(polygon
			(pts
				(arc
					(start 86.093808 -210.385914)
					(mid 85.583014 -210.896327)
					(end 86.093554 -211.406994)
				)
				(xy 86.260178 -211.406994)
				(arc
					(start 86.260178 -211.3026)
					(mid 86.247394 -211.215736)
					(end 86.21014 -211.13623)
				)
				(arc
					(start 86.21014 -211.13623)
					(mid 85.909004 -210.704032)
					(end 86.32825 -211.022946)
				)
				(arc
					(start 86.32825 -211.022946)
					(mid 86.392249 -211.138693)
					(end 86.42096 -211.267802)
				)
				(xy 86.42223 -211.269072) (xy 86.42223 -211.406994) (xy 86.564978 -211.406994) (xy 86.564978 -211.279994)
				(arc
					(start 86.566248 -211.278724)
					(mid 86.598296 -211.141609)
					(end 86.670388 -211.02066)
				)
				(arc
					(start 86.670388 -211.02066)
					(mid 87.093094 -210.706099)
					(end 86.78672 -211.134706)
				)
				(arc
					(start 86.78672 -211.134706)
					(mid 86.742349 -211.219136)
					(end 86.72703 -211.313268)
				)
				(xy 86.72703 -211.406994)
				(arc
					(start 86.906354 -211.406994)
					(mid 87.416894 -210.896454)
					(end 86.906354 -210.385914)
				)
			)
		)
	)
	(zone
		(net "GND")
		(layer "F.Cu")
		(hatch none 0.5)
		(connect_pads
			(clearance 0.5)
		)
		(min_thickness 0.25)
		(fill yes
			(thermal_gap 0.5)
			(thermal_bridge_width 0.5)
			(island_removal_mode 0)
		)
		(polygon
			(pts
				(xy 210.82 -2.159) (xy 210.693 -2.286) (xy 208.661 -2.286) (xy 208.534 -2.413) (xy 208.534 -3.81)
				(xy 208.661 -3.937) (xy 215.233758 -3.937) (xy 215.233758 -2.873756) (xy 215.234774 -2.87274) (xy 215.230456 -2.868422)
				(xy 215.230456 -2.708656) (xy 214.6808 -2.159)
			)
		)
		(polygon
			(pts
				(xy 214.770208 -3.2512) (xy 214.567008 -3.2512) (xy 214.567008 -3.4544) (xy 214.770208 -3.4544)
			)
		)
		(polygon
			(pts
				(xy 214.313008 -3.2512) (xy 214.109808 -3.2512) (xy 214.109808 -3.4544) (xy 214.313008 -3.4544)
			)
		)
		(polygon
			(pts
				(xy 213.754208 -3.2512) (xy 213.551008 -3.2512) (xy 213.551008 -3.4544) (xy 213.754208 -3.4544)
			)
		)
		(polygon
			(pts
				(xy 213.297008 -3.2512) (xy 213.093808 -3.2512) (xy 213.093808 -3.4544) (xy 213.297008 -3.4544)
			)
		)
		(polygon
			(pts
				(xy 212.738208 -3.2512) (xy 212.535008 -3.2512) (xy 212.535008 -3.4544) (xy 212.738208 -3.4544)
			)
		)
		(polygon
			(pts
				(xy 212.281008 -3.2512) (xy 212.077808 -3.2512) (xy 212.077808 -3.4544) (xy 212.281008 -3.4544)
			)
		)
		(polygon
			(pts
				(xy 211.722208 -3.2512) (xy 211.519008 -3.2512) (xy 211.519008 -3.4544) (xy 211.722208 -3.4544)
			)
		)
		(polygon
			(pts
				(xy 211.265008 -3.2512) (xy 211.061808 -3.2512) (xy 211.061808 -3.4544) (xy 211.265008 -3.4544)
			)
		)
		(polygon
			(pts
				(xy 210.706208 -3.2512) (xy 210.503008 -3.2512) (xy 210.503008 -3.4544) (xy 210.706208 -3.4544)
			)
		)
		(polygon
			(pts
				(xy 210.249008 -3.2512) (xy 210.045808 -3.2512) (xy 210.045808 -3.4544) (xy 210.249008 -3.4544)
			)
		)
		(polygon
			(pts
				(xy 209.690208 -3.2512) (xy 209.487008 -3.2512) (xy 209.487008 -3.4544) (xy 209.690208 -3.4544)
			)
		)
		(polygon
			(pts
				(xy 209.233008 -3.2512) (xy 209.029808 -3.2512) (xy 209.029808 -3.4544) (xy 209.233008 -3.4544)
			)
		)
	)
	(zone
		(layer "F.Cu")
		(hatch none 0.5)
		(connect_pads
			(clearance 0)
		)
		(min_thickness 0.25)
		(keepout
			(tracks allowed)
			(vias allowed)
			(pads allowed)
			(copperpour allowed)
			(footprints not_allowed)
		)
		(placement
			(enabled no)
			(sheetname "")
		)
		(fill
			(thermal_gap 0.5)
			(thermal_bridge_width 0.5)
			(island_removal_mode 0)
		)
		(polygon
			(pts
				(xy 3.999992 -77.0001) (xy 3.999992 -213.499954)
				(arc
					(start 0.999998 -213.499954)
					(mid 0.292893 -213.207061)
					(end 0 -212.499956)
				)
				(xy 0 -77.0001)
			)
		)
	)
	(zone
		(layer "F.Cu")
		(hatch none 0.5)
		(connect_pads
			(clearance 0)
		)
		(min_thickness 0.25)
		(keepout
			(tracks not_allowed)
			(vias allowed)
			(pads allowed)
			(copperpour not_allowed)
			(footprints allowed)
		)
		(placement
			(enabled no)
			(sheetname "")
		)
		(fill
			(thermal_gap 0.5)
			(thermal_bridge_width 0.5)
			(island_removal_mode 0)
		)
		(polygon
			(pts
				(arc
					(start 18.852388 -81.39684)
					(mid 18.341594 -81.907253)
					(end 18.852134 -82.41792)
				)
				(arc
					(start 19.664934 -82.41792)
					(mid 20.175474 -81.90738)
					(end 19.664934 -81.39684)
				)
				(xy 19.46402 -81.39684) (xy 19.46402 -81.591912)
				(arc
					(start 19.542506 -81.670398)
					(mid 19.853546 -82.095992)
					(end 19.427952 -81.784952)
				)
				(xy 19.301968 -81.658968) (xy 19.301968 -81.39684) (xy 19.122136 -81.39684) (xy 19.15922 -81.433924)
				(xy 19.15922 -81.714848)
				(arc
					(start 19.089116 -81.784952)
					(mid 18.663522 -82.095992)
					(end 18.974562 -81.670398)
				)
				(xy 18.997168 -81.647792) (xy 18.997168 -81.50098) (xy 18.893028 -81.39684)
			)
		)
	)
	(zone
		(layer "F.Cu")
		(hatch none 0.5)
		(connect_pads
			(clearance 0)
		)
		(min_thickness 0.25)
		(keepout
			(tracks not_allowed)
			(vias allowed)
			(pads allowed)
			(copperpour not_allowed)
			(footprints allowed)
		)
		(placement
			(enabled no)
			(sheetname "")
		)
		(fill
			(thermal_gap 0.5)
			(thermal_bridge_width 0.5)
			(island_removal_mode 0)
		)
		(polygon
			(pts
				(arc
					(start 316.49416 -210.385914)
					(mid 315.983366 -210.896327)
					(end 316.493906 -211.406994)
				)
				(xy 316.66053 -211.406994)
				(arc
					(start 316.66053 -211.306156)
					(mid 316.647628 -211.217634)
					(end 316.609984 -211.136484)
				)
				(arc
					(start 316.609984 -211.136484)
					(mid 316.3096 -210.703219)
					(end 316.728602 -211.0232)
				)
				(arc
					(start 316.728602 -211.0232)
					(mid 316.792719 -211.140644)
					(end 316.821312 -211.271358)
				)
				(xy 316.822582 -211.272628) (xy 316.822582 -211.406994) (xy 316.96533 -211.406994) (xy 316.96533 -211.272628)
				(arc
					(start 316.9666 -211.271104)
					(mid 316.998787 -211.137453)
					(end 317.070486 -211.020152)
				)
				(arc
					(start 317.070486 -211.020152)
					(mid 317.493924 -210.706585)
					(end 317.18631 -211.134452)
				)
				(arc
					(start 317.18631 -211.134452)
					(mid 317.142529 -211.21539)
					(end 317.127382 -211.306156)
				)
				(xy 317.127382 -211.406994)
				(arc
					(start 317.306706 -211.406994)
					(mid 317.817246 -210.896454)
					(end 317.306706 -210.385914)
				)
			)
		)
	)
	(zone
		(net "GND")
		(layer "F.Cu")
		(hatch none 0.5)
		(connect_pads
			(clearance 0.5)
		)
		(min_thickness 0.25)
		(fill yes
			(thermal_gap 0.5)
			(thermal_bridge_width 0.5)
			(island_removal_mode 0)
		)
		(polygon
			(pts
				(xy 152.162002 -56.796432) (xy 151.654002 -57.304432) (xy 151.654002 -65.432432) (xy 152.416002 -66.194432)
				(xy 152.416002 -67.845432) (xy 152.136602 -68.124832) (xy 152.136602 -76.896976) (xy 152.688798 -77.449172)
				(xy 174.181262 -77.449172) (xy 174.303944 -77.326744) (xy 174.303944 -71.918576) (xy 174.0154 -71.630032)
				(xy 157.597602 -71.630032) (xy 154.829002 -68.861432) (xy 154.829002 -57.177432) (xy 154.448002 -56.796432)
			)
		)
		(polygon
			(pts
				(xy 152.974802 -65.762632) (xy 152.771602 -65.762632) (xy 152.771602 -65.965832) (xy 152.974802 -65.965832)
			)
		)
		(polygon
			(pts
				(xy 152.974802 -64.899032) (xy 152.771602 -64.899032) (xy 152.771602 -65.102232) (xy 152.974802 -65.102232)
			)
		)
		(polygon
			(pts
				(xy 152.111202 -64.899032) (xy 151.908002 -64.899032) (xy 151.908002 -65.102232) (xy 152.111202 -65.102232)
			)
		)
	)
	(zone
		(layer "F.Cu")
		(hatch none 0.5)
		(connect_pads
			(clearance 0)
		)
		(min_thickness 0.25)
		(keepout
			(tracks not_allowed)
			(vias allowed)
			(pads allowed)
			(copperpour not_allowed)
			(footprints allowed)
		)
		(placement
			(enabled no)
			(sheetname "")
		)
		(fill
			(thermal_gap 0.5)
			(thermal_bridge_width 0.5)
			(island_removal_mode 0)
		)
		(polygon
			(pts
				(arc
					(start 311.685178 -20.425156)
					(mid 311.429502 -19.579255)
					(end 310.58358 -19.835114)
				)
				(xy 310.581548 -19.833844) (xy 309.831486 -21.233892)
				(arc
					(start 309.833518 -21.235162)
					(mid 310.08955 -22.080982)
					(end 310.93537 -21.82495)
				)
				(xy 310.937402 -21.82622) (xy 311.014364 -21.68271)
				(arc
					(start 311.014364 -21.506688)
					(mid 311.006776 -21.438846)
					(end 310.984392 -21.374354)
				)
				(arc
					(start 310.85028 -21.187918)
					(mid 310.769524 -21.109541)
					(end 310.666638 -21.063966)
				)
				(arc
					(start 310.666384 -21.063966)
					(mid 310.590828 -21.069386)
					(end 310.533034 -21.118322)
				)
				(xy 310.507126 -21.16074)
				(arc
					(start 310.502808 -21.167852)
					(mid 310.351456 -21.909578)
					(end 310.331358 -21.152866)
				)
				(arc
					(start 310.331358 -21.152866)
					(mid 310.341196 -21.12868)
					(end 310.35244 -21.105114)
				)
				(xy 310.351932 -21.103336) (xy 310.36895 -21.07565) (xy 310.369458 -21.074888) (xy 310.412892 -21.00453)
				(arc
					(start 310.41594 -21.003768)
					(mid 310.546436 -20.91298)
					(end 310.705246 -20.906486)
				)
				(arc
					(start 310.705246 -20.906486)
					(mid 310.845609 -20.965713)
					(end 310.960516 -21.065744)
				)
				(xy 310.962294 -21.065998) (xy 310.981852 -21.093176) (xy 310.981852 -21.09343) (xy 311.139586 -21.312632)
				(arc
					(start 311.138316 -21.321268)
					(mid 311.153348 -21.361057)
					(end 311.164732 -21.40204)
				)
				(xy 311.254902 -21.233638)
				(arc
					(start 311.254648 -21.232876)
					(mid 311.18202 -21.071489)
					(end 311.122822 -20.904708)
				)
				(arc
					(start 311.122822 -20.904454)
					(mid 311.109088 -20.857867)
					(end 311.096406 -20.810982)
				)
				(arc
					(start 311.096406 -20.810982)
					(mid 311.063435 -20.65668)
					(end 311.044082 -20.500086)
				)
				(arc
					(start 311.044082 -20.500086)
					(mid 311.14463 -19.749044)
					(end 311.20715 -20.50415)
				)
				(arc
					(start 311.20715 -20.50415)
					(mid 311.22478 -20.638198)
					(end 311.253378 -20.770342)
				)
				(arc
					(start 311.253378 -20.770342)
					(mid 311.265084 -20.813786)
					(end 311.277762 -20.856956)
				)
				(arc
					(start 311.277762 -20.856956)
					(mid 311.311595 -20.956979)
					(end 311.35066 -21.055076)
				)
				(xy 311.687464 -20.426426) (xy 311.68721 -20.426172)
			)
		)
	)
	(zone
		(layer "F.Cu")
		(hatch none 0.5)
		(connect_pads
			(clearance 0)
		)
		(min_thickness 0.25)
		(keepout
			(tracks allowed)
			(vias allowed)
			(pads allowed)
			(copperpour allowed)
			(footprints not_allowed)
		)
		(placement
			(enabled no)
			(sheetname "")
		)
		(fill
			(thermal_gap 0.5)
			(thermal_bridge_width 0.5)
			(island_removal_mode 0)
		)
		(polygon
			(pts
				(xy 256.141982 -158.999936) (xy 229.142036 -158.999936)
				(arc
					(start 229.142036 -213.499954)
					(mid 232.677563 -212.035491)
					(end 234.142026 -208.499964)
				)
				(arc
					(start 234.142026 -165.269926)
					(mid 234.514 -164.3719)
					(end 235.412026 -163.999926)
				)
				(arc
					(start 249.871992 -163.999926)
					(mid 250.770018 -164.3719)
					(end 251.141992 -165.269926)
				)
				(arc
					(start 251.141992 -208.499964)
					(mid 252.606455 -212.035491)
					(end 256.141982 -213.499954)
				)
			)
		)
	)
	(zone
		(layer "F.Cu")
		(hatch none 0.5)
		(connect_pads
			(clearance 0)
		)
		(min_thickness 0.25)
		(keepout
			(tracks not_allowed)
			(vias allowed)
			(pads allowed)
			(copperpour not_allowed)
			(footprints allowed)
		)
		(placement
			(enabled no)
			(sheetname "")
		)
		(fill
			(thermal_gap 0.5)
			(thermal_bridge_width 0.5)
			(island_removal_mode 0)
		)
		(polygon
			(pts
				(arc
					(start 169.685462 -24.224996)
					(mid 169.42943 -23.379176)
					(end 168.58361 -23.635208)
				)
				(xy 168.581578 -23.633938) (xy 167.831516 -25.033732) (xy 167.83177 -25.033986)
				(arc
					(start 167.833802 -25.035002)
					(mid 168.089478 -25.880903)
					(end 168.9354 -25.625044)
				)
				(xy 168.937432 -25.626314) (xy 169.059606 -25.398476)
				(arc
					(start 169.045382 -25.371298)
					(mid 169.006762 -25.29355)
					(end 168.970706 -25.21458)
				)
				(arc
					(start 168.970706 -25.21458)
					(mid 168.899085 -25.165514)
					(end 168.816782 -25.137872)
				)
				(arc
					(start 168.816782 -25.137872)
					(mid 168.769045 -25.142584)
					(end 168.722548 -25.154382)
				)
				(arc
					(start 168.722548 -25.154382)
					(mid 168.093654 -25.576558)
					(end 168.612312 -25.024588)
				)
				(arc
					(start 168.612312 -25.024588)
					(mid 168.715068 -24.988164)
					(end 168.823386 -24.97582)
				)
				(arc
					(start 168.836594 -24.976836)
					(mid 168.976689 -25.023066)
					(end 169.095928 -25.109932)
				)
				(arc
					(start 169.095928 -25.109932)
					(mid 169.10566 -25.121815)
					(end 169.112946 -25.135332)
				)
				(xy 169.153078 -25.223978) (xy 169.238168 -25.064974) (xy 169.205148 -24.98217) (xy 169.185844 -24.929846)
				(xy 169.18559 -24.929084)
				(arc
					(start 169.170858 -24.884126)
					(mid 169.096253 -24.597359)
					(end 169.058336 -24.303482)
				)
				(arc
					(start 169.058336 -24.303482)
					(mid 169.128951 -23.549114)
					(end 169.220642 -24.301196)
				)
				(arc
					(start 169.220642 -24.301196)
					(mid 169.256116 -24.570761)
					(end 169.324782 -24.833834)
				)
				(xy 169.325036 -24.834596) (xy 169.338752 -24.876252) (xy 169.339006 -24.87676) (xy 169.687494 -24.226266)
			)
		)
	)
	(zone
		(net "P3V3_STBY")
		(layer "F.Cu")
		(hatch none 0.5)
		(connect_pads
			(clearance 0.5)
		)
		(min_thickness 0.25)
		(fill yes
			(thermal_gap 0.5)
			(thermal_bridge_width 0.5)
			(island_removal_mode 0)
		)
		(polygon
			(pts
				(xy 321.335146 -33.561274) (xy 321.033648 -33.862772) (xy 321.033648 -36.255198) (xy 321.766946 -36.988496)
				(xy 321.766946 -37.550598) (xy 321.02552 -38.292024) (xy 320.388234 -38.292024) (xy 320.385948 -38.289992)
				(xy 319.795398 -38.880542) (xy 316.776608 -38.880542) (xy 316.495684 -38.599618) (xy 316.495684 -36.627308)
				(xy 316.050168 -36.181792) (xy 315.185044 -36.181792) (xy 314.651136 -36.715446) (xy 310.131714 -36.715446)
				(xy 308.952138 -35.53587) (xy 308.952138 -34.770314) (xy 309.342282 -34.38017) (xy 309.342282 -33.715452)
				(xy 309.255668 -33.628838) (xy 309.237634 -33.646872) (xy 307.763926 -33.646872) (xy 307.724048 -33.68675)
				(xy 307.724048 -34.468308) (xy 307.245258 -34.947098) (xy 307.245258 -39.978838) (xy 306.907692 -40.316404)
				(xy 302.161702 -40.316404) (xy 298.598844 -36.753546) (xy 298.398946 -36.753546) (xy 298.0944 -36.449)
				(xy 298.0944 -35.941) (xy 298.598844 -35.436556) (xy 298.598844 -33.7312) (xy 298.497244 -33.6296)
				(xy 296.545 -33.6296) (xy 296.4434 -33.7312) (xy 296.4434 -35.511994) (xy 296.207434 -35.74796)
				(xy 296.207434 -39.747952) (xy 298.980352 -42.52087) (xy 313.084972 -42.52087) (xy 314.67171 -40.934132)
				(xy 322.144644 -40.934132) (xy 324.059804 -39.018972) (xy 324.059804 -37.19068) (xy 322.617084 -35.74796)
				(xy 322.617084 -35.309048) (xy 322.952872 -34.97326) (xy 322.952872 -33.773618) (xy 322.740528 -33.561274)
			)
		)
		(polygon
			(pts
				(xy 315.997336 -37.062918) (xy 315.794136 -37.062918) (xy 315.794136 -37.266118) (xy 315.997336 -37.266118)
			)
		)
		(polygon
			(pts
				(xy 315.997336 -36.504118) (xy 315.794136 -36.504118) (xy 315.794136 -36.707318) (xy 315.997336 -36.707318)
			)
		)
		(polygon
			(pts
				(xy 321.944238 -34.117788) (xy 321.741038 -34.117788) (xy 321.741038 -34.320988) (xy 321.944238 -34.320988)
			)
		)
		(polygon
			(pts
				(xy 321.385438 -34.117788) (xy 321.182238 -34.117788) (xy 321.182238 -34.320988) (xy 321.385438 -34.320988)
			)
		)
		(polygon
			(pts
				(xy 322.40347 -34.117534) (xy 322.20027 -34.117534) (xy 322.20027 -34.320734) (xy 322.40347 -34.320734)
			)
		)
		(polygon
			(pts
				(xy 297.425618 -34.106104) (xy 297.222418 -34.106104) (xy 297.222418 -34.309304) (xy 297.425618 -34.309304)
			)
		)
		(polygon
			(pts
				(xy 296.866818 -34.106104) (xy 296.663618 -34.106104) (xy 296.663618 -34.309304) (xy 296.866818 -34.309304)
			)
		)
		(polygon
			(pts
				(xy 298.444666 -34.104834) (xy 298.241466 -34.104834) (xy 298.241466 -34.308034) (xy 298.444666 -34.308034)
			)
		)
		(polygon
			(pts
				(xy 297.885866 -34.104834) (xy 297.682666 -34.104834) (xy 297.682666 -34.308034) (xy 297.885866 -34.308034)
			)
		)
		(polygon
			(pts
				(xy 308.877208 -34.09061) (xy 308.674008 -34.09061) (xy 308.674008 -34.29381) (xy 308.877208 -34.29381)
			)
		)
		(polygon
			(pts
				(xy 308.418992 -34.09061) (xy 308.215792 -34.09061) (xy 308.215792 -34.29381) (xy 308.418992 -34.29381)
			)
		)
	)
	(zone
		(net "Q3203_G")
		(layer "F.Cu")
		(hatch none 0.5)
		(connect_pads
			(clearance 0.5)
		)
		(min_thickness 0.25)
		(fill yes
			(thermal_gap 0.5)
			(thermal_bridge_width 0.5)
			(island_removal_mode 0)
		)
		(polygon
			(pts
				(xy 258.572 -17.399) (xy 258.445 -17.526) (xy 258.445 -19.177) (xy 258.953 -19.685) (xy 262.382 -19.685)
				(xy 262.763 -19.304) (xy 262.763 -17.526) (xy 262.636 -17.399)
			)
		)
		(polygon
			(pts
				(xy 261.7724 -18.3134) (xy 261.5692 -18.3134) (xy 261.5692 -18.5166) (xy 261.7724 -18.5166)
			)
		)
		(polygon
			(pts
				(xy 260.9088 -18.3134) (xy 260.7056 -18.3134) (xy 260.7056 -18.5166) (xy 260.9088 -18.5166)
			)
		)
		(polygon
			(pts
				(xy 262.2042 -17.8816) (xy 262.001 -17.8816) (xy 262.001 -18.0848) (xy 262.2042 -18.0848)
			)
		)
	)
	(zone
		(net "GND")
		(layer "F.Cu")
		(hatch none 0.5)
		(connect_pads
			(clearance 0.5)
		)
		(min_thickness 0.25)
		(fill yes
			(thermal_gap 0.5)
			(thermal_bridge_width 0.5)
			(island_removal_mode 0)
		)
		(polygon
			(pts
				(xy 29.083 -43.561) (xy 28.702 -43.942) (xy 28.702 -55.3974) (xy 29.3116 -56.007) (xy 30.5816 -56.007)
				(xy 31.115 -55.4736) (xy 31.115 -43.688) (xy 30.988 -43.561)
			)
		)
		(polygon
			(pts
				(xy 30.7086 -48.2092) (xy 30.5054 -48.2092) (xy 30.5054 -48.4124) (xy 30.7086 -48.4124)
			)
		)
		(polygon
			(pts
				(xy 30.7086 -47.5996) (xy 30.5054 -47.5996) (xy 30.5054 -47.8028) (xy 30.7086 -47.8028)
			)
		)
		(polygon
			(pts
				(xy 30.7086 -47.1932) (xy 30.5054 -47.1932) (xy 30.5054 -47.3964) (xy 30.7086 -47.3964)
			)
		)
		(polygon
			(pts
				(xy 30.7086 -46.5836) (xy 30.5054 -46.5836) (xy 30.5054 -46.7868) (xy 30.7086 -46.7868)
			)
		)
		(polygon
			(pts
				(xy 30.7086 -46.1772) (xy 30.5054 -46.1772) (xy 30.5054 -46.3804) (xy 30.7086 -46.3804)
			)
		)
		(polygon
			(pts
				(xy 30.7086 -45.5676) (xy 30.5054 -45.5676) (xy 30.5054 -45.7708) (xy 30.7086 -45.7708)
			)
		)
		(polygon
			(pts
				(xy 30.7086 -45.1612) (xy 30.5054 -45.1612) (xy 30.5054 -45.3644) (xy 30.7086 -45.3644)
			)
		)
		(polygon
			(pts
				(xy 30.7086 -44.5516) (xy 30.5054 -44.5516) (xy 30.5054 -44.7548) (xy 30.7086 -44.7548)
			)
		)
		(polygon
			(pts
				(xy 30.7086 -44.1452) (xy 30.5054 -44.1452) (xy 30.5054 -44.3484) (xy 30.7086 -44.3484)
			)
		)
	)
	(zone
		(net "GND")
		(layer "F.Cu")
		(hatch none 0.5)
		(connect_pads
			(clearance 0.5)
		)
		(min_thickness 0.25)
		(fill yes
			(thermal_gap 0.5)
			(thermal_bridge_width 0.5)
			(island_removal_mode 0)
		)
		(polygon
			(pts
				(xy 38.1254 -59.8424) (xy 37.7571 -60.2107) (xy 37.7571 -66.3067) (xy 37.8714 -66.421) (xy 40.513 -66.421)
				(xy 41.1734 -65.7606) (xy 41.1734 -62.3062) (xy 40.513 -61.6458) (xy 40.513 -60.0964) (xy 40.259 -59.8424)
			)
		)
	)
	(zone
		(layer "F.Cu")
		(hatch none 0.5)
		(connect_pads
			(clearance 0)
		)
		(min_thickness 0.25)
		(keepout
			(tracks not_allowed)
			(vias allowed)
			(pads allowed)
			(copperpour not_allowed)
			(footprints allowed)
		)
		(placement
			(enabled no)
			(sheetname "")
		)
		(fill
			(thermal_gap 0.5)
			(thermal_bridge_width 0.5)
			(island_removal_mode 0)
		)
		(polygon
			(pts
				(arc
					(start 264.49401 -210.385914)
					(mid 263.983216 -210.896327)
					(end 264.493756 -211.406994)
				)
				(xy 264.66038 -211.406994)
				(arc
					(start 264.66038 -211.2772)
					(mid 264.648289 -211.202193)
					(end 264.61339 -211.134706)
				)
				(arc
					(start 264.61339 -211.134706)
					(mid 264.307056 -210.70614)
					(end 264.729722 -211.02066)
				)
				(arc
					(start 264.729722 -211.02066)
					(mid 264.792231 -211.124447)
					(end 264.820908 -211.242148)
				)
				(xy 264.822432 -211.243672) (xy 264.822432 -211.406994) (xy 264.96518 -211.406994) (xy 264.96518 -211.243418)
				(arc
					(start 264.966958 -211.24164)
					(mid 264.993398 -211.134823)
					(end 265.050016 -211.040472)
				)
				(xy 265.050016 -211.038186)
				(arc
					(start 265.069574 -211.018628)
					(mid 265.495739 -210.708423)
					(end 265.184128 -211.133436)
				)
				(arc
					(start 265.184128 -211.133436)
					(mid 265.142072 -211.199516)
					(end 265.127232 -211.276438)
				)
				(xy 265.127232 -211.406994)
				(arc
					(start 265.306556 -211.406994)
					(mid 265.817096 -210.896454)
					(end 265.306556 -210.385914)
				)
			)
		)
	)
	(zone
		(layer "F.Cu")
		(hatch none 0.5)
		(connect_pads
			(clearance 0)
		)
		(min_thickness 0.25)
		(keepout
			(tracks not_allowed)
			(vias allowed)
			(pads allowed)
			(copperpour not_allowed)
			(footprints allowed)
		)
		(placement
			(enabled no)
			(sheetname "")
		)
		(fill
			(thermal_gap 0.5)
			(thermal_bridge_width 0.5)
			(island_removal_mode 0)
		)
		(polygon
			(pts
				(arc
					(start 200.093834 -210.385914)
					(mid 199.58304 -210.896327)
					(end 200.09358 -211.406994)
				)
				(xy 200.260204 -211.406994)
				(arc
					(start 200.260204 -211.304886)
					(mid 200.247276 -211.216974)
					(end 200.209658 -211.136484)
				)
				(arc
					(start 200.209658 -211.136484)
					(mid 199.909274 -210.703219)
					(end 200.328276 -211.0232)
				)
				(arc
					(start 200.328276 -211.0232)
					(mid 200.392325 -211.139998)
					(end 200.420986 -211.270088)
				)
				(xy 200.422256 -211.271358) (xy 200.422256 -211.406994) (xy 200.565004 -211.406994) (xy 200.565004 -211.271104)
				(arc
					(start 200.566528 -211.26958)
					(mid 200.598517 -211.137132)
					(end 200.669652 -211.020914)
				)
				(arc
					(start 200.669652 -211.019136)
					(mid 201.093989 -210.706997)
					(end 200.785984 -211.134452)
				)
				(arc
					(start 200.785984 -211.134452)
					(mid 200.742232 -211.214596)
					(end 200.727056 -211.304632)
				)
				(xy 200.727056 -211.406994)
				(arc
					(start 200.90638 -211.406994)
					(mid 201.41692 -210.896454)
					(end 200.90638 -210.385914)
				)
			)
		)
	)
	(zone
		(layer "F.Cu")
		(hatch none 0.5)
		(connect_pads
			(clearance 0)
		)
		(min_thickness 0.25)
		(keepout
			(tracks not_allowed)
			(vias allowed)
			(pads allowed)
			(copperpour not_allowed)
			(footprints allowed)
		)
		(placement
			(enabled no)
			(sheetname "")
		)
		(fill
			(thermal_gap 0.5)
			(thermal_bridge_width 0.5)
			(island_removal_mode 0)
		)
		(polygon
			(pts
				(arc
					(start 51.693826 -210.385914)
					(mid 51.183032 -210.896327)
					(end 51.693572 -211.406994)
				)
				(xy 51.860196 -211.406994)
				(arc
					(start 51.860196 -211.3026)
					(mid 51.847412 -211.215736)
					(end 51.810158 -211.13623)
				)
				(arc
					(start 51.810158 -211.13623)
					(mid 51.509022 -210.704032)
					(end 51.928268 -211.022946)
				)
				(arc
					(start 51.928268 -211.022946)
					(mid 51.992267 -211.138693)
					(end 52.020978 -211.267802)
				)
				(xy 52.022248 -211.269072) (xy 52.022248 -211.406994) (xy 52.164996 -211.406994) (xy 52.164996 -211.27974)
				(arc
					(start 52.166266 -211.27847)
					(mid 52.198366 -211.141618)
					(end 52.270406 -211.020914)
				)
				(arc
					(start 52.270406 -211.020914)
					(mid 52.693074 -210.705896)
					(end 52.386738 -211.13496)
				)
				(arc
					(start 52.386738 -211.13496)
					(mid 52.342368 -211.219256)
					(end 52.327048 -211.313268)
				)
				(xy 52.327048 -211.406994)
				(arc
					(start 52.506372 -211.406994)
					(mid 53.016912 -210.896454)
					(end 52.506372 -210.385914)
				)
			)
		)
	)
	(zone
		(net "GND")
		(layer "F.Cu")
		(hatch none 0.5)
		(connect_pads
			(clearance 0.5)
		)
		(min_thickness 0.25)
		(fill yes
			(thermal_gap 0.5)
			(thermal_bridge_width 0.5)
			(island_removal_mode 0)
		)
		(polygon
			(pts
				(xy 189.417198 -48.842168) (xy 189.290198 -48.969168) (xy 189.290198 -50.874168) (xy 189.544198 -51.128168)
				(xy 191.830198 -51.128168) (xy 191.957198 -51.001168) (xy 191.957198 -49.096168) (xy 191.703198 -48.842168)
			)
		)
	)
	(zone
		(net "P0V9")
		(layer "F.Cu")
		(hatch none 0.5)
		(connect_pads
			(clearance 0.5)
		)
		(min_thickness 0.25)
		(fill yes
			(thermal_gap 0.5)
			(thermal_bridge_width 0.5)
			(island_removal_mode 0)
		)
		(polygon
			(pts
				(xy 165.751002 -59.463432) (xy 165.243002 -59.971432) (xy 165.243002 -70.512432) (xy 165.624002 -70.893432)
				(xy 177.7238 -70.893432) (xy 177.9524 -70.664832) (xy 177.9524 -61.547756) (xy 177.7238 -61.319156)
				(xy 170.400726 -61.319156) (xy 168.545002 -59.463432)
			)
		)
	)
	(zone
		(layer "F.Cu")
		(hatch none 0.5)
		(connect_pads
			(clearance 0)
		)
		(min_thickness 0.25)
		(keepout
			(tracks allowed)
			(vias allowed)
			(pads allowed)
			(copperpour allowed)
			(footprints allowed)
		)
		(placement
			(enabled no)
			(sheetname "")
		)
		(fill
			(thermal_gap 0.5)
			(thermal_bridge_width 0.5)
			(island_removal_mode 0)
		)
		(polygon
			(pts
				(xy 32.74568 -98.986086) (xy 32.916622 -99.157028) (xy 35.11931 -99.157028) (xy 35.34156 -98.934778)
				(xy 35.34156 -97.854262) (xy 34.90595 -97.418652) (xy 32.803084 -97.418652) (xy 32.74568 -97.476056)
			)
		)
	)
	(zone
		(layer "F.Cu")
		(hatch none 0.5)
		(connect_pads
			(clearance 0)
		)
		(min_thickness 0.25)
		(keepout
			(tracks allowed)
			(vias allowed)
			(pads allowed)
			(copperpour allowed)
			(footprints allowed)
		)
		(placement
			(enabled no)
			(sheetname "")
		)
		(fill
			(thermal_gap 0.5)
			(thermal_bridge_width 0.5)
			(island_removal_mode 0)
		)
		(polygon
			(pts
				(xy 37.41293 -47.038768) (xy 37.41293 -42.644568) (xy 37.4142 -42.644568) (xy 37.4142 -42.1386)
				(xy 37.592 -41.9608) (xy 39.0144 -41.9608) (xy 39.26713 -42.21353) (xy 39.26713 -42.644568) (xy 39.26713 -47.038768)
			)
		)
	)
	(zone
		(layer "F.Cu")
		(hatch none 0.5)
		(connect_pads
			(clearance 0)
		)
		(min_thickness 0.25)
		(keepout
			(tracks not_allowed)
			(vias allowed)
			(pads allowed)
			(copperpour not_allowed)
			(footprints allowed)
		)
		(placement
			(enabled no)
			(sheetname "")
		)
		(fill
			(thermal_gap 0.5)
			(thermal_bridge_width 0.5)
			(island_removal_mode 0)
		)
		(polygon
			(pts
				(arc
					(start 14.68374 -67.638676)
					(mid 14.173327 -67.127882)
					(end 13.66266 -67.638422)
				)
				(xy 13.66266 -67.809364) (xy 13.91031 -67.809364)
				(arc
					(start 13.944346 -67.775328)
					(mid 14.36177 -67.449852)
					(end 14.036294 -67.867276)
				)
				(xy 13.964158 -67.939412) (xy 13.66266 -67.939412) (xy 13.66266 -68.17741) (xy 13.68806 -68.152264)
				(xy 13.96619 -68.152264)
				(arc
					(start 14.036294 -68.222368)
					(mid 14.36177 -68.639792)
					(end 13.944346 -68.314316)
				)
				(xy 13.912342 -68.282312) (xy 13.741908 -68.282312) (xy 13.704824 -68.319396)
				(arc
					(start 13.704824 -68.654676)
					(mid 14.2771 -68.951196)
					(end 14.68374 -68.451222)
				)
			)
		)
	)
	(zone
		(layer "F.Cu")
		(hatch none 0.5)
		(connect_pads
			(clearance 0)
		)
		(min_thickness 0.25)
		(keepout
			(tracks not_allowed)
			(vias allowed)
			(pads allowed)
			(copperpour not_allowed)
			(footprints allowed)
		)
		(placement
			(enabled no)
			(sheetname "")
		)
		(fill
			(thermal_gap 0.5)
			(thermal_bridge_width 0.5)
			(island_removal_mode 0)
		)
		(polygon
			(pts
				(arc
					(start 13.563854 -53.319172)
					(mid 13.05306 -53.829585)
					(end 13.5636 -54.340252)
				)
				(arc
					(start 14.3764 -54.340252)
					(mid 14.88694 -53.829712)
					(end 14.3764 -53.319172)
				)
				(xy 14.206728 -53.319172) (xy 14.206728 -53.567838)
				(arc
					(start 14.239494 -53.600858)
					(mid 14.56497 -54.018282)
					(end 14.147546 -53.692806)
				)
				(xy 14.076426 -53.621686) (xy 14.076172 -53.621686) (xy 14.076172 -53.319172) (xy 13.863828 -53.319172)
				(xy 13.863828 -53.621686) (xy 13.863574 -53.621686)
				(arc
					(start 13.792454 -53.692806)
					(mid 13.37503 -54.018282)
					(end 13.700506 -53.600858)
				)
				(xy 13.733272 -53.567838) (xy 13.733272 -53.319172)
			)
		)
	)
	(zone
		(layer "F.Cu")
		(hatch none 0.5)
		(connect_pads
			(clearance 0)
		)
		(min_thickness 0.25)
		(keepout
			(tracks not_allowed)
			(vias allowed)
			(pads allowed)
			(copperpour not_allowed)
			(footprints allowed)
		)
		(placement
			(enabled no)
			(sheetname "")
		)
		(fill
			(thermal_gap 0.5)
			(thermal_bridge_width 0.5)
			(island_removal_mode 0)
		)
		(polygon
			(pts
				(arc
					(start 274.09394 -210.385914)
					(mid 273.583146 -210.896327)
					(end 274.093686 -211.406994)
				)
				(xy 274.26031 -211.406994)
				(arc
					(start 274.26031 -211.2772)
					(mid 274.248219 -211.202193)
					(end 274.21332 -211.134706)
				)
				(arc
					(start 274.21332 -211.134706)
					(mid 273.906986 -210.70614)
					(end 274.329652 -211.02066)
				)
				(arc
					(start 274.329652 -211.02066)
					(mid 274.392161 -211.124447)
					(end 274.420838 -211.242148)
				)
				(xy 274.422362 -211.243672) (xy 274.422362 -211.406994) (xy 274.56511 -211.406994) (xy 274.56511 -211.243418)
				(arc
					(start 274.566888 -211.24164)
					(mid 274.593328 -211.134823)
					(end 274.649946 -211.040472)
				)
				(xy 274.649946 -211.038186)
				(arc
					(start 274.669504 -211.018628)
					(mid 275.095669 -210.708423)
					(end 274.784058 -211.133436)
				)
				(arc
					(start 274.784058 -211.133436)
					(mid 274.742002 -211.199516)
					(end 274.727162 -211.276438)
				)
				(xy 274.727162 -211.406994)
				(arc
					(start 274.906486 -211.406994)
					(mid 275.417026 -210.896454)
					(end 274.906486 -210.385914)
				)
			)
		)
	)
	(zone
		(layer "F.Cu")
		(hatch none 0.5)
		(connect_pads
			(clearance 0)
		)
		(min_thickness 0.25)
		(keepout
			(tracks allowed)
			(vias allowed)
			(pads allowed)
			(copperpour allowed)
			(footprints not_allowed)
		)
		(placement
			(enabled no)
			(sheetname "")
		)
		(fill
			(thermal_gap 0.5)
			(thermal_bridge_width 0.5)
			(island_removal_mode 0)
		)
		(polygon
			(pts
				(arc
					(start 89.950036 -10.199878)
					(mid 90.096445 -9.846415)
					(end 90.449908 -9.700006)
				)
				(arc
					(start 92.95003 -9.700006)
					(mid 93.303493 -9.846415)
					(end 93.449902 -10.199878)
				)
				(arc
					(start 93.449902 -18.200116)
					(mid 93.303493 -18.553579)
					(end 92.95003 -18.699988)
				)
				(arc
					(start 90.449908 -18.699988)
					(mid 90.096445 -18.553579)
					(end 89.950036 -18.200116)
				)
			)
		)
	)
	(zone
		(layer "F.Cu")
		(hatch none 0.5)
		(connect_pads
			(clearance 0)
		)
		(min_thickness 0.25)
		(keepout
			(tracks not_allowed)
			(vias allowed)
			(pads allowed)
			(copperpour not_allowed)
			(footprints allowed)
		)
		(placement
			(enabled no)
			(sheetname "")
		)
		(fill
			(thermal_gap 0.5)
			(thermal_bridge_width 0.5)
			(island_removal_mode 0)
		)
		(polygon
			(pts
				(arc
					(start 54.893718 -210.385914)
					(mid 54.383178 -210.896454)
					(end 54.893718 -211.406994)
				)
				(xy 55.060342 -211.406994)
				(arc
					(start 55.060342 -211.282788)
					(mid 55.048174 -211.205154)
					(end 55.012844 -211.13496)
				)
				(arc
					(start 55.012844 -211.13496)
					(mid 54.70772 -210.705289)
					(end 55.129684 -211.020914)
				)
				(arc
					(start 55.129684 -211.020914)
					(mid 55.192324 -211.127471)
					(end 55.22087 -211.247736)
				)
				(xy 55.222394 -211.24926) (xy 55.222394 -211.406994) (xy 55.365142 -211.406994) (xy 55.365142 -211.24926)
				(arc
					(start 55.366666 -211.247482)
					(mid 55.394522 -211.135444)
					(end 55.454296 -211.036662)
				)
				(xy 55.454296 -211.034376)
				(arc
					(start 55.469536 -211.018882)
					(mid 55.894929 -210.707641)
					(end 55.584598 -211.13369)
				)
				(arc
					(start 55.584598 -211.13369)
					(mid 55.542089 -211.202922)
					(end 55.527194 -211.282788)
				)
				(xy 55.527194 -211.406994)
				(arc
					(start 55.706264 -211.406994)
					(mid 56.217058 -210.896581)
					(end 55.706518 -210.385914)
				)
			)
		)
	)
	(zone
		(net "GND")
		(layer "F.Cu")
		(hatch none 0.5)
		(connect_pads
			(clearance 0.5)
		)
		(min_thickness 0.25)
		(fill yes
			(thermal_gap 0.5)
			(thermal_bridge_width 0.5)
			(island_removal_mode 0)
		)
		(polygon
			(pts
				(xy 234.188 -13.335) (xy 233.807 -13.716) (xy 233.807 -15.494) (xy 234.315 -16.002) (xy 236.347 -16.002)
				(xy 236.601 -15.748) (xy 236.601 -13.716) (xy 236.22 -13.335)
			)
		)
	)
	(zone
		(layer "F.Cu")
		(hatch none 0.5)
		(connect_pads
			(clearance 0)
		)
		(min_thickness 0.25)
		(keepout
			(tracks allowed)
			(vias allowed)
			(pads allowed)
			(copperpour allowed)
			(footprints not_allowed)
		)
		(placement
			(enabled no)
			(sheetname "")
		)
		(fill
			(thermal_gap 0.5)
			(thermal_bridge_width 0.5)
			(island_removal_mode 0)
		)
		(polygon
			(pts
				(arc
					(start 8.10006 -203.499974)
					(mid 9.99998 -201.600054)
					(end 11.8999 -203.499974)
				)
				(arc
					(start 11.8999 -203.499974)
					(mid 9.99998 -205.399894)
					(end 8.10006 -203.499974)
				)
			)
		)
	)
	(zone
		(layer "F.Cu")
		(hatch none 0.5)
		(connect_pads
			(clearance 0)
		)
		(min_thickness 0.25)
		(keepout
			(tracks not_allowed)
			(vias allowed)
			(pads allowed)
			(copperpour not_allowed)
			(footprints allowed)
		)
		(placement
			(enabled no)
			(sheetname "")
		)
		(fill
			(thermal_gap 0.5)
			(thermal_bridge_width 0.5)
			(island_removal_mode 0)
		)
		(polygon
			(pts
				(arc
					(start 332.494128 -210.385914)
					(mid 331.983334 -210.896327)
					(end 332.493874 -211.406994)
				)
				(xy 332.660498 -211.406994)
				(arc
					(start 332.660498 -211.3026)
					(mid 332.647714 -211.215736)
					(end 332.61046 -211.13623)
				)
				(arc
					(start 332.61046 -211.13623)
					(mid 332.309324 -210.704032)
					(end 332.72857 -211.022946)
				)
				(arc
					(start 332.72857 -211.022946)
					(mid 332.792569 -211.138693)
					(end 332.82128 -211.267802)
				)
				(xy 332.82255 -211.269072) (xy 332.82255 -211.406994) (xy 332.965298 -211.406994) (xy 332.965298 -211.281518)
				(arc
					(start 332.966568 -211.280248)
					(mid 332.998704 -211.142503)
					(end 333.070962 -211.020914)
				)
				(arc
					(start 333.070962 -211.020914)
					(mid 333.493668 -210.706353)
					(end 333.187294 -211.13496)
				)
				(arc
					(start 333.187294 -211.13496)
					(mid 333.142731 -211.220151)
					(end 333.12735 -211.315046)
				)
				(xy 333.12735 -211.406994)
				(arc
					(start 333.306674 -211.406994)
					(mid 333.817214 -210.896454)
					(end 333.306674 -210.385914)
				)
			)
		)
	)
	(zone
		(layer "F.Cu")
		(hatch none 0.5)
		(connect_pads
			(clearance 0)
		)
		(min_thickness 0.25)
		(keepout
			(tracks not_allowed)
			(vias allowed)
			(pads allowed)
			(copperpour not_allowed)
			(footprints allowed)
		)
		(placement
			(enabled no)
			(sheetname "")
		)
		(fill
			(thermal_gap 0.5)
			(thermal_bridge_width 0.5)
			(island_removal_mode 0)
		)
		(polygon
			(pts
				(arc
					(start 310.425592 -34.5313)
					(mid 309.915052 -35.04184)
					(end 310.425592 -35.55238)
				)
				(arc
					(start 311.238138 -35.55238)
					(mid 311.748932 -35.041967)
					(end 311.238392 -34.5313)
				)
				(xy 311.078118 -34.5313)
				(arc
					(start 311.078118 -34.609786)
					(mid 311.091005 -34.707587)
					(end 311.128664 -34.798762)
				)
				(arc
					(start 311.128664 -34.798762)
					(mid 311.417889 -35.239091)
					(end 311.006744 -34.90976)
				)
				(arc
					(start 311.006744 -34.90976)
					(mid 310.944478 -34.783066)
					(end 310.917082 -34.644584)
				)
				(xy 310.916066 -34.643314) (xy 310.916066 -34.5313) (xy 310.773318 -34.5313) (xy 310.773318 -34.643314)
				(arc
					(start 310.772048 -34.644584)
					(mid 310.738438 -34.789918)
					(end 310.661812 -34.917888)
				)
				(arc
					(start 310.661812 -34.917888)
					(mid 310.238573 -35.232072)
					(end 310.54548 -34.803588)
				)
				(arc
					(start 310.54548 -34.803588)
					(mid 310.594345 -34.712241)
					(end 310.611266 -34.61004)
				)
				(xy 310.611266 -34.5313)
			)
		)
	)
	(zone
		(layer "F.Cu")
		(hatch none 0.5)
		(connect_pads
			(clearance 0)
		)
		(min_thickness 0.25)
		(keepout
			(tracks allowed)
			(vias allowed)
			(pads allowed)
			(copperpour allowed)
			(footprints not_allowed)
		)
		(placement
			(enabled no)
			(sheetname "")
		)
		(fill
			(thermal_gap 0.5)
			(thermal_bridge_width 0.5)
			(island_removal_mode 0)
		)
		(polygon
			(pts
				(xy 350.60001 -29.99994) (xy 331.749908 -29.99994)
				(arc
					(start 331.749908 0.999998)
					(mid 332.042801 0.292893)
					(end 332.749906 0)
				)
				(arc
					(start 354.600002 0)
					(mid 355.307107 -0.292893)
					(end 355.6 -0.999998)
				)
				(arc
					(start 355.6 -9.19988)
					(mid 355.453516 -9.553522)
					(end 355.099874 -9.700006)
				)
				(arc
					(start 354.750116 -9.700006)
					(mid 354.396563 -9.8464)
					(end 354.24999 -10.199878)
				)
				(arc
					(start 354.24999 -18.200116)
					(mid 354.396489 -18.553669)
					(end 354.750116 -18.699988)
				)
				(arc
					(start 355.099874 -18.699988)
					(mid 355.453516 -18.846472)
					(end 355.6 -19.200114)
				)
				(xy 355.6 -34.99993) (xy 350.60001 -34.99993)
			)
		)
	)
	(zone
		(net "DUT_AVD_PCIE")
		(layer "F.Cu")
		(hatch none 0.5)
		(connect_pads
			(clearance 0.5)
		)
		(min_thickness 0.25)
		(fill yes
			(thermal_gap 0.5)
			(thermal_bridge_width 0.5)
			(island_removal_mode 0)
		)
		(polygon
			(pts
				(xy 177.0126 -51.3588) (xy 176.7078 -51.6636) (xy 176.7078 -55.7784) (xy 177.4952 -56.5658) (xy 180.7972 -56.5658)
				(xy 181.3052 -56.0578) (xy 181.3052 -51.6128) (xy 181.0512 -51.3588)
			)
		)
	)
	(zone
		(layer "F.Cu")
		(hatch none 0.5)
		(connect_pads
			(clearance 0)
		)
		(min_thickness 0.25)
		(keepout
			(tracks not_allowed)
			(vias allowed)
			(pads allowed)
			(copperpour not_allowed)
			(footprints allowed)
		)
		(placement
			(enabled no)
			(sheetname "")
		)
		(fill
			(thermal_gap 0.5)
			(thermal_bridge_width 0.5)
			(island_removal_mode 0)
		)
		(polygon
			(pts
				(arc
					(start 322.893944 -210.385914)
					(mid 322.38315 -210.896327)
					(end 322.89369 -211.406994)
				)
				(xy 323.060314 -211.406994)
				(arc
					(start 323.060314 -211.2772)
					(mid 323.048223 -211.202193)
					(end 323.013324 -211.134706)
				)
				(arc
					(start 323.013324 -211.134706)
					(mid 322.70699 -210.70614)
					(end 323.129656 -211.02066)
				)
				(arc
					(start 323.129656 -211.02066)
					(mid 323.192165 -211.124447)
					(end 323.220842 -211.242148)
				)
				(xy 323.222366 -211.243672) (xy 323.222366 -211.406994) (xy 323.365114 -211.406994) (xy 323.365114 -211.254848)
				(arc
					(start 323.366638 -211.253324)
					(mid 323.395395 -211.135702)
					(end 323.458078 -211.03209)
				)
				(xy 323.458078 -211.030058)
				(arc
					(start 323.469508 -211.018628)
					(mid 323.895433 -210.707765)
					(end 323.58457 -211.13369)
				)
				(arc
					(start 323.58457 -211.13369)
					(mid 323.541955 -211.205744)
					(end 323.527166 -211.288122)
				)
				(xy 323.527166 -211.406994)
				(arc
					(start 323.70649 -211.406994)
					(mid 324.21703 -210.896454)
					(end 323.70649 -210.385914)
				)
			)
		)
	)
	(zone
		(net "GND")
		(layer "F.Cu")
		(hatch none 0.5)
		(connect_pads
			(clearance 0.5)
		)
		(min_thickness 0.25)
		(fill yes
			(thermal_gap 0.5)
			(thermal_bridge_width 0.5)
			(island_removal_mode 0)
		)
		(polygon
			(pts
				(xy 35.941 -128.27) (xy 35.814 -128.397) (xy 35.814 -132.588) (xy 35.941 -132.715) (xy 40.259 -132.715)
				(xy 40.386 -132.588) (xy 40.386 -128.397) (xy 40.259 -128.27)
			)
		)
	)
	(zone
		(layer "F.Cu")
		(hatch none 0.5)
		(connect_pads
			(clearance 0)
		)
		(min_thickness 0.25)
		(keepout
			(tracks not_allowed)
			(vias allowed)
			(pads allowed)
			(copperpour not_allowed)
			(footprints allowed)
		)
		(placement
			(enabled no)
			(sheetname "")
		)
		(fill
			(thermal_gap 0.5)
			(thermal_bridge_width 0.5)
			(island_removal_mode 0)
		)
		(polygon
			(pts
				(arc
					(start 52.399692 -47.366428)
					(mid 51.888898 -47.876841)
					(end 52.399438 -48.387508)
				)
				(arc
					(start 53.305964 -48.387508)
					(mid 53.816504 -47.876968)
					(end 53.305964 -47.366428)
				)
				(xy 53.086 -47.366428) (xy 53.086 -47.54245)
				(arc
					(start 53.183536 -47.639986)
					(mid 53.494576 -48.06558)
					(end 53.068982 -47.75454)
				)
				(xy 52.923948 -47.609506) (xy 52.923948 -47.366428) (xy 52.7812 -47.366428) (xy 52.7812 -47.60976)
				(arc
					(start 52.63642 -47.75454)
					(mid 52.210826 -48.06558)
					(end 52.521866 -47.639986)
				)
				(xy 52.619148 -47.542704) (xy 52.619148 -47.366428)
			)
		)
	)
	(zone
		(layer "F.Cu")
		(hatch none 0.5)
		(connect_pads
			(clearance 0)
		)
		(min_thickness 0.25)
		(keepout
			(tracks allowed)
			(vias allowed)
			(pads allowed)
			(copperpour allowed)
			(footprints not_allowed)
		)
		(placement
			(enabled no)
			(sheetname "")
		)
		(fill
			(thermal_gap 0.5)
			(thermal_bridge_width 0.5)
			(island_removal_mode 0)
		)
		(polygon
			(pts
				(arc
					(start 17.562068 -60.300108)
					(mid 13.812012 -64.050164)
					(end 10.061956 -60.300108)
				)
				(arc
					(start 10.061956 -60.300108)
					(mid 13.812012 -56.550052)
					(end 17.562068 -60.300108)
				)
			)
		)
	)
	(zone
		(layer "F.Cu")
		(hatch none 0.5)
		(connect_pads
			(clearance 0)
		)
		(min_thickness 0.25)
		(keepout
			(tracks not_allowed)
			(vias allowed)
			(pads allowed)
			(copperpour not_allowed)
			(footprints allowed)
		)
		(placement
			(enabled no)
			(sheetname "")
		)
		(fill
			(thermal_gap 0.5)
			(thermal_bridge_width 0.5)
			(island_removal_mode 0)
		)
		(polygon
			(pts
				(arc
					(start 320.012314 -13.614654)
					(mid 319.975774 -13.564184)
					(end 319.934082 -13.51788)
				)
				(xy 319.889632 -13.473176) (xy 319.888108 -13.471652) (xy 319.865756 -13.4493) (xy 319.865756 -13.446506)
				(xy 319.855088 -13.432028)
				(arc
					(start 319.854834 -13.431774)
					(mid 319.833614 -13.395634)
					(end 319.81775 -13.356844)
				)
				(arc
					(start 319.81775 -13.356336)
					(mid 319.810164 -13.3287)
					(end 319.805304 -13.300456)
				)
				(xy 319.803272 -13.298424) (xy 319.803272 -13.26642) (xy 319.803272 -13.264896)
				(arc
					(start 319.803272 -12.902438)
					(mid 319.884298 -12.148996)
					(end 319.965324 -12.902438)
				)
				(arc
					(start 319.965324 -13.266166)
					(mid 319.966967 -13.286473)
					(end 319.971674 -13.306298)
				)
				(arc
					(start 319.971674 -13.306298)
					(mid 319.978735 -13.323651)
					(end 319.988184 -13.339826)
				)
				(xy 320.002916 -13.357352) (xy 320.072512 -13.426948) (xy 320.072512 -13.427964) (xy 320.09715 -13.456412)
				(arc
					(start 320.435224 -12.824968)
					(mid 320.179192 -11.979148)
					(end 319.333372 -12.23518)
				)
				(arc
					(start 318.587628 -13.627608)
					(mid 318.835762 -14.479061)
					(end 319.685416 -14.225016)
				)
				(xy 319.801494 -14.008354)
				(arc
					(start 319.801494 -13.933678)
					(mid 319.77997 -13.825381)
					(end 319.71869 -13.733526)
				)
				(arc
					(start 319.494154 -13.50899)
					(mid 319.43696 -13.471704)
					(end 319.369948 -13.458698)
				)
				(arc
					(start 319.320164 -13.458698)
					(mid 319.284836 -13.465819)
					(end 319.254886 -13.485876)
				)
				(arc
					(start 319.254886 -13.485876)
					(mid 319.230464 -13.519153)
					(end 319.217294 -13.558266)
				)
				(arc
					(start 319.217294 -13.558266)
					(mid 319.134221 -14.31103)
					(end 319.05321 -13.558012)
				)
				(xy 319.05321 -13.547598)
				(arc
					(start 319.055242 -13.545312)
					(mid 319.083054 -13.451079)
					(end 319.140078 -13.371068)
				)
				(arc
					(start 319.140078 -13.371068)
					(mid 319.206255 -13.323442)
					(end 319.284096 -13.299186)
				)
				(xy 319.286636 -13.296646) (xy 319.403476 -13.296646)
				(arc
					(start 319.405254 -13.298424)
					(mid 319.500184 -13.322486)
					(end 319.584324 -13.372592)
				)
				(xy 319.586864 -13.372592) (xy 319.6082 -13.393928) (xy 319.61074 -13.396468) (xy 319.833244 -13.618718)
				(xy 319.833244 -13.618972) (xy 319.856866 -13.642594)
				(arc
					(start 319.856866 -13.644372)
					(mid 319.898874 -13.702469)
					(end 319.931034 -13.766546)
				)
			)
		)
	)
	(zone
		(layer "F.Cu")
		(hatch none 0.5)
		(connect_pads
			(clearance 0)
		)
		(min_thickness 0.25)
		(keepout
			(tracks not_allowed)
			(vias allowed)
			(pads allowed)
			(copperpour not_allowed)
			(footprints allowed)
		)
		(placement
			(enabled no)
			(sheetname "")
		)
		(fill
			(thermal_gap 0.5)
			(thermal_bridge_width 0.5)
			(island_removal_mode 0)
		)
		(polygon
			(pts
				(arc
					(start 313.504834 -25.033478)
					(mid 313.45367 -24.948669)
					(end 313.389518 -24.873204)
				)
				(arc
					(start 313.389518 -24.873204)
					(mid 313.333158 -24.79399)
					(end 313.305698 -24.700738)
				)
				(xy 313.303412 -24.698452)
				(arc
					(start 313.303412 -24.302466)
					(mid 313.384438 -23.549024)
					(end 313.465464 -24.302466)
				)
				(arc
					(start 313.465464 -24.664924)
					(mid 313.47562 -24.715512)
					(end 313.504326 -24.758396)
				)
				(arc
					(start 313.504326 -24.758396)
					(mid 313.551745 -24.810453)
					(end 313.594242 -24.8666)
				)
				(xy 313.937396 -24.226266)
				(arc
					(start 313.935364 -24.224996)
					(mid 313.679332 -23.379176)
					(end 312.833512 -23.635208)
				)
				(xy 312.83148 -23.633938) (xy 312.081418 -25.033732) (xy 312.081672 -25.033986)
				(arc
					(start 312.083704 -25.035002)
					(mid 312.33938 -25.880903)
					(end 313.185302 -25.625044)
				)
				(xy 313.187334 -25.626314) (xy 313.264296 -25.48255)
				(arc
					(start 313.264296 -25.306782)
					(mid 313.240741 -25.188833)
					(end 313.173872 -25.08885)
				)
				(arc
					(start 312.993786 -24.908764)
					(mid 312.964045 -24.8814)
					(end 312.932064 -24.856694)
				)
				(arc
					(start 312.932064 -24.856694)
					(mid 312.794383 -24.844303)
					(end 312.715402 -24.957786)
				)
				(arc
					(start 312.715402 -24.957786)
					(mid 312.6345 -25.711228)
					(end 312.553096 -24.957786)
				)
				(xy 312.55335 -24.954738) (xy 312.55335 -24.947626)
				(arc
					(start 312.553858 -24.947118)
					(mid 312.724661 -24.697983)
					(end 313.025536 -24.724106)
				)
				(arc
					(start 313.025536 -24.724106)
					(mid 313.056504 -24.747439)
					(end 313.085988 -24.77262)
				)
				(xy 313.087004 -24.77262) (xy 313.10834 -24.793956) (xy 313.11088 -24.796496) (xy 313.312302 -24.997918)
				(arc
					(start 313.312302 -24.999696)
					(mid 313.375874 -25.094651)
					(end 313.414664 -25.202134)
				)
			)
		)
	)
	(zone
		(layer "F.Cu")
		(hatch none 0.5)
		(connect_pads
			(clearance 0)
		)
		(min_thickness 0.25)
		(keepout
			(tracks allowed)
			(vias allowed)
			(pads allowed)
			(copperpour allowed)
			(footprints not_allowed)
		)
		(placement
			(enabled no)
			(sheetname "")
		)
		(fill
			(thermal_gap 0.5)
			(thermal_bridge_width 0.5)
			(island_removal_mode 0)
		)
		(polygon
			(pts
				(arc
					(start 10.061956 -60.300108)
					(mid 13.812012 -56.550052)
					(end 17.562068 -60.300108)
				)
				(arc
					(start 17.562068 -60.300108)
					(mid 13.812012 -64.050164)
					(end 10.061956 -60.300108)
				)
			)
		)
	)
	(zone
		(layer "F.Cu")
		(hatch none 0.5)
		(connect_pads
			(clearance 0)
		)
		(min_thickness 0.25)
		(keepout
			(tracks allowed)
			(vias allowed)
			(pads allowed)
			(copperpour allowed)
			(footprints not_allowed)
		)
		(placement
			(enabled no)
			(sheetname "")
		)
		(fill
			(thermal_gap 0.5)
			(thermal_bridge_width 0.5)
			(island_removal_mode 0)
		)
		(polygon
			(pts
				(arc
					(start 87.050118 -22.999954)
					(mid 85.450172 -24.5999)
					(end 83.849972 -22.999954)
				)
				(arc
					(start 83.849972 -22.999954)
					(mid 85.450172 -21.399754)
					(end 87.050118 -22.999954)
				)
			)
		)
	)
	(zone
		(net "GND")
		(layer "F.Cu")
		(hatch none 0.5)
		(connect_pads
			(clearance 0.5)
		)
		(min_thickness 0.25)
		(fill yes
			(thermal_gap 0.5)
			(thermal_bridge_width 0.5)
			(island_removal_mode 0)
		)
		(polygon
			(pts
				(xy 144.333722 -61.57595) (xy 143.32458 -62.585092) (xy 142.157704 -62.585092) (xy 141.494002 -63.248794)
				(xy 141.494002 -77.203808) (xy 141.968728 -77.678534) (xy 144.423892 -77.678534) (xy 144.542002 -77.560424)
				(xy 144.542002 -67.865498) (xy 145.39722 -67.01028) (xy 145.39722 -61.670946) (xy 145.302224 -61.57595)
			)
		)
	)
	(zone
		(layer "F.Cu")
		(hatch none 0.5)
		(connect_pads
			(clearance 0)
		)
		(min_thickness 0.25)
		(keepout
			(tracks not_allowed)
			(vias allowed)
			(pads allowed)
			(copperpour not_allowed)
			(footprints allowed)
		)
		(placement
			(enabled no)
			(sheetname "")
		)
		(fill
			(thermal_gap 0.5)
			(thermal_bridge_width 0.5)
			(island_removal_mode 0)
		)
		(polygon
			(pts
				(arc
					(start 285.498794 -33.051496)
					(mid 284.988254 -32.540956)
					(end 284.477714 -33.051496)
				)
				(arc
					(start 284.477714 -33.864042)
					(mid 284.988127 -34.374836)
					(end 285.498794 -33.864296)
				)
				(xy 285.498794 -33.659826)
				(arc
					(start 285.369 -33.659826)
					(mid 285.312094 -33.671239)
					(end 285.263844 -33.703514)
				)
				(arc
					(start 285.225236 -33.741868)
					(mid 284.799642 -34.052908)
					(end 285.110682 -33.627314)
				)
				(xy 285.172912 -33.565084)
				(arc
					(start 285.175706 -33.565084)
					(mid 285.249998 -33.52138)
					(end 285.33344 -33.499806)
				)
				(xy 285.335472 -33.497774) (xy 285.498794 -33.497774) (xy 285.498794 -33.355026) (xy 285.335472 -33.355026)
				(arc
					(start 285.334202 -33.353756)
					(mid 285.223143 -33.331495)
					(end 285.120842 -33.28289)
				)
				(arc
					(start 285.120842 -33.28289)
					(mid 284.79036 -32.87272)
					(end 285.23184 -33.159954)
				)
				(arc
					(start 285.23184 -33.159954)
					(mid 285.298456 -33.184634)
					(end 285.369 -33.192974)
				)
				(xy 285.498794 -33.192974)
			)
		)
	)
	(zone
		(layer "F.Cu")
		(hatch none 0.5)
		(connect_pads
			(clearance 0)
		)
		(min_thickness 0.25)
		(keepout
			(tracks not_allowed)
			(vias allowed)
			(pads allowed)
			(copperpour not_allowed)
			(footprints allowed)
		)
		(placement
			(enabled no)
			(sheetname "")
		)
		(fill
			(thermal_gap 0.5)
			(thermal_bridge_width 0.5)
			(island_removal_mode 0)
		)
		(polygon
			(pts
				(arc
					(start 160.894014 -210.385914)
					(mid 160.38322 -210.896327)
					(end 160.89376 -211.406994)
				)
				(xy 161.060384 -211.406994)
				(arc
					(start 161.060384 -211.2772)
					(mid 161.048293 -211.202193)
					(end 161.013394 -211.134706)
				)
				(arc
					(start 161.013394 -211.134706)
					(mid 160.70706 -210.70614)
					(end 161.129726 -211.02066)
				)
				(arc
					(start 161.129726 -211.02066)
					(mid 161.192235 -211.124447)
					(end 161.220912 -211.242148)
				)
				(xy 161.222436 -211.243672) (xy 161.222436 -211.406994) (xy 161.365184 -211.406994) (xy 161.365184 -211.243672)
				(arc
					(start 161.366962 -211.241894)
					(mid 161.393504 -211.134928)
					(end 161.450274 -211.040472)
				)
				(xy 161.450274 -211.038186)
				(arc
					(start 161.469578 -211.018882)
					(mid 161.894519 -210.707343)
					(end 161.584386 -211.133436)
				)
				(arc
					(start 161.584386 -211.133436)
					(mid 161.542027 -211.199841)
					(end 161.527236 -211.2772)
				)
				(xy 161.527236 -211.406994)
				(arc
					(start 161.70656 -211.406994)
					(mid 162.2171 -210.896454)
					(end 161.70656 -210.385914)
				)
			)
		)
	)
	(zone
		(layer "F.Cu")
		(hatch none 0.5)
		(connect_pads
			(clearance 0)
		)
		(min_thickness 0.25)
		(keepout
			(tracks allowed)
			(vias allowed)
			(pads allowed)
			(copperpour allowed)
			(footprints allowed)
		)
		(placement
			(enabled no)
			(sheetname "")
		)
		(fill
			(thermal_gap 0.5)
			(thermal_bridge_width 0.5)
			(island_removal_mode 0)
		)
		(polygon
			(pts
				(xy 211.836 -6.985) (xy 211.836 -8.255) (xy 210.947 -8.255) (xy 210.947 -6.985)
			)
		)
	)
	(zone
		(layer "F.Cu")
		(hatch none 0.5)
		(connect_pads
			(clearance 0)
		)
		(min_thickness 0.25)
		(keepout
			(tracks not_allowed)
			(vias allowed)
			(pads allowed)
			(copperpour not_allowed)
			(footprints allowed)
		)
		(placement
			(enabled no)
			(sheetname "")
		)
		(fill
			(thermal_gap 0.5)
			(thermal_bridge_width 0.5)
			(island_removal_mode 0)
		)
		(polygon
			(pts
				(arc
					(start 343.7001 -203.499974)
					(mid 345.60002 -201.600054)
					(end 347.49994 -203.499974)
				)
				(arc
					(start 347.49994 -203.499974)
					(mid 345.60002 -205.399894)
					(end 343.7001 -203.499974)
				)
			)
		)
	)
	(zone
		(layer "F.Cu")
		(hatch none 0.5)
		(connect_pads
			(clearance 0)
		)
		(min_thickness 0.25)
		(keepout
			(tracks not_allowed)
			(vias allowed)
			(pads allowed)
			(copperpour not_allowed)
			(footprints allowed)
		)
		(placement
			(enabled no)
			(sheetname "")
		)
		(fill
			(thermal_gap 0.5)
			(thermal_bridge_width 0.5)
			(island_removal_mode 0)
		)
		(polygon
			(pts
				(arc
					(start 289.685222 -24.224996)
					(mid 289.42919 -23.379176)
					(end 288.58337 -23.635208)
				)
				(arc
					(start 287.837626 -25.027636)
					(mid 288.08576 -25.879089)
					(end 288.935414 -25.625044)
				)
				(xy 288.969196 -25.562052) (xy 288.969196 -25.306528) (xy 288.968942 -25.306274)
				(arc
					(start 288.968942 -25.27046)
					(mid 288.959892 -25.158566)
					(end 288.933382 -25.04948)
				)
				(arc
					(start 288.933382 -25.04948)
					(mid 288.918276 -25.007949)
					(end 288.900616 -24.967438)
				)
				(xy 288.886138 -24.95296)
				(arc
					(start 288.886138 -24.93899)
					(mid 288.829837 -24.849616)
					(end 288.760916 -24.769572)
				)
				(arc
					(start 288.705798 -24.714708)
					(mid 288.666366 -24.688549)
					(end 288.619946 -24.679402)
				)
				(arc
					(start 288.483294 -24.679402)
					(mid 288.454994 -24.685013)
					(end 288.43097 -24.700992)
				)
				(arc
					(start 288.401252 -24.73071)
					(mid 288.375687 -24.769065)
					(end 288.366708 -24.814276)
				)
				(xy 288.366708 -24.906986)
				(arc
					(start 288.376868 -24.94915)
					(mid 288.47353 -25.700744)
					(end 288.219134 -24.986996)
				)
				(xy 288.212276 -24.957786) (xy 288.204656 -24.950166) (xy 288.204656 -24.92629) (xy 288.199068 -24.902922)
				(xy 288.204656 -24.893778) (xy 288.204656 -24.780748)
				(arc
					(start 288.206942 -24.778462)
					(mid 288.226026 -24.707049)
					(end 288.263076 -24.64308)
				)
				(xy 288.263076 -24.639778) (xy 288.286698 -24.616156) (xy 288.286698 -24.615902) (xy 288.316162 -24.586438)
				(xy 288.316416 -24.586438) (xy 288.340038 -24.562816)
				(arc
					(start 288.344102 -24.562816)
					(mid 288.392985 -24.535326)
					(end 288.446972 -24.520144)
				)
				(xy 288.449766 -24.51735) (xy 288.653474 -24.51735)
				(arc
					(start 288.65576 -24.519636)
					(mid 288.728557 -24.538961)
					(end 288.793682 -24.576786)
				)
				(xy 288.79673 -24.576786) (xy 288.819844 -24.599646) (xy 288.820606 -24.600408) (xy 288.899092 -24.678386)
				(arc
					(start 288.899092 -24.679402)
					(mid 288.972584 -24.770522)
					(end 289.033204 -24.870664)
				)
				(xy 289.04819 -24.88565)
				(arc
					(start 289.04819 -24.900636)
					(mid 289.069228 -24.949068)
					(end 289.087306 -24.99868)
				)
				(arc
					(start 289.087306 -24.99868)
					(mid 289.117268 -25.116931)
					(end 289.130486 -25.238202)
				)
				(xy 289.131248 -25.239218) (xy 289.131248 -25.259284)
				(arc
					(start 289.24758 -25.042114)
					(mid 289.236245 -24.997896)
					(end 289.222942 -24.95423)
				)
				(arc
					(start 289.222942 -24.95423)
					(mid 289.197668 -24.885928)
					(end 289.16757 -24.81961)
				)
				(arc
					(start 289.16757 -24.81961)
					(mid 289.12227 -24.715257)
					(end 289.088068 -24.606758)
				)
				(arc
					(start 289.088068 -24.606758)
					(mid 289.06442 -24.488195)
					(end 289.054032 -24.367744)
				)
				(xy 289.053524 -24.367236)
				(arc
					(start 289.053524 -24.302466)
					(mid 289.133519 -23.549132)
					(end 289.215576 -24.302212)
				)
				(arc
					(start 289.215576 -24.33447)
					(mid 289.222999 -24.451224)
					(end 289.24504 -24.566118)
				)
				(arc
					(start 289.24504 -24.566118)
					(mid 289.274208 -24.658569)
					(end 289.312858 -24.747474)
				)
				(arc
					(start 289.312858 -24.747474)
					(mid 289.334845 -24.79426)
					(end 289.354768 -24.841962)
				)
			)
		)
	)
	(zone
		(layer "F.Cu")
		(hatch none 0.5)
		(connect_pads
			(clearance 0)
		)
		(min_thickness 0.25)
		(keepout
			(tracks not_allowed)
			(vias allowed)
			(pads allowed)
			(copperpour not_allowed)
			(footprints allowed)
		)
		(placement
			(enabled no)
			(sheetname "")
		)
		(fill
			(thermal_gap 0.5)
			(thermal_bridge_width 0.5)
			(island_removal_mode 0)
		)
		(polygon
			(pts
				(arc
					(start 212.89391 -210.385914)
					(mid 212.383116 -210.896327)
					(end 212.893656 -211.406994)
				)
				(xy 213.06028 -211.406994)
				(arc
					(start 213.06028 -211.301076)
					(mid 213.047558 -211.214979)
					(end 213.010496 -211.13623)
				)
				(arc
					(start 213.010496 -211.13623)
					(mid 212.708823 -210.70415)
					(end 213.128606 -211.022692)
				)
				(arc
					(start 213.128606 -211.022692)
					(mid 213.192444 -211.137802)
					(end 213.221062 -211.266278)
				)
				(xy 213.222332 -211.267548) (xy 213.222332 -211.406994) (xy 213.36508 -211.406994) (xy 213.36508 -211.267548)
				(arc
					(start 213.366604 -211.266024)
					(mid 213.397909 -211.13687)
					(end 213.467188 -211.023454)
				)
				(xy 213.467188 -211.022692) (xy 213.467188 -211.021422)
				(arc
					(start 213.469474 -211.019136)
					(mid 213.893813 -210.706581)
					(end 213.585806 -211.134198)
				)
				(arc
					(start 213.585806 -211.134198)
					(mid 213.542242 -211.212638)
					(end 213.527132 -211.301076)
				)
				(xy 213.527132 -211.406994)
				(arc
					(start 213.706456 -211.406994)
					(mid 214.216996 -210.896454)
					(end 213.706456 -210.385914)
				)
			)
		)
	)
	(zone
		(net "GND")
		(layer "F.Cu")
		(hatch none 0.5)
		(connect_pads
			(clearance 0.5)
		)
		(min_thickness 0.25)
		(fill yes
			(thermal_gap 0.5)
			(thermal_bridge_width 0.5)
			(island_removal_mode 0)
		)
		(polygon
			(pts
				(xy 29.77896 -67.64782) (xy 29.45765 -67.96913) (xy 29.45765 -68.89115) (xy 28.38069 -69.96811)
				(xy 28.38069 -70.68947) (xy 28.2448 -70.82536) (xy 28.2448 -73.152) (xy 29.972 -74.8792) (xy 31.3944 -74.8792)
				(xy 31.4452 -74.93) (xy 31.4452 -76.2254) (xy 31.4706 -76.2508) (xy 32.0929 -76.2508) (xy 32.1183 -76.2254)
				(xy 32.1183 -74.3077) (xy 31.8008 -73.9902) (xy 30.353 -73.9902) (xy 30.099 -73.7362) (xy 30.099 -71.41464)
				(xy 30.36062 -71.15302) (xy 30.97022 -71.15302) (xy 30.988 -71.13524) (xy 30.988 -68.00342) (xy 30.6324 -67.64782)
			)
		)
		(polygon
			(pts
				(xy 30.640528 -68.61048) (xy 30.437328 -68.61048) (xy 30.437328 -68.81368) (xy 30.640528 -68.81368)
			)
		)
		(polygon
			(pts
				(xy 29.776928 -68.61048) (xy 29.573728 -68.61048) (xy 29.573728 -68.81368) (xy 29.776928 -68.81368)
			)
		)
	)
	(zone
		(layer "F.Cu")
		(hatch none 0.5)
		(connect_pads
			(clearance 0)
		)
		(min_thickness 0.25)
		(keepout
			(tracks not_allowed)
			(vias allowed)
			(pads allowed)
			(copperpour not_allowed)
			(footprints allowed)
		)
		(placement
			(enabled no)
			(sheetname "")
		)
		(fill
			(thermal_gap 0.5)
			(thermal_bridge_width 0.5)
			(island_removal_mode 0)
		)
		(polygon
			(pts
				(arc
					(start 313.294014 -210.385914)
					(mid 312.78322 -210.896327)
					(end 313.29376 -211.406994)
				)
				(xy 313.460384 -211.406994)
				(arc
					(start 313.460384 -211.2772)
					(mid 313.448293 -211.202193)
					(end 313.413394 -211.134706)
				)
				(arc
					(start 313.413394 -211.134706)
					(mid 313.10706 -210.70614)
					(end 313.529726 -211.02066)
				)
				(arc
					(start 313.529726 -211.02066)
					(mid 313.592235 -211.124447)
					(end 313.620912 -211.242148)
				)
				(xy 313.622436 -211.243672) (xy 313.622436 -211.406994) (xy 313.765184 -211.406994) (xy 313.765184 -211.254848)
				(arc
					(start 313.766708 -211.253324)
					(mid 313.795465 -211.135702)
					(end 313.858148 -211.03209)
				)
				(xy 313.858148 -211.030058)
				(arc
					(start 313.869578 -211.018628)
					(mid 314.295503 -210.707765)
					(end 313.98464 -211.13369)
				)
				(arc
					(start 313.98464 -211.13369)
					(mid 313.942025 -211.205744)
					(end 313.927236 -211.288122)
				)
				(xy 313.927236 -211.406994)
				(arc
					(start 314.10656 -211.406994)
					(mid 314.6171 -210.896454)
					(end 314.10656 -210.385914)
				)
			)
		)
	)
	(zone
		(net "GND")
		(layer "F.Cu")
		(hatch none 0.5)
		(connect_pads
			(clearance 0.5)
		)
		(min_thickness 0.25)
		(fill yes
			(thermal_gap 0.5)
			(thermal_bridge_width 0.5)
			(island_removal_mode 0)
		)
		(polygon
			(pts
				(xy 30.675326 -165.28288) (xy 29.976826 -165.98138) (xy 29.976826 -166.23538) (xy 30.738826 -166.99738)
				(xy 33.405826 -166.99738) (xy 33.532826 -166.87038) (xy 33.532826 -165.53688) (xy 33.278826 -165.28288)
			)
		)
		(polygon
			(pts
				(xy 32.829754 -165.797484) (xy 32.626554 -165.797484) (xy 32.626554 -166.000684) (xy 32.829754 -166.000684)
			)
		)
	)
	(zone
		(layer "F.Cu")
		(hatch none 0.5)
		(connect_pads
			(clearance 0)
		)
		(min_thickness 0.25)
		(keepout
			(tracks allowed)
			(vias allowed)
			(pads allowed)
			(copperpour allowed)
			(footprints not_allowed)
		)
		(placement
			(enabled no)
			(sheetname "")
		)
		(fill
			(thermal_gap 0.5)
			(thermal_bridge_width 0.5)
			(island_removal_mode 0)
		)
		(polygon
			(pts
				(xy 90.950034 -208.499964) (xy 115.24996 -208.499964) (xy 115.24996 -213.499954) (xy 90.950034 -213.499954)
			)
		)
	)
	(zone
		(layer "F.Cu")
		(hatch none 0.5)
		(connect_pads
			(clearance 0)
		)
		(min_thickness 0.25)
		(keepout
			(tracks not_allowed)
			(vias allowed)
			(pads allowed)
			(copperpour not_allowed)
			(footprints allowed)
		)
		(placement
			(enabled no)
			(sheetname "")
		)
		(fill
			(thermal_gap 0.5)
			(thermal_bridge_width 0.5)
			(island_removal_mode 0)
		)
		(polygon
			(pts
				(arc
					(start 56.86298 -85.210904)
					(mid 56.250967 -84.59851)
					(end 55.6387 -85.21065)
				)
				(arc
					(start 55.6387 -86.32825)
					(mid 56.25084 -86.94039)
					(end 56.86298 -86.32825)
				)
				(xy 56.86298 -85.977476)
				(arc
					(start 56.68264 -85.977476)
					(mid 56.529118 -86.012856)
					(end 56.406542 -86.111842)
				)
				(arc
					(start 56.406542 -86.111842)
					(mid 56.171552 -86.583021)
					(end 56.24449 -86.06155)
				)
				(arc
					(start 56.24449 -86.06155)
					(mid 56.416325 -85.889965)
					(end 56.647842 -85.816694)
				)
				(xy 56.649112 -85.815424) (xy 56.86298 -85.815424) (xy 56.86298 -85.672676) (xy 56.588152 -85.672676)
				(arc
					(start 56.586882 -85.671406)
					(mid 56.396282 -85.612529)
					(end 56.24957 -85.47735)
				)
				(arc
					(start 56.24957 -85.47735)
					(mid 56.16573 -84.957892)
					(end 56.413146 -85.422232)
				)
				(arc
					(start 56.413146 -85.422232)
					(mid 56.508427 -85.48761)
					(end 56.62168 -85.510624)
				)
				(xy 56.86298 -85.510624)
			)
		)
	)
	(zone
		(layer "F.Cu")
		(hatch none 0.5)
		(connect_pads
			(clearance 0)
		)
		(min_thickness 0.25)
		(keepout
			(tracks allowed)
			(vias allowed)
			(pads allowed)
			(copperpour allowed)
			(footprints not_allowed)
		)
		(placement
			(enabled no)
			(sheetname "")
		)
		(fill
			(thermal_gap 0.5)
			(thermal_bridge_width 0.5)
			(island_removal_mode 0)
		)
		(polygon
			(pts
				(arc
					(start 13.999972 -203.499974)
					(mid 9.99998 -207.499966)
					(end 5.999988 -203.499974)
				)
				(arc
					(start 5.999988 -203.499974)
					(mid 9.99998 -199.499982)
					(end 13.999972 -203.499974)
				)
			)
		)
	)
	(zone
		(layer "F.Cu")
		(hatch none 0.5)
		(connect_pads
			(clearance 0)
		)
		(min_thickness 0.25)
		(keepout
			(tracks not_allowed)
			(vias allowed)
			(pads allowed)
			(copperpour not_allowed)
			(footprints allowed)
		)
		(placement
			(enabled no)
			(sheetname "")
		)
		(fill
			(thermal_gap 0.5)
			(thermal_bridge_width 0.5)
			(island_removal_mode 0)
		)
		(polygon
			(pts
				(arc
					(start 13.999972 -203.499974)
					(mid 9.99998 -207.499966)
					(end 5.999988 -203.499974)
				)
				(arc
					(start 5.999988 -203.499974)
					(mid 9.99998 -199.499982)
					(end 13.999972 -203.499974)
				)
			)
		)
	)
	(zone
		(layer "F.Cu")
		(hatch none 0.5)
		(connect_pads
			(clearance 0)
		)
		(min_thickness 0.25)
		(keepout
			(tracks not_allowed)
			(vias allowed)
			(pads allowed)
			(copperpour not_allowed)
			(footprints allowed)
		)
		(placement
			(enabled no)
			(sheetname "")
		)
		(fill
			(thermal_gap 0.5)
			(thermal_bridge_width 0.5)
			(island_removal_mode 0)
		)
		(polygon
			(pts
				(arc
					(start 196.893942 -210.385914)
					(mid 196.383148 -210.896327)
					(end 196.893688 -211.406994)
				)
				(xy 197.060312 -211.406994)
				(arc
					(start 197.060312 -211.284058)
					(mid 197.048142 -211.205823)
					(end 197.012814 -211.13496)
				)
				(arc
					(start 197.012814 -211.13496)
					(mid 196.70769 -210.705289)
					(end 197.129654 -211.020914)
				)
				(arc
					(start 197.129654 -211.020914)
					(mid 197.192307 -211.128268)
					(end 197.22084 -211.24926)
				)
				(xy 197.222364 -211.250784) (xy 197.222364 -211.406994) (xy 197.365112 -211.406994) (xy 197.365112 -211.251038)
				(arc
					(start 197.366636 -211.249514)
					(mid 197.394811 -211.135702)
					(end 197.455536 -211.035392)
				)
				(xy 197.455536 -211.033106)
				(arc
					(start 197.469506 -211.018882)
					(mid 197.894899 -210.707641)
					(end 197.584568 -211.13369)
				)
				(arc
					(start 197.584568 -211.13369)
					(mid 197.542065 -211.203868)
					(end 197.527164 -211.284566)
				)
				(xy 197.527164 -211.406994)
				(arc
					(start 197.706488 -211.406994)
					(mid 198.217028 -210.896454)
					(end 197.706488 -210.385914)
				)
			)
		)
	)
	(zone
		(layer "F.Cu")
		(hatch none 0.5)
		(connect_pads
			(clearance 0)
		)
		(min_thickness 0.25)
		(keepout
			(tracks not_allowed)
			(vias allowed)
			(pads allowed)
			(copperpour not_allowed)
			(footprints allowed)
		)
		(placement
			(enabled no)
			(sheetname "")
		)
		(fill
			(thermal_gap 0.5)
			(thermal_bridge_width 0.5)
			(island_removal_mode 0)
		)
		(polygon
			(pts
				(arc
					(start 48.493934 -210.385914)
					(mid 47.98314 -210.896327)
					(end 48.49368 -211.406994)
				)
				(xy 48.660304 -211.406994)
				(arc
					(start 48.660304 -211.2772)
					(mid 48.648213 -211.202193)
					(end 48.613314 -211.134706)
				)
				(arc
					(start 48.613314 -211.134706)
					(mid 48.30698 -210.70614)
					(end 48.729646 -211.02066)
				)
				(arc
					(start 48.729646 -211.02066)
					(mid 48.792155 -211.124447)
					(end 48.820832 -211.242148)
				)
				(xy 48.822356 -211.243672) (xy 48.822356 -211.406994) (xy 48.965104 -211.406994) (xy 48.965104 -211.255864)
				(arc
					(start 48.966628 -211.25434)
					(mid 48.99563 -211.13589)
					(end 49.05883 -211.031582)
				)
				(xy 49.05883 -211.02955)
				(arc
					(start 49.069498 -211.018882)
					(mid 49.494238 -210.707143)
					(end 49.184814 -211.13369)
				)
				(arc
					(start 49.184814 -211.13369)
					(mid 49.142025 -211.206373)
					(end 49.127156 -211.289392)
				)
				(xy 49.127156 -211.406994)
				(arc
					(start 49.30648 -211.406994)
					(mid 49.81702 -210.896454)
					(end 49.30648 -210.385914)
				)
			)
		)
	)
	(zone
		(net "P0V9_VIN")
		(layer "F.Cu")
		(hatch none 0.5)
		(connect_pads
			(clearance 0.5)
		)
		(min_thickness 0.25)
		(fill yes
			(thermal_gap 0.5)
			(thermal_bridge_width 0.5)
			(island_removal_mode 0)
		)
		(polygon
			(pts
				(xy 149.876002 -61.114432) (xy 149.34692 -61.643514) (xy 146.090894 -61.643514) (xy 145.77441 -61.959998)
				(xy 145.77441 -67.248024) (xy 144.923002 -68.099432) (xy 144.923002 -80.159606) (xy 145.207228 -80.443832)
				(xy 150.588472 -80.443832) (xy 151.400002 -79.632302) (xy 151.400002 -68.10756) (xy 151.734774 -67.772788)
				(xy 151.734774 -66.16319) (xy 151.400002 -65.828418) (xy 151.400002 -61.368432) (xy 151.146002 -61.114432)
			)
		)
		(polygon
			(pts
				(xy 150.688802 -65.762632) (xy 150.485602 -65.762632) (xy 150.485602 -65.965832) (xy 150.688802 -65.965832)
			)
		)
		(polygon
			(pts
				(xy 150.688802 -64.899032) (xy 150.485602 -64.899032) (xy 150.485602 -65.102232) (xy 150.688802 -65.102232)
			)
		)
	)
	(zone
		(layers "F.Cu" "B.Cu")
		(hatch none 0.5)
		(connect_pads
			(clearance 0)
		)
		(min_thickness 0.25)
		(keepout
			(tracks not_allowed)
			(vias allowed)
			(pads allowed)
			(copperpour not_allowed)
			(footprints allowed)
		)
		(placement
			(enabled no)
			(sheetname "")
		)
		(fill yes
			(thermal_gap 0.5)
			(thermal_bridge_width 0.5)
			(island_removal_mode 0)
		)
		(polygon
			(pts
				(arc
					(start 209.118454 -72.479916)
					(mid 207.081373 -72.481186)
					(end 209.118454 -72.482456)
				)
				(arc
					(start 208.823814 -72.482456)
					(mid 208.099914 -73.20382)
					(end 207.376014 -72.482456)
				)
				(arc
					(start 207.376014 -72.479916)
					(mid 208.099914 -71.756016)
					(end 208.823814 -72.479916)
				)
			)
		)
	)
	(zone
		(layers "F.Cu" "B.Cu")
		(hatch none 0.5)
		(connect_pads
			(clearance 0)
		)
		(min_thickness 0.25)
		(keepout
			(tracks not_allowed)
			(vias allowed)
			(pads allowed)
			(copperpour not_allowed)
			(footprints allowed)
		)
		(placement
			(enabled no)
			(sheetname "")
		)
		(fill yes
			(thermal_gap 0.5)
			(thermal_bridge_width 0.5)
			(island_removal_mode 0)
		)
		(polygon
			(pts
				(arc
					(start 87.290148 -76.589636)
					(mid 86.779608 -76.079096)
					(end 86.269068 -76.589636)
				)
				(arc
					(start 86.269068 -77.478382)
					(mid 86.778211 -77.989174)
					(end 87.290148 -77.481176)
				)
				(arc
					(start 87.046308 -77.481176)
					(mid 86.779608 -77.745348)
					(end 86.512908 -77.481176)
				)
				(arc
					(start 86.512908 -77.478636)
					(mid 86.779608 -77.211936)
					(end 87.046308 -77.478636)
				)
				(xy 87.290148 -77.478636) (xy 87.290148 -76.592176)
				(arc
					(start 87.046308 -76.592176)
					(mid 86.779608 -76.856348)
					(end 86.512908 -76.592176)
				)
				(arc
					(start 86.512908 -76.589636)
					(mid 86.779608 -76.322936)
					(end 87.046308 -76.589636)
				)
			)
		)
	)
	(zone
		(layers "F.Cu" "B.Cu")
		(hatch none 0.5)
		(connect_pads
			(clearance 0)
		)
		(min_thickness 0.25)
		(keepout
			(tracks not_allowed)
			(vias allowed)
			(pads allowed)
			(copperpour not_allowed)
			(footprints allowed)
		)
		(placement
			(enabled no)
			(sheetname "")
		)
		(fill yes
			(thermal_gap 0.5)
			(thermal_bridge_width 0.5)
			(island_removal_mode 0)
		)
		(polygon
			(pts
				(arc
					(start 102.44074 -38.91661)
					(mid 101.9302 -38.40607)
					(end 101.41966 -38.91661)
				)
				(arc
					(start 101.41966 -39.80561)
					(mid 101.92893 -40.316148)
					(end 102.44074 -39.80815)
				)
				(arc
					(start 102.1969 -39.80815)
					(mid 101.9302 -40.072322)
					(end 101.6635 -39.80815)
				)
				(arc
					(start 101.6635 -39.80561)
					(mid 101.9302 -39.53891)
					(end 102.1969 -39.80561)
				)
				(xy 102.44074 -39.80561) (xy 102.44074 -38.91915)
				(arc
					(start 102.1969 -38.91915)
					(mid 101.9302 -39.183322)
					(end 101.6635 -38.91915)
				)
				(arc
					(start 101.6635 -38.91661)
					(mid 101.9302 -38.64991)
					(end 102.1969 -38.91661)
				)
			)
		)
	)
	(zone
		(layers "F.Cu" "B.Cu")
		(hatch none 0.5)
		(connect_pads
			(clearance 0)
		)
		(min_thickness 0.25)
		(keepout
			(tracks not_allowed)
			(vias allowed)
			(pads allowed)
			(copperpour not_allowed)
			(footprints allowed)
		)
		(placement
			(enabled no)
			(sheetname "")
		)
		(fill yes
			(thermal_gap 0.5)
			(thermal_bridge_width 0.5)
			(island_removal_mode 0)
		)
		(polygon
			(pts
				(arc
					(start 172.745654 -95.683832)
					(mid 172.23486 -96.194245)
					(end 172.7454 -96.704912)
				)
				(arc
					(start 173.6344 -96.704912)
					(mid 173.994507 -96.556275)
					(end 174.14494 -96.196912)
				)
				(arc
					(start 173.9011 -96.196912)
					(mid 173.6344 -96.461084)
					(end 173.3677 -96.196912)
				)
				(arc
					(start 173.0121 -96.196912)
					(mid 172.7454 -96.461084)
					(end 172.4787 -96.196912)
				)
				(arc
					(start 172.4787 -96.194372)
					(mid 172.7454 -95.927672)
					(end 173.0121 -96.194372)
				)
				(arc
					(start 173.3677 -96.194372)
					(mid 173.6344 -95.927672)
					(end 173.9011 -96.194372)
				)
				(arc
					(start 174.14494 -96.194372)
					(mid 173.995406 -95.833366)
					(end 173.6344 -95.683832)
				)
			)
		)
	)
	(zone
		(layers "F.Cu" "B.Cu")
		(hatch none 0.5)
		(connect_pads
			(clearance 0)
		)
		(min_thickness 0.25)
		(keepout
			(tracks allowed)
			(vias allowed)
			(pads allowed)
			(copperpour allowed)
			(footprints not_allowed)
		)
		(placement
			(enabled no)
			(sheetname "")
		)
		(fill yes
			(thermal_gap 0.5)
			(thermal_bridge_width 0.5)
			(island_removal_mode 0)
		)
		(polygon
			(pts
				(arc
					(start 258.700016 -214.799926)
					(mid 258.319263 -213.880707)
					(end 257.400044 -213.499954)
				)
				(arc
					(start 347.600016 -213.499954)
					(mid 346.680797 -213.880707)
					(end 346.300044 -214.799926)
				)
				(arc
					(start 346.300044 -221.400116)
					(mid 346.153471 -221.753594)
					(end 345.799918 -221.899988)
				)
				(arc
					(start 345.000072 -221.899988)
					(mid 344.64643 -222.046472)
					(end 344.499946 -222.400114)
				)
				(xy 344.499946 -226.70008) (xy 343.499948 -228.000052) (xy 309.39994 -228.000052) (xy 308.399942 -226.70008)
				(arc
					(start 308.399942 -222.499936)
					(mid 307.300122 -221.400116)
					(end 306.200048 -222.499936)
				)
				(xy 306.200048 -226.70008) (xy 305.20005 -228.000052) (xy 261.500112 -228.000052) (xy 260.500114 -226.70008)
				(arc
					(start 260.500114 -222.400114)
					(mid 260.35363 -222.046472)
					(end 259.999988 -221.899988)
				)
				(arc
					(start 259.199888 -221.899988)
					(mid 258.846425 -221.753579)
					(end 258.700016 -221.400116)
				)
			)
		)
	)
	(zone
		(layers "F.Cu" "B.Cu")
		(hatch none 0.5)
		(connect_pads
			(clearance 0)
		)
		(min_thickness 0.25)
		(keepout
			(tracks allowed)
			(vias allowed)
			(pads allowed)
			(copperpour allowed)
			(footprints not_allowed)
		)
		(placement
			(enabled no)
			(sheetname "")
		)
		(fill yes
			(thermal_gap 0.5)
			(thermal_bridge_width 0.5)
			(island_removal_mode 0)
		)
		(polygon
			(pts
				(arc
					(start 132.700014 -214.799926)
					(mid 132.319261 -213.880707)
					(end 131.400042 -213.499954)
				)
				(arc
					(start 221.600014 -213.499954)
					(mid 220.680795 -213.880707)
					(end 220.300042 -214.799926)
				)
				(arc
					(start 220.300042 -221.400116)
					(mid 220.153469 -221.753594)
					(end 219.799916 -221.899988)
				)
				(arc
					(start 219.00007 -221.899988)
					(mid 218.646428 -222.046472)
					(end 218.499944 -222.400114)
				)
				(xy 218.499944 -226.70008) (xy 217.499946 -228.000052) (xy 183.399938 -228.000052) (xy 182.39994 -226.70008)
				(arc
					(start 182.39994 -222.499936)
					(mid 181.30012 -221.400116)
					(end 180.200046 -222.499936)
				)
				(xy 180.200046 -226.70008) (xy 179.200048 -228.000052) (xy 135.50011 -228.000052) (xy 134.500112 -226.70008)
				(arc
					(start 134.500112 -222.400114)
					(mid 134.353628 -222.046472)
					(end 133.999986 -221.899988)
				)
				(arc
					(start 133.199886 -221.899988)
					(mid 132.846423 -221.753579)
					(end 132.700014 -221.400116)
				)
			)
		)
	)
	(zone
		(layers "F.Cu" "B.Cu")
		(hatch none 0.5)
		(connect_pads
			(clearance 0)
		)
		(min_thickness 0.25)
		(keepout
			(tracks allowed)
			(vias allowed)
			(pads allowed)
			(copperpour allowed)
			(footprints not_allowed)
		)
		(placement
			(enabled no)
			(sheetname "")
		)
		(fill yes
			(thermal_gap 0.5)
			(thermal_bridge_width 0.5)
			(island_removal_mode 0)
		)
		(polygon
			(pts
				(arc
					(start 26.699972 -214.799926)
					(mid 26.319219 -213.880707)
					(end 25.4 -213.499954)
				)
				(arc
					(start 115.599972 -213.499954)
					(mid 114.680753 -213.880707)
					(end 114.3 -214.799926)
				)
				(arc
					(start 114.3 -221.400116)
					(mid 114.153501 -221.753669)
					(end 113.799874 -221.899988)
				)
				(arc
					(start 113.000028 -221.899988)
					(mid 112.646386 -222.046472)
					(end 112.499902 -222.400114)
				)
				(xy 112.499902 -226.70008) (xy 111.499904 -228.000052) (xy 77.399896 -228.000052) (xy 76.399898 -226.70008)
				(arc
					(start 76.399898 -222.499936)
					(mid 75.300078 -221.400116)
					(end 74.200004 -222.499936)
				)
				(xy 74.200004 -226.70008) (xy 73.200006 -228.000052) (xy 29.500068 -228.000052) (xy 28.50007 -226.70008)
				(arc
					(start 28.50007 -222.400114)
					(mid 28.353586 -222.046472)
					(end 27.999944 -221.899988)
				)
				(arc
					(start 27.200098 -221.899988)
					(mid 26.846545 -221.753594)
					(end 26.699972 -221.400116)
				)
			)
		)
	)
	(zone
		(layers "F.Cu" "B.Cu")
		(hatch none 0.5)
		(connect_pads
			(clearance 0)
		)
		(min_thickness 0.25)
		(keepout
			(tracks not_allowed)
			(vias allowed)
			(pads allowed)
			(copperpour not_allowed)
			(footprints allowed)
		)
		(placement
			(enabled no)
			(sheetname "")
		)
		(fill yes
			(thermal_gap 0.5)
			(thermal_bridge_width 0.5)
			(island_removal_mode 0)
		)
		(polygon
			(pts
				(arc
					(start 209.118454 -67.399916)
					(mid 207.081373 -67.401186)
					(end 209.118454 -67.402456)
				)
				(arc
					(start 208.823814 -67.402456)
					(mid 208.099914 -68.12382)
					(end 207.376014 -67.402456)
				)
				(arc
					(start 207.376014 -67.399916)
					(mid 208.099914 -66.676016)
					(end 208.823814 -67.399916)
				)
			)
		)
	)
	(zone
		(layers "F.Cu" "B.Cu")
		(hatch none 0.5)
		(connect_pads
			(clearance 0)
		)
		(min_thickness 0.25)
		(keepout
			(tracks not_allowed)
			(vias allowed)
			(pads allowed)
			(copperpour not_allowed)
			(footprints allowed)
		)
		(placement
			(enabled no)
			(sheetname "")
		)
		(fill yes
			(thermal_gap 0.5)
			(thermal_bridge_width 0.5)
			(island_removal_mode 0)
		)
		(polygon
			(pts
				(arc
					(start 103.02494 -36.205668)
					(mid 102.5144 -35.695128)
					(end 102.00386 -36.205668)
				)
				(arc
					(start 102.00386 -37.094414)
					(mid 102.513003 -37.605206)
					(end 103.02494 -37.097208)
				)
				(arc
					(start 102.7811 -37.097208)
					(mid 102.5144 -37.36138)
					(end 102.2477 -37.097208)
				)
				(arc
					(start 102.2477 -37.094668)
					(mid 102.5144 -36.827968)
					(end 102.7811 -37.094668)
				)
				(xy 103.02494 -37.094668) (xy 103.02494 -36.208208)
				(arc
					(start 102.7811 -36.208208)
					(mid 102.5144 -36.47238)
					(end 102.2477 -36.208208)
				)
				(arc
					(start 102.2477 -36.205668)
					(mid 102.5144 -35.938968)
					(end 102.7811 -36.205668)
				)
			)
		)
	)
	(zone
		(layers "F.Cu" "B.Cu" "In1.Cu" "In2.Cu" "In3.Cu" "In4.Cu" "In5.Cu" "In6.Cu")
		(name "Package Keepin")
		(hatch none 0.5)
		(connect_pads
			(clearance 0)
		)
		(min_thickness 0.25)
		(keepout
			(tracks allowed)
			(vias allowed)
			(pads allowed)
			(copperpour allowed)
			(footprints allowed)
		)
		(placement
			(enabled no)
			(sheetname "")
		)
		(fill
			(thermal_gap 0.5)
			(thermal_bridge_width 0.5)
			(island_removal_mode 0)
		)
		(polygon
			(pts
				(xy 350.5962 -208.496154)
				(arc
					(start 350.5962 -21.810726)
					(mid 349.594761 -20.127603)
					(end 349.24619 -18.20037)
				)
				(arc
					(start 349.24619 -10.199624)
					(mid 350.262458 -7.013323)
					(end 352.935794 -5.0038)
				)
				(arc
					(start 332.749906 -5.0038)
					(mid 328.875705 -3.586521)
					(end 326.83069 -0.00381)
				)
				(arc
					(start 126.34849 -0.00381)
					(mid 123.82192 -3.616317)
					(end 119.637556 -5.0038)
				)
				(xy 56.953912 -5.0038)
				(arc
					(start 56.953912 -24.010112)
					(mid 54.902548 -28.962544)
					(end 49.950116 -31.013908)
				)
				(xy 5.0038 -31.013908) (xy 5.0038 -208.496154)
				(arc
					(start 25.4 -208.496154)
					(mid 29.85744 -210.342486)
					(end 31.703772 -214.799926)
				)
				(arc
					(start 31.703772 -218.328748)
					(mid 32.880825 -219.856379)
					(end 33.458658 -221.69628)
				)
				(arc
					(start 69.24929 -221.69628)
					(mid 75.300061 -216.396011)
					(end 81.350612 -221.69628)
				)
				(arc
					(start 107.541314 -221.69628)
					(mid 108.119124 -219.856367)
					(end 109.2962 -218.328748)
				)
				(arc
					(start 109.2962 -214.799926)
					(mid 111.142532 -210.342486)
					(end 115.599972 -208.496154)
				)
				(arc
					(start 131.400042 -208.496154)
					(mid 135.857482 -210.342486)
					(end 137.703814 -214.799926)
				)
				(arc
					(start 137.703814 -218.328748)
					(mid 138.880867 -219.856379)
					(end 139.4587 -221.69628)
				)
				(arc
					(start 175.249332 -221.69628)
					(mid 181.300103 -216.396011)
					(end 187.350654 -221.69628)
				)
				(arc
					(start 213.541356 -221.69628)
					(mid 214.119166 -219.856367)
					(end 215.296242 -218.328748)
				)
				(arc
					(start 215.296242 -214.799926)
					(mid 217.142574 -210.342486)
					(end 221.600014 -208.496154)
				)
				(xy 229.138226 -208.496154)
				(arc
					(start 229.138226 -165.269926)
					(mid 230.975779 -160.833679)
					(end 235.412026 -158.996126)
				)
				(arc
					(start 249.871992 -158.996126)
					(mid 254.308239 -160.833679)
					(end 256.145792 -165.269926)
				)
				(xy 256.145792 -208.496154)
				(arc
					(start 257.400044 -208.496154)
					(mid 261.857484 -210.342486)
					(end 263.703816 -214.799926)
				)
				(arc
					(start 263.703816 -218.328748)
					(mid 264.880869 -219.856379)
					(end 265.458702 -221.69628)
				)
				(arc
					(start 301.249334 -221.69628)
					(mid 307.300105 -216.396011)
					(end 313.350656 -221.69628)
				)
				(arc
					(start 339.541358 -221.69628)
					(mid 340.119168 -219.856367)
					(end 341.296244 -218.328748)
				)
				(arc
					(start 341.296244 -214.799926)
					(mid 343.142576 -210.342486)
					(end 347.600016 -208.496154)
				)
			)
		)
	)
	(zone
		(layers "F.Cu" "B.Cu" "In1.Cu" "In2.Cu" "In3.Cu" "In4.Cu" "In5.Cu" "In6.Cu")
		(name "Route Keepin")
		(hatch none 0.5)
		(connect_pads
			(clearance 0)
		)
		(min_thickness 0.25)
		(keepout
			(tracks allowed)
			(vias allowed)
			(pads allowed)
			(copperpour allowed)
			(footprints allowed)
		)
		(placement
			(enabled no)
			(sheetname "")
		)
		(fill
			(thermal_gap 0.5)
			(thermal_bridge_width 0.5)
			(island_removal_mode 0)
		)
		(polygon
			(pts
				(arc
					(start 354.600002 -212.737954)
					(mid 354.768292 -212.668246)
					(end 354.838 -212.499956)
				)
				(xy 354.838 -19.461988)
				(arc
					(start 354.749862 -19.461988)
					(mid 353.857584 -19.092394)
					(end 353.48799 -18.200116)
				)
				(arc
					(start 353.48799 -10.199878)
					(mid 353.857584 -9.3076)
					(end 354.749862 -8.938006)
				)
				(xy 354.838 -8.938006)
				(arc
					(start 354.838 -0.999998)
					(mid 354.768292 -0.831708)
					(end 354.600002 -0.762)
				)
				(arc
					(start 332.749906 -0.762)
					(mid 331.503985 -0.245923)
					(end 330.987908 0.999998)
				)
				(arc
					(start 330.987908 3.999992)
					(mid 330.9182 4.168282)
					(end 330.74991 4.23799)
				)
				(arc
					(start 123.637548 4.23799)
					(mid 122.762153 3.875389)
					(end 122.399552 2.999994)
				)
				(arc
					(start 122.399552 1.999996)
					(mid 121.590582 0.04697)
					(end 119.637556 -0.762)
				)
				(arc
					(start 53.950108 -0.762)
					(mid 53.074713 -1.124601)
					(end 52.712112 -1.999996)
				)
				(arc
					(start 52.712112 -24.010112)
					(mid 51.903142 -25.963138)
					(end 49.950116 -26.772108)
				)
				(arc
					(start 1.999996 -26.772108)
					(mid 1.124601 -27.134709)
					(end 0.762 -28.010104)
				)
				(arc
					(start 0.762 -212.499956)
					(mid 0.831708 -212.668246)
					(end 0.999998 -212.737954)
				)
				(arc
					(start 25.4 -212.737954)
					(mid 26.858034 -213.341892)
					(end 27.461972 -214.799926)
				)
				(xy 27.461972 -221.137988)
				(arc
					(start 28.000198 -221.137988)
					(mid 28.892402 -221.507656)
					(end 29.26207 -222.39986)
				)
				(xy 29.26207 -226.441) (xy 29.875226 -227.238052) (xy 72.824848 -227.238052) (xy 73.438004 -226.441)
				(arc
					(start 73.438004 -222.499936)
					(mid 75.300078 -220.637862)
					(end 77.161898 -222.499936)
				)
				(xy 77.161898 -226.441) (xy 77.775054 -227.238052) (xy 111.124746 -227.238052) (xy 111.737902 -226.441)
				(arc
					(start 111.737902 -222.39986)
					(mid 112.10757 -221.507656)
					(end 112.999774 -221.137988)
				)
				(xy 113.538 -221.137988)
				(arc
					(start 113.538 -214.799926)
					(mid 114.141938 -213.341892)
					(end 115.599972 -212.737954)
				)
				(arc
					(start 131.400042 -212.737954)
					(mid 132.858076 -213.341892)
					(end 133.462014 -214.799926)
				)
				(xy 133.462014 -221.137988)
				(arc
					(start 134.00024 -221.137988)
					(mid 134.892444 -221.507656)
					(end 135.262112 -222.39986)
				)
				(xy 135.262112 -226.441) (xy 135.875268 -227.238052) (xy 178.82489 -227.238052) (xy 179.438046 -226.441)
				(arc
					(start 179.438046 -222.499936)
					(mid 181.30012 -220.637862)
					(end 183.16194 -222.499936)
				)
				(xy 183.16194 -226.441) (xy 183.775096 -227.238052) (xy 217.124788 -227.238052) (xy 217.737944 -226.441)
				(arc
					(start 217.737944 -222.39986)
					(mid 218.107612 -221.507656)
					(end 218.999816 -221.137988)
				)
				(xy 219.538042 -221.137988)
				(arc
					(start 219.538042 -214.799926)
					(mid 220.14198 -213.341892)
					(end 221.600014 -212.737954)
				)
				(arc
					(start 229.142036 -212.737954)
					(mid 232.138747 -211.496675)
					(end 233.380026 -208.499964)
				)
				(arc
					(start 233.380026 -165.269926)
					(mid 233.975185 -163.833085)
					(end 235.412026 -163.237926)
				)
				(arc
					(start 249.871992 -163.237926)
					(mid 251.308833 -163.833085)
					(end 251.903992 -165.269926)
				)
				(arc
					(start 251.903992 -208.499964)
					(mid 253.145271 -211.496675)
					(end 256.141982 -212.737954)
				)
				(arc
					(start 257.400044 -212.737954)
					(mid 258.858078 -213.341892)
					(end 259.462016 -214.799926)
				)
				(xy 259.462016 -221.137988)
				(arc
					(start 260.000242 -221.137988)
					(mid 260.892446 -221.507656)
					(end 261.262114 -222.39986)
				)
				(xy 261.262114 -226.441) (xy 261.87527 -227.238052) (xy 304.824892 -227.238052) (xy 305.438048 -226.441)
				(arc
					(start 305.438048 -222.499936)
					(mid 307.300122 -220.637862)
					(end 309.161942 -222.499936)
				)
				(xy 309.161942 -226.441) (xy 309.775098 -227.238052) (xy 343.12479 -227.238052) (xy 343.737946 -226.441)
				(arc
					(start 343.737946 -222.39986)
					(mid 344.107614 -221.507656)
					(end 344.999818 -221.137988)
				)
				(xy 345.538044 -221.137988)
				(arc
					(start 345.538044 -214.799926)
					(mid 346.141982 -213.341892)
					(end 347.600016 -212.737954)
				)
			)
		)
	)
	(zone
		(layers "F.Cu" "B.Cu" "In1.Cu" "In2.Cu" "In3.Cu" "In4.Cu" "In5.Cu" "In6.Cu")
		(hatch none 0.5)
		(connect_pads
			(clearance 0)
		)
		(min_thickness 0.25)
		(keepout
			(tracks not_allowed)
			(vias allowed)
			(pads allowed)
			(copperpour not_allowed)
			(footprints allowed)
		)
		(placement
			(enabled no)
			(sheetname "")
		)
		(fill
			(thermal_gap 0.5)
			(thermal_bridge_width 0.5)
			(island_removal_mode 0)
		)
		(polygon
			(pts
				(arc
					(start 92.95003 -19.461988)
					(mid 93.842308 -19.092394)
					(end 94.211902 -18.200116)
				)
				(arc
					(start 94.211902 -10.199878)
					(mid 93.842308 -9.3076)
					(end 92.95003 -8.938006)
				)
				(arc
					(start 90.449908 -8.938006)
					(mid 89.55763 -9.3076)
					(end 89.188036 -10.199878)
				)
				(arc
					(start 89.188036 -18.200116)
					(mid 89.55763 -19.092394)
					(end 90.449908 -19.461988)
				)
			)
		)
	)
	(zone
		(layers "F.Cu" "B.Cu" "In2.Cu")
		(hatch none 0.5)
		(connect_pads
			(clearance 0)
		)
		(min_thickness 0.25)
		(keepout
			(tracks not_allowed)
			(vias allowed)
			(pads allowed)
			(copperpour not_allowed)
			(footprints allowed)
		)
		(placement
			(enabled no)
			(sheetname "")
		)
		(fill yes
			(thermal_gap 0.5)
			(thermal_bridge_width 0.5)
			(island_removal_mode 0)
		)
		(polygon
			(pts
				(arc
					(start 291.64026 -9.529826)
					(mid 286.634428 -9.529826)
					(end 291.64026 -9.529826)
				)
			)
		)
	)
	(zone
		(layers "F.Cu" "B.Cu" "In2.Cu")
		(hatch none 0.5)
		(connect_pads
			(clearance 0)
		)
		(min_thickness 0.25)
		(keepout
			(tracks not_allowed)
			(vias allowed)
			(pads allowed)
			(copperpour not_allowed)
			(footprints allowed)
		)
		(placement
			(enabled no)
			(sheetname "")
		)
		(fill yes
			(thermal_gap 0.5)
			(thermal_bridge_width 0.5)
			(island_removal_mode 0)
		)
		(polygon
			(pts
				(arc
					(start 324.640448 -9.529826)
					(mid 319.634616 -9.529826)
					(end 324.640448 -9.529826)
				)
			)
		)
	)
	(zone
		(layers "F.Cu" "B.Cu" "In2.Cu")
		(hatch none 0.5)
		(connect_pads
			(clearance 0)
		)
		(min_thickness 0.25)
		(keepout
			(tracks not_allowed)
			(vias allowed)
			(pads allowed)
			(copperpour not_allowed)
			(footprints allowed)
		)
		(placement
			(enabled no)
			(sheetname "")
		)
		(fill yes
			(thermal_gap 0.5)
			(thermal_bridge_width 0.5)
			(island_removal_mode 0)
		)
		(polygon
			(pts
				(arc
					(start 313.64047 -9.529826)
					(mid 308.634638 -9.529826)
					(end 313.64047 -9.529826)
				)
			)
		)
	)
	(zone
		(layers "F.Cu" "B.Cu" "In2.Cu")
		(hatch none 0.5)
		(connect_pads
			(clearance 0)
		)
		(min_thickness 0.25)
		(keepout
			(tracks not_allowed)
			(vias allowed)
			(pads allowed)
			(copperpour not_allowed)
			(footprints allowed)
		)
		(placement
			(enabled no)
			(sheetname "")
		)
		(fill yes
			(thermal_gap 0.5)
			(thermal_bridge_width 0.5)
			(island_removal_mode 0)
		)
		(polygon
			(pts
				(arc
					(start 302.640238 -9.529826)
					(mid 297.634406 -9.529826)
					(end 302.640238 -9.529826)
				)
			)
		)
	)
	(zone
		(layers "F.Cu" "B.Cu" "In2.Cu" "In5.Cu")
		(hatch none 0.5)
		(connect_pads
			(clearance 0)
		)
		(min_thickness 0.25)
		(keepout
			(tracks not_allowed)
			(vias allowed)
			(pads allowed)
			(copperpour not_allowed)
			(footprints allowed)
		)
		(placement
			(enabled no)
			(sheetname "")
		)
		(fill yes
			(thermal_gap 0.5)
			(thermal_bridge_width 0.5)
			(island_removal_mode 0)
		)
		(polygon
			(pts
				(arc
					(start 251.9807 -1.011936)
					(mid 249.943619 -1.013206)
					(end 251.9807 -1.014476)
				)
				(arc
					(start 251.68606 -1.014476)
					(mid 250.96216 -1.73584)
					(end 250.23826 -1.014476)
				)
				(arc
					(start 250.23826 -1.011936)
					(mid 250.96216 -0.288036)
					(end 251.68606 -1.011936)
				)
			)
		)
	)
	(zone
		(layers "F.Cu" "B.Cu" "In2.Cu" "In5.Cu")
		(hatch none 0.5)
		(connect_pads
			(clearance 0)
		)
		(min_thickness 0.25)
		(keepout
			(tracks not_allowed)
			(vias allowed)
			(pads allowed)
			(copperpour not_allowed)
			(footprints allowed)
		)
		(placement
			(enabled no)
			(sheetname "")
		)
		(fill yes
			(thermal_gap 0.5)
			(thermal_bridge_width 0.5)
			(island_removal_mode 0)
		)
		(polygon
			(pts
				(arc
					(start 171.6405 -9.529826)
					(mid 166.634668 -9.529826)
					(end 171.6405 -9.529826)
				)
			)
		)
	)
	(zone
		(layers "F.Cu" "B.Cu" "In2.Cu" "In5.Cu")
		(hatch none 0.5)
		(connect_pads
			(clearance 0)
		)
		(min_thickness 0.25)
		(keepout
			(tracks not_allowed)
			(vias allowed)
			(pads allowed)
			(copperpour not_allowed)
			(footprints allowed)
		)
		(placement
			(enabled no)
			(sheetname "")
		)
		(fill yes
			(thermal_gap 0.5)
			(thermal_bridge_width 0.5)
			(island_removal_mode 0)
		)
		(polygon
			(pts
				(arc
					(start 8.150098 -38.509956)
					(mid 5.554217 -38.511226)
					(end 8.150098 -38.512496)
				)
				(arc
					(start 7.855458 -38.512496)
					(mid 6.852158 -39.513259)
					(end 5.848858 -38.512496)
				)
				(arc
					(start 5.848858 -38.509956)
					(mid 6.852158 -37.506656)
					(end 7.855458 -38.509956)
				)
			)
		)
	)
	(zone
		(layers "F.Cu" "B.Cu" "In2.Cu" "In5.Cu")
		(hatch none 0.5)
		(connect_pads
			(clearance 0)
		)
		(min_thickness 0.25)
		(keepout
			(tracks not_allowed)
			(vias allowed)
			(pads allowed)
			(copperpour not_allowed)
			(footprints allowed)
		)
		(placement
			(enabled no)
			(sheetname "")
		)
		(fill yes
			(thermal_gap 0.5)
			(thermal_bridge_width 0.5)
			(island_removal_mode 0)
		)
		(polygon
			(pts
				(arc
					(start 258.48056 -1.011936)
					(mid 256.443479 -1.013206)
					(end 258.48056 -1.014476)
				)
				(arc
					(start 258.18592 -1.014476)
					(mid 257.46202 -1.73584)
					(end 256.73812 -1.014476)
				)
				(arc
					(start 256.73812 -1.011936)
					(mid 257.46202 -0.288036)
					(end 258.18592 -1.011936)
				)
			)
		)
	)
	(zone
		(layers "F.Cu" "B.Cu" "In2.Cu" "In5.Cu")
		(hatch none 0.5)
		(connect_pads
			(clearance 0)
		)
		(min_thickness 0.25)
		(keepout
			(tracks not_allowed)
			(vias allowed)
			(pads allowed)
			(copperpour not_allowed)
			(footprints allowed)
		)
		(placement
			(enabled no)
			(sheetname "")
		)
		(fill yes
			(thermal_gap 0.5)
			(thermal_bridge_width 0.5)
			(island_removal_mode 0)
		)
		(polygon
			(pts
				(arc
					(start 124.84481 -64.83096)
					(mid 122.756929 -64.83223)
					(end 124.84481 -64.8335)
				)
				(arc
					(start 124.55017 -64.8335)
					(mid 123.80087 -65.580264)
					(end 123.05157 -64.8335)
				)
				(arc
					(start 123.05157 -64.83096)
					(mid 123.80087 -64.08166)
					(end 124.55017 -64.83096)
				)
			)
		)
	)
	(zone
		(layers "F.Cu" "B.Cu" "In2.Cu" "In5.Cu")
		(hatch none 0.5)
		(connect_pads
			(clearance 0)
		)
		(min_thickness 0.25)
		(keepout
			(tracks not_allowed)
			(vias allowed)
			(pads allowed)
			(copperpour not_allowed)
			(footprints allowed)
		)
		(placement
			(enabled no)
			(sheetname "")
		)
		(fill yes
			(thermal_gap 0.5)
			(thermal_bridge_width 0.5)
			(island_removal_mode 0)
		)
		(polygon
			(pts
				(arc
					(start 138.640312 -9.529826)
					(mid 133.63448 -9.529826)
					(end 138.640312 -9.529826)
				)
			)
		)
	)
	(zone
		(layers "F.Cu" "B.Cu" "In2.Cu" "In5.Cu")
		(hatch none 0.5)
		(connect_pads
			(clearance 0)
		)
		(min_thickness 0.25)
		(keepout
			(tracks not_allowed)
			(vias allowed)
			(pads allowed)
			(copperpour not_allowed)
			(footprints allowed)
		)
		(placement
			(enabled no)
			(sheetname "")
		)
		(fill yes
			(thermal_gap 0.5)
			(thermal_bridge_width 0.5)
			(island_removal_mode 0)
		)
		(polygon
			(pts
				(arc
					(start 160.640522 -9.529826)
					(mid 155.63469 -9.529826)
					(end 160.640522 -9.529826)
				)
			)
		)
	)
	(zone
		(layers "F.Cu" "B.Cu" "In2.Cu" "In5.Cu")
		(hatch none 0.5)
		(connect_pads
			(clearance 0)
		)
		(min_thickness 0.25)
		(keepout
			(tracks not_allowed)
			(vias allowed)
			(pads allowed)
			(copperpour not_allowed)
			(footprints allowed)
		)
		(placement
			(enabled no)
			(sheetname "")
		)
		(fill yes
			(thermal_gap 0.5)
			(thermal_bridge_width 0.5)
			(island_removal_mode 0)
		)
		(polygon
			(pts
				(arc
					(start 149.64029 -9.529826)
					(mid 144.634458 -9.529826)
					(end 149.64029 -9.529826)
				)
			)
		)
	)
	(zone
		(layers "F.Cu" "B.Cu" "In2.Cu" "In5.Cu")
		(hatch none 0.5)
		(connect_pads
			(clearance 0)
		)
		(min_thickness 0.25)
		(keepout
			(tracks not_allowed)
			(vias allowed)
			(pads allowed)
			(copperpour not_allowed)
			(footprints allowed)
		)
		(placement
			(enabled no)
			(sheetname "")
		)
		(fill yes
			(thermal_gap 0.5)
			(thermal_bridge_width 0.5)
			(island_removal_mode 0)
		)
		(polygon
			(pts
				(arc
					(start 25.729946 -38.509956)
					(mid 23.134065 -38.511226)
					(end 25.729946 -38.512496)
				)
				(arc
					(start 25.435306 -38.512496)
					(mid 24.432006 -39.513259)
					(end 23.428706 -38.512496)
				)
				(arc
					(start 23.428706 -38.509956)
					(mid 24.432006 -37.506656)
					(end 25.435306 -38.509956)
				)
			)
		)
	)
	(zone
		(layers "F.Cu" "B.Cu" "In5.Cu")
		(hatch none 0.5)
		(connect_pads
			(clearance 0)
		)
		(min_thickness 0.25)
		(keepout
			(tracks not_allowed)
			(vias allowed)
			(pads allowed)
			(copperpour not_allowed)
			(footprints allowed)
		)
		(placement
			(enabled no)
			(sheetname "")
		)
		(fill yes
			(thermal_gap 0.5)
			(thermal_bridge_width 0.5)
			(island_removal_mode 0)
		)
		(polygon
			(pts
				(arc
					(start 274.118578 -23.400004)
					(mid 272.081497 -23.401274)
					(end 274.118578 -23.402544)
				)
				(arc
					(start 273.823938 -23.402544)
					(mid 273.100038 -24.123908)
					(end 272.376138 -23.402544)
				)
				(arc
					(start 272.376138 -23.400004)
					(mid 273.100038 -22.676104)
					(end 273.823938 -23.400004)
				)
			)
		)
	)
	(zone
		(layers "F.Cu" "B.Cu" "In5.Cu")
		(hatch none 0.5)
		(connect_pads
			(clearance 0)
		)
		(min_thickness 0.25)
		(keepout
			(tracks not_allowed)
			(vias allowed)
			(pads allowed)
			(copperpour not_allowed)
			(footprints allowed)
		)
		(placement
			(enabled no)
			(sheetname "")
		)
		(fill yes
			(thermal_gap 0.5)
			(thermal_bridge_width 0.5)
			(island_removal_mode 0)
		)
		(polygon
			(pts
				(arc
					(start 150.009352 -16.330168)
					(mid 149.536681 -15.72414)
					(end 148.83384 -16.03502)
				)
				(xy 148.831554 -16.03375) (xy 148.081492 -17.433544) (xy 148.081746 -17.433798)
				(arc
					(start 148.083778 -17.434814)
					(mid 148.339302 -18.280634)
					(end 149.185122 -18.02511)
				)
				(xy 149.187408 -18.02638) (xy 149.344888 -17.732502)
				(arc
					(start 149.01545 -17.732502)
					(mid 148.63445 -18.11097)
					(end 148.25345 -17.732502)
				)
				(arc
					(start 148.25345 -17.729962)
					(mid 148.63445 -17.348962)
					(end 149.01545 -17.729962)
				)
				(xy 149.346158 -17.729962) (xy 149.93747 -16.626586)
				(arc
					(start 149.935184 -16.625316)
					(mid 149.99023 -16.483561)
					(end 150.009352 -16.332708)
				)
				(arc
					(start 149.765512 -16.332708)
					(mid 149.384512 -16.711176)
					(end 149.003512 -16.332708)
				)
				(arc
					(start 149.003512 -16.330168)
					(mid 149.384512 -15.949168)
					(end 149.765512 -16.330168)
				)
			)
		)
	)
	(zone
		(layers "F.Cu" "B.Cu" "In5.Cu")
		(hatch none 0.5)
		(connect_pads
			(clearance 0)
		)
		(min_thickness 0.25)
		(keepout
			(tracks not_allowed)
			(vias allowed)
			(pads allowed)
			(copperpour not_allowed)
			(footprints allowed)
		)
		(placement
			(enabled no)
			(sheetname "")
		)
		(fill yes
			(thermal_gap 0.5)
			(thermal_bridge_width 0.5)
			(island_removal_mode 0)
		)
		(polygon
			(pts
				(arc
					(start 322.759324 -16.330168)
					(mid 322.286653 -15.72414)
					(end 321.583812 -16.03502)
				)
				(xy 321.581526 -16.03375) (xy 320.831464 -17.433544) (xy 320.831718 -17.433798)
				(arc
					(start 320.83375 -17.434814)
					(mid 321.089274 -18.280634)
					(end 321.935094 -18.02511)
				)
				(xy 321.93738 -18.02638) (xy 322.09486 -17.732502)
				(arc
					(start 321.765422 -17.732502)
					(mid 321.384422 -18.11097)
					(end 321.003422 -17.732502)
				)
				(arc
					(start 321.003422 -17.729962)
					(mid 321.384422 -17.348962)
					(end 321.765422 -17.729962)
				)
				(xy 322.09613 -17.729962) (xy 322.687442 -16.626586)
				(arc
					(start 322.685156 -16.625316)
					(mid 322.740202 -16.483561)
					(end 322.759324 -16.332708)
				)
				(arc
					(start 322.515484 -16.332708)
					(mid 322.134484 -16.711176)
					(end 321.753484 -16.332708)
				)
				(arc
					(start 321.753484 -16.330168)
					(mid 322.134484 -15.949168)
					(end 322.515484 -16.330168)
				)
			)
		)
	)
	(zone
		(layers "F.Cu" "B.Cu" "In5.Cu")
		(hatch none 0.5)
		(connect_pads
			(clearance 0)
		)
		(min_thickness 0.25)
		(keepout
			(tracks not_allowed)
			(vias allowed)
			(pads allowed)
			(copperpour not_allowed)
			(footprints allowed)
		)
		(placement
			(enabled no)
			(sheetname "")
		)
		(fill yes
			(thermal_gap 0.5)
			(thermal_bridge_width 0.5)
			(island_removal_mode 0)
		)
		(polygon
			(pts
				(arc
					(start 161.00933 -16.330168)
					(mid 160.536659 -15.72414)
					(end 159.833818 -16.03502)
				)
				(xy 159.831532 -16.03375) (xy 159.08147 -17.433544) (xy 159.081724 -17.433798)
				(arc
					(start 159.083756 -17.434814)
					(mid 159.33928 -18.280634)
					(end 160.1851 -18.02511)
				)
				(xy 160.187386 -18.02638) (xy 160.344866 -17.732502)
				(arc
					(start 160.015428 -17.732502)
					(mid 159.634428 -18.11097)
					(end 159.253428 -17.732502)
				)
				(arc
					(start 159.253428 -17.729962)
					(mid 159.634428 -17.348962)
					(end 160.015428 -17.729962)
				)
				(xy 160.346136 -17.729962) (xy 160.937448 -16.626586)
				(arc
					(start 160.935162 -16.625316)
					(mid 160.990208 -16.483561)
					(end 161.00933 -16.332708)
				)
				(arc
					(start 160.76549 -16.332708)
					(mid 160.38449 -16.711176)
					(end 160.00349 -16.332708)
				)
				(arc
					(start 160.00349 -16.330168)
					(mid 160.38449 -15.949168)
					(end 160.76549 -16.330168)
				)
			)
		)
	)
	(zone
		(layers "F.Cu" "B.Cu" "In5.Cu")
		(hatch none 0.5)
		(connect_pads
			(clearance 0)
		)
		(min_thickness 0.25)
		(keepout
			(tracks not_allowed)
			(vias allowed)
			(pads allowed)
			(copperpour not_allowed)
			(footprints allowed)
		)
		(placement
			(enabled no)
			(sheetname "")
		)
		(fill yes
			(thermal_gap 0.5)
			(thermal_bridge_width 0.5)
			(island_removal_mode 0)
		)
		(polygon
			(pts
				(arc
					(start 136.759188 -16.330168)
					(mid 136.28635 -15.724098)
					(end 135.583422 -16.035274)
				)
				(xy 135.58139 -16.034004) (xy 134.831582 -17.433544) (xy 134.831836 -17.433798)
				(arc
					(start 134.833868 -17.434814)
					(mid 135.089544 -18.280715)
					(end 135.935466 -18.024856)
				)
				(xy 135.937498 -18.026126) (xy 136.094724 -17.732502)
				(arc
					(start 135.76554 -17.732502)
					(mid 135.38454 -18.11097)
					(end 135.00354 -17.732502)
				)
				(arc
					(start 135.00354 -17.729962)
					(mid 135.38454 -17.348962)
					(end 135.76554 -17.729962)
				)
				(xy 136.096248 -17.729962) (xy 136.687306 -16.626332)
				(arc
					(start 136.685274 -16.625062)
					(mid 136.740151 -16.483413)
					(end 136.759188 -16.332708)
				)
				(arc
					(start 136.515348 -16.332708)
					(mid 136.134348 -16.711176)
					(end 135.753348 -16.332708)
				)
				(arc
					(start 135.753348 -16.330168)
					(mid 136.134348 -15.949168)
					(end 136.515348 -16.330168)
				)
			)
		)
	)
	(zone
		(layers "F.Cu" "B.Cu" "In5.Cu")
		(hatch none 0.5)
		(connect_pads
			(clearance 0)
		)
		(min_thickness 0.25)
		(keepout
			(tracks not_allowed)
			(vias allowed)
			(pads allowed)
			(copperpour not_allowed)
			(footprints allowed)
		)
		(placement
			(enabled no)
			(sheetname "")
		)
		(fill yes
			(thermal_gap 0.5)
			(thermal_bridge_width 0.5)
			(island_removal_mode 0)
		)
		(polygon
			(pts
				(arc
					(start 303.0093 -12.530074)
					(mid 302.536462 -11.924004)
					(end 301.833534 -12.23518)
				)
				(xy 301.831502 -12.23391) (xy 301.08144 -13.633704) (xy 301.081694 -13.633958)
				(arc
					(start 301.083726 -13.634974)
					(mid 301.339402 -14.480875)
					(end 302.185324 -14.225016)
				)
				(xy 302.187356 -14.226286) (xy 302.344582 -13.932662)
				(arc
					(start 302.015398 -13.932662)
					(mid 301.634398 -14.31113)
					(end 301.253398 -13.932662)
				)
				(arc
					(start 301.253398 -13.930122)
					(mid 301.634398 -13.549122)
					(end 302.015398 -13.930122)
				)
				(xy 302.346106 -13.930122) (xy 302.937418 -12.826238)
				(arc
					(start 302.935386 -12.824968)
					(mid 302.990263 -12.683319)
					(end 303.0093 -12.532614)
				)
				(arc
					(start 302.76546 -12.532614)
					(mid 302.38446 -12.911082)
					(end 302.00346 -12.532614)
				)
				(arc
					(start 302.00346 -12.530074)
					(mid 302.38446 -12.149074)
					(end 302.76546 -12.530074)
				)
			)
		)
	)
	(zone
		(layers "F.Cu" "B.Cu" "In5.Cu")
		(hatch none 0.5)
		(connect_pads
			(clearance 0)
		)
		(min_thickness 0.25)
		(keepout
			(tracks not_allowed)
			(vias allowed)
			(pads allowed)
			(copperpour not_allowed)
			(footprints allowed)
		)
		(placement
			(enabled no)
			(sheetname "")
		)
		(fill yes
			(thermal_gap 0.5)
			(thermal_bridge_width 0.5)
			(island_removal_mode 0)
		)
		(polygon
			(pts
				(arc
					(start 147.759166 -16.330168)
					(mid 147.286328 -15.724098)
					(end 146.5834 -16.035274)
				)
				(xy 146.581368 -16.034004) (xy 145.83156 -17.433544) (xy 145.831814 -17.433798)
				(arc
					(start 145.833846 -17.434814)
					(mid 146.089522 -18.280715)
					(end 146.935444 -18.024856)
				)
				(xy 146.937476 -18.026126) (xy 147.094702 -17.732502)
				(arc
					(start 146.765518 -17.732502)
					(mid 146.384518 -18.11097)
					(end 146.003518 -17.732502)
				)
				(arc
					(start 146.003518 -17.729962)
					(mid 146.384518 -17.348962)
					(end 146.765518 -17.729962)
				)
				(xy 147.096226 -17.729962) (xy 147.687284 -16.626332)
				(arc
					(start 147.685252 -16.625062)
					(mid 147.740129 -16.483413)
					(end 147.759166 -16.332708)
				)
				(arc
					(start 147.515326 -16.332708)
					(mid 147.134326 -16.711176)
					(end 146.753326 -16.332708)
				)
				(arc
					(start 146.753326 -16.330168)
					(mid 147.134326 -15.949168)
					(end 147.515326 -16.330168)
				)
			)
		)
	)
	(zone
		(layers "F.Cu" "B.Cu" "In5.Cu")
		(hatch none 0.5)
		(connect_pads
			(clearance 0)
		)
		(min_thickness 0.25)
		(keepout
			(tracks not_allowed)
			(vias allowed)
			(pads allowed)
			(copperpour not_allowed)
			(footprints allowed)
		)
		(placement
			(enabled no)
			(sheetname "")
		)
		(fill yes
			(thermal_gap 0.5)
			(thermal_bridge_width 0.5)
			(island_removal_mode 0)
		)
		(polygon
			(pts
				(arc
					(start 139.009374 -12.530074)
					(mid 138.536536 -11.924004)
					(end 137.833608 -12.23518)
				)
				(xy 137.831576 -12.23391) (xy 137.081514 -13.633958)
				(arc
					(start 137.083546 -13.635228)
					(mid 137.339578 -14.481048)
					(end 138.185398 -14.225016)
				)
				(xy 138.18743 -14.226286) (xy 138.344656 -13.932662)
				(arc
					(start 138.015472 -13.932662)
					(mid 137.634472 -14.31113)
					(end 137.253472 -13.932662)
				)
				(arc
					(start 137.253472 -13.930122)
					(mid 137.634472 -13.549122)
					(end 138.015472 -13.930122)
				)
				(xy 138.34618 -13.930122) (xy 138.937492 -12.826492) (xy 138.937238 -12.826238)
				(arc
					(start 138.935206 -12.825222)
					(mid 138.990252 -12.683467)
					(end 139.009374 -12.532614)
				)
				(arc
					(start 138.765534 -12.532614)
					(mid 138.384534 -12.911082)
					(end 138.003534 -12.532614)
				)
				(arc
					(start 138.003534 -12.530074)
					(mid 138.384534 -12.149074)
					(end 138.765534 -12.530074)
				)
			)
		)
	)
	(zone
		(layers "F.Cu" "B.Cu" "In5.Cu")
		(hatch none 0.5)
		(connect_pads
			(clearance 0)
		)
		(min_thickness 0.25)
		(keepout
			(tracks not_allowed)
			(vias allowed)
			(pads allowed)
			(copperpour not_allowed)
			(footprints allowed)
		)
		(placement
			(enabled no)
			(sheetname "")
		)
		(fill yes
			(thermal_gap 0.5)
			(thermal_bridge_width 0.5)
			(island_removal_mode 0)
		)
		(polygon
			(pts
				(arc
					(start 289.759136 -12.530074)
					(mid 289.286298 -11.924004)
					(end 288.58337 -12.23518)
				)
				(arc
					(start 287.833562 -13.635228)
					(mid 288.089594 -14.481048)
					(end 288.935414 -14.225016)
				)
				(xy 289.091878 -13.932662)
				(arc
					(start 288.765488 -13.932662)
					(mid 288.384488 -14.31113)
					(end 288.003488 -13.932662)
				)
				(arc
					(start 288.003488 -13.930122)
					(mid 288.384488 -13.549122)
					(end 288.765488 -13.930122)
				)
				(xy 289.093402 -13.930122)
				(arc
					(start 289.681158 -12.832588)
					(mid 289.739038 -12.687512)
					(end 289.759136 -12.532614)
				)
				(arc
					(start 289.515296 -12.532614)
					(mid 289.134296 -12.911082)
					(end 288.753296 -12.532614)
				)
				(arc
					(start 288.753296 -12.530074)
					(mid 289.134296 -12.149074)
					(end 289.515296 -12.530074)
				)
			)
		)
	)
	(zone
		(layers "F.Cu" "B.Cu" "In5.Cu")
		(hatch none 0.5)
		(connect_pads
			(clearance 0)
		)
		(min_thickness 0.25)
		(keepout
			(tracks not_allowed)
			(vias allowed)
			(pads allowed)
			(copperpour not_allowed)
			(footprints allowed)
		)
		(placement
			(enabled no)
			(sheetname "")
		)
		(fill yes
			(thermal_gap 0.5)
			(thermal_bridge_width 0.5)
			(island_removal_mode 0)
		)
		(polygon
			(pts
				(arc
					(start 303.0093 -16.330168)
					(mid 302.536629 -15.72414)
					(end 301.833788 -16.03502)
				)
				(xy 301.831502 -16.03375) (xy 301.08144 -17.433544) (xy 301.081694 -17.433798)
				(arc
					(start 301.083726 -17.434814)
					(mid 301.33925 -18.280634)
					(end 302.18507 -18.02511)
				)
				(xy 302.187356 -18.02638) (xy 302.344836 -17.732502)
				(arc
					(start 302.015398 -17.732502)
					(mid 301.634398 -18.11097)
					(end 301.253398 -17.732502)
				)
				(arc
					(start 301.253398 -17.729962)
					(mid 301.634398 -17.348962)
					(end 302.015398 -17.729962)
				)
				(xy 302.346106 -17.729962) (xy 302.937418 -16.626586)
				(arc
					(start 302.935132 -16.625316)
					(mid 302.990178 -16.483561)
					(end 303.0093 -16.332708)
				)
				(arc
					(start 302.76546 -16.332708)
					(mid 302.38446 -16.711176)
					(end 302.00346 -16.332708)
				)
				(arc
					(start 302.00346 -16.330168)
					(mid 302.38446 -15.949168)
					(end 302.76546 -16.330168)
				)
			)
		)
	)
	(zone
		(layers "F.Cu" "B.Cu" "In5.Cu")
		(hatch none 0.5)
		(connect_pads
			(clearance 0)
		)
		(min_thickness 0.25)
		(keepout
			(tracks not_allowed)
			(vias allowed)
			(pads allowed)
			(copperpour not_allowed)
			(footprints allowed)
		)
		(placement
			(enabled no)
			(sheetname "")
		)
		(fill yes
			(thermal_gap 0.5)
			(thermal_bridge_width 0.5)
			(island_removal_mode 0)
		)
		(polygon
			(pts
				(arc
					(start 322.759324 -12.530074)
					(mid 322.286486 -11.924004)
					(end 321.583558 -12.23518)
				)
				(xy 321.581526 -12.23391) (xy 320.831464 -13.633704) (xy 320.831718 -13.633958)
				(arc
					(start 320.83375 -13.634974)
					(mid 321.089426 -14.480875)
					(end 321.935348 -14.225016)
				)
				(xy 321.93738 -14.226286) (xy 322.094606 -13.932662)
				(arc
					(start 321.765422 -13.932662)
					(mid 321.384422 -14.31113)
					(end 321.003422 -13.932662)
				)
				(arc
					(start 321.003422 -13.930122)
					(mid 321.384422 -13.549122)
					(end 321.765422 -13.930122)
				)
				(xy 322.09613 -13.930122) (xy 322.687442 -12.826238)
				(arc
					(start 322.68541 -12.824968)
					(mid 322.740287 -12.683319)
					(end 322.759324 -12.532614)
				)
				(arc
					(start 322.515484 -12.532614)
					(mid 322.134484 -12.911082)
					(end 321.753484 -12.532614)
				)
				(arc
					(start 321.753484 -12.530074)
					(mid 322.134484 -12.149074)
					(end 322.515484 -12.530074)
				)
			)
		)
	)
	(zone
		(layers "F.Cu" "B.Cu" "In5.Cu")
		(hatch none 0.5)
		(connect_pads
			(clearance 0)
		)
		(min_thickness 0.25)
		(keepout
			(tracks not_allowed)
			(vias allowed)
			(pads allowed)
			(copperpour not_allowed)
			(footprints allowed)
		)
		(placement
			(enabled no)
			(sheetname "")
		)
		(fill yes
			(thermal_gap 0.5)
			(thermal_bridge_width 0.5)
			(island_removal_mode 0)
		)
		(polygon
			(pts
				(arc
					(start 314.009278 -12.530074)
					(mid 313.53644 -11.924004)
					(end 312.833512 -12.23518)
				)
				(xy 312.83148 -12.23391) (xy 312.081418 -13.633704) (xy 312.081672 -13.633958)
				(arc
					(start 312.083704 -13.634974)
					(mid 312.33938 -14.480875)
					(end 313.185302 -14.225016)
				)
				(xy 313.187334 -14.226286) (xy 313.34456 -13.932662)
				(arc
					(start 313.015376 -13.932662)
					(mid 312.634376 -14.31113)
					(end 312.253376 -13.932662)
				)
				(arc
					(start 312.253376 -13.930122)
					(mid 312.634376 -13.549122)
					(end 313.015376 -13.930122)
				)
				(xy 313.346084 -13.930122) (xy 313.937396 -12.826238)
				(arc
					(start 313.935364 -12.824968)
					(mid 313.990241 -12.683319)
					(end 314.009278 -12.532614)
				)
				(arc
					(start 313.765438 -12.532614)
					(mid 313.384438 -12.911082)
					(end 313.003438 -12.532614)
				)
				(arc
					(start 313.003438 -12.530074)
					(mid 313.384438 -12.149074)
					(end 313.765438 -12.530074)
				)
			)
		)
	)
	(zone
		(layers "F.Cu" "B.Cu" "In5.Cu")
		(hatch none 0.5)
		(connect_pads
			(clearance 0)
		)
		(min_thickness 0.25)
		(keepout
			(tracks allowed)
			(vias allowed)
			(pads allowed)
			(copperpour allowed)
			(footprints allowed)
		)
		(placement
			(enabled no)
			(sheetname "")
		)
		(fill yes
			(thermal_gap 0.5)
			(thermal_bridge_width 0.5)
			(island_removal_mode 0)
		)
		(polygon
			(pts
				(xy 27.178 -160.02) (xy 27.178 -147.955) (xy 44.323 -147.955) (xy 44.323 -160.02)
			)
		)
	)
	(zone
		(layers "F.Cu" "B.Cu" "In5.Cu")
		(hatch none 0.5)
		(connect_pads
			(clearance 0)
		)
		(min_thickness 0.25)
		(keepout
			(tracks not_allowed)
			(vias allowed)
			(pads allowed)
			(copperpour not_allowed)
			(footprints allowed)
		)
		(placement
			(enabled no)
			(sheetname "")
		)
		(fill yes
			(thermal_gap 0.5)
			(thermal_bridge_width 0.5)
			(island_removal_mode 0)
		)
		(polygon
			(pts
				(arc
					(start 150.009352 -12.530074)
					(mid 149.536514 -11.924004)
					(end 148.833586 -12.23518)
				)
				(xy 148.831554 -12.23391) (xy 148.081492 -13.633704) (xy 148.081746 -13.633958)
				(arc
					(start 148.083778 -13.634974)
					(mid 148.339454 -14.480875)
					(end 149.185376 -14.225016)
				)
				(xy 149.187408 -14.226286) (xy 149.344634 -13.932662)
				(arc
					(start 149.01545 -13.932662)
					(mid 148.63445 -14.31113)
					(end 148.25345 -13.932662)
				)
				(arc
					(start 148.25345 -13.930122)
					(mid 148.63445 -13.549122)
					(end 149.01545 -13.930122)
				)
				(xy 149.346158 -13.930122) (xy 149.93747 -12.826238)
				(arc
					(start 149.935438 -12.824968)
					(mid 149.990315 -12.683319)
					(end 150.009352 -12.532614)
				)
				(arc
					(start 149.765512 -12.532614)
					(mid 149.384512 -12.911082)
					(end 149.003512 -12.532614)
				)
				(arc
					(start 149.003512 -12.530074)
					(mid 149.384512 -12.149074)
					(end 149.765512 -12.530074)
				)
			)
		)
	)
	(zone
		(layers "F.Cu" "B.Cu" "In5.Cu")
		(hatch none 0.5)
		(connect_pads
			(clearance 0)
		)
		(min_thickness 0.25)
		(keepout
			(tracks not_allowed)
			(vias allowed)
			(pads allowed)
			(copperpour not_allowed)
			(footprints allowed)
		)
		(placement
			(enabled no)
			(sheetname "")
		)
		(fill yes
			(thermal_gap 0.5)
			(thermal_bridge_width 0.5)
			(island_removal_mode 0)
		)
		(polygon
			(pts
				(arc
					(start 147.759166 -12.530074)
					(mid 147.286328 -11.924004)
					(end 146.5834 -12.23518)
				)
				(arc
					(start 145.837656 -13.627608)
					(mid 146.08579 -14.479061)
					(end 146.935444 -14.225016)
				)
				(xy 147.091908 -13.932662)
				(arc
					(start 146.765518 -13.932662)
					(mid 146.384518 -14.31113)
					(end 146.003518 -13.932662)
				)
				(arc
					(start 146.003518 -13.930122)
					(mid 146.384518 -13.549122)
					(end 146.765518 -13.930122)
				)
				(xy 147.093432 -13.930122)
				(arc
					(start 147.685252 -12.824968)
					(mid 147.740129 -12.683319)
					(end 147.759166 -12.532614)
				)
				(arc
					(start 147.515326 -12.532614)
					(mid 147.134326 -12.911082)
					(end 146.753326 -12.532614)
				)
				(arc
					(start 146.753326 -12.530074)
					(mid 147.134326 -12.149074)
					(end 147.515326 -12.530074)
				)
			)
		)
	)
	(zone
		(layers "F.Cu" "B.Cu" "In5.Cu")
		(hatch none 0.5)
		(connect_pads
			(clearance 0)
		)
		(min_thickness 0.25)
		(keepout
			(tracks not_allowed)
			(vias allowed)
			(pads allowed)
			(copperpour not_allowed)
			(footprints allowed)
		)
		(placement
			(enabled no)
			(sheetname "")
		)
		(fill yes
			(thermal_gap 0.5)
			(thermal_bridge_width 0.5)
			(island_removal_mode 0)
		)
		(polygon
			(pts
				(arc
					(start 300.759114 -16.330168)
					(mid 300.286276 -15.724098)
					(end 299.583348 -16.035274)
				)
				(xy 299.581316 -16.034004) (xy 298.831508 -17.433544) (xy 298.831762 -17.433798)
				(arc
					(start 298.833794 -17.434814)
					(mid 299.08947 -18.280715)
					(end 299.935392 -18.024856)
				)
				(xy 299.937424 -18.026126) (xy 300.09465 -17.732502)
				(arc
					(start 299.765466 -17.732502)
					(mid 299.384466 -18.11097)
					(end 299.003466 -17.732502)
				)
				(arc
					(start 299.003466 -17.729962)
					(mid 299.384466 -17.348962)
					(end 299.765466 -17.729962)
				)
				(xy 300.096174 -17.729962) (xy 300.687232 -16.626332)
				(arc
					(start 300.6852 -16.625062)
					(mid 300.740077 -16.483413)
					(end 300.759114 -16.332708)
				)
				(arc
					(start 300.515274 -16.332708)
					(mid 300.134274 -16.711176)
					(end 299.753274 -16.332708)
				)
				(arc
					(start 299.753274 -16.330168)
					(mid 300.134274 -15.949168)
					(end 300.515274 -16.330168)
				)
			)
		)
	)
	(zone
		(layers "F.Cu" "B.Cu" "In5.Cu")
		(hatch none 0.5)
		(connect_pads
			(clearance 0)
		)
		(min_thickness 0.25)
		(keepout
			(tracks not_allowed)
			(vias allowed)
			(pads allowed)
			(copperpour not_allowed)
			(footprints allowed)
		)
		(placement
			(enabled no)
			(sheetname "")
		)
		(fill yes
			(thermal_gap 0.5)
			(thermal_bridge_width 0.5)
			(island_removal_mode 0)
		)
		(polygon
			(pts
				(arc
					(start 139.009374 -16.330168)
					(mid 138.536703 -15.72414)
					(end 137.833862 -16.03502)
				)
				(xy 137.831576 -16.03375) (xy 137.081514 -17.433544) (xy 137.081768 -17.433798)
				(arc
					(start 137.0838 -17.434814)
					(mid 137.339324 -18.280634)
					(end 138.185144 -18.02511)
				)
				(xy 138.18743 -18.02638) (xy 138.34491 -17.732502)
				(arc
					(start 138.015472 -17.732502)
					(mid 137.634472 -18.11097)
					(end 137.253472 -17.732502)
				)
				(arc
					(start 137.253472 -17.729962)
					(mid 137.634472 -17.348962)
					(end 138.015472 -17.729962)
				)
				(xy 138.34618 -17.729962) (xy 138.937492 -16.626586)
				(arc
					(start 138.935206 -16.625316)
					(mid 138.990252 -16.483561)
					(end 139.009374 -16.332708)
				)
				(arc
					(start 138.765534 -16.332708)
					(mid 138.384534 -16.711176)
					(end 138.003534 -16.332708)
				)
				(arc
					(start 138.003534 -16.330168)
					(mid 138.384534 -15.949168)
					(end 138.765534 -16.330168)
				)
			)
		)
	)
	(zone
		(layers "F.Cu" "B.Cu" "In5.Cu")
		(hatch none 0.5)
		(connect_pads
			(clearance 0)
		)
		(min_thickness 0.25)
		(keepout
			(tracks not_allowed)
			(vias allowed)
			(pads allowed)
			(copperpour not_allowed)
			(footprints allowed)
		)
		(placement
			(enabled no)
			(sheetname "")
		)
		(fill yes
			(thermal_gap 0.5)
			(thermal_bridge_width 0.5)
			(island_removal_mode 0)
		)
		(polygon
			(pts
				(arc
					(start 158.759398 -12.530074)
					(mid 158.28656 -11.924004)
					(end 157.583632 -12.23518)
				)
				(xy 157.5816 -12.23391) (xy 156.831538 -13.633704) (xy 156.831792 -13.633958)
				(arc
					(start 156.833824 -13.634974)
					(mid 157.0895 -14.480875)
					(end 157.935422 -14.225016)
				)
				(xy 157.937454 -14.226286) (xy 158.09468 -13.932662)
				(arc
					(start 157.765496 -13.932662)
					(mid 157.384496 -14.31113)
					(end 157.003496 -13.932662)
				)
				(arc
					(start 157.003496 -13.930122)
					(mid 157.384496 -13.549122)
					(end 157.765496 -13.930122)
				)
				(xy 158.096204 -13.930122) (xy 158.687516 -12.826238)
				(arc
					(start 158.685484 -12.824968)
					(mid 158.740361 -12.683319)
					(end 158.759398 -12.532614)
				)
				(arc
					(start 158.515558 -12.532614)
					(mid 158.134558 -12.911082)
					(end 157.753558 -12.532614)
				)
				(arc
					(start 157.753558 -12.530074)
					(mid 158.134558 -12.149074)
					(end 158.515558 -12.530074)
				)
			)
		)
	)
	(zone
		(layers "F.Cu" "B.Cu" "In5.Cu")
		(hatch none 0.5)
		(connect_pads
			(clearance 0)
		)
		(min_thickness 0.25)
		(keepout
			(tracks not_allowed)
			(vias allowed)
			(pads allowed)
			(copperpour not_allowed)
			(footprints allowed)
		)
		(placement
			(enabled no)
			(sheetname "")
		)
		(fill yes
			(thermal_gap 0.5)
			(thermal_bridge_width 0.5)
			(island_removal_mode 0)
		)
		(polygon
			(pts
				(arc
					(start 289.759136 -16.330168)
					(mid 289.286298 -15.724098)
					(end 288.58337 -16.035274)
				)
				(xy 288.581338 -16.034004) (xy 287.83153 -17.433544) (xy 287.831784 -17.433798)
				(arc
					(start 287.833816 -17.434814)
					(mid 288.089492 -18.280715)
					(end 288.935414 -18.024856)
				)
				(xy 288.937446 -18.026126) (xy 289.094672 -17.732502)
				(arc
					(start 288.765488 -17.732502)
					(mid 288.384488 -18.11097)
					(end 288.003488 -17.732502)
				)
				(arc
					(start 288.003488 -17.729962)
					(mid 288.384488 -17.348962)
					(end 288.765488 -17.729962)
				)
				(xy 289.096196 -17.729962) (xy 289.687254 -16.626332)
				(arc
					(start 289.685222 -16.625062)
					(mid 289.740099 -16.483413)
					(end 289.759136 -16.332708)
				)
				(arc
					(start 289.515296 -16.332708)
					(mid 289.134296 -16.711176)
					(end 288.753296 -16.332708)
				)
				(arc
					(start 288.753296 -16.330168)
					(mid 289.134296 -15.949168)
					(end 289.515296 -16.330168)
				)
			)
		)
	)
	(zone
		(layers "F.Cu" "B.Cu" "In5.Cu")
		(hatch none 0.5)
		(connect_pads
			(clearance 0)
		)
		(min_thickness 0.25)
		(keepout
			(tracks not_allowed)
			(vias allowed)
			(pads allowed)
			(copperpour not_allowed)
			(footprints allowed)
		)
		(placement
			(enabled no)
			(sheetname "")
		)
		(fill yes
			(thermal_gap 0.5)
			(thermal_bridge_width 0.5)
			(island_removal_mode 0)
		)
		(polygon
			(pts
				(arc
					(start 169.759376 -16.330168)
					(mid 169.286705 -15.72414)
					(end 168.583864 -16.03502)
				)
				(xy 168.581578 -16.03375) (xy 167.831516 -17.433544) (xy 167.83177 -17.433798)
				(arc
					(start 167.833802 -17.434814)
					(mid 168.089326 -18.280634)
					(end 168.935146 -18.02511)
				)
				(xy 168.937432 -18.02638) (xy 169.094912 -17.732502)
				(arc
					(start 168.765474 -17.732502)
					(mid 168.384474 -18.11097)
					(end 168.003474 -17.732502)
				)
				(arc
					(start 168.003474 -17.729962)
					(mid 168.384474 -17.348962)
					(end 168.765474 -17.729962)
				)
				(xy 169.096182 -17.729962) (xy 169.687494 -16.626586)
				(arc
					(start 169.685208 -16.625316)
					(mid 169.740254 -16.483561)
					(end 169.759376 -16.332708)
				)
				(arc
					(start 169.515536 -16.332708)
					(mid 169.134536 -16.711176)
					(end 168.753536 -16.332708)
				)
				(arc
					(start 168.753536 -16.330168)
					(mid 169.134536 -15.949168)
					(end 169.515536 -16.330168)
				)
			)
		)
	)
	(zone
		(layers "F.Cu" "B.Cu" "In5.Cu")
		(hatch none 0.5)
		(connect_pads
			(clearance 0)
		)
		(min_thickness 0.25)
		(keepout
			(tracks not_allowed)
			(vias allowed)
			(pads allowed)
			(copperpour not_allowed)
			(footprints allowed)
		)
		(placement
			(enabled no)
			(sheetname "")
		)
		(fill yes
			(thermal_gap 0.5)
			(thermal_bridge_width 0.5)
			(island_removal_mode 0)
		)
		(polygon
			(pts
				(arc
					(start 311.759346 -16.330168)
					(mid 311.286675 -15.72414)
					(end 310.583834 -16.03502)
				)
				(xy 310.581548 -16.03375) (xy 309.831486 -17.433544) (xy 309.83174 -17.433798)
				(arc
					(start 309.833772 -17.434814)
					(mid 310.089296 -18.280634)
					(end 310.935116 -18.02511)
				)
				(xy 310.937402 -18.02638) (xy 311.094882 -17.732502)
				(arc
					(start 310.765444 -17.732502)
					(mid 310.384444 -18.11097)
					(end 310.003444 -17.732502)
				)
				(arc
					(start 310.003444 -17.729962)
					(mid 310.384444 -17.348962)
					(end 310.765444 -17.729962)
				)
				(xy 311.096152 -17.729962) (xy 311.687464 -16.626586)
				(arc
					(start 311.685178 -16.625316)
					(mid 311.740224 -16.483561)
					(end 311.759346 -16.332708)
				)
				(arc
					(start 311.515506 -16.332708)
					(mid 311.134506 -16.711176)
					(end 310.753506 -16.332708)
				)
				(arc
					(start 310.753506 -16.330168)
					(mid 311.134506 -15.949168)
					(end 311.515506 -16.330168)
				)
			)
		)
	)
	(zone
		(layers "F.Cu" "B.Cu" "In5.Cu")
		(hatch none 0.5)
		(connect_pads
			(clearance 0)
		)
		(min_thickness 0.25)
		(keepout
			(tracks not_allowed)
			(vias allowed)
			(pads allowed)
			(copperpour not_allowed)
			(footprints allowed)
		)
		(placement
			(enabled no)
			(sheetname "")
		)
		(fill yes
			(thermal_gap 0.5)
			(thermal_bridge_width 0.5)
			(island_removal_mode 0)
		)
		(polygon
			(pts
				(arc
					(start 314.009278 -16.330168)
					(mid 313.536607 -15.72414)
					(end 312.833766 -16.03502)
				)
				(xy 312.83148 -16.03375) (xy 312.081418 -17.433544) (xy 312.081672 -17.433798)
				(arc
					(start 312.083704 -17.434814)
					(mid 312.339228 -18.280634)
					(end 313.185048 -18.02511)
				)
				(xy 313.187334 -18.02638) (xy 313.344814 -17.732502)
				(arc
					(start 313.015376 -17.732502)
					(mid 312.634376 -18.11097)
					(end 312.253376 -17.732502)
				)
				(arc
					(start 312.253376 -17.729962)
					(mid 312.634376 -17.348962)
					(end 313.015376 -17.729962)
				)
				(xy 313.346084 -17.729962) (xy 313.937396 -16.626586)
				(arc
					(start 313.93511 -16.625316)
					(mid 313.990156 -16.483561)
					(end 314.009278 -16.332708)
				)
				(arc
					(start 313.765438 -16.332708)
					(mid 313.384438 -16.711176)
					(end 313.003438 -16.332708)
				)
				(arc
					(start 313.003438 -16.330168)
					(mid 313.384438 -15.949168)
					(end 313.765438 -16.330168)
				)
			)
		)
	)
	(zone
		(layers "F.Cu" "B.Cu" "In5.Cu")
		(hatch none 0.5)
		(connect_pads
			(clearance 0)
		)
		(min_thickness 0.25)
		(keepout
			(tracks not_allowed)
			(vias allowed)
			(pads allowed)
			(copperpour not_allowed)
			(footprints allowed)
		)
		(placement
			(enabled no)
			(sheetname "")
		)
		(fill yes
			(thermal_gap 0.5)
			(thermal_bridge_width 0.5)
			(island_removal_mode 0)
		)
		(polygon
			(pts
				(arc
					(start 169.759376 -12.530074)
					(mid 169.286538 -11.924004)
					(end 168.58361 -12.23518)
				)
				(xy 168.581578 -12.23391) (xy 167.831516 -13.633704) (xy 167.83177 -13.633958)
				(arc
					(start 167.833802 -13.634974)
					(mid 168.089478 -14.480875)
					(end 168.9354 -14.225016)
				)
				(xy 168.937432 -14.226286) (xy 169.094658 -13.932662)
				(arc
					(start 168.765474 -13.932662)
					(mid 168.384474 -14.31113)
					(end 168.003474 -13.932662)
				)
				(arc
					(start 168.003474 -13.930122)
					(mid 168.384474 -13.549122)
					(end 168.765474 -13.930122)
				)
				(xy 169.096182 -13.930122) (xy 169.687494 -12.826238)
				(arc
					(start 169.685462 -12.824968)
					(mid 169.740339 -12.683319)
					(end 169.759376 -12.532614)
				)
				(arc
					(start 169.515536 -12.532614)
					(mid 169.134536 -12.911082)
					(end 168.753536 -12.532614)
				)
				(arc
					(start 168.753536 -12.530074)
					(mid 169.134536 -12.149074)
					(end 169.515536 -12.530074)
				)
			)
		)
	)
	(zone
		(layers "F.Cu" "B.Cu" "In5.Cu")
		(hatch none 0.5)
		(connect_pads
			(clearance 0)
		)
		(min_thickness 0.25)
		(keepout
			(tracks not_allowed)
			(vias allowed)
			(pads allowed)
			(copperpour not_allowed)
			(footprints allowed)
		)
		(placement
			(enabled no)
			(sheetname "")
		)
		(fill yes
			(thermal_gap 0.5)
			(thermal_bridge_width 0.5)
			(island_removal_mode 0)
		)
		(polygon
			(pts
				(arc
					(start 325.009256 -12.530074)
					(mid 324.536418 -11.924004)
					(end 323.83349 -12.23518)
				)
				(xy 323.831458 -12.23391) (xy 323.081396 -13.633704) (xy 323.08165 -13.633958)
				(arc
					(start 323.083682 -13.634974)
					(mid 323.339358 -14.480875)
					(end 324.18528 -14.225016)
				)
				(xy 324.187312 -14.226286) (xy 324.344538 -13.932662)
				(arc
					(start 324.015354 -13.932662)
					(mid 323.634354 -14.31113)
					(end 323.253354 -13.932662)
				)
				(arc
					(start 323.253354 -13.930122)
					(mid 323.634354 -13.549122)
					(end 324.015354 -13.930122)
				)
				(xy 324.346062 -13.930122) (xy 324.937374 -12.826238)
				(arc
					(start 324.935342 -12.824968)
					(mid 324.990219 -12.683319)
					(end 325.009256 -12.532614)
				)
				(arc
					(start 324.765416 -12.532614)
					(mid 324.384416 -12.911082)
					(end 324.003416 -12.532614)
				)
				(arc
					(start 324.003416 -12.530074)
					(mid 324.384416 -12.149074)
					(end 324.765416 -12.530074)
				)
			)
		)
	)
	(zone
		(layers "F.Cu" "B.Cu" "In5.Cu")
		(hatch none 0.5)
		(connect_pads
			(clearance 0)
		)
		(min_thickness 0.25)
		(keepout
			(tracks not_allowed)
			(vias allowed)
			(pads allowed)
			(copperpour not_allowed)
			(footprints allowed)
		)
		(placement
			(enabled no)
			(sheetname "")
		)
		(fill yes
			(thermal_gap 0.5)
			(thermal_bridge_width 0.5)
			(island_removal_mode 0)
		)
		(polygon
			(pts
				(arc
					(start 161.00933 -12.530074)
					(mid 160.536492 -11.924004)
					(end 159.833564 -12.23518)
				)
				(xy 159.831532 -12.23391) (xy 159.08147 -13.633704) (xy 159.081724 -13.633958)
				(arc
					(start 159.083756 -13.634974)
					(mid 159.339432 -14.480875)
					(end 160.185354 -14.225016)
				)
				(xy 160.187386 -14.226286) (xy 160.344612 -13.932662)
				(arc
					(start 160.015428 -13.932662)
					(mid 159.634428 -14.31113)
					(end 159.253428 -13.932662)
				)
				(arc
					(start 159.253428 -13.930122)
					(mid 159.634428 -13.549122)
					(end 160.015428 -13.930122)
				)
				(xy 160.346136 -13.930122) (xy 160.937448 -12.826238)
				(arc
					(start 160.935416 -12.824968)
					(mid 160.990293 -12.683319)
					(end 161.00933 -12.532614)
				)
				(arc
					(start 160.76549 -12.532614)
					(mid 160.38449 -12.911082)
					(end 160.00349 -12.532614)
				)
				(arc
					(start 160.00349 -12.530074)
					(mid 160.38449 -12.149074)
					(end 160.76549 -12.530074)
				)
			)
		)
	)
	(zone
		(layers "F.Cu" "B.Cu" "In5.Cu")
		(hatch none 0.5)
		(connect_pads
			(clearance 0)
		)
		(min_thickness 0.25)
		(keepout
			(tracks not_allowed)
			(vias allowed)
			(pads allowed)
			(copperpour not_allowed)
			(footprints allowed)
		)
		(placement
			(enabled no)
			(sheetname "")
		)
		(fill yes
			(thermal_gap 0.5)
			(thermal_bridge_width 0.5)
			(island_removal_mode 0)
		)
		(polygon
			(pts
				(arc
					(start 292.009322 -16.330168)
					(mid 291.536651 -15.72414)
					(end 290.83381 -16.03502)
				)
				(xy 290.831524 -16.03375) (xy 290.081462 -17.433544) (xy 290.081716 -17.433798)
				(arc
					(start 290.083748 -17.434814)
					(mid 290.339272 -18.280634)
					(end 291.185092 -18.02511)
				)
				(xy 291.187378 -18.02638) (xy 291.344858 -17.732502)
				(arc
					(start 291.01542 -17.732502)
					(mid 290.63442 -18.11097)
					(end 290.25342 -17.732502)
				)
				(arc
					(start 290.25342 -17.729962)
					(mid 290.63442 -17.348962)
					(end 291.01542 -17.729962)
				)
				(xy 291.346128 -17.729962) (xy 291.93744 -16.626586)
				(arc
					(start 291.935154 -16.625316)
					(mid 291.9902 -16.483561)
					(end 292.009322 -16.332708)
				)
				(arc
					(start 291.765482 -16.332708)
					(mid 291.384482 -16.711176)
					(end 291.003482 -16.332708)
				)
				(arc
					(start 291.003482 -16.330168)
					(mid 291.384482 -15.949168)
					(end 291.765482 -16.330168)
				)
			)
		)
	)
	(zone
		(layers "F.Cu" "B.Cu" "In5.Cu")
		(hatch none 0.5)
		(connect_pads
			(clearance 0)
		)
		(min_thickness 0.25)
		(keepout
			(tracks not_allowed)
			(vias allowed)
			(pads allowed)
			(copperpour not_allowed)
			(footprints allowed)
		)
		(placement
			(enabled no)
			(sheetname "")
		)
		(fill yes
			(thermal_gap 0.5)
			(thermal_bridge_width 0.5)
			(island_removal_mode 0)
		)
		(polygon
			(pts
				(arc
					(start 136.759188 -12.530074)
					(mid 136.28635 -11.924004)
					(end 135.583422 -12.23518)
				)
				(arc
					(start 134.833614 -13.635228)
					(mid 135.089646 -14.481048)
					(end 135.935466 -14.225016)
				)
				(xy 136.09193 -13.932662)
				(arc
					(start 135.76554 -13.932662)
					(mid 135.38454 -14.31113)
					(end 135.00354 -13.932662)
				)
				(arc
					(start 135.00354 -13.930122)
					(mid 135.38454 -13.549122)
					(end 135.76554 -13.930122)
				)
				(xy 136.093454 -13.930122)
				(arc
					(start 136.68121 -12.832588)
					(mid 136.73909 -12.687512)
					(end 136.759188 -12.532614)
				)
				(arc
					(start 136.515348 -12.532614)
					(mid 136.134348 -12.911082)
					(end 135.753348 -12.532614)
				)
				(arc
					(start 135.753348 -12.530074)
					(mid 136.134348 -12.149074)
					(end 136.515348 -12.530074)
				)
			)
		)
	)
	(zone
		(layers "F.Cu" "B.Cu" "In5.Cu")
		(hatch none 0.5)
		(connect_pads
			(clearance 0)
		)
		(min_thickness 0.25)
		(keepout
			(tracks not_allowed)
			(vias allowed)
			(pads allowed)
			(copperpour not_allowed)
			(footprints allowed)
		)
		(placement
			(enabled no)
			(sheetname "")
		)
		(fill yes
			(thermal_gap 0.5)
			(thermal_bridge_width 0.5)
			(island_removal_mode 0)
		)
		(polygon
			(pts
				(arc
					(start 172.009308 -12.530074)
					(mid 171.53647 -11.924004)
					(end 170.833542 -12.23518)
				)
				(xy 170.83151 -12.23391) (xy 170.081448 -13.633704) (xy 170.081702 -13.633958)
				(arc
					(start 170.083734 -13.634974)
					(mid 170.33941 -14.480875)
					(end 171.185332 -14.225016)
				)
				(xy 171.187364 -14.226286) (xy 171.34459 -13.932662)
				(arc
					(start 171.015406 -13.932662)
					(mid 170.634406 -14.31113)
					(end 170.253406 -13.932662)
				)
				(arc
					(start 170.253406 -13.930122)
					(mid 170.634406 -13.549122)
					(end 171.015406 -13.930122)
				)
				(xy 171.346114 -13.930122) (xy 171.937426 -12.826238)
				(arc
					(start 171.935394 -12.824968)
					(mid 171.990271 -12.683319)
					(end 172.009308 -12.532614)
				)
				(arc
					(start 171.765468 -12.532614)
					(mid 171.384468 -12.911082)
					(end 171.003468 -12.532614)
				)
				(arc
					(start 171.003468 -12.530074)
					(mid 171.384468 -12.149074)
					(end 171.765468 -12.530074)
				)
			)
		)
	)
	(zone
		(layers "F.Cu" "B.Cu" "In5.Cu")
		(hatch none 0.5)
		(connect_pads
			(clearance 0)
		)
		(min_thickness 0.25)
		(keepout
			(tracks not_allowed)
			(vias allowed)
			(pads allowed)
			(copperpour not_allowed)
			(footprints allowed)
		)
		(placement
			(enabled no)
			(sheetname "")
		)
		(fill yes
			(thermal_gap 0.5)
			(thermal_bridge_width 0.5)
			(island_removal_mode 0)
		)
		(polygon
			(pts
				(arc
					(start 325.009256 -16.330168)
					(mid 324.536585 -15.72414)
					(end 323.833744 -16.03502)
				)
				(xy 323.831458 -16.03375) (xy 323.081396 -17.433544) (xy 323.08165 -17.433798)
				(arc
					(start 323.083682 -17.434814)
					(mid 323.339206 -18.280634)
					(end 324.185026 -18.02511)
				)
				(xy 324.187312 -18.02638) (xy 324.344792 -17.732502)
				(arc
					(start 324.015354 -17.732502)
					(mid 323.634354 -18.11097)
					(end 323.253354 -17.732502)
				)
				(arc
					(start 323.253354 -17.729962)
					(mid 323.634354 -17.348962)
					(end 324.015354 -17.729962)
				)
				(xy 324.346062 -17.729962) (xy 324.937374 -16.626586)
				(arc
					(start 324.935088 -16.625316)
					(mid 324.990134 -16.483561)
					(end 325.009256 -16.332708)
				)
				(arc
					(start 324.765416 -16.332708)
					(mid 324.384416 -16.711176)
					(end 324.003416 -16.332708)
				)
				(arc
					(start 324.003416 -16.330168)
					(mid 324.384416 -15.949168)
					(end 324.765416 -16.330168)
				)
			)
		)
	)
	(zone
		(layers "F.Cu" "B.Cu" "In5.Cu")
		(hatch none 0.5)
		(connect_pads
			(clearance 0)
		)
		(min_thickness 0.25)
		(keepout
			(tracks not_allowed)
			(vias allowed)
			(pads allowed)
			(copperpour not_allowed)
			(footprints allowed)
		)
		(placement
			(enabled no)
			(sheetname "")
		)
		(fill yes
			(thermal_gap 0.5)
			(thermal_bridge_width 0.5)
			(island_removal_mode 0)
		)
		(polygon
			(pts
				(arc
					(start 311.759346 -12.530074)
					(mid 311.286508 -11.924004)
					(end 310.58358 -12.23518)
				)
				(xy 310.581548 -12.23391) (xy 309.831486 -13.633704) (xy 309.83174 -13.633958)
				(arc
					(start 309.833772 -13.634974)
					(mid 310.089448 -14.480875)
					(end 310.93537 -14.225016)
				)
				(xy 310.937402 -14.226286) (xy 311.094628 -13.932662)
				(arc
					(start 310.765444 -13.932662)
					(mid 310.384444 -14.31113)
					(end 310.003444 -13.932662)
				)
				(arc
					(start 310.003444 -13.930122)
					(mid 310.384444 -13.549122)
					(end 310.765444 -13.930122)
				)
				(xy 311.096152 -13.930122) (xy 311.687464 -12.826238)
				(arc
					(start 311.685432 -12.824968)
					(mid 311.740309 -12.683319)
					(end 311.759346 -12.532614)
				)
				(arc
					(start 311.515506 -12.532614)
					(mid 311.134506 -12.911082)
					(end 310.753506 -12.532614)
				)
				(arc
					(start 310.753506 -12.530074)
					(mid 311.134506 -12.149074)
					(end 311.515506 -12.530074)
				)
			)
		)
	)
	(zone
		(layers "F.Cu" "B.Cu" "In5.Cu")
		(hatch none 0.5)
		(connect_pads
			(clearance 0)
		)
		(min_thickness 0.25)
		(keepout
			(tracks not_allowed)
			(vias allowed)
			(pads allowed)
			(copperpour not_allowed)
			(footprints allowed)
		)
		(placement
			(enabled no)
			(sheetname "")
		)
		(fill yes
			(thermal_gap 0.5)
			(thermal_bridge_width 0.5)
			(island_removal_mode 0)
		)
		(polygon
			(pts
				(arc
					(start 172.009308 -16.330168)
					(mid 171.536637 -15.72414)
					(end 170.833796 -16.03502)
				)
				(xy 170.83151 -16.03375) (xy 170.081448 -17.433544) (xy 170.081702 -17.433798)
				(arc
					(start 170.083734 -17.434814)
					(mid 170.339258 -18.280634)
					(end 171.185078 -18.02511)
				)
				(xy 171.187364 -18.02638) (xy 171.344844 -17.732502)
				(arc
					(start 171.015406 -17.732502)
					(mid 170.634406 -18.11097)
					(end 170.253406 -17.732502)
				)
				(arc
					(start 170.253406 -17.729962)
					(mid 170.634406 -17.348962)
					(end 171.015406 -17.729962)
				)
				(xy 171.346114 -17.729962) (xy 171.937426 -16.626586)
				(arc
					(start 171.93514 -16.625316)
					(mid 171.990186 -16.483561)
					(end 172.009308 -16.332708)
				)
				(arc
					(start 171.765468 -16.332708)
					(mid 171.384468 -16.711176)
					(end 171.003468 -16.332708)
				)
				(arc
					(start 171.003468 -16.330168)
					(mid 171.384468 -15.949168)
					(end 171.765468 -16.330168)
				)
			)
		)
	)
	(zone
		(layers "F.Cu" "B.Cu" "In5.Cu")
		(hatch none 0.5)
		(connect_pads
			(clearance 0)
		)
		(min_thickness 0.25)
		(keepout
			(tracks not_allowed)
			(vias allowed)
			(pads allowed)
			(copperpour not_allowed)
			(footprints allowed)
		)
		(placement
			(enabled no)
			(sheetname "")
		)
		(fill yes
			(thermal_gap 0.5)
			(thermal_bridge_width 0.5)
			(island_removal_mode 0)
		)
		(polygon
			(pts
				(arc
					(start 158.759398 -16.330168)
					(mid 158.286727 -15.72414)
					(end 157.583886 -16.03502)
				)
				(xy 157.5816 -16.03375) (xy 156.831538 -17.433544) (xy 156.831792 -17.433798)
				(arc
					(start 156.833824 -17.434814)
					(mid 157.089348 -18.280634)
					(end 157.935168 -18.02511)
				)
				(xy 157.937454 -18.02638) (xy 158.094934 -17.732502)
				(arc
					(start 157.765496 -17.732502)
					(mid 157.384496 -18.11097)
					(end 157.003496 -17.732502)
				)
				(arc
					(start 157.003496 -17.729962)
					(mid 157.384496 -17.348962)
					(end 157.765496 -17.729962)
				)
				(xy 158.096204 -17.729962) (xy 158.687516 -16.626586)
				(arc
					(start 158.68523 -16.625316)
					(mid 158.740276 -16.483561)
					(end 158.759398 -16.332708)
				)
				(arc
					(start 158.515558 -16.332708)
					(mid 158.134558 -16.711176)
					(end 157.753558 -16.332708)
				)
				(arc
					(start 157.753558 -16.330168)
					(mid 158.134558 -15.949168)
					(end 158.515558 -16.330168)
				)
			)
		)
	)
	(zone
		(layers "F.Cu" "In2.Cu" "In5.Cu")
		(hatch none 0.5)
		(connect_pads
			(clearance 0)
		)
		(min_thickness 0.25)
		(keepout
			(tracks not_allowed)
			(vias allowed)
			(pads allowed)
			(copperpour not_allowed)
			(footprints allowed)
		)
		(placement
			(enabled no)
			(sheetname "")
		)
		(fill yes
			(thermal_gap 0.5)
			(thermal_bridge_width 0.5)
			(island_removal_mode 0)
		)
		(polygon
			(pts
				(arc
					(start 292.009322 -12.530074)
					(mid 291.536484 -11.924004)
					(end 290.833556 -12.23518)
				)
				(xy 290.831524 -12.23391) (xy 290.081462 -13.633958)
				(arc
					(start 290.083494 -13.635228)
					(mid 290.339526 -14.481048)
					(end 291.185346 -14.225016)
				)
				(xy 291.187378 -14.226286) (xy 291.344604 -13.932662)
				(arc
					(start 291.01542 -13.932662)
					(mid 290.63442 -14.31113)
					(end 290.25342 -13.932662)
				)
				(arc
					(start 290.25342 -13.930122)
					(mid 290.63442 -13.549122)
					(end 291.01542 -13.930122)
				)
				(xy 291.346128 -13.930122) (xy 291.93744 -12.826492) (xy 291.937186 -12.826238)
				(arc
					(start 291.935154 -12.825222)
					(mid 291.9902 -12.683467)
					(end 292.009322 -12.532614)
				)
				(arc
					(start 291.765482 -12.532614)
					(mid 291.384482 -12.911082)
					(end 291.003482 -12.532614)
				)
				(arc
					(start 291.003482 -12.530074)
					(mid 291.384482 -12.149074)
					(end 291.765482 -12.530074)
				)
			)
		)
	)
	(zone
		(layers "F.Cu" "In2.Cu" "In5.Cu")
		(hatch none 0.5)
		(connect_pads
			(clearance 0)
		)
		(min_thickness 0.25)
		(keepout
			(tracks not_allowed)
			(vias allowed)
			(pads allowed)
			(copperpour not_allowed)
			(footprints allowed)
		)
		(placement
			(enabled no)
			(sheetname "")
		)
		(fill yes
			(thermal_gap 0.5)
			(thermal_bridge_width 0.5)
			(island_removal_mode 0)
		)
		(polygon
			(pts
				(arc
					(start 287.509204 -12.530074)
					(mid 287.036366 -11.924004)
					(end 286.333438 -12.23518)
				)
				(xy 286.331406 -12.23391) (xy 285.581344 -13.633958)
				(arc
					(start 285.583376 -13.635228)
					(mid 285.839408 -14.481048)
					(end 286.685228 -14.225016)
				)
				(xy 286.68726 -14.226286) (xy 286.844486 -13.932662)
				(arc
					(start 286.515302 -13.932662)
					(mid 286.134302 -14.31113)
					(end 285.753302 -13.932662)
				)
				(arc
					(start 285.753302 -13.930122)
					(mid 286.134302 -13.549122)
					(end 286.515302 -13.930122)
				)
				(xy 286.84601 -13.930122) (xy 287.437322 -12.826492) (xy 287.437068 -12.826238)
				(arc
					(start 287.435036 -12.825222)
					(mid 287.490082 -12.683467)
					(end 287.509204 -12.532614)
				)
				(arc
					(start 287.265364 -12.532614)
					(mid 286.884364 -12.911082)
					(end 286.503364 -12.532614)
				)
				(arc
					(start 286.503364 -12.530074)
					(mid 286.884364 -12.149074)
					(end 287.265364 -12.530074)
				)
			)
		)
	)
	(zone
		(layers "F.Cu" "In2.Cu" "In5.Cu")
		(hatch none 0.5)
		(connect_pads
			(clearance 0)
		)
		(min_thickness 0.25)
		(keepout
			(tracks not_allowed)
			(vias allowed)
			(pads allowed)
			(copperpour not_allowed)
			(footprints allowed)
		)
		(placement
			(enabled no)
			(sheetname "")
		)
		(fill yes
			(thermal_gap 0.5)
			(thermal_bridge_width 0.5)
			(island_removal_mode 0)
		)
		(polygon
			(pts
				(arc
					(start 156.509212 -12.530074)
					(mid 156.036374 -11.924004)
					(end 155.333446 -12.23518)
				)
				(arc
					(start 154.587702 -13.627608)
					(mid 154.835836 -14.479061)
					(end 155.68549 -14.225016)
				)
				(xy 155.841954 -13.932662)
				(arc
					(start 155.515564 -13.932662)
					(mid 155.134564 -14.31113)
					(end 154.753564 -13.932662)
				)
				(arc
					(start 154.753564 -13.930122)
					(mid 155.134564 -13.549122)
					(end 155.515564 -13.930122)
				)
				(xy 155.843478 -13.930122)
				(arc
					(start 156.435298 -12.824968)
					(mid 156.490175 -12.683319)
					(end 156.509212 -12.532614)
				)
				(arc
					(start 156.265372 -12.532614)
					(mid 155.884372 -12.911082)
					(end 155.503372 -12.532614)
				)
				(arc
					(start 155.503372 -12.530074)
					(mid 155.884372 -12.149074)
					(end 156.265372 -12.530074)
				)
			)
		)
	)
	(zone
		(layers "F.Cu" "In2.Cu" "In5.Cu")
		(hatch none 0.5)
		(connect_pads
			(clearance 0)
		)
		(min_thickness 0.25)
		(keepout
			(tracks not_allowed)
			(vias allowed)
			(pads allowed)
			(copperpour not_allowed)
			(footprints allowed)
		)
		(placement
			(enabled no)
			(sheetname "")
		)
		(fill yes
			(thermal_gap 0.5)
			(thermal_bridge_width 0.5)
			(island_removal_mode 0)
		)
		(polygon
			(pts
				(arc
					(start 287.509204 -23.930102)
					(mid 287.036366 -23.324032)
					(end 286.333438 -23.635208)
				)
				(xy 286.331406 -23.633938) (xy 285.581344 -25.033732) (xy 285.581598 -25.033986)
				(arc
					(start 285.58363 -25.035002)
					(mid 285.839306 -25.880903)
					(end 286.685228 -25.625044)
				)
				(xy 286.68726 -25.626314) (xy 286.844486 -25.33269)
				(arc
					(start 286.515302 -25.33269)
					(mid 286.134302 -25.711158)
					(end 285.753302 -25.33269)
				)
				(arc
					(start 285.753302 -25.33015)
					(mid 286.134302 -24.94915)
					(end 286.515302 -25.33015)
				)
				(xy 286.84601 -25.33015) (xy 287.437322 -24.226266)
				(arc
					(start 287.43529 -24.224996)
					(mid 287.490167 -24.083347)
					(end 287.509204 -23.932642)
				)
				(arc
					(start 287.265364 -23.932642)
					(mid 286.884364 -24.31111)
					(end 286.503364 -23.932642)
				)
				(arc
					(start 286.503364 -23.930102)
					(mid 286.884364 -23.549102)
					(end 287.265364 -23.930102)
				)
			)
		)
	)
	(zone
		(layers "F.Cu" "In2.Cu" "In5.Cu")
		(hatch none 0.5)
		(connect_pads
			(clearance 0)
		)
		(min_thickness 0.25)
		(keepout
			(tracks not_allowed)
			(vias allowed)
			(pads allowed)
			(copperpour not_allowed)
			(footprints allowed)
		)
		(placement
			(enabled no)
			(sheetname "")
		)
		(fill yes
			(thermal_gap 0.5)
			(thermal_bridge_width 0.5)
			(island_removal_mode 0)
		)
		(polygon
			(pts
				(arc
					(start 300.759114 -12.530074)
					(mid 300.286276 -11.924004)
					(end 299.583348 -12.23518)
				)
				(arc
					(start 298.837604 -13.627608)
					(mid 299.085738 -14.479061)
					(end 299.935392 -14.225016)
				)
				(xy 300.091856 -13.932662)
				(arc
					(start 299.765466 -13.932662)
					(mid 299.384466 -14.31113)
					(end 299.003466 -13.932662)
				)
				(arc
					(start 299.003466 -13.930122)
					(mid 299.384466 -13.549122)
					(end 299.765466 -13.930122)
				)
				(xy 300.09338 -13.930122)
				(arc
					(start 300.6852 -12.824968)
					(mid 300.740077 -12.683319)
					(end 300.759114 -12.532614)
				)
				(arc
					(start 300.515274 -12.532614)
					(mid 300.134274 -12.911082)
					(end 299.753274 -12.532614)
				)
				(arc
					(start 299.753274 -12.530074)
					(mid 300.134274 -12.149074)
					(end 300.515274 -12.530074)
				)
			)
		)
	)
	(zone
		(layers "F.Cu" "In2.Cu" "In5.Cu")
		(hatch none 0.5)
		(connect_pads
			(clearance 0)
		)
		(min_thickness 0.25)
		(keepout
			(tracks not_allowed)
			(vias allowed)
			(pads allowed)
			(copperpour not_allowed)
			(footprints allowed)
		)
		(placement
			(enabled no)
			(sheetname "")
		)
		(fill yes
			(thermal_gap 0.5)
			(thermal_bridge_width 0.5)
			(island_removal_mode 0)
		)
		(polygon
			(pts
				(arc
					(start 134.509256 -12.530074)
					(mid 134.036418 -11.924004)
					(end 133.33349 -12.23518)
				)
				(xy 133.331458 -12.23391) (xy 132.581396 -13.633958)
				(arc
					(start 132.583428 -13.635228)
					(mid 132.83946 -14.481048)
					(end 133.68528 -14.225016)
				)
				(xy 133.687312 -14.226286) (xy 133.844538 -13.932662)
				(arc
					(start 133.515354 -13.932662)
					(mid 133.134354 -14.31113)
					(end 132.753354 -13.932662)
				)
				(arc
					(start 132.753354 -13.930122)
					(mid 133.134354 -13.549122)
					(end 133.515354 -13.930122)
				)
				(xy 133.846062 -13.930122) (xy 134.437374 -12.826492) (xy 134.43712 -12.826238)
				(arc
					(start 134.435088 -12.825222)
					(mid 134.490134 -12.683467)
					(end 134.509256 -12.532614)
				)
				(arc
					(start 134.265416 -12.532614)
					(mid 133.884416 -12.911082)
					(end 133.503416 -12.532614)
				)
				(arc
					(start 133.503416 -12.530074)
					(mid 133.884416 -12.149074)
					(end 134.265416 -12.530074)
				)
			)
		)
	)
	(zone
		(layers "F.Cu" "In2.Cu" "In5.Cu")
		(hatch none 0.5)
		(connect_pads
			(clearance 0)
		)
		(min_thickness 0.25)
		(keepout
			(tracks not_allowed)
			(vias allowed)
			(pads allowed)
			(copperpour not_allowed)
			(footprints allowed)
		)
		(placement
			(enabled no)
			(sheetname "")
		)
		(fill yes
			(thermal_gap 0.5)
			(thermal_bridge_width 0.5)
			(island_removal_mode 0)
		)
		(polygon
			(pts
				(arc
					(start 309.50916 -12.530074)
					(mid 309.036322 -11.924004)
					(end 308.333394 -12.23518)
				)
				(arc
					(start 307.58765 -13.627608)
					(mid 307.835784 -14.479061)
					(end 308.685438 -14.225016)
				)
				(xy 308.841902 -13.932662)
				(arc
					(start 308.515512 -13.932662)
					(mid 308.134512 -14.31113)
					(end 307.753512 -13.932662)
				)
				(arc
					(start 307.753512 -13.930122)
					(mid 308.134512 -13.549122)
					(end 308.515512 -13.930122)
				)
				(xy 308.843426 -13.930122)
				(arc
					(start 309.435246 -12.824968)
					(mid 309.490123 -12.683319)
					(end 309.50916 -12.532614)
				)
				(arc
					(start 309.26532 -12.532614)
					(mid 308.88432 -12.911082)
					(end 308.50332 -12.532614)
				)
				(arc
					(start 308.50332 -12.530074)
					(mid 308.88432 -12.149074)
					(end 309.26532 -12.530074)
				)
			)
		)
	)
	(zone
		(layers "F.Cu" "In5.Cu")
		(hatch none 0.5)
		(connect_pads
			(clearance 0)
		)
		(min_thickness 0.25)
		(keepout
			(tracks not_allowed)
			(vias allowed)
			(pads allowed)
			(copperpour not_allowed)
			(footprints allowed)
		)
		(placement
			(enabled no)
			(sheetname "")
		)
		(fill yes
			(thermal_gap 0.5)
			(thermal_bridge_width 0.5)
			(island_removal_mode 0)
		)
		(polygon
			(pts
				(arc
					(start 96.493584 -221.784164)
					(mid 95.983044 -222.294704)
					(end 96.493584 -222.805244)
				)
				(arc
					(start 97.30613 -222.805244)
					(mid 97.666401 -222.656697)
					(end 97.816924 -222.297244)
				)
				(arc
					(start 97.573084 -222.297244)
					(mid 97.306384 -222.561416)
					(end 97.039684 -222.297244)
				)
				(arc
					(start 96.760284 -222.297244)
					(mid 96.493584 -222.561416)
					(end 96.226884 -222.297244)
				)
				(arc
					(start 96.226884 -222.294704)
					(mid 96.493584 -222.028004)
					(end 96.760284 -222.294704)
				)
				(arc
					(start 97.039684 -222.294704)
					(mid 97.306384 -222.028004)
					(end 97.573084 -222.294704)
				)
				(arc
					(start 97.816924 -222.294704)
					(mid 97.66739 -221.933698)
					(end 97.306384 -221.784164)
				)
			)
		)
	)
	(zone
		(layers "F.Cu" "In5.Cu")
		(hatch none 0.5)
		(connect_pads
			(clearance 0)
		)
		(min_thickness 0.25)
		(keepout
			(tracks not_allowed)
			(vias allowed)
			(pads allowed)
			(copperpour not_allowed)
			(footprints allowed)
		)
		(placement
			(enabled no)
			(sheetname "")
		)
		(fill yes
			(thermal_gap 0.5)
			(thermal_bridge_width 0.5)
			(island_removal_mode 0)
		)
		(polygon
			(pts
				(arc
					(start 201.69378 -221.784164)
					(mid 201.18324 -222.294704)
					(end 201.69378 -222.805244)
				)
				(arc
					(start 202.506326 -222.805244)
					(mid 202.866597 -222.656697)
					(end 203.01712 -222.297244)
				)
				(arc
					(start 202.77328 -222.297244)
					(mid 202.50658 -222.561416)
					(end 202.23988 -222.297244)
				)
				(arc
					(start 201.96048 -222.297244)
					(mid 201.69378 -222.561416)
					(end 201.42708 -222.297244)
				)
				(arc
					(start 201.42708 -222.294704)
					(mid 201.69378 -222.028004)
					(end 201.96048 -222.294704)
				)
				(arc
					(start 202.23988 -222.294704)
					(mid 202.50658 -222.028004)
					(end 202.77328 -222.294704)
				)
				(arc
					(start 203.01712 -222.294704)
					(mid 202.867586 -221.933698)
					(end 202.50658 -221.784164)
				)
			)
		)
	)
	(zone
		(layers "F.Cu" "In5.Cu")
		(hatch none 0.5)
		(connect_pads
			(clearance 0)
		)
		(min_thickness 0.25)
		(keepout
			(tracks not_allowed)
			(vias allowed)
			(pads allowed)
			(copperpour not_allowed)
			(footprints allowed)
		)
		(placement
			(enabled no)
			(sheetname "")
		)
		(fill yes
			(thermal_gap 0.5)
			(thermal_bridge_width 0.5)
			(island_removal_mode 0)
		)
		(polygon
			(pts
				(arc
					(start 65.293494 -221.784164)
					(mid 64.782954 -222.294704)
					(end 65.293494 -222.805244)
				)
				(arc
					(start 66.10604 -222.805244)
					(mid 66.466311 -222.656697)
					(end 66.616834 -222.297244)
				)
				(arc
					(start 66.372994 -222.297244)
					(mid 66.106294 -222.561416)
					(end 65.839594 -222.297244)
				)
				(arc
					(start 65.560194 -222.297244)
					(mid 65.293494 -222.561416)
					(end 65.026794 -222.297244)
				)
				(arc
					(start 65.026794 -222.294704)
					(mid 65.293494 -222.028004)
					(end 65.560194 -222.294704)
				)
				(arc
					(start 65.839594 -222.294704)
					(mid 66.106294 -222.028004)
					(end 66.372994 -222.294704)
				)
				(arc
					(start 66.616834 -222.294704)
					(mid 66.4673 -221.933698)
					(end 66.106294 -221.784164)
				)
			)
		)
	)
	(zone
		(layers "F.Cu" "In5.Cu")
		(hatch none 0.5)
		(connect_pads
			(clearance 0)
		)
		(min_thickness 0.25)
		(keepout
			(tracks not_allowed)
			(vias allowed)
			(pads allowed)
			(copperpour not_allowed)
			(footprints allowed)
		)
		(placement
			(enabled no)
			(sheetname "")
		)
		(fill yes
			(thermal_gap 0.5)
			(thermal_bridge_width 0.5)
			(island_removal_mode 0)
		)
		(polygon
			(pts
				(arc
					(start 198.493634 -221.784164)
					(mid 197.983094 -222.294704)
					(end 198.493634 -222.805244)
				)
				(arc
					(start 199.30618 -222.805244)
					(mid 199.666451 -222.656697)
					(end 199.816974 -222.297244)
				)
				(arc
					(start 199.573134 -222.297244)
					(mid 199.306434 -222.561416)
					(end 199.039734 -222.297244)
				)
				(arc
					(start 198.760334 -222.297244)
					(mid 198.493634 -222.561416)
					(end 198.226934 -222.297244)
				)
				(arc
					(start 198.226934 -222.294704)
					(mid 198.493634 -222.028004)
					(end 198.760334 -222.294704)
				)
				(arc
					(start 199.039734 -222.294704)
					(mid 199.306434 -222.028004)
					(end 199.573134 -222.294704)
				)
				(arc
					(start 199.816974 -222.294704)
					(mid 199.66744 -221.933698)
					(end 199.306434 -221.784164)
				)
			)
		)
	)
	(zone
		(layers "F.Cu" "In5.Cu")
		(hatch none 0.5)
		(connect_pads
			(clearance 0)
		)
		(min_thickness 0.25)
		(keepout
			(tracks not_allowed)
			(vias allowed)
			(pads allowed)
			(copperpour not_allowed)
			(footprints allowed)
		)
		(placement
			(enabled no)
			(sheetname "")
		)
		(fill yes
			(thermal_gap 0.5)
			(thermal_bridge_width 0.5)
			(island_removal_mode 0)
		)
		(polygon
			(pts
				(arc
					(start 50.144934 -208.201514)
					(mid 49.63414 -208.711927)
					(end 50.14468 -209.222594)
				)
				(arc
					(start 50.95748 -209.222594)
					(mid 51.317587 -209.073957)
					(end 51.46802 -208.714594)
				)
				(arc
					(start 51.22418 -208.714594)
					(mid 50.95748 -208.978766)
					(end 50.69078 -208.714594)
				)
				(arc
					(start 50.41138 -208.714594)
					(mid 50.14468 -208.978766)
					(end 49.87798 -208.714594)
				)
				(arc
					(start 49.87798 -208.712054)
					(mid 50.14468 -208.445354)
					(end 50.41138 -208.712054)
				)
				(arc
					(start 50.69078 -208.712054)
					(mid 50.95748 -208.445354)
					(end 51.22418 -208.712054)
				)
				(arc
					(start 51.46802 -208.712054)
					(mid 51.318486 -208.351048)
					(end 50.95748 -208.201514)
				)
			)
		)
	)
	(zone
		(layers "F.Cu" "In5.Cu")
		(hatch none 0.5)
		(connect_pads
			(clearance 0)
		)
		(min_thickness 0.25)
		(keepout
			(tracks not_allowed)
			(vias allowed)
			(pads allowed)
			(copperpour not_allowed)
			(footprints allowed)
		)
		(placement
			(enabled no)
			(sheetname "")
		)
		(fill yes
			(thermal_gap 0.5)
			(thermal_bridge_width 0.5)
			(island_removal_mode 0)
		)
		(polygon
			(pts
				(arc
					(start 334.093566 -221.784164)
					(mid 333.583026 -222.294704)
					(end 334.093566 -222.805244)
				)
				(arc
					(start 334.906112 -222.805244)
					(mid 335.266383 -222.656697)
					(end 335.416906 -222.297244)
				)
				(arc
					(start 335.173066 -222.297244)
					(mid 334.906366 -222.561416)
					(end 334.639666 -222.297244)
				)
				(arc
					(start 334.360266 -222.297244)
					(mid 334.093566 -222.561416)
					(end 333.826866 -222.297244)
				)
				(arc
					(start 333.826866 -222.294704)
					(mid 334.093566 -222.028004)
					(end 334.360266 -222.294704)
				)
				(arc
					(start 334.639666 -222.294704)
					(mid 334.906366 -222.028004)
					(end 335.173066 -222.294704)
				)
				(arc
					(start 335.416906 -222.294704)
					(mid 335.267372 -221.933698)
					(end 334.906366 -221.784164)
				)
			)
		)
	)
	(zone
		(layers "F.Cu" "In5.Cu")
		(hatch none 0.5)
		(connect_pads
			(clearance 0)
		)
		(min_thickness 0.25)
		(keepout
			(tracks not_allowed)
			(vias allowed)
			(pads allowed)
			(copperpour not_allowed)
			(footprints allowed)
		)
		(placement
			(enabled no)
			(sheetname "")
		)
		(fill yes
			(thermal_gap 0.5)
			(thermal_bridge_width 0.5)
			(island_removal_mode 0)
		)
		(polygon
			(pts
				(arc
					(start 282.09367 -221.784164)
					(mid 281.58313 -222.294704)
					(end 282.09367 -222.805244)
				)
				(arc
					(start 282.906216 -222.805244)
					(mid 283.266487 -222.656697)
					(end 283.41701 -222.297244)
				)
				(arc
					(start 283.17317 -222.297244)
					(mid 282.90647 -222.561416)
					(end 282.63977 -222.297244)
				)
				(arc
					(start 282.36037 -222.297244)
					(mid 282.09367 -222.561416)
					(end 281.82697 -222.297244)
				)
				(arc
					(start 281.82697 -222.294704)
					(mid 282.09367 -222.028004)
					(end 282.36037 -222.294704)
				)
				(arc
					(start 282.63977 -222.294704)
					(mid 282.90647 -222.028004)
					(end 283.17317 -222.294704)
				)
				(arc
					(start 283.41701 -222.294704)
					(mid 283.267476 -221.933698)
					(end 282.90647 -221.784164)
				)
			)
		)
	)
	(zone
		(layers "F.Cu" "In5.Cu")
		(hatch none 0.5)
		(connect_pads
			(clearance 0)
		)
		(min_thickness 0.25)
		(keepout
			(tracks not_allowed)
			(vias allowed)
			(pads allowed)
			(copperpour not_allowed)
			(footprints allowed)
		)
		(placement
			(enabled no)
			(sheetname "")
		)
		(fill yes
			(thermal_gap 0.5)
			(thermal_bridge_width 0.5)
			(island_removal_mode 0)
		)
		(polygon
			(pts
				(arc
					(start 288.493708 -221.784164)
					(mid 287.983168 -222.294704)
					(end 288.493708 -222.805244)
				)
				(arc
					(start 289.306254 -222.805244)
					(mid 289.666525 -222.656697)
					(end 289.817048 -222.297244)
				)
				(arc
					(start 289.573208 -222.297244)
					(mid 289.306508 -222.561416)
					(end 289.039808 -222.297244)
				)
				(arc
					(start 288.760408 -222.297244)
					(mid 288.493708 -222.561416)
					(end 288.227008 -222.297244)
				)
				(arc
					(start 288.227008 -222.294704)
					(mid 288.493708 -222.028004)
					(end 288.760408 -222.294704)
				)
				(arc
					(start 289.039808 -222.294704)
					(mid 289.306508 -222.028004)
					(end 289.573208 -222.294704)
				)
				(arc
					(start 289.817048 -222.294704)
					(mid 289.667514 -221.933698)
					(end 289.306508 -221.784164)
				)
			)
		)
	)
	(zone
		(layers "F.Cu" "In5.Cu")
		(hatch none 0.5)
		(connect_pads
			(clearance 0)
		)
		(min_thickness 0.25)
		(keepout
			(tracks not_allowed)
			(vias allowed)
			(pads allowed)
			(copperpour not_allowed)
			(footprints allowed)
		)
		(placement
			(enabled no)
			(sheetname "")
		)
		(fill yes
			(thermal_gap 0.5)
			(thermal_bridge_width 0.5)
			(island_removal_mode 0)
		)
		(polygon
			(pts
				(arc
					(start 59.693302 -221.784164)
					(mid 59.182762 -222.294704)
					(end 59.693302 -222.805244)
				)
				(arc
					(start 60.505848 -222.805244)
					(mid 60.866119 -222.656697)
					(end 61.016642 -222.297244)
				)
				(arc
					(start 60.772802 -222.297244)
					(mid 60.506102 -222.561416)
					(end 60.239402 -222.297244)
				)
				(arc
					(start 59.960002 -222.297244)
					(mid 59.693302 -222.561416)
					(end 59.426602 -222.297244)
				)
				(arc
					(start 59.426602 -222.294704)
					(mid 59.693302 -222.028004)
					(end 59.960002 -222.294704)
				)
				(arc
					(start 60.239402 -222.294704)
					(mid 60.506102 -222.028004)
					(end 60.772802 -222.294704)
				)
				(arc
					(start 61.016642 -222.294704)
					(mid 60.867108 -221.933698)
					(end 60.506102 -221.784164)
				)
			)
		)
	)
	(zone
		(layers "F.Cu" "In5.Cu")
		(hatch none 0.5)
		(connect_pads
			(clearance 0)
		)
		(min_thickness 0.25)
		(keepout
			(tracks not_allowed)
			(vias allowed)
			(pads allowed)
			(copperpour not_allowed)
			(footprints allowed)
		)
		(placement
			(enabled no)
			(sheetname "")
		)
		(fill yes
			(thermal_gap 0.5)
			(thermal_bridge_width 0.5)
			(island_removal_mode 0)
		)
		(polygon
			(pts
				(arc
					(start 140.0937 -221.784164)
					(mid 139.58316 -222.294704)
					(end 140.0937 -222.805244)
				)
				(arc
					(start 140.906246 -222.805244)
					(mid 141.266517 -222.656697)
					(end 141.41704 -222.297244)
				)
				(arc
					(start 141.1732 -222.297244)
					(mid 140.9065 -222.561416)
					(end 140.6398 -222.297244)
				)
				(arc
					(start 140.3604 -222.297244)
					(mid 140.0937 -222.561416)
					(end 139.827 -222.297244)
				)
				(arc
					(start 139.827 -222.294704)
					(mid 140.0937 -222.028004)
					(end 140.3604 -222.294704)
				)
				(arc
					(start 140.6398 -222.294704)
					(mid 140.9065 -222.028004)
					(end 141.1732 -222.294704)
				)
				(arc
					(start 141.41704 -222.294704)
					(mid 141.267506 -221.933698)
					(end 140.9065 -221.784164)
				)
			)
		)
	)
	(zone
		(layers "F.Cu" "In5.Cu")
		(hatch none 0.5)
		(connect_pads
			(clearance 0)
		)
		(min_thickness 0.25)
		(keepout
			(tracks not_allowed)
			(vias allowed)
			(pads allowed)
			(copperpour not_allowed)
			(footprints allowed)
		)
		(placement
			(enabled no)
			(sheetname "")
		)
		(fill yes
			(thermal_gap 0.5)
			(thermal_bridge_width 0.5)
			(island_removal_mode 0)
		)
		(polygon
			(pts
				(arc
					(start 185.693812 -221.784164)
					(mid 185.183018 -222.294577)
					(end 185.693558 -222.805244)
				)
				(arc
					(start 186.506358 -222.805244)
					(mid 186.866465 -222.656607)
					(end 187.016898 -222.297244)
				)
				(arc
					(start 186.773058 -222.297244)
					(mid 186.506358 -222.561416)
					(end 186.239658 -222.297244)
				)
				(arc
					(start 185.960258 -222.297244)
					(mid 185.693558 -222.561416)
					(end 185.426858 -222.297244)
				)
				(arc
					(start 185.426858 -222.294704)
					(mid 185.693558 -222.028004)
					(end 185.960258 -222.294704)
				)
				(arc
					(start 186.239658 -222.294704)
					(mid 186.506358 -222.028004)
					(end 186.773058 -222.294704)
				)
				(arc
					(start 187.016898 -222.294704)
					(mid 186.867364 -221.933698)
					(end 186.506358 -221.784164)
				)
			)
		)
	)
	(zone
		(layers "F.Cu" "In5.Cu")
		(hatch none 0.5)
		(connect_pads
			(clearance 0)
		)
		(min_thickness 0.25)
		(keepout
			(tracks not_allowed)
			(vias allowed)
			(pads allowed)
			(copperpour not_allowed)
			(footprints allowed)
		)
		(placement
			(enabled no)
			(sheetname "")
		)
		(fill yes
			(thermal_gap 0.5)
			(thermal_bridge_width 0.5)
			(island_removal_mode 0)
		)
		(polygon
			(pts
				(arc
					(start 143.293592 -221.784164)
					(mid 142.783052 -222.294704)
					(end 143.293592 -222.805244)
				)
				(arc
					(start 144.106138 -222.805244)
					(mid 144.466409 -222.656697)
					(end 144.616932 -222.297244)
				)
				(arc
					(start 144.373092 -222.297244)
					(mid 144.106392 -222.561416)
					(end 143.839692 -222.297244)
				)
				(arc
					(start 143.560292 -222.297244)
					(mid 143.293592 -222.561416)
					(end 143.026892 -222.297244)
				)
				(arc
					(start 143.026892 -222.294704)
					(mid 143.293592 -222.028004)
					(end 143.560292 -222.294704)
				)
				(arc
					(start 143.839692 -222.294704)
					(mid 144.106392 -222.028004)
					(end 144.373092 -222.294704)
				)
				(arc
					(start 144.616932 -222.294704)
					(mid 144.467398 -221.933698)
					(end 144.106392 -221.784164)
				)
			)
		)
	)
	(zone
		(layers "F.Cu" "In5.Cu")
		(hatch none 0.5)
		(connect_pads
			(clearance 0)
		)
		(min_thickness 0.25)
		(keepout
			(tracks not_allowed)
			(vias allowed)
			(pads allowed)
			(copperpour not_allowed)
			(footprints allowed)
		)
		(placement
			(enabled no)
			(sheetname "")
		)
		(fill yes
			(thermal_gap 0.5)
			(thermal_bridge_width 0.5)
			(island_removal_mode 0)
		)
		(polygon
			(pts
				(arc
					(start 159.29356 -221.784164)
					(mid 158.78302 -222.294704)
					(end 159.29356 -222.805244)
				)
				(arc
					(start 160.106106 -222.805244)
					(mid 160.466377 -222.656697)
					(end 160.6169 -222.297244)
				)
				(arc
					(start 160.37306 -222.297244)
					(mid 160.10636 -222.561416)
					(end 159.83966 -222.297244)
				)
				(arc
					(start 159.56026 -222.297244)
					(mid 159.29356 -222.561416)
					(end 159.02686 -222.297244)
				)
				(arc
					(start 159.02686 -222.294704)
					(mid 159.29356 -222.028004)
					(end 159.56026 -222.294704)
				)
				(arc
					(start 159.83966 -222.294704)
					(mid 160.10636 -222.028004)
					(end 160.37306 -222.294704)
				)
				(arc
					(start 160.6169 -222.294704)
					(mid 160.467366 -221.933698)
					(end 160.10636 -221.784164)
				)
			)
		)
	)
	(zone
		(layers "F.Cu" "In5.Cu")
		(hatch none 0.5)
		(connect_pads
			(clearance 0)
		)
		(min_thickness 0.25)
		(keepout
			(tracks not_allowed)
			(vias allowed)
			(pads allowed)
			(copperpour not_allowed)
			(footprints allowed)
		)
		(placement
			(enabled no)
			(sheetname "")
		)
		(fill yes
			(thermal_gap 0.5)
			(thermal_bridge_width 0.5)
			(island_removal_mode 0)
		)
		(polygon
			(pts
				(arc
					(start 71.7042 -219.50426)
					(mid 71.19366 -220.0148)
					(end 71.7042 -220.52534)
				)
				(arc
					(start 72.516746 -220.52534)
					(mid 72.877017 -220.376793)
					(end 73.02754 -220.01734)
				)
				(arc
					(start 72.7837 -220.01734)
					(mid 72.517 -220.281512)
					(end 72.2503 -220.01734)
				)
				(arc
					(start 71.9709 -220.01734)
					(mid 71.7042 -220.281512)
					(end 71.4375 -220.01734)
				)
				(arc
					(start 71.4375 -220.0148)
					(mid 71.7042 -219.7481)
					(end 71.9709 -220.0148)
				)
				(arc
					(start 72.2503 -220.0148)
					(mid 72.517 -219.7481)
					(end 72.7837 -220.0148)
				)
				(arc
					(start 73.02754 -220.0148)
					(mid 72.878006 -219.653794)
					(end 72.517 -219.50426)
				)
			)
		)
	)
	(zone
		(layers "F.Cu" "In5.Cu")
		(hatch none 0.5)
		(connect_pads
			(clearance 0)
		)
		(min_thickness 0.25)
		(keepout
			(tracks not_allowed)
			(vias allowed)
			(pads allowed)
			(copperpour not_allowed)
			(footprints allowed)
		)
		(placement
			(enabled no)
			(sheetname "")
		)
		(fill yes
			(thermal_gap 0.5)
			(thermal_bridge_width 0.5)
			(island_removal_mode 0)
		)
		(polygon
			(pts
				(arc
					(start 291.6936 -221.784164)
					(mid 291.18306 -222.294704)
					(end 291.6936 -222.805244)
				)
				(arc
					(start 292.506146 -222.805244)
					(mid 292.866417 -222.656697)
					(end 293.01694 -222.297244)
				)
				(arc
					(start 292.7731 -222.297244)
					(mid 292.5064 -222.561416)
					(end 292.2397 -222.297244)
				)
				(arc
					(start 291.9603 -222.297244)
					(mid 291.6936 -222.561416)
					(end 291.4269 -222.297244)
				)
				(arc
					(start 291.4269 -222.294704)
					(mid 291.6936 -222.028004)
					(end 291.9603 -222.294704)
				)
				(arc
					(start 292.2397 -222.294704)
					(mid 292.5064 -222.028004)
					(end 292.7731 -222.294704)
				)
				(arc
					(start 293.01694 -222.294704)
					(mid 292.867406 -221.933698)
					(end 292.5064 -221.784164)
				)
			)
		)
	)
	(zone
		(layers "F.Cu" "In5.Cu")
		(hatch none 0.5)
		(connect_pads
			(clearance 0)
		)
		(min_thickness 0.25)
		(keepout
			(tracks not_allowed)
			(vias allowed)
			(pads allowed)
			(copperpour not_allowed)
			(footprints allowed)
		)
		(placement
			(enabled no)
			(sheetname "")
		)
		(fill yes
			(thermal_gap 0.5)
			(thermal_bridge_width 0.5)
			(island_removal_mode 0)
		)
		(polygon
			(pts
				(arc
					(start 183.63057 -7.89559)
					(mid 183.12003 -8.40613)
					(end 183.63057 -8.91667)
				)
				(arc
					(start 184.443116 -8.91667)
					(mid 184.803387 -8.768123)
					(end 184.95391 -8.40867)
				)
				(arc
					(start 184.71007 -8.40867)
					(mid 184.44337 -8.672842)
					(end 184.17667 -8.40867)
				)
				(arc
					(start 183.89727 -8.40867)
					(mid 183.63057 -8.672842)
					(end 183.36387 -8.40867)
				)
				(arc
					(start 183.36387 -8.40613)
					(mid 183.63057 -8.13943)
					(end 183.89727 -8.40613)
				)
				(arc
					(start 184.17667 -8.40613)
					(mid 184.44337 -8.13943)
					(end 184.71007 -8.40613)
				)
				(arc
					(start 184.95391 -8.40613)
					(mid 184.804376 -8.045124)
					(end 184.44337 -7.89559)
				)
			)
		)
	)
	(zone
		(layers "F.Cu" "In5.Cu")
		(hatch none 0.5)
		(connect_pads
			(clearance 0)
		)
		(min_thickness 0.25)
		(keepout
			(tracks not_allowed)
			(vias allowed)
			(pads allowed)
			(copperpour not_allowed)
			(footprints allowed)
		)
		(placement
			(enabled no)
			(sheetname "")
		)
		(fill yes
			(thermal_gap 0.5)
			(thermal_bridge_width 0.5)
			(island_removal_mode 0)
		)
		(polygon
			(pts
				(arc
					(start 324.493636 -221.784164)
					(mid 323.983096 -222.294704)
					(end 324.493636 -222.805244)
				)
				(arc
					(start 325.306182 -222.805244)
					(mid 325.666453 -222.656697)
					(end 325.816976 -222.297244)
				)
				(arc
					(start 325.573136 -222.297244)
					(mid 325.306436 -222.561416)
					(end 325.039736 -222.297244)
				)
				(arc
					(start 324.760336 -222.297244)
					(mid 324.493636 -222.561416)
					(end 324.226936 -222.297244)
				)
				(arc
					(start 324.226936 -222.294704)
					(mid 324.493636 -222.028004)
					(end 324.760336 -222.294704)
				)
				(arc
					(start 325.039736 -222.294704)
					(mid 325.306436 -222.028004)
					(end 325.573136 -222.294704)
				)
				(arc
					(start 325.816976 -222.294704)
					(mid 325.667442 -221.933698)
					(end 325.306436 -221.784164)
				)
			)
		)
	)
	(zone
		(layers "F.Cu" "In5.Cu")
		(hatch none 0.5)
		(connect_pads
			(clearance 0)
		)
		(min_thickness 0.25)
		(keepout
			(tracks not_allowed)
			(vias allowed)
			(pads allowed)
			(copperpour not_allowed)
			(footprints allowed)
		)
		(placement
			(enabled no)
			(sheetname "")
		)
		(fill yes
			(thermal_gap 0.5)
			(thermal_bridge_width 0.5)
			(island_removal_mode 0)
		)
		(polygon
			(pts
				(arc
					(start 318.093598 -221.784164)
					(mid 317.583058 -222.294704)
					(end 318.093598 -222.805244)
				)
				(arc
					(start 318.906144 -222.805244)
					(mid 319.266415 -222.656697)
					(end 319.416938 -222.297244)
				)
				(arc
					(start 319.173098 -222.297244)
					(mid 318.906398 -222.561416)
					(end 318.639698 -222.297244)
				)
				(arc
					(start 318.360298 -222.297244)
					(mid 318.093598 -222.561416)
					(end 317.826898 -222.297244)
				)
				(arc
					(start 317.826898 -222.294704)
					(mid 318.093598 -222.028004)
					(end 318.360298 -222.294704)
				)
				(arc
					(start 318.639698 -222.294704)
					(mid 318.906398 -222.028004)
					(end 319.173098 -222.294704)
				)
				(arc
					(start 319.416938 -222.294704)
					(mid 319.267404 -221.933698)
					(end 318.906398 -221.784164)
				)
			)
		)
	)
	(zone
		(layers "F.Cu" "In5.Cu")
		(hatch none 0.5)
		(connect_pads
			(clearance 0)
		)
		(min_thickness 0.25)
		(keepout
			(tracks not_allowed)
			(vias allowed)
			(pads allowed)
			(copperpour not_allowed)
			(footprints allowed)
		)
		(placement
			(enabled no)
			(sheetname "")
		)
		(fill yes
			(thermal_gap 0.5)
			(thermal_bridge_width 0.5)
			(island_removal_mode 0)
		)
		(polygon
			(pts
				(arc
					(start 168.093644 -221.784164)
					(mid 167.583104 -222.294704)
					(end 168.093644 -222.805244)
				)
				(arc
					(start 168.90619 -222.805244)
					(mid 169.266461 -222.656697)
					(end 169.416984 -222.297244)
				)
				(arc
					(start 169.173144 -222.297244)
					(mid 168.906444 -222.561416)
					(end 168.639744 -222.297244)
				)
				(arc
					(start 168.360344 -222.297244)
					(mid 168.093644 -222.561416)
					(end 167.826944 -222.297244)
				)
				(arc
					(start 167.826944 -222.294704)
					(mid 168.093644 -222.028004)
					(end 168.360344 -222.294704)
				)
				(arc
					(start 168.639744 -222.294704)
					(mid 168.906444 -222.028004)
					(end 169.173144 -222.294704)
				)
				(arc
					(start 169.416984 -222.294704)
					(mid 169.26745 -221.933698)
					(end 168.906444 -221.784164)
				)
			)
		)
	)
	(zone
		(layers "F.Cu" "In5.Cu")
		(hatch none 0.5)
		(connect_pads
			(clearance 0)
		)
		(min_thickness 0.25)
		(keepout
			(tracks not_allowed)
			(vias allowed)
			(pads allowed)
			(copperpour not_allowed)
			(footprints allowed)
		)
		(placement
			(enabled no)
			(sheetname "")
		)
		(fill yes
			(thermal_gap 0.5)
			(thermal_bridge_width 0.5)
			(island_removal_mode 0)
		)
		(polygon
			(pts
				(arc
					(start 78.16977 -219.371164)
					(mid 77.65923 -219.881704)
					(end 78.16977 -220.392244)
				)
				(arc
					(start 78.982316 -220.392244)
					(mid 79.342587 -220.243697)
					(end 79.49311 -219.884244)
				)
				(arc
					(start 79.24927 -219.884244)
					(mid 78.98257 -220.148416)
					(end 78.71587 -219.884244)
				)
				(arc
					(start 78.43647 -219.884244)
					(mid 78.16977 -220.148416)
					(end 77.90307 -219.884244)
				)
				(arc
					(start 77.90307 -219.881704)
					(mid 78.16977 -219.615004)
					(end 78.43647 -219.881704)
				)
				(arc
					(start 78.71587 -219.881704)
					(mid 78.98257 -219.615004)
					(end 79.24927 -219.881704)
				)
				(arc
					(start 79.49311 -219.881704)
					(mid 79.343576 -219.520698)
					(end 78.98257 -219.371164)
				)
			)
		)
	)
	(zone
		(layers "F.Cu" "In5.Cu")
		(hatch none 0.5)
		(connect_pads
			(clearance 0)
		)
		(min_thickness 0.25)
		(keepout
			(tracks not_allowed)
			(vias allowed)
			(pads allowed)
			(copperpour not_allowed)
			(footprints allowed)
		)
		(placement
			(enabled no)
			(sheetname "")
		)
		(fill yes
			(thermal_gap 0.5)
			(thermal_bridge_width 0.5)
			(island_removal_mode 0)
		)
		(polygon
			(pts
				(arc
					(start 177.5968 -220.16466)
					(mid 177.08626 -220.6752)
					(end 177.5968 -221.18574)
				)
				(arc
					(start 178.409346 -221.18574)
					(mid 178.769617 -221.037193)
					(end 178.92014 -220.67774)
				)
				(arc
					(start 178.6763 -220.67774)
					(mid 178.4096 -220.941912)
					(end 178.1429 -220.67774)
				)
				(arc
					(start 177.8635 -220.67774)
					(mid 177.5968 -220.941912)
					(end 177.3301 -220.67774)
				)
				(arc
					(start 177.3301 -220.6752)
					(mid 177.5968 -220.4085)
					(end 177.8635 -220.6752)
				)
				(arc
					(start 178.1429 -220.6752)
					(mid 178.4096 -220.4085)
					(end 178.6763 -220.6752)
				)
				(arc
					(start 178.92014 -220.6752)
					(mid 178.770606 -220.314194)
					(end 178.4096 -220.16466)
				)
			)
		)
	)
	(zone
		(layers "F.Cu" "In5.Cu")
		(hatch none 0.5)
		(connect_pads
			(clearance 0)
		)
		(min_thickness 0.25)
		(keepout
			(tracks not_allowed)
			(vias allowed)
			(pads allowed)
			(copperpour not_allowed)
			(footprints allowed)
		)
		(placement
			(enabled no)
			(sheetname "")
		)
		(fill yes
			(thermal_gap 0.5)
			(thermal_bridge_width 0.5)
			(island_removal_mode 0)
		)
		(polygon
			(pts
				(arc
					(start 214.493602 -221.784164)
					(mid 213.983062 -222.294704)
					(end 214.493602 -222.805244)
				)
				(arc
					(start 215.306148 -222.805244)
					(mid 215.666419 -222.656697)
					(end 215.816942 -222.297244)
				)
				(arc
					(start 215.573102 -222.297244)
					(mid 215.306402 -222.561416)
					(end 215.039702 -222.297244)
				)
				(arc
					(start 214.760302 -222.297244)
					(mid 214.493602 -222.561416)
					(end 214.226902 -222.297244)
				)
				(arc
					(start 214.226902 -222.294704)
					(mid 214.493602 -222.028004)
					(end 214.760302 -222.294704)
				)
				(arc
					(start 215.039702 -222.294704)
					(mid 215.306402 -222.028004)
					(end 215.573102 -222.294704)
				)
				(arc
					(start 215.816942 -222.294704)
					(mid 215.667408 -221.933698)
					(end 215.306402 -221.784164)
				)
			)
		)
	)
	(zone
		(layers "F.Cu" "In5.Cu")
		(hatch none 0.5)
		(connect_pads
			(clearance 0)
		)
		(min_thickness 0.25)
		(keepout
			(tracks not_allowed)
			(vias allowed)
			(pads allowed)
			(copperpour not_allowed)
			(footprints allowed)
		)
		(placement
			(enabled no)
			(sheetname "")
		)
		(fill yes
			(thermal_gap 0.5)
			(thermal_bridge_width 0.5)
			(island_removal_mode 0)
		)
		(polygon
			(pts
				(arc
					(start 136.893554 -221.784164)
					(mid 136.383014 -222.294704)
					(end 136.893554 -222.805244)
				)
				(arc
					(start 137.7061 -222.805244)
					(mid 138.066371 -222.656697)
					(end 138.216894 -222.297244)
				)
				(arc
					(start 137.973054 -222.297244)
					(mid 137.706354 -222.561416)
					(end 137.439654 -222.297244)
				)
				(arc
					(start 137.160254 -222.297244)
					(mid 136.893554 -222.561416)
					(end 136.626854 -222.297244)
				)
				(arc
					(start 136.626854 -222.294704)
					(mid 136.893554 -222.028004)
					(end 137.160254 -222.294704)
				)
				(arc
					(start 137.439654 -222.294704)
					(mid 137.706354 -222.028004)
					(end 137.973054 -222.294704)
				)
				(arc
					(start 138.216894 -222.294704)
					(mid 138.06736 -221.933698)
					(end 137.706354 -221.784164)
				)
			)
		)
	)
	(zone
		(layers "F.Cu" "In5.Cu")
		(hatch none 0.5)
		(connect_pads
			(clearance 0)
		)
		(min_thickness 0.25)
		(keepout
			(tracks not_allowed)
			(vias allowed)
			(pads allowed)
			(copperpour not_allowed)
			(footprints allowed)
		)
		(placement
			(enabled no)
			(sheetname "")
		)
		(fill yes
			(thermal_gap 0.5)
			(thermal_bridge_width 0.5)
			(island_removal_mode 0)
		)
		(polygon
			(pts
				(arc
					(start 202.946254 -49.27346)
					(mid 202.43546 -49.783873)
					(end 202.946 -50.29454)
				)
				(arc
					(start 203.7588 -50.29454)
					(mid 204.118907 -50.145903)
					(end 204.26934 -49.78654)
				)
				(arc
					(start 204.0255 -49.78654)
					(mid 203.7588 -50.050712)
					(end 203.4921 -49.78654)
				)
				(arc
					(start 203.2127 -49.78654)
					(mid 202.946 -50.050712)
					(end 202.6793 -49.78654)
				)
				(arc
					(start 202.6793 -49.784)
					(mid 202.946 -49.5173)
					(end 203.2127 -49.784)
				)
				(arc
					(start 203.4921 -49.784)
					(mid 203.7588 -49.5173)
					(end 204.0255 -49.784)
				)
				(arc
					(start 204.26934 -49.784)
					(mid 204.119806 -49.422994)
					(end 203.7588 -49.27346)
				)
			)
		)
	)
	(zone
		(layers "F.Cu" "In5.Cu")
		(hatch none 0.5)
		(connect_pads
			(clearance 0)
		)
		(min_thickness 0.25)
		(keepout
			(tracks not_allowed)
			(vias allowed)
			(pads allowed)
			(copperpour not_allowed)
			(footprints allowed)
		)
		(placement
			(enabled no)
			(sheetname "")
		)
		(fill yes
			(thermal_gap 0.5)
			(thermal_bridge_width 0.5)
			(island_removal_mode 0)
		)
		(polygon
			(pts
				(arc
					(start 146.493738 -221.784164)
					(mid 145.983198 -222.294704)
					(end 146.493738 -222.805244)
				)
				(arc
					(start 147.306284 -222.805244)
					(mid 147.666555 -222.656697)
					(end 147.817078 -222.297244)
				)
				(arc
					(start 147.573238 -222.297244)
					(mid 147.306538 -222.561416)
					(end 147.039838 -222.297244)
				)
				(arc
					(start 146.760438 -222.297244)
					(mid 146.493738 -222.561416)
					(end 146.227038 -222.297244)
				)
				(arc
					(start 146.227038 -222.294704)
					(mid 146.493738 -222.028004)
					(end 146.760438 -222.294704)
				)
				(arc
					(start 147.039838 -222.294704)
					(mid 147.306538 -222.028004)
					(end 147.573238 -222.294704)
				)
				(arc
					(start 147.817078 -222.294704)
					(mid 147.667544 -221.933698)
					(end 147.306538 -221.784164)
				)
			)
		)
	)
	(zone
		(layers "F.Cu" "In5.Cu")
		(hatch none 0.5)
		(connect_pads
			(clearance 0)
		)
		(min_thickness 0.25)
		(keepout
			(tracks not_allowed)
			(vias allowed)
			(pads allowed)
			(copperpour not_allowed)
			(footprints allowed)
		)
		(placement
			(enabled no)
			(sheetname "")
		)
		(fill yes
			(thermal_gap 0.5)
			(thermal_bridge_width 0.5)
			(island_removal_mode 0)
		)
		(polygon
			(pts
				(arc
					(start 192.093596 -221.784164)
					(mid 191.583056 -222.294704)
					(end 192.093596 -222.805244)
				)
				(arc
					(start 192.906142 -222.805244)
					(mid 193.266413 -222.656697)
					(end 193.416936 -222.297244)
				)
				(arc
					(start 193.173096 -222.297244)
					(mid 192.906396 -222.561416)
					(end 192.639696 -222.297244)
				)
				(arc
					(start 192.360296 -222.297244)
					(mid 192.093596 -222.561416)
					(end 191.826896 -222.297244)
				)
				(arc
					(start 191.826896 -222.294704)
					(mid 192.093596 -222.028004)
					(end 192.360296 -222.294704)
				)
				(arc
					(start 192.639696 -222.294704)
					(mid 192.906396 -222.028004)
					(end 193.173096 -222.294704)
				)
				(arc
					(start 193.416936 -222.294704)
					(mid 193.267402 -221.933698)
					(end 192.906396 -221.784164)
				)
			)
		)
	)
	(zone
		(layers "F.Cu" "In5.Cu")
		(hatch none 0.5)
		(connect_pads
			(clearance 0)
		)
		(min_thickness 0.25)
		(keepout
			(tracks not_allowed)
			(vias allowed)
			(pads allowed)
			(copperpour not_allowed)
			(footprints allowed)
		)
		(placement
			(enabled no)
			(sheetname "")
		)
		(fill yes
			(thermal_gap 0.5)
			(thermal_bridge_width 0.5)
			(island_removal_mode 0)
		)
		(polygon
			(pts
				(arc
					(start 195.293742 -221.784164)
					(mid 194.783202 -222.294704)
					(end 195.293742 -222.805244)
				)
				(arc
					(start 196.106288 -222.805244)
					(mid 196.466559 -222.656697)
					(end 196.617082 -222.297244)
				)
				(arc
					(start 196.373242 -222.297244)
					(mid 196.106542 -222.561416)
					(end 195.839842 -222.297244)
				)
				(arc
					(start 195.560442 -222.297244)
					(mid 195.293742 -222.561416)
					(end 195.027042 -222.297244)
				)
				(arc
					(start 195.027042 -222.294704)
					(mid 195.293742 -222.028004)
					(end 195.560442 -222.294704)
				)
				(arc
					(start 195.839842 -222.294704)
					(mid 196.106542 -222.028004)
					(end 196.373242 -222.294704)
				)
				(arc
					(start 196.617082 -222.294704)
					(mid 196.467548 -221.933698)
					(end 196.106542 -221.784164)
				)
			)
		)
	)
	(zone
		(layers "F.Cu" "In5.Cu")
		(hatch none 0.5)
		(connect_pads
			(clearance 0)
		)
		(min_thickness 0.25)
		(keepout
			(tracks not_allowed)
			(vias allowed)
			(pads allowed)
			(copperpour not_allowed)
			(footprints allowed)
		)
		(placement
			(enabled no)
			(sheetname "")
		)
		(fill yes
			(thermal_gap 0.5)
			(thermal_bridge_width 0.5)
			(island_removal_mode 0)
		)
		(polygon
			(pts
				(arc
					(start 275.693632 -221.784164)
					(mid 275.183092 -222.294704)
					(end 275.693632 -222.805244)
				)
				(arc
					(start 276.506178 -222.805244)
					(mid 276.866449 -222.656697)
					(end 277.016972 -222.297244)
				)
				(arc
					(start 276.773132 -222.297244)
					(mid 276.506432 -222.561416)
					(end 276.239732 -222.297244)
				)
				(arc
					(start 275.960332 -222.297244)
					(mid 275.693632 -222.561416)
					(end 275.426932 -222.297244)
				)
				(arc
					(start 275.426932 -222.294704)
					(mid 275.693632 -222.028004)
					(end 275.960332 -222.294704)
				)
				(arc
					(start 276.239732 -222.294704)
					(mid 276.506432 -222.028004)
					(end 276.773132 -222.294704)
				)
				(arc
					(start 277.016972 -222.294704)
					(mid 276.867438 -221.933698)
					(end 276.506432 -221.784164)
				)
			)
		)
	)
	(zone
		(layers "F.Cu" "In5.Cu")
		(hatch none 0.5)
		(connect_pads
			(clearance 0)
		)
		(min_thickness 0.25)
		(keepout
			(tracks not_allowed)
			(vias allowed)
			(pads allowed)
			(copperpour not_allowed)
			(footprints allowed)
		)
		(placement
			(enabled no)
			(sheetname "")
		)
		(fill yes
			(thermal_gap 0.5)
			(thermal_bridge_width 0.5)
			(island_removal_mode 0)
		)
		(polygon
			(pts
				(arc
					(start 56.49341 -221.784164)
					(mid 55.98287 -222.294704)
					(end 56.49341 -222.805244)
				)
				(arc
					(start 57.305956 -222.805244)
					(mid 57.666227 -222.656697)
					(end 57.81675 -222.297244)
				)
				(arc
					(start 57.57291 -222.297244)
					(mid 57.30621 -222.561416)
					(end 57.03951 -222.297244)
				)
				(arc
					(start 56.76011 -222.297244)
					(mid 56.49341 -222.561416)
					(end 56.22671 -222.297244)
				)
				(arc
					(start 56.22671 -222.294704)
					(mid 56.49341 -222.028004)
					(end 56.76011 -222.294704)
				)
				(arc
					(start 57.03951 -222.294704)
					(mid 57.30621 -222.028004)
					(end 57.57291 -222.294704)
				)
				(arc
					(start 57.81675 -222.294704)
					(mid 57.667216 -221.933698)
					(end 57.30621 -221.784164)
				)
			)
		)
	)
	(zone
		(layers "F.Cu" "In5.Cu")
		(hatch none 0.5)
		(connect_pads
			(clearance 0)
		)
		(min_thickness 0.25)
		(keepout
			(tracks not_allowed)
			(vias allowed)
			(pads allowed)
			(copperpour not_allowed)
			(footprints allowed)
		)
		(placement
			(enabled no)
			(sheetname "")
		)
		(fill yes
			(thermal_gap 0.5)
			(thermal_bridge_width 0.5)
			(island_removal_mode 0)
		)
		(polygon
			(pts
				(arc
					(start 68.493386 -221.784164)
					(mid 67.982846 -222.294704)
					(end 68.493386 -222.805244)
				)
				(arc
					(start 69.305932 -222.805244)
					(mid 69.666203 -222.656697)
					(end 69.816726 -222.297244)
				)
				(arc
					(start 69.572886 -222.297244)
					(mid 69.306186 -222.561416)
					(end 69.039486 -222.297244)
				)
				(arc
					(start 68.760086 -222.297244)
					(mid 68.493386 -222.561416)
					(end 68.226686 -222.297244)
				)
				(arc
					(start 68.226686 -222.294704)
					(mid 68.493386 -222.028004)
					(end 68.760086 -222.294704)
				)
				(arc
					(start 69.039486 -222.294704)
					(mid 69.306186 -222.028004)
					(end 69.572886 -222.294704)
				)
				(arc
					(start 69.816726 -222.294704)
					(mid 69.667192 -221.933698)
					(end 69.306186 -221.784164)
				)
			)
		)
	)
	(zone
		(layers "F.Cu" "In5.Cu")
		(hatch none 0.5)
		(connect_pads
			(clearance 0)
		)
		(min_thickness 0.25)
		(keepout
			(tracks not_allowed)
			(vias allowed)
			(pads allowed)
			(copperpour not_allowed)
			(footprints allowed)
		)
		(placement
			(enabled no)
			(sheetname "")
		)
		(fill yes
			(thermal_gap 0.5)
			(thermal_bridge_width 0.5)
			(island_removal_mode 0)
		)
		(polygon
			(pts
				(arc
					(start 327.693782 -221.784164)
					(mid 327.183242 -222.294704)
					(end 327.693782 -222.805244)
				)
				(arc
					(start 328.506328 -222.805244)
					(mid 328.866599 -222.656697)
					(end 329.017122 -222.297244)
				)
				(arc
					(start 328.773282 -222.297244)
					(mid 328.506582 -222.561416)
					(end 328.239882 -222.297244)
				)
				(arc
					(start 327.960482 -222.297244)
					(mid 327.693782 -222.561416)
					(end 327.427082 -222.297244)
				)
				(arc
					(start 327.427082 -222.294704)
					(mid 327.693782 -222.028004)
					(end 327.960482 -222.294704)
				)
				(arc
					(start 328.239882 -222.294704)
					(mid 328.506582 -222.028004)
					(end 328.773282 -222.294704)
				)
				(arc
					(start 329.017122 -222.294704)
					(mid 328.867588 -221.933698)
					(end 328.506582 -221.784164)
				)
			)
		)
	)
	(zone
		(layers "F.Cu" "In5.Cu")
		(hatch none 0.5)
		(connect_pads
			(clearance 0)
		)
		(min_thickness 0.25)
		(keepout
			(tracks not_allowed)
			(vias allowed)
			(pads allowed)
			(copperpour not_allowed)
			(footprints allowed)
		)
		(placement
			(enabled no)
			(sheetname "")
		)
		(fill yes
			(thermal_gap 0.5)
			(thermal_bridge_width 0.5)
			(island_removal_mode 0)
		)
		(polygon
			(pts
				(arc
					(start 314.893706 -221.784164)
					(mid 314.383166 -222.294704)
					(end 314.893706 -222.805244)
				)
				(arc
					(start 315.706252 -222.805244)
					(mid 316.066523 -222.656697)
					(end 316.217046 -222.297244)
				)
				(arc
					(start 315.973206 -222.297244)
					(mid 315.706506 -222.561416)
					(end 315.439806 -222.297244)
				)
				(arc
					(start 315.160406 -222.297244)
					(mid 314.893706 -222.561416)
					(end 314.627006 -222.297244)
				)
				(arc
					(start 314.627006 -222.294704)
					(mid 314.893706 -222.028004)
					(end 315.160406 -222.294704)
				)
				(arc
					(start 315.439806 -222.294704)
					(mid 315.706506 -222.028004)
					(end 315.973206 -222.294704)
				)
				(arc
					(start 316.217046 -222.294704)
					(mid 316.067512 -221.933698)
					(end 315.706506 -221.784164)
				)
			)
		)
	)
	(zone
		(layers "F.Cu" "In5.Cu")
		(hatch none 0.5)
		(connect_pads
			(clearance 0)
		)
		(min_thickness 0.25)
		(keepout
			(tracks not_allowed)
			(vias allowed)
			(pads allowed)
			(copperpour not_allowed)
			(footprints allowed)
		)
		(placement
			(enabled no)
			(sheetname "")
		)
		(fill yes
			(thermal_gap 0.5)
			(thermal_bridge_width 0.5)
			(island_removal_mode 0)
		)
		(polygon
			(pts
				(arc
					(start 53.293518 -221.784164)
					(mid 52.782978 -222.294704)
					(end 53.293518 -222.805244)
				)
				(arc
					(start 54.106064 -222.805244)
					(mid 54.466335 -222.656697)
					(end 54.616858 -222.297244)
				)
				(arc
					(start 54.373018 -222.297244)
					(mid 54.106318 -222.561416)
					(end 53.839618 -222.297244)
				)
				(arc
					(start 53.560218 -222.297244)
					(mid 53.293518 -222.561416)
					(end 53.026818 -222.297244)
				)
				(arc
					(start 53.026818 -222.294704)
					(mid 53.293518 -222.028004)
					(end 53.560218 -222.294704)
				)
				(arc
					(start 53.839618 -222.294704)
					(mid 54.106318 -222.028004)
					(end 54.373018 -222.294704)
				)
				(arc
					(start 54.616858 -222.294704)
					(mid 54.467324 -221.933698)
					(end 54.106318 -221.784164)
				)
			)
		)
	)
	(zone
		(layers "F.Cu" "In5.Cu")
		(hatch none 0.5)
		(connect_pads
			(clearance 0)
		)
		(min_thickness 0.25)
		(keepout
			(tracks not_allowed)
			(vias allowed)
			(pads allowed)
			(copperpour not_allowed)
			(footprints allowed)
		)
		(placement
			(enabled no)
			(sheetname "")
		)
		(fill yes
			(thermal_gap 0.5)
			(thermal_bridge_width 0.5)
			(island_removal_mode 0)
		)
		(polygon
			(pts
				(arc
					(start 106.093514 -221.784164)
					(mid 105.582974 -222.294704)
					(end 106.093514 -222.805244)
				)
				(arc
					(start 106.90606 -222.805244)
					(mid 107.266331 -222.656697)
					(end 107.416854 -222.297244)
				)
				(arc
					(start 107.173014 -222.297244)
					(mid 106.906314 -222.561416)
					(end 106.639614 -222.297244)
				)
				(arc
					(start 106.360214 -222.297244)
					(mid 106.093514 -222.561416)
					(end 105.826814 -222.297244)
				)
				(arc
					(start 105.826814 -222.294704)
					(mid 106.093514 -222.028004)
					(end 106.360214 -222.294704)
				)
				(arc
					(start 106.639614 -222.294704)
					(mid 106.906314 -222.028004)
					(end 107.173014 -222.294704)
				)
				(arc
					(start 107.416854 -222.294704)
					(mid 107.26732 -221.933698)
					(end 106.906314 -221.784164)
				)
			)
		)
	)
	(zone
		(layers "F.Cu" "In5.Cu")
		(hatch none 0.5)
		(connect_pads
			(clearance 0)
		)
		(min_thickness 0.25)
		(keepout
			(tracks not_allowed)
			(vias allowed)
			(pads allowed)
			(copperpour not_allowed)
			(footprints allowed)
		)
		(placement
			(enabled no)
			(sheetname "")
		)
		(fill yes
			(thermal_gap 0.5)
			(thermal_bridge_width 0.5)
			(island_removal_mode 0)
		)
		(polygon
			(pts
				(arc
					(start 93.38945 -183.13146)
					(mid 92.87891 -183.642)
					(end 93.38945 -184.15254)
				)
				(arc
					(start 94.201996 -184.15254)
					(mid 94.562267 -184.003993)
					(end 94.71279 -183.64454)
				)
				(arc
					(start 94.46895 -183.64454)
					(mid 94.20225 -183.908712)
					(end 93.93555 -183.64454)
				)
				(arc
					(start 93.65615 -183.64454)
					(mid 93.38945 -183.908712)
					(end 93.12275 -183.64454)
				)
				(arc
					(start 93.12275 -183.642)
					(mid 93.38945 -183.3753)
					(end 93.65615 -183.642)
				)
				(arc
					(start 93.93555 -183.642)
					(mid 94.20225 -183.3753)
					(end 94.46895 -183.642)
				)
				(arc
					(start 94.71279 -183.642)
					(mid 94.563256 -183.280994)
					(end 94.20225 -183.13146)
				)
			)
		)
	)
	(zone
		(layers "F.Cu" "In5.Cu")
		(hatch none 0.5)
		(connect_pads
			(clearance 0)
		)
		(min_thickness 0.25)
		(keepout
			(tracks not_allowed)
			(vias allowed)
			(pads allowed)
			(copperpour not_allowed)
			(footprints allowed)
		)
		(placement
			(enabled no)
			(sheetname "")
		)
		(fill yes
			(thermal_gap 0.5)
			(thermal_bridge_width 0.5)
			(island_removal_mode 0)
		)
		(polygon
			(pts
				(arc
					(start 156.093668 -221.784164)
					(mid 155.583128 -222.294704)
					(end 156.093668 -222.805244)
				)
				(arc
					(start 156.906214 -222.805244)
					(mid 157.266485 -222.656697)
					(end 157.417008 -222.297244)
				)
				(arc
					(start 157.173168 -222.297244)
					(mid 156.906468 -222.561416)
					(end 156.639768 -222.297244)
				)
				(arc
					(start 156.360368 -222.297244)
					(mid 156.093668 -222.561416)
					(end 155.826968 -222.297244)
				)
				(arc
					(start 155.826968 -222.294704)
					(mid 156.093668 -222.028004)
					(end 156.360368 -222.294704)
				)
				(arc
					(start 156.639768 -222.294704)
					(mid 156.906468 -222.028004)
					(end 157.173168 -222.294704)
				)
				(arc
					(start 157.417008 -222.294704)
					(mid 157.267474 -221.933698)
					(end 156.906468 -221.784164)
				)
			)
		)
	)
	(zone
		(layers "F.Cu" "In5.Cu")
		(hatch none 0.5)
		(connect_pads
			(clearance 0)
		)
		(min_thickness 0.25)
		(keepout
			(tracks not_allowed)
			(vias allowed)
			(pads allowed)
			(copperpour not_allowed)
			(footprints allowed)
		)
		(placement
			(enabled no)
			(sheetname "")
		)
		(fill yes
			(thermal_gap 0.5)
			(thermal_bridge_width 0.5)
			(island_removal_mode 0)
		)
		(polygon
			(pts
				(arc
					(start 337.293712 -221.784164)
					(mid 336.783172 -222.294704)
					(end 337.293712 -222.805244)
				)
				(arc
					(start 338.106258 -222.805244)
					(mid 338.466529 -222.656697)
					(end 338.617052 -222.297244)
				)
				(arc
					(start 338.373212 -222.297244)
					(mid 338.106512 -222.561416)
					(end 337.839812 -222.297244)
				)
				(arc
					(start 337.560412 -222.297244)
					(mid 337.293712 -222.561416)
					(end 337.027012 -222.297244)
				)
				(arc
					(start 337.027012 -222.294704)
					(mid 337.293712 -222.028004)
					(end 337.560412 -222.294704)
				)
				(arc
					(start 337.839812 -222.294704)
					(mid 338.106512 -222.028004)
					(end 338.373212 -222.294704)
				)
				(arc
					(start 338.617052 -222.294704)
					(mid 338.467518 -221.933698)
					(end 338.106512 -221.784164)
				)
			)
		)
	)
	(zone
		(layers "F.Cu" "In5.Cu")
		(hatch none 0.5)
		(connect_pads
			(clearance 0)
		)
		(min_thickness 0.25)
		(keepout
			(tracks not_allowed)
			(vias allowed)
			(pads allowed)
			(copperpour not_allowed)
			(footprints allowed)
		)
		(placement
			(enabled no)
			(sheetname "")
		)
		(fill yes
			(thermal_gap 0.5)
			(thermal_bridge_width 0.5)
			(island_removal_mode 0)
		)
		(polygon
			(pts
				(arc
					(start 81.293462 -221.784164)
					(mid 80.782922 -222.294704)
					(end 81.293462 -222.805244)
				)
				(arc
					(start 82.106008 -222.805244)
					(mid 82.466279 -222.656697)
					(end 82.616802 -222.297244)
				)
				(arc
					(start 82.372962 -222.297244)
					(mid 82.106262 -222.561416)
					(end 81.839562 -222.297244)
				)
				(arc
					(start 81.560162 -222.297244)
					(mid 81.293462 -222.561416)
					(end 81.026762 -222.297244)
				)
				(arc
					(start 81.026762 -222.294704)
					(mid 81.293462 -222.028004)
					(end 81.560162 -222.294704)
				)
				(arc
					(start 81.839562 -222.294704)
					(mid 82.106262 -222.028004)
					(end 82.372962 -222.294704)
				)
				(arc
					(start 82.616802 -222.294704)
					(mid 82.467268 -221.933698)
					(end 82.106262 -221.784164)
				)
			)
		)
	)
	(zone
		(layers "F.Cu" "In5.Cu")
		(hatch none 0.5)
		(connect_pads
			(clearance 0)
		)
		(min_thickness 0.25)
		(keepout
			(tracks not_allowed)
			(vias allowed)
			(pads allowed)
			(copperpour not_allowed)
			(footprints allowed)
		)
		(placement
			(enabled no)
			(sheetname "")
		)
		(fill yes
			(thermal_gap 0.5)
			(thermal_bridge_width 0.5)
			(island_removal_mode 0)
		)
		(polygon
			(pts
				(arc
					(start 278.893778 -221.784164)
					(mid 278.383238 -222.294704)
					(end 278.893778 -222.805244)
				)
				(arc
					(start 279.706324 -222.805244)
					(mid 280.066595 -222.656697)
					(end 280.217118 -222.297244)
				)
				(arc
					(start 279.973278 -222.297244)
					(mid 279.706578 -222.561416)
					(end 279.439878 -222.297244)
				)
				(arc
					(start 279.160478 -222.297244)
					(mid 278.893778 -222.561416)
					(end 278.627078 -222.297244)
				)
				(arc
					(start 278.627078 -222.294704)
					(mid 278.893778 -222.028004)
					(end 279.160478 -222.294704)
				)
				(arc
					(start 279.439878 -222.294704)
					(mid 279.706578 -222.028004)
					(end 279.973278 -222.294704)
				)
				(arc
					(start 280.217118 -222.294704)
					(mid 280.067584 -221.933698)
					(end 279.706578 -221.784164)
				)
			)
		)
	)
	(zone
		(layers "F.Cu" "In5.Cu")
		(hatch none 0.5)
		(connect_pads
			(clearance 0)
		)
		(min_thickness 0.25)
		(keepout
			(tracks not_allowed)
			(vias allowed)
			(pads allowed)
			(copperpour not_allowed)
			(footprints allowed)
		)
		(placement
			(enabled no)
			(sheetname "")
		)
		(fill yes
			(thermal_gap 0.5)
			(thermal_bridge_width 0.5)
			(island_removal_mode 0)
		)
		(polygon
			(pts
				(arc
					(start 99.693476 -221.784164)
					(mid 99.182936 -222.294704)
					(end 99.693476 -222.805244)
				)
				(arc
					(start 100.506022 -222.805244)
					(mid 100.866293 -222.656697)
					(end 101.016816 -222.297244)
				)
				(arc
					(start 100.772976 -222.297244)
					(mid 100.506276 -222.561416)
					(end 100.239576 -222.297244)
				)
				(arc
					(start 99.960176 -222.297244)
					(mid 99.693476 -222.561416)
					(end 99.426776 -222.297244)
				)
				(arc
					(start 99.426776 -222.294704)
					(mid 99.693476 -222.028004)
					(end 99.960176 -222.294704)
				)
				(arc
					(start 100.239576 -222.294704)
					(mid 100.506276 -222.028004)
					(end 100.772976 -222.294704)
				)
				(arc
					(start 101.016816 -222.294704)
					(mid 100.867282 -221.933698)
					(end 100.506276 -221.784164)
				)
			)
		)
	)
	(zone
		(layers "F.Cu" "In5.Cu")
		(hatch none 0.5)
		(connect_pads
			(clearance 0)
		)
		(min_thickness 0.25)
		(keepout
			(tracks not_allowed)
			(vias allowed)
			(pads allowed)
			(copperpour not_allowed)
			(footprints allowed)
		)
		(placement
			(enabled no)
			(sheetname "")
		)
		(fill yes
			(thermal_gap 0.5)
			(thermal_bridge_width 0.5)
			(island_removal_mode 0)
		)
		(polygon
			(pts
				(arc
					(start 102.893368 -221.784164)
					(mid 102.382828 -222.294704)
					(end 102.893368 -222.805244)
				)
				(arc
					(start 103.705914 -222.805244)
					(mid 104.066185 -222.656697)
					(end 104.216708 -222.297244)
				)
				(arc
					(start 103.972868 -222.297244)
					(mid 103.706168 -222.561416)
					(end 103.439468 -222.297244)
				)
				(arc
					(start 103.160068 -222.297244)
					(mid 102.893368 -222.561416)
					(end 102.626668 -222.297244)
				)
				(arc
					(start 102.626668 -222.294704)
					(mid 102.893368 -222.028004)
					(end 103.160068 -222.294704)
				)
				(arc
					(start 103.439468 -222.294704)
					(mid 103.706168 -222.028004)
					(end 103.972868 -222.294704)
				)
				(arc
					(start 104.216708 -222.294704)
					(mid 104.067174 -221.933698)
					(end 103.706168 -221.784164)
				)
			)
		)
	)
	(zone
		(layers "F.Cu" "In5.Cu")
		(hatch none 0.5)
		(connect_pads
			(clearance 0)
		)
		(min_thickness 0.25)
		(keepout
			(tracks not_allowed)
			(vias allowed)
			(pads allowed)
			(copperpour not_allowed)
			(footprints allowed)
		)
		(placement
			(enabled no)
			(sheetname "")
		)
		(fill yes
			(thermal_gap 0.5)
			(thermal_bridge_width 0.5)
			(island_removal_mode 0)
		)
		(polygon
			(pts
				(arc
					(start 266.093702 -221.784164)
					(mid 265.583162 -222.294704)
					(end 266.093702 -222.805244)
				)
				(arc
					(start 266.906248 -222.805244)
					(mid 267.266519 -222.656697)
					(end 267.417042 -222.297244)
				)
				(arc
					(start 267.173202 -222.297244)
					(mid 266.906502 -222.561416)
					(end 266.639802 -222.297244)
				)
				(arc
					(start 266.360402 -222.297244)
					(mid 266.093702 -222.561416)
					(end 265.827002 -222.297244)
				)
				(arc
					(start 265.827002 -222.294704)
					(mid 266.093702 -222.028004)
					(end 266.360402 -222.294704)
				)
				(arc
					(start 266.639802 -222.294704)
					(mid 266.906502 -222.028004)
					(end 267.173202 -222.294704)
				)
				(arc
					(start 267.417042 -222.294704)
					(mid 267.267508 -221.933698)
					(end 266.906502 -221.784164)
				)
			)
		)
	)
	(zone
		(layers "F.Cu" "In5.Cu")
		(hatch none 0.5)
		(connect_pads
			(clearance 0)
		)
		(min_thickness 0.25)
		(keepout
			(tracks not_allowed)
			(vias allowed)
			(pads allowed)
			(copperpour not_allowed)
			(footprints allowed)
		)
		(placement
			(enabled no)
			(sheetname "")
		)
		(fill yes
			(thermal_gap 0.5)
			(thermal_bridge_width 0.5)
			(island_removal_mode 0)
		)
		(polygon
			(pts
				(arc
					(start 164.893752 -221.784164)
					(mid 164.383212 -222.294704)
					(end 164.893752 -222.805244)
				)
				(arc
					(start 165.706298 -222.805244)
					(mid 166.066569 -222.656697)
					(end 166.217092 -222.297244)
				)
				(arc
					(start 165.973252 -222.297244)
					(mid 165.706552 -222.561416)
					(end 165.439852 -222.297244)
				)
				(arc
					(start 165.160452 -222.297244)
					(mid 164.893752 -222.561416)
					(end 164.627052 -222.297244)
				)
				(arc
					(start 164.627052 -222.294704)
					(mid 164.893752 -222.028004)
					(end 165.160452 -222.294704)
				)
				(arc
					(start 165.439852 -222.294704)
					(mid 165.706552 -222.028004)
					(end 165.973252 -222.294704)
				)
				(arc
					(start 166.217092 -222.294704)
					(mid 166.067558 -221.933698)
					(end 165.706552 -221.784164)
				)
			)
		)
	)
	(zone
		(layers "F.Cu" "In5.Cu")
		(hatch none 0.5)
		(connect_pads
			(clearance 0)
		)
		(min_thickness 0.25)
		(keepout
			(tracks not_allowed)
			(vias allowed)
			(pads allowed)
			(copperpour not_allowed)
			(footprints allowed)
		)
		(placement
			(enabled no)
			(sheetname "")
		)
		(fill yes
			(thermal_gap 0.5)
			(thermal_bridge_width 0.5)
			(island_removal_mode 0)
		)
		(polygon
			(pts
				(xy 304.529998 -219.755974) (xy 303.717198 -219.781374)
				(arc
					(start 303.717198 -219.783914)
					(mid 303.222914 -220.310202)
					(end 303.749202 -220.804486)
				)
				(xy 303.749202 -220.807026) (xy 304.561748 -220.781626) (xy 304.562002 -220.781372)
				(arc
					(start 304.562002 -220.779086)
					(mid 304.911733 -220.625012)
					(end 305.05654 -220.27134)
				)
				(arc
					(start 304.8127 -220.27134)
					(mid 304.558724 -220.534957)
					(end 304.280824 -220.29674)
				)
				(arc
					(start 303.9999 -220.29674)
					(mid 303.7332 -220.560912)
					(end 303.4665 -220.29674)
				)
				(arc
					(start 303.4665 -220.2942)
					(mid 303.7332 -220.0275)
					(end 303.9999 -220.2942)
				)
				(xy 304.28057 -220.2942) (xy 304.2793 -220.27134)
				(arc
					(start 304.2793 -220.2688)
					(mid 304.546 -220.0021)
					(end 304.8127 -220.2688)
				)
				(arc
					(start 305.05654 -220.2688)
					(mid 304.901304 -219.90218)
					(end 304.529998 -219.758514)
				)
			)
		)
	)
	(zone
		(layers "F.Cu" "In5.Cu")
		(hatch none 0.5)
		(connect_pads
			(clearance 0)
		)
		(min_thickness 0.25)
		(keepout
			(tracks not_allowed)
			(vias allowed)
			(pads allowed)
			(copperpour not_allowed)
			(footprints allowed)
		)
		(placement
			(enabled no)
			(sheetname "")
		)
		(fill yes
			(thermal_gap 0.5)
			(thermal_bridge_width 0.5)
			(island_removal_mode 0)
		)
		(polygon
			(pts
				(arc
					(start 174.493682 -221.784164)
					(mid 173.983142 -222.294704)
					(end 174.493682 -222.805244)
				)
				(arc
					(start 175.306228 -222.805244)
					(mid 175.666499 -222.656697)
					(end 175.817022 -222.297244)
				)
				(arc
					(start 175.573182 -222.297244)
					(mid 175.306482 -222.561416)
					(end 175.039782 -222.297244)
				)
				(arc
					(start 174.760382 -222.297244)
					(mid 174.493682 -222.561416)
					(end 174.226982 -222.297244)
				)
				(arc
					(start 174.226982 -222.294704)
					(mid 174.493682 -222.028004)
					(end 174.760382 -222.294704)
				)
				(arc
					(start 175.039782 -222.294704)
					(mid 175.306482 -222.028004)
					(end 175.573182 -222.294704)
				)
				(arc
					(start 175.817022 -222.294704)
					(mid 175.667488 -221.933698)
					(end 175.306482 -221.784164)
				)
			)
		)
	)
	(zone
		(layers "F.Cu" "In5.Cu")
		(hatch none 0.5)
		(connect_pads
			(clearance 0)
		)
		(min_thickness 0.25)
		(keepout
			(tracks not_allowed)
			(vias allowed)
			(pads allowed)
			(copperpour not_allowed)
			(footprints allowed)
		)
		(placement
			(enabled no)
			(sheetname "")
		)
		(fill yes
			(thermal_gap 0.5)
			(thermal_bridge_width 0.5)
			(island_removal_mode 0)
		)
		(polygon
			(pts
				(arc
					(start 185.069226 -11.696954)
					(mid 184.558686 -11.186414)
					(end 184.048146 -11.696954)
				)
				(arc
					(start 184.048146 -12.509754)
					(mid 184.557416 -13.020292)
					(end 185.069226 -12.512294)
				)
				(arc
					(start 184.825386 -12.512294)
					(mid 184.558686 -12.776466)
					(end 184.291986 -12.512294)
				)
				(arc
					(start 184.291986 -12.509754)
					(mid 184.558686 -12.243054)
					(end 184.825386 -12.509754)
				)
				(xy 185.069226 -12.509754) (xy 185.069226 -11.699494)
				(arc
					(start 184.825386 -11.699494)
					(mid 184.558686 -11.963666)
					(end 184.291986 -11.699494)
				)
				(arc
					(start 184.291986 -11.696954)
					(mid 184.558686 -11.430254)
					(end 184.825386 -11.696954)
				)
			)
		)
	)
	(zone
		(layers "F.Cu" "In5.Cu")
		(hatch none 0.5)
		(connect_pads
			(clearance 0)
		)
		(min_thickness 0.25)
		(keepout
			(tracks not_allowed)
			(vias allowed)
			(pads allowed)
			(copperpour not_allowed)
			(footprints allowed)
		)
		(placement
			(enabled no)
			(sheetname "")
		)
		(fill yes
			(thermal_gap 0.5)
			(thermal_bridge_width 0.5)
			(island_removal_mode 0)
		)
		(polygon
			(pts
				(arc
					(start 270.05534 -5.305552)
					(mid 269.5448 -4.795012)
					(end 269.03426 -5.305552)
				)
				(arc
					(start 269.03426 -6.118352)
					(mid 269.54353 -6.62889)
					(end 270.05534 -6.120892)
				)
				(arc
					(start 269.8115 -6.120892)
					(mid 269.5448 -6.385064)
					(end 269.2781 -6.120892)
				)
				(arc
					(start 269.2781 -6.118352)
					(mid 269.5448 -5.851652)
					(end 269.8115 -6.118352)
				)
				(xy 270.05534 -6.118352) (xy 270.05534 -5.308092)
				(arc
					(start 269.8115 -5.308092)
					(mid 269.5448 -5.572264)
					(end 269.2781 -5.308092)
				)
				(arc
					(start 269.2781 -5.305552)
					(mid 269.5448 -5.038852)
					(end 269.8115 -5.305552)
				)
			)
		)
	)
	(zone
		(layers "F.Cu" "In5.Cu")
		(hatch none 0.5)
		(connect_pads
			(clearance 0)
		)
		(min_thickness 0.25)
		(keepout
			(tracks not_allowed)
			(vias allowed)
			(pads allowed)
			(copperpour not_allowed)
			(footprints allowed)
		)
		(placement
			(enabled no)
			(sheetname "")
		)
		(fill yes
			(thermal_gap 0.5)
			(thermal_bridge_width 0.5)
			(island_removal_mode 0)
		)
		(polygon
			(pts
				(arc
					(start 211.29371 -221.784164)
					(mid 210.78317 -222.294704)
					(end 211.29371 -222.805244)
				)
				(arc
					(start 212.106256 -222.805244)
					(mid 212.466527 -222.656697)
					(end 212.61705 -222.297244)
				)
				(arc
					(start 212.37321 -222.297244)
					(mid 212.10651 -222.561416)
					(end 211.83981 -222.297244)
				)
				(arc
					(start 211.56041 -222.297244)
					(mid 211.29371 -222.561416)
					(end 211.02701 -222.297244)
				)
				(arc
					(start 211.02701 -222.294704)
					(mid 211.29371 -222.028004)
					(end 211.56041 -222.294704)
				)
				(arc
					(start 211.83981 -222.294704)
					(mid 212.10651 -222.028004)
					(end 212.37321 -222.294704)
				)
				(arc
					(start 212.61705 -222.294704)
					(mid 212.467516 -221.933698)
					(end 212.10651 -221.784164)
				)
			)
		)
	)
	(zone
		(layers "F.Cu" "In5.Cu")
		(hatch none 0.5)
		(connect_pads
			(clearance 0)
		)
		(min_thickness 0.25)
		(keepout
			(tracks not_allowed)
			(vias allowed)
			(pads allowed)
			(copperpour not_allowed)
			(footprints allowed)
		)
		(placement
			(enabled no)
			(sheetname "")
		)
		(fill yes
			(thermal_gap 0.5)
			(thermal_bridge_width 0.5)
			(island_removal_mode 0)
		)
		(polygon
			(pts
				(arc
					(start 204.893672 -221.784164)
					(mid 204.383132 -222.294704)
					(end 204.893672 -222.805244)
				)
				(arc
					(start 205.706218 -222.805244)
					(mid 206.066489 -222.656697)
					(end 206.217012 -222.297244)
				)
				(arc
					(start 205.973172 -222.297244)
					(mid 205.706472 -222.561416)
					(end 205.439772 -222.297244)
				)
				(arc
					(start 205.160372 -222.297244)
					(mid 204.893672 -222.561416)
					(end 204.626972 -222.297244)
				)
				(arc
					(start 204.626972 -222.294704)
					(mid 204.893672 -222.028004)
					(end 205.160372 -222.294704)
				)
				(arc
					(start 205.439772 -222.294704)
					(mid 205.706472 -222.028004)
					(end 205.973172 -222.294704)
				)
				(arc
					(start 206.217012 -222.294704)
					(mid 206.067478 -221.933698)
					(end 205.706472 -221.784164)
				)
			)
		)
	)
	(zone
		(layers "F.Cu" "In5.Cu")
		(hatch none 0.5)
		(connect_pads
			(clearance 0)
		)
		(min_thickness 0.25)
		(keepout
			(tracks not_allowed)
			(vias allowed)
			(pads allowed)
			(copperpour not_allowed)
			(footprints allowed)
		)
		(placement
			(enabled no)
			(sheetname "")
		)
		(fill yes
			(thermal_gap 0.5)
			(thermal_bridge_width 0.5)
			(island_removal_mode 0)
		)
		(polygon
			(pts
				(arc
					(start 90.893392 -221.784164)
					(mid 90.382852 -222.294704)
					(end 90.893392 -222.805244)
				)
				(arc
					(start 91.705938 -222.805244)
					(mid 92.066209 -222.656697)
					(end 92.216732 -222.297244)
				)
				(arc
					(start 91.972892 -222.297244)
					(mid 91.706192 -222.561416)
					(end 91.439492 -222.297244)
				)
				(arc
					(start 91.160092 -222.297244)
					(mid 90.893392 -222.561416)
					(end 90.626692 -222.297244)
				)
				(arc
					(start 90.626692 -222.294704)
					(mid 90.893392 -222.028004)
					(end 91.160092 -222.294704)
				)
				(arc
					(start 91.439492 -222.294704)
					(mid 91.706192 -222.028004)
					(end 91.972892 -222.294704)
				)
				(arc
					(start 92.216732 -222.294704)
					(mid 92.067198 -221.933698)
					(end 91.706192 -221.784164)
				)
			)
		)
	)
	(zone
		(layers "F.Cu" "In5.Cu")
		(hatch none 0.5)
		(connect_pads
			(clearance 0)
		)
		(min_thickness 0.25)
		(keepout
			(tracks not_allowed)
			(vias allowed)
			(pads allowed)
			(copperpour not_allowed)
			(footprints allowed)
		)
		(placement
			(enabled no)
			(sheetname "")
		)
		(fill yes
			(thermal_gap 0.5)
			(thermal_bridge_width 0.5)
			(island_removal_mode 0)
		)
		(polygon
			(pts
				(arc
					(start 280.761186 -17.9578)
					(mid 280.254583 -17.447275)
					(end 279.740106 -17.949926)
				)
				(arc
					(start 279.72766 -18.762726)
					(mid 280.230326 -19.28114)
					(end 280.74874 -18.778474)
				)
				(xy 280.74874 -18.77314)
				(arc
					(start 280.5049 -18.77314)
					(mid 280.2382 -19.037312)
					(end 279.9715 -18.77314)
				)
				(arc
					(start 279.9715 -18.7706)
					(mid 280.2382 -18.5039)
					(end 280.5049 -18.7706)
				)
				(xy 280.74874 -18.7706) (xy 280.761186 -17.965928) (xy 280.761186 -17.96034)
				(arc
					(start 280.517346 -17.96034)
					(mid 280.250646 -18.224512)
					(end 279.983946 -17.96034)
				)
				(arc
					(start 279.983946 -17.9578)
					(mid 280.250646 -17.6911)
					(end 280.517346 -17.9578)
				)
			)
		)
	)
	(zone
		(layers "F.Cu" "In5.Cu")
		(hatch none 0.5)
		(connect_pads
			(clearance 0)
		)
		(min_thickness 0.25)
		(keepout
			(tracks not_allowed)
			(vias allowed)
			(pads allowed)
			(copperpour not_allowed)
			(footprints allowed)
		)
		(placement
			(enabled no)
			(sheetname "")
		)
		(fill yes
			(thermal_gap 0.5)
			(thermal_bridge_width 0.5)
			(island_removal_mode 0)
		)
		(polygon
			(pts
				(arc
					(start 87.6935 -221.784164)
					(mid 87.18296 -222.294704)
					(end 87.6935 -222.805244)
				)
				(arc
					(start 88.506046 -222.805244)
					(mid 88.866317 -222.656697)
					(end 89.01684 -222.297244)
				)
				(arc
					(start 88.773 -222.297244)
					(mid 88.5063 -222.561416)
					(end 88.2396 -222.297244)
				)
				(arc
					(start 87.9602 -222.297244)
					(mid 87.6935 -222.561416)
					(end 87.4268 -222.297244)
				)
				(arc
					(start 87.4268 -222.294704)
					(mid 87.6935 -222.028004)
					(end 87.9602 -222.294704)
				)
				(arc
					(start 88.2396 -222.294704)
					(mid 88.5063 -222.028004)
					(end 88.773 -222.294704)
				)
				(arc
					(start 89.01684 -222.294704)
					(mid 88.867306 -221.933698)
					(end 88.5063 -221.784164)
				)
			)
		)
	)
	(zone
		(layers "F.Cu" "In5.Cu")
		(hatch none 0.5)
		(connect_pads
			(clearance 0)
		)
		(min_thickness 0.25)
		(keepout
			(tracks not_allowed)
			(vias allowed)
			(pads allowed)
			(copperpour not_allowed)
			(footprints allowed)
		)
		(placement
			(enabled no)
			(sheetname "")
		)
		(fill yes
			(thermal_gap 0.5)
			(thermal_bridge_width 0.5)
			(island_removal_mode 0)
		)
		(polygon
			(pts
				(arc
					(start 262.893556 -221.784164)
					(mid 262.383016 -222.294704)
					(end 262.893556 -222.805244)
				)
				(arc
					(start 263.706102 -222.805244)
					(mid 264.066373 -222.656697)
					(end 264.216896 -222.297244)
				)
				(arc
					(start 263.973056 -222.297244)
					(mid 263.706356 -222.561416)
					(end 263.439656 -222.297244)
				)
				(arc
					(start 263.160256 -222.297244)
					(mid 262.893556 -222.561416)
					(end 262.626856 -222.297244)
				)
				(arc
					(start 262.626856 -222.294704)
					(mid 262.893556 -222.028004)
					(end 263.160256 -222.294704)
				)
				(arc
					(start 263.439656 -222.294704)
					(mid 263.706356 -222.028004)
					(end 263.973056 -222.294704)
				)
				(arc
					(start 264.216896 -222.294704)
					(mid 264.067362 -221.933698)
					(end 263.706356 -221.784164)
				)
			)
		)
	)
	(zone
		(layers "F.Cu" "In5.Cu")
		(hatch none 0.5)
		(connect_pads
			(clearance 0)
		)
		(min_thickness 0.25)
		(keepout
			(tracks not_allowed)
			(vias allowed)
			(pads allowed)
			(copperpour not_allowed)
			(footprints allowed)
		)
		(placement
			(enabled no)
			(sheetname "")
		)
		(fill yes
			(thermal_gap 0.5)
			(thermal_bridge_width 0.5)
			(island_removal_mode 0)
		)
		(polygon
			(pts
				(arc
					(start 300.493684 -221.784164)
					(mid 299.983144 -222.294704)
					(end 300.493684 -222.805244)
				)
				(arc
					(start 301.30623 -222.805244)
					(mid 301.666501 -222.656697)
					(end 301.817024 -222.297244)
				)
				(arc
					(start 301.573184 -222.297244)
					(mid 301.306484 -222.561416)
					(end 301.039784 -222.297244)
				)
				(arc
					(start 300.760384 -222.297244)
					(mid 300.493684 -222.561416)
					(end 300.226984 -222.297244)
				)
				(arc
					(start 300.226984 -222.294704)
					(mid 300.493684 -222.028004)
					(end 300.760384 -222.294704)
				)
				(arc
					(start 301.039784 -222.294704)
					(mid 301.306484 -222.028004)
					(end 301.573184 -222.294704)
				)
				(arc
					(start 301.817024 -222.294704)
					(mid 301.66749 -221.933698)
					(end 301.306484 -221.784164)
				)
			)
		)
	)
	(zone
		(layers "F.Cu" "In5.Cu")
		(hatch none 0.5)
		(connect_pads
			(clearance 0)
		)
		(min_thickness 0.25)
		(keepout
			(tracks not_allowed)
			(vias allowed)
			(pads allowed)
			(copperpour not_allowed)
			(footprints allowed)
		)
		(placement
			(enabled no)
			(sheetname "")
		)
		(fill yes
			(thermal_gap 0.5)
			(thermal_bridge_width 0.5)
			(island_removal_mode 0)
		)
		(polygon
			(pts
				(arc
					(start 311.69356 -221.784164)
					(mid 311.18302 -222.294704)
					(end 311.69356 -222.805244)
				)
				(arc
					(start 312.506106 -222.805244)
					(mid 312.866377 -222.656697)
					(end 313.0169 -222.297244)
				)
				(arc
					(start 312.77306 -222.297244)
					(mid 312.50636 -222.561416)
					(end 312.23966 -222.297244)
				)
				(arc
					(start 311.96026 -222.297244)
					(mid 311.69356 -222.561416)
					(end 311.42686 -222.297244)
				)
				(arc
					(start 311.42686 -222.294704)
					(mid 311.69356 -222.028004)
					(end 311.96026 -222.294704)
				)
				(arc
					(start 312.23966 -222.294704)
					(mid 312.50636 -222.028004)
					(end 312.77306 -222.294704)
				)
				(arc
					(start 313.0169 -222.294704)
					(mid 312.867366 -221.933698)
					(end 312.50636 -221.784164)
				)
			)
		)
	)
	(zone
		(layers "F.Cu" "In5.Cu")
		(hatch none 0.5)
		(connect_pads
			(clearance 0)
		)
		(min_thickness 0.25)
		(keepout
			(tracks not_allowed)
			(vias allowed)
			(pads allowed)
			(copperpour not_allowed)
			(footprints allowed)
		)
		(placement
			(enabled no)
			(sheetname "")
		)
		(fill yes
			(thermal_gap 0.5)
			(thermal_bridge_width 0.5)
			(island_removal_mode 0)
		)
		(polygon
			(pts
				(arc
					(start 340.493858 -221.784164)
					(mid 339.983064 -222.294577)
					(end 340.493604 -222.805244)
				)
				(arc
					(start 341.306404 -222.805244)
					(mid 341.666511 -222.656607)
					(end 341.816944 -222.297244)
				)
				(arc
					(start 341.573104 -222.297244)
					(mid 341.306404 -222.561416)
					(end 341.039704 -222.297244)
				)
				(arc
					(start 340.760304 -222.297244)
					(mid 340.493604 -222.561416)
					(end 340.226904 -222.297244)
				)
				(arc
					(start 340.226904 -222.294704)
					(mid 340.493604 -222.028004)
					(end 340.760304 -222.294704)
				)
				(arc
					(start 341.039704 -222.294704)
					(mid 341.306404 -222.028004)
					(end 341.573104 -222.294704)
				)
				(arc
					(start 341.816944 -222.294704)
					(mid 341.66741 -221.933698)
					(end 341.306404 -221.784164)
				)
			)
		)
	)
	(zone
		(layers "F.Cu" "In5.Cu")
		(hatch none 0.5)
		(connect_pads
			(clearance 0)
		)
		(min_thickness 0.25)
		(keepout
			(tracks not_allowed)
			(vias allowed)
			(pads allowed)
			(copperpour not_allowed)
			(footprints allowed)
		)
		(placement
			(enabled no)
			(sheetname "")
		)
		(fill yes
			(thermal_gap 0.5)
			(thermal_bridge_width 0.5)
			(island_removal_mode 0)
		)
		(polygon
			(pts
				(arc
					(start 50.093372 -220.895164)
					(mid 49.582832 -221.405704)
					(end 50.093372 -221.916244)
				)
				(arc
					(start 50.905918 -221.916244)
					(mid 51.266189 -221.767697)
					(end 51.416712 -221.408244)
				)
				(arc
					(start 51.172872 -221.408244)
					(mid 50.906172 -221.672416)
					(end 50.639472 -221.408244)
				)
				(arc
					(start 50.360072 -221.408244)
					(mid 50.093372 -221.672416)
					(end 49.826672 -221.408244)
				)
				(arc
					(start 49.826672 -221.405704)
					(mid 50.093372 -221.139004)
					(end 50.360072 -221.405704)
				)
				(arc
					(start 50.639472 -221.405704)
					(mid 50.906172 -221.139004)
					(end 51.172872 -221.405704)
				)
				(arc
					(start 51.416712 -221.405704)
					(mid 51.267178 -221.044698)
					(end 50.906172 -220.895164)
				)
			)
		)
	)
	(zone
		(layers "F.Cu" "In5.Cu")
		(hatch none 0.5)
		(connect_pads
			(clearance 0)
		)
		(min_thickness 0.25)
		(keepout
			(tracks not_allowed)
			(vias allowed)
			(pads allowed)
			(copperpour not_allowed)
			(footprints allowed)
		)
		(placement
			(enabled no)
			(sheetname "")
		)
		(fill yes
			(thermal_gap 0.5)
			(thermal_bridge_width 0.5)
			(island_removal_mode 0)
		)
		(polygon
			(pts
				(arc
					(start 152.893776 -221.784164)
					(mid 152.383236 -222.294704)
					(end 152.893776 -222.805244)
				)
				(arc
					(start 153.706322 -222.805244)
					(mid 154.066593 -222.656697)
					(end 154.217116 -222.297244)
				)
				(arc
					(start 153.973276 -222.297244)
					(mid 153.706576 -222.561416)
					(end 153.439876 -222.297244)
				)
				(arc
					(start 153.160476 -222.297244)
					(mid 152.893776 -222.561416)
					(end 152.627076 -222.297244)
				)
				(arc
					(start 152.627076 -222.294704)
					(mid 152.893776 -222.028004)
					(end 153.160476 -222.294704)
				)
				(arc
					(start 153.439876 -222.294704)
					(mid 153.706576 -222.028004)
					(end 153.973276 -222.294704)
				)
				(arc
					(start 154.217116 -222.294704)
					(mid 154.067582 -221.933698)
					(end 153.706576 -221.784164)
				)
			)
		)
	)
	(zone
		(layers "F.Cu" "In5.Cu")
		(hatch none 0.5)
		(connect_pads
			(clearance 0)
		)
		(min_thickness 0.25)
		(keepout
			(tracks not_allowed)
			(vias allowed)
			(pads allowed)
			(copperpour not_allowed)
			(footprints allowed)
		)
		(placement
			(enabled no)
			(sheetname "")
		)
		(fill yes
			(thermal_gap 0.5)
			(thermal_bridge_width 0.5)
			(island_removal_mode 0)
		)
		(polygon
			(pts
				(arc
					(start 149.69363 -221.784164)
					(mid 149.18309 -222.294704)
					(end 149.69363 -222.805244)
				)
				(arc
					(start 150.506176 -222.805244)
					(mid 150.866447 -222.656697)
					(end 151.01697 -222.297244)
				)
				(arc
					(start 150.77313 -222.297244)
					(mid 150.50643 -222.561416)
					(end 150.23973 -222.297244)
				)
				(arc
					(start 149.96033 -222.297244)
					(mid 149.69363 -222.561416)
					(end 149.42693 -222.297244)
				)
				(arc
					(start 149.42693 -222.294704)
					(mid 149.69363 -222.028004)
					(end 149.96033 -222.294704)
				)
				(arc
					(start 150.23973 -222.294704)
					(mid 150.50643 -222.028004)
					(end 150.77313 -222.294704)
				)
				(arc
					(start 151.01697 -222.294704)
					(mid 150.867436 -221.933698)
					(end 150.50643 -221.784164)
				)
			)
		)
	)
	(zone
		(layers "F.Cu" "In5.Cu")
		(hatch none 0.5)
		(connect_pads
			(clearance 0)
		)
		(min_thickness 0.25)
		(keepout
			(tracks not_allowed)
			(vias allowed)
			(pads allowed)
			(copperpour not_allowed)
			(footprints allowed)
		)
		(placement
			(enabled no)
			(sheetname "")
		)
		(fill yes
			(thermal_gap 0.5)
			(thermal_bridge_width 0.5)
			(island_removal_mode 0)
		)
		(polygon
			(pts
				(arc
					(start 294.893746 -221.784164)
					(mid 294.383206 -222.294704)
					(end 294.893746 -222.805244)
				)
				(arc
					(start 295.706292 -222.805244)
					(mid 296.066563 -222.656697)
					(end 296.217086 -222.297244)
				)
				(arc
					(start 295.973246 -222.297244)
					(mid 295.706546 -222.561416)
					(end 295.439846 -222.297244)
				)
				(arc
					(start 295.160446 -222.297244)
					(mid 294.893746 -222.561416)
					(end 294.627046 -222.297244)
				)
				(arc
					(start 294.627046 -222.294704)
					(mid 294.893746 -222.028004)
					(end 295.160446 -222.294704)
				)
				(arc
					(start 295.439846 -222.294704)
					(mid 295.706546 -222.028004)
					(end 295.973246 -222.294704)
				)
				(arc
					(start 296.217086 -222.294704)
					(mid 296.067552 -221.933698)
					(end 295.706546 -221.784164)
				)
			)
		)
	)
	(zone
		(layers "F.Cu" "In5.Cu")
		(hatch none 0.5)
		(connect_pads
			(clearance 0)
		)
		(min_thickness 0.25)
		(keepout
			(tracks not_allowed)
			(vias allowed)
			(pads allowed)
			(copperpour not_allowed)
			(footprints allowed)
		)
		(placement
			(enabled no)
			(sheetname "")
		)
		(fill yes
			(thermal_gap 0.5)
			(thermal_bridge_width 0.5)
			(island_removal_mode 0)
		)
		(polygon
			(pts
				(arc
					(start 330.893674 -221.784164)
					(mid 330.383134 -222.294704)
					(end 330.893674 -222.805244)
				)
				(arc
					(start 331.70622 -222.805244)
					(mid 332.066491 -222.656697)
					(end 332.217014 -222.297244)
				)
				(arc
					(start 331.973174 -222.297244)
					(mid 331.706474 -222.561416)
					(end 331.439774 -222.297244)
				)
				(arc
					(start 331.160374 -222.297244)
					(mid 330.893674 -222.561416)
					(end 330.626974 -222.297244)
				)
				(arc
					(start 330.626974 -222.294704)
					(mid 330.893674 -222.028004)
					(end 331.160374 -222.294704)
				)
				(arc
					(start 331.439774 -222.294704)
					(mid 331.706474 -222.028004)
					(end 331.973174 -222.294704)
				)
				(arc
					(start 332.217014 -222.294704)
					(mid 332.06748 -221.933698)
					(end 331.706474 -221.784164)
				)
			)
		)
	)
	(zone
		(layers "F.Cu" "In5.Cu")
		(hatch none 0.5)
		(connect_pads
			(clearance 0)
		)
		(min_thickness 0.25)
		(keepout
			(tracks not_allowed)
			(vias allowed)
			(pads allowed)
			(copperpour not_allowed)
			(footprints allowed)
		)
		(placement
			(enabled no)
			(sheetname "")
		)
		(fill yes
			(thermal_gap 0.5)
			(thermal_bridge_width 0.5)
			(island_removal_mode 0)
		)
		(polygon
			(pts
				(arc
					(start 171.29379 -221.784164)
					(mid 170.78325 -222.294704)
					(end 171.29379 -222.805244)
				)
				(arc
					(start 172.106336 -222.805244)
					(mid 172.466607 -222.656697)
					(end 172.61713 -222.297244)
				)
				(arc
					(start 172.37329 -222.297244)
					(mid 172.10659 -222.561416)
					(end 171.83989 -222.297244)
				)
				(arc
					(start 171.56049 -222.297244)
					(mid 171.29379 -222.561416)
					(end 171.02709 -222.297244)
				)
				(arc
					(start 171.02709 -222.294704)
					(mid 171.29379 -222.028004)
					(end 171.56049 -222.294704)
				)
				(arc
					(start 171.83989 -222.294704)
					(mid 172.10659 -222.028004)
					(end 172.37329 -222.294704)
				)
				(arc
					(start 172.61713 -222.294704)
					(mid 172.467596 -221.933698)
					(end 172.10659 -221.784164)
				)
			)
		)
	)
	(zone
		(layers "F.Cu" "In5.Cu")
		(hatch none 0.5)
		(connect_pads
			(clearance 0)
		)
		(min_thickness 0.25)
		(keepout
			(tracks not_allowed)
			(vias allowed)
			(pads allowed)
			(copperpour not_allowed)
			(footprints allowed)
		)
		(placement
			(enabled no)
			(sheetname "")
		)
		(fill yes
			(thermal_gap 0.5)
			(thermal_bridge_width 0.5)
			(island_removal_mode 0)
		)
		(polygon
			(pts
				(arc
					(start 283.005276 -20.15617)
					(mid 282.284107 -20.118381)
					(end 282.246578 -20.83943)
				)
				(xy 282.244546 -20.841208) (xy 282.788614 -21.44522)
				(arc
					(start 282.790646 -21.443442)
					(mid 283.351659 -21.578753)
					(end 283.680408 -21.104352)
				)
				(arc
					(start 283.436568 -21.104352)
					(mid 283.169868 -21.368524)
					(end 282.903168 -21.104352)
				)
				(arc
					(start 282.903168 -21.101812)
					(mid 283.169868 -20.835112)
					(end 283.436568 -21.101812)
				)
				(arc
					(start 283.680408 -21.101812)
					(mid 283.646395 -20.918837)
					(end 283.54909 -20.760182)
				)
				(xy 283.551122 -20.758404) (xy 283.318712 -20.50034)
				(arc
					(start 282.8925 -20.50034)
					(mid 282.6258 -20.764512)
					(end 282.3591 -20.50034)
				)
				(arc
					(start 282.3591 -20.4978)
					(mid 282.6258 -20.2311)
					(end 282.8925 -20.4978)
				)
				(xy 283.316426 -20.4978) (xy 283.007308 -20.154646) (xy 283.0068 -20.154646)
			)
		)
	)
	(zone
		(layers "F.Cu" "In5.Cu")
		(hatch none 0.5)
		(connect_pads
			(clearance 0)
		)
		(min_thickness 0.25)
		(keepout
			(tracks not_allowed)
			(vias allowed)
			(pads allowed)
			(copperpour not_allowed)
			(footprints allowed)
		)
		(placement
			(enabled no)
			(sheetname "")
		)
		(fill yes
			(thermal_gap 0.5)
			(thermal_bridge_width 0.5)
			(island_removal_mode 0)
		)
		(polygon
			(pts
				(arc
					(start 272.49374 -221.784164)
					(mid 271.9832 -222.294704)
					(end 272.49374 -222.805244)
				)
				(arc
					(start 273.306286 -222.805244)
					(mid 273.666557 -222.656697)
					(end 273.81708 -222.297244)
				)
				(arc
					(start 273.57324 -222.297244)
					(mid 273.30654 -222.561416)
					(end 273.03984 -222.297244)
				)
				(arc
					(start 272.76044 -222.297244)
					(mid 272.49374 -222.561416)
					(end 272.22704 -222.297244)
				)
				(arc
					(start 272.22704 -222.294704)
					(mid 272.49374 -222.028004)
					(end 272.76044 -222.294704)
				)
				(arc
					(start 273.03984 -222.294704)
					(mid 273.30654 -222.028004)
					(end 273.57324 -222.294704)
				)
				(arc
					(start 273.81708 -222.294704)
					(mid 273.667546 -221.933698)
					(end 273.30654 -221.784164)
				)
			)
		)
	)
	(zone
		(layers "F.Cu" "In5.Cu")
		(hatch none 0.5)
		(connect_pads
			(clearance 0)
		)
		(min_thickness 0.25)
		(keepout
			(tracks not_allowed)
			(vias allowed)
			(pads allowed)
			(copperpour not_allowed)
			(footprints allowed)
		)
		(placement
			(enabled no)
			(sheetname "")
		)
		(fill yes
			(thermal_gap 0.5)
			(thermal_bridge_width 0.5)
			(island_removal_mode 0)
		)
		(polygon
			(pts
				(arc
					(start 188.893704 -221.784164)
					(mid 188.383164 -222.294704)
					(end 188.893704 -222.805244)
				)
				(arc
					(start 189.70625 -222.805244)
					(mid 190.066521 -222.656697)
					(end 190.217044 -222.297244)
				)
				(arc
					(start 189.973204 -222.297244)
					(mid 189.706504 -222.561416)
					(end 189.439804 -222.297244)
				)
				(arc
					(start 189.160404 -222.297244)
					(mid 188.893704 -222.561416)
					(end 188.627004 -222.297244)
				)
				(arc
					(start 188.627004 -222.294704)
					(mid 188.893704 -222.028004)
					(end 189.160404 -222.294704)
				)
				(arc
					(start 189.439804 -222.294704)
					(mid 189.706504 -222.028004)
					(end 189.973204 -222.294704)
				)
				(arc
					(start 190.217044 -222.294704)
					(mid 190.06751 -221.933698)
					(end 189.706504 -221.784164)
				)
			)
		)
	)
	(zone
		(layers "F.Cu" "In5.Cu")
		(hatch none 0.5)
		(connect_pads
			(clearance 0)
		)
		(min_thickness 0.25)
		(keepout
			(tracks not_allowed)
			(vias allowed)
			(pads allowed)
			(copperpour not_allowed)
			(footprints allowed)
		)
		(placement
			(enabled no)
			(sheetname "")
		)
		(fill yes
			(thermal_gap 0.5)
			(thermal_bridge_width 0.5)
			(island_removal_mode 0)
		)
		(polygon
			(pts
				(arc
					(start 321.293744 -221.784164)
					(mid 320.783204 -222.294704)
					(end 321.293744 -222.805244)
				)
				(arc
					(start 322.10629 -222.805244)
					(mid 322.466561 -222.656697)
					(end 322.617084 -222.297244)
				)
				(arc
					(start 322.373244 -222.297244)
					(mid 322.106544 -222.561416)
					(end 321.839844 -222.297244)
				)
				(arc
					(start 321.560444 -222.297244)
					(mid 321.293744 -222.561416)
					(end 321.027044 -222.297244)
				)
				(arc
					(start 321.027044 -222.294704)
					(mid 321.293744 -222.028004)
					(end 321.560444 -222.294704)
				)
				(arc
					(start 321.839844 -222.294704)
					(mid 322.106544 -222.028004)
					(end 322.373244 -222.294704)
				)
				(arc
					(start 322.617084 -222.294704)
					(mid 322.46755 -221.933698)
					(end 322.106544 -221.784164)
				)
			)
		)
	)
	(zone
		(layers "F.Cu" "In5.Cu")
		(hatch none 0.5)
		(connect_pads
			(clearance 0)
		)
		(min_thickness 0.25)
		(keepout
			(tracks not_allowed)
			(vias allowed)
			(pads allowed)
			(copperpour not_allowed)
			(footprints allowed)
		)
		(placement
			(enabled no)
			(sheetname "")
		)
		(fill yes
			(thermal_gap 0.5)
			(thermal_bridge_width 0.5)
			(island_removal_mode 0)
		)
		(polygon
			(pts
				(arc
					(start 271.19834 -8.353552)
					(mid 270.6878 -7.843012)
					(end 270.17726 -8.353552)
				)
				(arc
					(start 270.17726 -9.166352)
					(mid 270.68653 -9.67689)
					(end 271.19834 -9.168892)
				)
				(arc
					(start 270.9545 -9.168892)
					(mid 270.6878 -9.433064)
					(end 270.4211 -9.168892)
				)
				(arc
					(start 270.4211 -9.166352)
					(mid 270.6878 -8.899652)
					(end 270.9545 -9.166352)
				)
				(xy 271.19834 -9.166352) (xy 271.19834 -8.356092)
				(arc
					(start 270.9545 -8.356092)
					(mid 270.6878 -8.620264)
					(end 270.4211 -8.356092)
				)
				(arc
					(start 270.4211 -8.353552)
					(mid 270.6878 -8.086852)
					(end 270.9545 -8.353552)
				)
			)
		)
	)
	(zone
		(layers "F.Cu" "In5.Cu")
		(hatch none 0.5)
		(connect_pads
			(clearance 0)
		)
		(min_thickness 0.25)
		(keepout
			(tracks not_allowed)
			(vias allowed)
			(pads allowed)
			(copperpour not_allowed)
			(footprints allowed)
		)
		(placement
			(enabled no)
			(sheetname "")
		)
		(fill yes
			(thermal_gap 0.5)
			(thermal_bridge_width 0.5)
			(island_removal_mode 0)
		)
		(polygon
			(pts
				(arc
					(start 285.293562 -221.784164)
					(mid 284.783022 -222.294704)
					(end 285.293562 -222.805244)
				)
				(arc
					(start 286.106108 -222.805244)
					(mid 286.466379 -222.656697)
					(end 286.616902 -222.297244)
				)
				(arc
					(start 286.373062 -222.297244)
					(mid 286.106362 -222.561416)
					(end 285.839662 -222.297244)
				)
				(arc
					(start 285.560262 -222.297244)
					(mid 285.293562 -222.561416)
					(end 285.026862 -222.297244)
				)
				(arc
					(start 285.026862 -222.294704)
					(mid 285.293562 -222.028004)
					(end 285.560262 -222.294704)
				)
				(arc
					(start 285.839662 -222.294704)
					(mid 286.106362 -222.028004)
					(end 286.373062 -222.294704)
				)
				(arc
					(start 286.616902 -222.294704)
					(mid 286.467368 -221.933698)
					(end 286.106362 -221.784164)
				)
			)
		)
	)
	(zone
		(layers "F.Cu" "In5.Cu")
		(hatch none 0.5)
		(connect_pads
			(clearance 0)
		)
		(min_thickness 0.25)
		(keepout
			(tracks not_allowed)
			(vias allowed)
			(pads allowed)
			(copperpour not_allowed)
			(footprints allowed)
		)
		(placement
			(enabled no)
			(sheetname "")
		)
		(fill yes
			(thermal_gap 0.5)
			(thermal_bridge_width 0.5)
			(island_removal_mode 0)
		)
		(polygon
			(pts
				(arc
					(start 84.493354 -221.784164)
					(mid 83.982814 -222.294704)
					(end 84.493354 -222.805244)
				)
				(arc
					(start 85.3059 -222.805244)
					(mid 85.666171 -222.656697)
					(end 85.816694 -222.297244)
				)
				(arc
					(start 85.572854 -222.297244)
					(mid 85.306154 -222.561416)
					(end 85.039454 -222.297244)
				)
				(arc
					(start 84.760054 -222.297244)
					(mid 84.493354 -222.561416)
					(end 84.226654 -222.297244)
				)
				(arc
					(start 84.226654 -222.294704)
					(mid 84.493354 -222.028004)
					(end 84.760054 -222.294704)
				)
				(arc
					(start 85.039454 -222.294704)
					(mid 85.306154 -222.028004)
					(end 85.572854 -222.294704)
				)
				(arc
					(start 85.816694 -222.294704)
					(mid 85.66716 -221.933698)
					(end 85.306154 -221.784164)
				)
			)
		)
	)
	(zone
		(net "P0V9_E_VIN")
		(layer "B.Cu")
		(hatch none 0.5)
		(connect_pads
			(clearance 0.5)
		)
		(min_thickness 0.25)
		(fill yes
			(thermal_gap 0.5)
			(thermal_bridge_width 0.5)
			(island_removal_mode 0)
		)
		(polygon
			(pts
				(xy 341.884 -48.133) (xy 341.249 -48.768) (xy 341.249 -63.754) (xy 341.503 -64.008) (xy 342.773 -64.008)
				(xy 343.027 -63.754) (xy 346.456 -63.754) (xy 346.583 -63.627) (xy 346.583 -62.23) (xy 345.948 -61.595)
				(xy 345.948 -50.038) (xy 344.043 -48.133)
			)
		)
	)
	(zone
		(net "DUT_AVD_PCIE")
		(layer "B.Cu")
		(hatch none 0.5)
		(connect_pads
			(clearance 0.5)
		)
		(min_thickness 0.25)
		(fill yes
			(thermal_gap 0.5)
			(thermal_bridge_width 0.5)
			(island_removal_mode 0)
		)
		(polygon
			(pts
				(xy 227.7618 -32.8676) (xy 227.7618 -41.1988) (xy 227.6856 -41.275) (xy 226.8982 -41.275) (xy 226.822 -41.3512)
				(xy 226.822 -42.037) (xy 226.8982 -42.1132) (xy 227.4062 -42.1132) (xy 227.5078 -42.2148) (xy 227.5078 -46.5582)
				(xy 226.4918 -47.5742) (xy 226.4918 -59.7916) (xy 226.695 -59.9948) (xy 226.695 -60.2488) (xy 227.4062 -60.96)
				(xy 234.7468 -60.96) (xy 234.823 -60.8838) (xy 234.823 -60.2742) (xy 234.7468 -60.198) (xy 229.2604 -60.198)
				(xy 229.1588 -60.2996) (xy 228.6254 -60.2996) (xy 228.5238 -60.198) (xy 228.5238 -47.8028) (xy 229.0826 -47.244)
				(xy 229.7176 -47.244) (xy 229.8192 -47.1424) (xy 229.8192 -46.9392) (xy 229.9716 -46.7868) (xy 230.2764 -46.7868)
				(xy 230.3272 -46.736) (xy 230.3272 -46.3296) (xy 230.3018 -46.3042) (xy 228.6254 -46.3042) (xy 228.5238 -46.2026)
				(xy 228.5238 -42.545) (xy 228.9048 -42.164) (xy 229.997 -42.164) (xy 230.0732 -42.0878) (xy 230.0732 -41.8338)
				(xy 230.3018 -41.6052) (xy 230.3018 -41.4274) (xy 230.1748 -41.3004) (xy 229.3112 -41.3004) (xy 229.2858 -41.275)
				(xy 229.0318 -41.275) (xy 228.9302 -41.1734) (xy 228.9302 -40.7924) (xy 228.7778 -40.64) (xy 228.7778 -33.274)
				(xy 228.3714 -32.8676)
			)
		)
		(polygon
			(pts
				(xy 234.519216 -60.5282) (xy 234.316016 -60.5282) (xy 234.316016 -60.7314) (xy 234.519216 -60.7314)
			)
		)
		(polygon
			(pts
				(xy 233.8832 -60.5028) (xy 233.68 -60.5028) (xy 233.68 -60.706) (xy 233.8832 -60.706)
			)
		)
		(polygon
			(pts
				(xy 233.5276 -60.5028) (xy 233.3244 -60.5028) (xy 233.3244 -60.706) (xy 233.5276 -60.706)
			)
		)
		(polygon
			(pts
				(xy 232.87482 -60.5028) (xy 232.67162 -60.5028) (xy 232.67162 -60.706) (xy 232.87482 -60.706)
			)
		)
		(polygon
			(pts
				(xy 232.51922 -60.5028) (xy 232.31602 -60.5028) (xy 232.31602 -60.706) (xy 232.51922 -60.706)
			)
		)
		(polygon
			(pts
				(xy 231.8766 -60.5028) (xy 231.6734 -60.5028) (xy 231.6734 -60.706) (xy 231.8766 -60.706)
			)
		)
		(polygon
			(pts
				(xy 231.521 -60.5028) (xy 231.3178 -60.5028) (xy 231.3178 -60.706) (xy 231.521 -60.706)
			)
		)
		(polygon
			(pts
				(xy 230.884222 -60.5028) (xy 230.681022 -60.5028) (xy 230.681022 -60.706) (xy 230.884222 -60.706)
			)
		)
		(polygon
			(pts
				(xy 230.528622 -60.5028) (xy 230.325422 -60.5028) (xy 230.325422 -60.706) (xy 230.528622 -60.706)
			)
		)
		(polygon
			(pts
				(xy 228.2444 -60.071) (xy 228.0412 -60.071) (xy 228.0412 -60.2742) (xy 228.2444 -60.2742)
			)
		)
		(polygon
			(pts
				(xy 227.1522 -60.071) (xy 226.949 -60.071) (xy 226.949 -60.2742) (xy 227.1522 -60.2742)
			)
		)
		(polygon
			(pts
				(xy 228.2444 -59.7154) (xy 228.0412 -59.7154) (xy 228.0412 -59.9186) (xy 228.2444 -59.9186)
			)
		)
		(polygon
			(pts
				(xy 228.2444 -59.072272) (xy 228.0412 -59.072272) (xy 228.0412 -59.275472) (xy 228.2444 -59.275472)
			)
		)
		(polygon
			(pts
				(xy 228.2444 -58.716672) (xy 228.0412 -58.716672) (xy 228.0412 -58.919872) (xy 228.2444 -58.919872)
			)
		)
		(polygon
			(pts
				(xy 228.2444 -58.068972) (xy 228.0412 -58.068972) (xy 228.0412 -58.272172) (xy 228.2444 -58.272172)
			)
		)
		(polygon
			(pts
				(xy 228.2444 -57.713372) (xy 228.0412 -57.713372) (xy 228.0412 -57.916572) (xy 228.2444 -57.916572)
			)
		)
		(polygon
			(pts
				(xy 228.2444 -57.065672) (xy 228.0412 -57.065672) (xy 228.0412 -57.268872) (xy 228.2444 -57.268872)
			)
		)
		(polygon
			(pts
				(xy 228.2444 -56.710072) (xy 228.0412 -56.710072) (xy 228.0412 -56.913272) (xy 228.2444 -56.913272)
			)
		)
		(polygon
			(pts
				(xy 228.2444 -56.075072) (xy 228.0412 -56.075072) (xy 228.0412 -56.278272) (xy 228.2444 -56.278272)
			)
		)
		(polygon
			(pts
				(xy 228.2444 -55.719472) (xy 228.0412 -55.719472) (xy 228.0412 -55.922672) (xy 228.2444 -55.922672)
			)
		)
		(polygon
			(pts
				(xy 228.2444 -55.071772) (xy 228.0412 -55.071772) (xy 228.0412 -55.274972) (xy 228.2444 -55.274972)
			)
		)
		(polygon
			(pts
				(xy 228.2444 -54.716172) (xy 228.0412 -54.716172) (xy 228.0412 -54.919372) (xy 228.2444 -54.919372)
			)
		)
		(polygon
			(pts
				(xy 228.2444 -54.068472) (xy 228.0412 -54.068472) (xy 228.0412 -54.271672) (xy 228.2444 -54.271672)
			)
		)
		(polygon
			(pts
				(xy 228.2444 -53.712872) (xy 228.0412 -53.712872) (xy 228.0412 -53.916072) (xy 228.2444 -53.916072)
			)
		)
		(polygon
			(pts
				(xy 228.2444 -53.077872) (xy 228.0412 -53.077872) (xy 228.0412 -53.281072) (xy 228.2444 -53.281072)
			)
		)
		(polygon
			(pts
				(xy 228.2444 -51.718972) (xy 228.0412 -51.718972) (xy 228.0412 -51.922172) (xy 228.2444 -51.922172)
			)
		)
		(polygon
			(pts
				(xy 228.2444 -51.071272) (xy 228.0412 -51.071272) (xy 228.0412 -51.274472) (xy 228.2444 -51.274472)
			)
		)
		(polygon
			(pts
				(xy 228.2444 -50.715672) (xy 228.0412 -50.715672) (xy 228.0412 -50.918872) (xy 228.2444 -50.918872)
			)
		)
		(polygon
			(pts
				(xy 228.2444 -50.067972) (xy 228.0412 -50.067972) (xy 228.0412 -50.271172) (xy 228.2444 -50.271172)
			)
		)
		(polygon
			(pts
				(xy 228.2444 -49.712372) (xy 228.0412 -49.712372) (xy 228.0412 -49.915572) (xy 228.2444 -49.915572)
			)
		)
		(polygon
			(pts
				(xy 228.2444 -49.077372) (xy 228.0412 -49.077372) (xy 228.0412 -49.280572) (xy 228.2444 -49.280572)
			)
		)
		(polygon
			(pts
				(xy 228.2444 -48.721772) (xy 228.0412 -48.721772) (xy 228.0412 -48.924972) (xy 228.2444 -48.924972)
			)
		)
		(polygon
			(pts
				(xy 228.2444 -48.074072) (xy 228.0412 -48.074072) (xy 228.0412 -48.277272) (xy 228.2444 -48.277272)
			)
		)
		(polygon
			(pts
				(xy 228.2444 -47.718472) (xy 228.0412 -47.718472) (xy 228.0412 -47.921672) (xy 228.2444 -47.921672)
			)
		)
		(polygon
			(pts
				(xy 229.5398 -46.7614) (xy 229.3366 -46.7614) (xy 229.3366 -46.9646) (xy 229.5398 -46.9646)
			)
		)
		(polygon
			(pts
				(xy 228.2444 -46.067472) (xy 228.0412 -46.067472) (xy 228.0412 -46.270672) (xy 228.2444 -46.270672)
			)
		)
		(polygon
			(pts
				(xy 228.2444 -45.711872) (xy 228.0412 -45.711872) (xy 228.0412 -45.915072) (xy 228.2444 -45.915072)
			)
		)
		(polygon
			(pts
				(xy 228.2444 -45.076872) (xy 228.0412 -45.076872) (xy 228.0412 -45.280072) (xy 228.2444 -45.280072)
			)
		)
		(polygon
			(pts
				(xy 228.2444 -44.721272) (xy 228.0412 -44.721272) (xy 228.0412 -44.924472) (xy 228.2444 -44.924472)
			)
		)
		(polygon
			(pts
				(xy 228.2444 -44.073572) (xy 228.0412 -44.073572) (xy 228.0412 -44.276772) (xy 228.2444 -44.276772)
			)
		)
		(polygon
			(pts
				(xy 228.2444 -43.717972) (xy 228.0412 -43.717972) (xy 228.0412 -43.921172) (xy 228.2444 -43.921172)
			)
		)
		(polygon
			(pts
				(xy 228.2444 -43.070272) (xy 228.0412 -43.070272) (xy 228.0412 -43.273472) (xy 228.2444 -43.273472)
			)
		)
		(polygon
			(pts
				(xy 228.2444 -42.714672) (xy 228.0412 -42.714672) (xy 228.0412 -42.917872) (xy 228.2444 -42.917872)
			)
		)
		(polygon
			(pts
				(xy 229.7684 -41.7068) (xy 229.5652 -41.7068) (xy 229.5652 -41.91) (xy 229.7684 -41.91)
			)
		)
		(polygon
			(pts
				(xy 228.668072 -41.089072) (xy 228.464872 -41.089072) (xy 228.464872 -41.292272) (xy 228.668072 -41.292272)
			)
		)
		(polygon
			(pts
				(xy 228.2698 -41.080944) (xy 228.0666 -41.080944) (xy 228.0666 -41.284144) (xy 228.2698 -41.284144)
			)
		)
		(polygon
			(pts
				(xy 228.668072 -40.733472) (xy 228.464872 -40.733472) (xy 228.464872 -40.936672) (xy 228.668072 -40.936672)
			)
		)
		(polygon
			(pts
				(xy 228.2698 -40.725344) (xy 228.0666 -40.725344) (xy 228.0666 -40.928544) (xy 228.2698 -40.928544)
			)
		)
		(polygon
			(pts
				(xy 228.2698 -40.080946) (xy 228.0666 -40.080946) (xy 228.0666 -40.284146) (xy 228.2698 -40.284146)
			)
		)
		(polygon
			(pts
				(xy 228.2698 -39.725346) (xy 228.0666 -39.725346) (xy 228.0666 -39.928546) (xy 228.2698 -39.928546)
			)
		)
		(polygon
			(pts
				(xy 228.2698 -39.080948) (xy 228.0666 -39.080948) (xy 228.0666 -39.284148) (xy 228.2698 -39.284148)
			)
		)
		(polygon
			(pts
				(xy 228.2698 -38.725348) (xy 228.0666 -38.725348) (xy 228.0666 -38.928548) (xy 228.2698 -38.928548)
			)
		)
		(polygon
			(pts
				(xy 228.2698 -38.0746) (xy 228.0666 -38.0746) (xy 228.0666 -38.2778) (xy 228.2698 -38.2778)
			)
		)
		(polygon
			(pts
				(xy 228.2698 -37.719) (xy 228.0666 -37.719) (xy 228.0666 -37.9222) (xy 228.2698 -37.9222)
			)
		)
		(polygon
			(pts
				(xy 228.2698 -37.080952) (xy 228.0666 -37.080952) (xy 228.0666 -37.284152) (xy 228.2698 -37.284152)
			)
		)
		(polygon
			(pts
				(xy 228.2698 -36.725352) (xy 228.0666 -36.725352) (xy 228.0666 -36.928552) (xy 228.2698 -36.928552)
			)
		)
		(polygon
			(pts
				(xy 228.2698 -36.071556) (xy 228.0666 -36.071556) (xy 228.0666 -36.274756) (xy 228.2698 -36.274756)
			)
		)
		(polygon
			(pts
				(xy 228.2698 -35.715956) (xy 228.0666 -35.715956) (xy 228.0666 -35.919156) (xy 228.2698 -35.919156)
			)
		)
		(polygon
			(pts
				(xy 228.2698 -35.0774) (xy 228.0666 -35.0774) (xy 228.0666 -35.2806) (xy 228.2698 -35.2806)
			)
		)
		(polygon
			(pts
				(xy 228.2698 -34.7218) (xy 228.0666 -34.7218) (xy 228.0666 -34.925) (xy 228.2698 -34.925)
			)
		)
		(polygon
			(pts
				(xy 228.2698 -34.080958) (xy 228.0666 -34.080958) (xy 228.0666 -34.284158) (xy 228.2698 -34.284158)
			)
		)
		(polygon
			(pts
				(xy 228.2698 -33.725358) (xy 228.0666 -33.725358) (xy 228.0666 -33.928558) (xy 228.2698 -33.928558)
			)
		)
		(polygon
			(pts
				(xy 228.2698 -33.071562) (xy 228.0666 -33.071562) (xy 228.0666 -33.274762) (xy 228.2698 -33.274762)
			)
		)
	)
	(zone
		(layer "B.Cu")
		(hatch none 0.5)
		(connect_pads
			(clearance 0)
		)
		(min_thickness 0.25)
		(keepout
			(tracks allowed)
			(vias allowed)
			(pads allowed)
			(copperpour allowed)
			(footprints not_allowed)
		)
		(placement
			(enabled no)
			(sheetname "")
		)
		(fill
			(thermal_gap 0.5)
			(thermal_bridge_width 0.5)
			(island_removal_mode 0)
		)
		(polygon
			(pts
				(arc
					(start 170.237404 -9.53008)
					(mid 169.137584 -8.43026)
					(end 168.03751 -9.53008)
				)
				(arc
					(start 168.03751 -9.53008)
					(mid 169.137584 -10.630154)
					(end 170.237404 -9.53008)
				)
			)
		)
	)
	(zone
		(layer "B.Cu")
		(hatch none 0.5)
		(connect_pads
			(clearance 0)
		)
		(min_thickness 0.25)
		(keepout
			(tracks not_allowed)
			(vias allowed)
			(pads allowed)
			(copperpour not_allowed)
			(footprints allowed)
		)
		(placement
			(enabled no)
			(sheetname "")
		)
		(fill
			(thermal_gap 0.5)
			(thermal_bridge_width 0.5)
			(island_removal_mode 0)
		)
		(polygon
			(pts
				(arc
					(start 81.449926 -5.40004)
					(mid 85.449918 -9.400032)
					(end 89.44991 -5.40004)
				)
				(arc
					(start 89.44991 -5.40004)
					(mid 85.449918 -1.400048)
					(end 81.449926 -5.40004)
				)
			)
		)
	)
	(zone
		(net "GND")
		(layer "B.Cu")
		(hatch none 0.5)
		(connect_pads
			(clearance 0.5)
		)
		(min_thickness 0.25)
		(fill yes
			(thermal_gap 0.5)
			(thermal_bridge_width 0.5)
			(island_removal_mode 0)
		)
		(polygon
			(pts
				(arc
					(start 235.412026 -161.967926)
					(mid 233.077159 -162.935059)
					(end 232.110026 -165.269926)
				)
				(arc
					(start 232.110026 -208.499964)
					(mid 231.240722 -210.59865)
					(end 229.142036 -211.467954)
				)
				(arc
					(start 221.600014 -211.467954)
					(mid 219.243954 -212.443866)
					(end 218.268042 -214.799926)
				)
				(xy 218.268042 -219.837) (xy 219.537026 -219.837)
				(arc
					(start 219.537026 -214.799926)
					(mid 220.141261 -213.341173)
					(end 221.600014 -212.736938)
				)
				(arc
					(start 229.142036 -212.736938)
					(mid 232.138029 -211.495957)
					(end 233.37901 -208.499964)
				)
				(arc
					(start 233.37901 -165.269926)
					(mid 233.974467 -163.832367)
					(end 235.412026 -163.23691)
				)
				(arc
					(start 249.871992 -163.23691)
					(mid 251.309551 -163.832367)
					(end 251.905008 -165.269926)
				)
				(arc
					(start 251.905008 -208.499964)
					(mid 253.145989 -211.495957)
					(end 256.141982 -212.736938)
				)
				(arc
					(start 257.400044 -212.736938)
					(mid 258.858797 -213.341173)
					(end 259.463032 -214.799926)
				)
				(xy 259.463032 -220.040454)
				(arc
					(start 260.918198 -220.040454)
					(mid 260.825731 -220.006515)
					(end 260.732016 -219.976192)
				)
				(arc
					(start 260.732016 -214.799926)
					(mid 259.756104 -212.443866)
					(end 257.400044 -211.467954)
				)
				(arc
					(start 256.141982 -211.467954)
					(mid 254.043296 -210.59865)
					(end 253.173992 -208.499964)
				)
				(arc
					(start 253.173992 -165.269926)
					(mid 252.206859 -162.935059)
					(end 249.871992 -161.967926)
				)
			)
		)
	)
	(zone
		(layer "B.Cu")
		(hatch none 0.5)
		(connect_pads
			(clearance 0)
		)
		(min_thickness 0.25)
		(keepout
			(tracks not_allowed)
			(vias allowed)
			(pads allowed)
			(copperpour not_allowed)
			(footprints allowed)
		)
		(placement
			(enabled no)
			(sheetname "")
		)
		(fill
			(thermal_gap 0.5)
			(thermal_bridge_width 0.5)
			(island_removal_mode 0)
		)
		(polygon
			(pts
				(xy 154.92476 -12.99845) (xy 155.354782 -13.228574) (xy 155.35529 -13.228574) (xy 155.3845 -13.244322)
				(arc
					(start 155.38577 -13.248386)
					(mid 155.460847 -13.357373)
					(end 155.458922 -13.489686)
				)
				(xy 155.460192 -13.49375) (xy 155.444444 -13.523214) (xy 155.44419 -13.523468)
				(arc
					(start 155.381706 -13.640054)
					(mid 154.954693 -14.266076)
					(end 155.238958 -13.5636)
				)
				(arc
					(start 155.301442 -13.44676)
					(mid 155.305616 -13.404541)
					(end 155.278836 -13.371576)
				)
				(xy 155.278582 -13.371322) (xy 154.848306 -13.141452)
				(arc
					(start 154.587702 -13.627608)
					(mid 154.835836 -14.479061)
					(end 155.68549 -14.225016)
				)
				(arc
					(start 156.435298 -12.824968)
					(mid 156.179266 -11.979148)
					(end 155.333446 -12.23518)
				)
				(xy 155.068778 -12.729464) (xy 155.481274 -12.95019) (xy 155.494736 -12.95019)
				(arc
					(start 155.508198 -12.963398)
					(mid 155.546251 -12.962301)
					(end 155.574746 -12.936982)
				)
				(arc
					(start 155.63723 -12.820142)
					(mid 156.064136 -12.194063)
					(end 155.780232 -12.896596)
				)
				(xy 155.701746 -13.043154)
				(arc
					(start 155.697428 -13.044424)
					(mid 155.588594 -13.119098)
					(end 155.456636 -13.117068)
				)
				(xy 155.452318 -13.118592) (xy 155.440634 -13.112242) (xy 155.427426 -13.112242) (xy 155.412186 -13.097002)
				(xy 154.992324 -12.872466)
			)
		)
	)
	(zone
		(net "DUT_VDD")
		(layer "B.Cu")
		(hatch none 0.5)
		(connect_pads
			(clearance 0.5)
		)
		(min_thickness 0.25)
		(fill yes
			(thermal_gap 0.5)
			(thermal_bridge_width 0.5)
			(island_removal_mode 0)
		)
		(polygon
			(pts
				(xy 247.015 -46.2788) (xy 246.888 -46.4058) (xy 246.888 -46.5328) (xy 247.1928 -46.8376) (xy 247.1928 -47.0789)
				(xy 240.411 -53.8607) (xy 240.411 -53.9877) (xy 240.6015 -54.1782) (xy 240.8047 -54.1782) (xy 247.6881 -47.2948)
				(xy 247.6881 -46.5074) (xy 247.4595 -46.2788)
			)
		)
	)
	(zone
		(layer "B.Cu")
		(hatch none 0.5)
		(connect_pads
			(clearance 0)
		)
		(min_thickness 0.25)
		(keepout
			(tracks not_allowed)
			(vias allowed)
			(pads allowed)
			(copperpour not_allowed)
			(footprints allowed)
		)
		(placement
			(enabled no)
			(sheetname "")
		)
		(fill
			(thermal_gap 0.5)
			(thermal_bridge_width 0.5)
			(island_removal_mode 0)
		)
		(polygon
			(pts
				(arc
					(start 286.126174 -24.94915)
					(mid 285.996821 -24.752734)
					(end 285.778194 -24.666194)
				)
				(xy 285.581344 -25.033732) (xy 285.581598 -25.033986)
				(arc
					(start 285.58363 -25.035002)
					(mid 285.839306 -25.880903)
					(end 286.685228 -25.625044)
				)
				(xy 286.68726 -25.626314) (xy 287.437322 -24.226266)
				(arc
					(start 287.43529 -24.224996)
					(mid 287.179258 -23.379176)
					(end 286.333438 -23.635208)
				)
				(xy 286.331406 -23.633938) (xy 286.028892 -24.198326)
				(arc
					(start 286.291782 -24.198326)
					(mid 286.430869 -24.181942)
					(end 286.562292 -24.133556)
				)
				(arc
					(start 286.562292 -24.133556)
					(mid 287.154047 -23.660927)
					(end 286.681418 -24.252682)
				)
				(arc
					(start 286.681418 -24.252682)
					(mid 286.510387 -24.328227)
					(end 286.326072 -24.359616)
				)
				(xy 286.32531 -24.360378) (xy 285.942278 -24.360378)
				(arc
					(start 285.859728 -24.514048)
					(mid 286.155167 -24.679676)
					(end 286.29864 -24.986488)
				)
				(arc
					(start 286.29864 -24.986488)
					(mid 286.0535 -25.702583)
					(end 286.126174 -24.94915)
				)
			)
		)
	)
	(zone
		(layer "B.Cu")
		(hatch none 0.5)
		(connect_pads
			(clearance 0)
		)
		(min_thickness 0.25)
		(keepout
			(tracks not_allowed)
			(vias allowed)
			(pads allowed)
			(copperpour not_allowed)
			(footprints allowed)
		)
		(placement
			(enabled no)
			(sheetname "")
		)
		(fill
			(thermal_gap 0.5)
			(thermal_bridge_width 0.5)
			(island_removal_mode 0)
		)
		(polygon
			(pts
				(arc
					(start 70.449948 -14.200124)
					(mid 74.44994 -18.200116)
					(end 78.449932 -14.200124)
				)
				(arc
					(start 78.449932 -14.200124)
					(mid 74.44994 -10.200132)
					(end 70.449948 -14.200124)
				)
			)
		)
	)
	(zone
		(layer "B.Cu")
		(hatch none 0.5)
		(connect_pads
			(clearance 0)
		)
		(min_thickness 0.25)
		(keepout
			(tracks not_allowed)
			(vias allowed)
			(pads allowed)
			(copperpour not_allowed)
			(footprints allowed)
		)
		(placement
			(enabled no)
			(sheetname "")
		)
		(fill
			(thermal_gap 0.5)
			(thermal_bridge_width 0.5)
			(island_removal_mode 0)
		)
		(polygon
			(pts
				(arc
					(start 324.493636 -221.784164)
					(mid 323.983096 -222.294704)
					(end 324.493636 -222.805244)
				)
				(arc
					(start 324.660006 -222.805244)
					(mid 324.630639 -222.672837)
					(end 324.57898 -222.547434)
				)
				(arc
					(start 324.57898 -222.547434)
					(mid 324.334308 -222.081026)
					(end 324.710552 -222.449644)
				)
				(arc
					(start 324.710552 -222.449644)
					(mid 324.784463 -222.621858)
					(end 324.823074 -222.805244)
				)
				(arc
					(start 324.977252 -222.805244)
					(mid 325.015733 -222.621993)
					(end 325.08952 -222.449898)
				)
				(arc
					(start 325.08952 -222.449898)
					(mid 325.465229 -222.080409)
					(end 325.221092 -222.547434)
				)
				(arc
					(start 325.221092 -222.547434)
					(mid 325.169549 -222.672842)
					(end 325.14032 -222.805244)
				)
				(arc
					(start 325.306182 -222.805244)
					(mid 325.816976 -222.294831)
					(end 325.306436 -221.784164)
				)
			)
		)
	)
	(zone
		(layer "B.Cu")
		(hatch none 0.5)
		(connect_pads
			(clearance 0)
		)
		(min_thickness 0.25)
		(keepout
			(tracks allowed)
			(vias allowed)
			(pads allowed)
			(copperpour allowed)
			(footprints allowed)
		)
		(placement
			(enabled no)
			(sheetname "")
		)
		(fill
			(thermal_gap 0.5)
			(thermal_bridge_width 0.5)
			(island_removal_mode 0)
		)
		(polygon
			(pts
				(xy 269.194026 -18.069814) (xy 269.194026 -16.215614) (xy 270.057626 -16.215614) (xy 270.057626 -18.069814)
			)
		)
	)
	(zone
		(layer "B.Cu")
		(hatch none 0.5)
		(connect_pads
			(clearance 0)
		)
		(min_thickness 0.25)
		(keepout
			(tracks allowed)
			(vias allowed)
			(pads allowed)
			(copperpour allowed)
			(footprints allowed)
		)
		(placement
			(enabled no)
			(sheetname "")
		)
		(fill
			(thermal_gap 0.5)
			(thermal_bridge_width 0.5)
			(island_removal_mode 0)
		)
		(polygon
			(pts
				(xy 259.334 -228.1428) (xy 259.334 -221.9198) (xy 344.932 -221.9198) (xy 344.932 -228.1428)
			)
		)
	)
	(zone
		(net "GND")
		(layer "B.Cu")
		(hatch none 0.5)
		(connect_pads
			(clearance 0.5)
		)
		(min_thickness 0.25)
		(fill yes
			(thermal_gap 0.5)
			(thermal_bridge_width 0.5)
			(island_removal_mode 0)
		)
		(polygon
			(pts
				(xy 250.5456 -39.7002) (xy 250.4313 -39.8145) (xy 250.4313 -40.0685) (xy 249.2629 -41.2369) (xy 248.9073 -41.2369)
				(xy 247.8786 -42.2656) (xy 247.8532 -42.2656) (xy 243.2431 -46.8757) (xy 243.2431 -47.0154) (xy 242.5954 -47.6631)
				(xy 242.5954 -48.4505) (xy 242.2144 -48.8315) (xy 241.3 -48.8315) (xy 241.2365 -48.895) (xy 241.2365 -49.0601)
				(xy 241.3762 -49.1998) (xy 241.3762 -49.7205) (xy 241.2111 -49.8856) (xy 240.2078 -49.8856) (xy 235.7501 -54.3433)
				(xy 235.7501 -54.4068) (xy 235.3183 -54.8386) (xy 234.8865 -54.8386) (xy 234.7214 -54.6735) (xy 234.7214 -54.356)
				(xy 247.3325 -41.7449) (xy 247.3325 -41.4782) (xy 247.1547 -41.3004) (xy 246.8753 -41.3004) (xy 234.4928 -53.6829)
				(xy 234.4801 -53.6829) (xy 234.3023 -53.8607) (xy 233.8705 -53.8607) (xy 233.7308 -53.721) (xy 233.7308 -53.3527)
				(xy 245.6688 -41.4147) (xy 245.6688 -40.894) (xy 245.618 -40.8432) (xy 245.2624 -40.8432) (xy 245.2497 -40.8559)
				(xy 245.2497 -41.1099) (xy 245.0465 -41.3131) (xy 244.856 -41.3131) (xy 233.2736 -52.8955) (xy 232.9053 -52.8955)
				(xy 232.6894 -52.6796) (xy 232.6894 -52.3367) (xy 237.7186 -47.3075) (xy 237.7186 -46.4439) (xy 239.0648 -45.0977)
				(xy 239.8903 -45.0977) (xy 243.2812 -41.7068) (xy 243.2812 -41.4274) (xy 243.1542 -41.3004) (xy 242.7986 -41.3004)
				(xy 240.35385 -43.74515) (xy 239.60455 -43.74515) (xy 239.0267 -44.323) (xy 238.8489 -44.323) (xy 236.8931 -46.2788)
				(xy 236.8931 -46.5074) (xy 237.1852 -46.7995) (xy 237.1852 -47.0408) (xy 233.3117 -50.9143) (xy 232.9815 -50.9143)
				(xy 232.6894 -50.6222) (xy 232.6894 -50.2412) (xy 235.0135 -47.9171) (xy 235.0135 -46.9011) (xy 239.3442 -42.5704)
				(xy 240.411 -42.5704) (xy 242.2906 -40.6908) (xy 242.2906 -40.3987) (xy 242.0366 -40.1447) (xy 242.0366 -39.9161)
				(xy 241.9985 -39.878) (xy 241.4016 -39.878) (xy 234.4039 -46.8757) (xy 233.8705 -46.8757) (xy 233.68 -46.6852)
				(xy 233.68 -46.2788) (xy 239.3696 -40.5892) (xy 239.3696 -39.9542) (xy 239.2807 -39.8653) (xy 238.7346 -39.8653)
				(xy 238.7219 -39.878) (xy 238.7219 -40.5511) (xy 234.3023 -44.9707) (xy 233.9975 -44.9707) (xy 233.68 -44.6532)
				(xy 233.68 -44.1579) (xy 235.2929 -42.545) (xy 235.2929 -42.2148) (xy 234.3404 -41.2623) (xy 231.0384 -41.2623)
				(xy 230.4288 -41.8719) (xy 230.3145 -41.8719) (xy 230.2256 -41.9608) (xy 230.2256 -42.1386) (xy 230.0732 -42.291)
				(xy 228.9556 -42.291) (xy 228.7524 -42.4942) (xy 228.7524 -46.1264) (xy 230.4034 -46.1264) (xy 230.505 -46.228)
				(xy 230.505 -46.8376) (xy 230.4288 -46.9138) (xy 230.0732 -46.9138) (xy 230.0224 -46.9646) (xy 230.0224 -47.2694)
				(xy 229.8446 -47.4472) (xy 229.0572 -47.4472) (xy 228.7524 -47.752) (xy 228.7524 -60.0964) (xy 228.8159 -60.1599)
				(xy 229.0572 -60.1599) (xy 229.1715 -60.0456) (xy 234.6833 -60.0456) (xy 234.8103 -59.9186) (xy 234.8103 -58.7375)
				(xy 234.8484 -58.6994) (xy 235.1659 -58.6994) (xy 235.4453 -58.42) (xy 235.4453 -57.8993) (xy 235.3818 -57.8358)
				(xy 235.0008 -57.8358) (xy 234.8103 -57.6453) (xy 234.8103 -56.7817) (xy 234.8738 -56.7182) (xy 235.3056 -56.7182)
				(xy 235.4834 -56.5404) (xy 235.4834 -55.7911) (xy 235.5596 -55.7149) (xy 236.3089 -55.7149) (xy 236.5883 -55.9943)
				(xy 236.5883 -56.4896) (xy 236.8042 -56.7055) (xy 237.1471 -56.7055) (xy 237.5281 -56.3245) (xy 237.5281 -55.7657)
				(xy 237.5535 -55.7403) (xy 239.6363 -55.7403) (xy 239.6744 -55.7022) (xy 241.6429 -55.7022) (xy 241.7191 -55.7784)
				(xy 241.7191 -56.5277) (xy 241.8588 -56.6674) (xy 242.6589 -56.6674) (xy 242.8113 -56.515) (xy 242.8113 -55.8673)
				(xy 242.9764 -55.7022) (xy 243.586 -55.7022) (xy 243.6622 -55.7784) (xy 243.6622 -56.5531) (xy 243.8527 -56.7436)
				(xy 244.5639 -56.7436) (xy 244.7544 -56.5531) (xy 244.7544 -55.8292) (xy 244.8814 -55.7022) (xy 245.5672 -55.7022)
				(xy 245.6942 -55.8292) (xy 245.6942 -56.4388) (xy 245.9355 -56.6801) (xy 246.1768 -56.6801) (xy 246.2911 -56.7944)
				(xy 246.2911 -57.7088) (xy 246.1641 -57.8358) (xy 245.7577 -57.8358) (xy 245.7069 -57.8866) (xy 245.7069 -58.5597)
				(xy 245.8593 -58.7121) (xy 246.3419 -58.7121) (xy 246.4435 -58.8137) (xy 246.4435 -59.9059) (xy 246.5324 -59.9948)
				(xy 250.8377 -59.9948) (xy 250.9774 -60.1345) (xy 252.4252 -60.1345) (xy 252.476 -60.0837) (xy 252.476 -47.5996)
				(xy 252.349 -47.4726) (xy 251.333 -47.4726) (xy 251.206 -47.3456) (xy 251.206 -46.9392) (xy 251.1552 -46.8884)
				(xy 250.8504 -46.8884) (xy 250.7488 -46.7868) (xy 250.7488 -46.2788) (xy 250.8504 -46.1772) (xy 252.4252 -46.1772)
				(xy 252.476 -46.1264) (xy 252.476 -42.4942) (xy 252.349 -42.3672) (xy 251.5362 -42.3672) (xy 251.46 -42.291)
				(xy 251.46 -41.91) (xy 251.4092 -41.8592) (xy 250.8504 -41.8592) (xy 250.7234 -41.7322) (xy 250.7234 -41.2242)
				(xy 250.825 -41.1226) (xy 252.476 -41.1226) (xy 252.476 -39.8653) (xy 252.3109 -39.7002)
			)
		)
		(polygon
			(pts
				(xy 252.222 -59.7154) (xy 252.0188 -59.7154) (xy 252.0188 -59.9186) (xy 252.222 -59.9186)
			)
		)
		(polygon
			(pts
				(xy 229.2096 -59.7154) (xy 229.0064 -59.7154) (xy 229.0064 -59.9186) (xy 229.2096 -59.9186)
			)
		)
		(polygon
			(pts
				(xy 234.519216 -59.563) (xy 234.316016 -59.563) (xy 234.316016 -59.7662) (xy 234.519216 -59.7662)
			)
		)
		(polygon
			(pts
				(xy 233.8832 -59.5376) (xy 233.68 -59.5376) (xy 233.68 -59.7408) (xy 233.8832 -59.7408)
			)
		)
		(polygon
			(pts
				(xy 233.5276 -59.5376) (xy 233.3244 -59.5376) (xy 233.3244 -59.7408) (xy 233.5276 -59.7408)
			)
		)
		(polygon
			(pts
				(xy 232.87482 -59.5376) (xy 232.67162 -59.5376) (xy 232.67162 -59.7408) (xy 232.87482 -59.7408)
			)
		)
		(polygon
			(pts
				(xy 232.51922 -59.5376) (xy 232.31602 -59.5376) (xy 232.31602 -59.7408) (xy 232.51922 -59.7408)
			)
		)
		(polygon
			(pts
				(xy 231.8766 -59.5376) (xy 231.6734 -59.5376) (xy 231.6734 -59.7408) (xy 231.8766 -59.7408)
			)
		)
		(polygon
			(pts
				(xy 231.521 -59.5376) (xy 231.3178 -59.5376) (xy 231.3178 -59.7408) (xy 231.521 -59.7408)
			)
		)
		(polygon
			(pts
				(xy 230.884222 -59.5376) (xy 230.681022 -59.5376) (xy 230.681022 -59.7408) (xy 230.884222 -59.7408)
			)
		)
		(polygon
			(pts
				(xy 230.528622 -59.5376) (xy 230.325422 -59.5376) (xy 230.325422 -59.7408) (xy 230.528622 -59.7408)
			)
		)
		(polygon
			(pts
				(xy 250.8758 -59.4868) (xy 250.6726 -59.4868) (xy 250.6726 -59.69) (xy 250.8758 -59.69)
			)
		)
		(polygon
			(pts
				(xy 250.5202 -59.4868) (xy 250.317 -59.4868) (xy 250.317 -59.69) (xy 250.5202 -59.69)
			)
		)
		(polygon
			(pts
				(xy 249.884438 -59.4868) (xy 249.681238 -59.4868) (xy 249.681238 -59.69) (xy 249.884438 -59.69)
			)
		)
		(polygon
			(pts
				(xy 249.528838 -59.4868) (xy 249.325638 -59.4868) (xy 249.325638 -59.69) (xy 249.528838 -59.69)
			)
		)
		(polygon
			(pts
				(xy 248.88444 -59.4868) (xy 248.68124 -59.4868) (xy 248.68124 -59.69) (xy 248.88444 -59.69)
			)
		)
		(polygon
			(pts
				(xy 248.52884 -59.4868) (xy 248.32564 -59.4868) (xy 248.32564 -59.69) (xy 248.52884 -59.69)
			)
		)
		(polygon
			(pts
				(xy 247.8786 -59.4868) (xy 247.6754 -59.4868) (xy 247.6754 -59.69) (xy 247.8786 -59.69)
			)
		)
		(polygon
			(pts
				(xy 247.523 -59.4868) (xy 247.3198 -59.4868) (xy 247.3198 -59.69) (xy 247.523 -59.69)
			)
		)
		(polygon
			(pts
				(xy 246.87403 -59.4868) (xy 246.67083 -59.4868) (xy 246.67083 -59.69) (xy 246.87403 -59.69)
			)
		)
		(polygon
			(pts
				(xy 252.222 -59.072272) (xy 252.0188 -59.072272) (xy 252.0188 -59.275472) (xy 252.222 -59.275472)
			)
		)
		(polygon
			(pts
				(xy 229.2096 -59.072272) (xy 229.0064 -59.072272) (xy 229.0064 -59.275472) (xy 229.2096 -59.275472)
			)
		)
		(polygon
			(pts
				(xy 252.222 -58.716672) (xy 252.0188 -58.716672) (xy 252.0188 -58.919872) (xy 252.222 -58.919872)
			)
		)
		(polygon
			(pts
				(xy 229.2096 -58.716672) (xy 229.0064 -58.716672) (xy 229.0064 -58.919872) (xy 229.2096 -58.919872)
			)
		)
		(polygon
			(pts
				(xy 252.222 -58.081672) (xy 252.0188 -58.081672) (xy 252.0188 -58.284872) (xy 252.222 -58.284872)
			)
		)
		(polygon
			(pts
				(xy 235.204 -58.071258) (xy 235.0008 -58.071258) (xy 235.0008 -58.274458) (xy 235.204 -58.274458)
			)
		)
		(polygon
			(pts
				(xy 229.2096 -58.068972) (xy 229.0064 -58.068972) (xy 229.0064 -58.272172) (xy 229.2096 -58.272172)
			)
		)
		(polygon
			(pts
				(xy 246.1768 -58.0644) (xy 245.9736 -58.0644) (xy 245.9736 -58.2676) (xy 246.1768 -58.2676)
			)
		)
		(polygon
			(pts
				(xy 252.222 -57.726072) (xy 252.0188 -57.726072) (xy 252.0188 -57.929272) (xy 252.222 -57.929272)
			)
		)
		(polygon
			(pts
				(xy 229.2096 -57.713372) (xy 229.0064 -57.713372) (xy 229.0064 -57.916572) (xy 229.2096 -57.916572)
			)
		)
		(polygon
			(pts
				(xy 252.222 -57.065672) (xy 252.0188 -57.065672) (xy 252.0188 -57.268872) (xy 252.222 -57.268872)
			)
		)
		(polygon
			(pts
				(xy 229.2096 -57.065672) (xy 229.0064 -57.065672) (xy 229.0064 -57.268872) (xy 229.2096 -57.268872)
			)
		)
		(polygon
			(pts
				(xy 252.222 -56.710072) (xy 252.0188 -56.710072) (xy 252.0188 -56.913272) (xy 252.222 -56.913272)
			)
		)
		(polygon
			(pts
				(xy 229.2096 -56.710072) (xy 229.0064 -56.710072) (xy 229.0064 -56.913272) (xy 229.2096 -56.913272)
			)
		)
		(polygon
			(pts
				(xy 246.1514 -56.0832) (xy 245.9482 -56.0832) (xy 245.9482 -56.2864) (xy 246.1514 -56.2864)
			)
		)
		(polygon
			(pts
				(xy 244.1448 -56.0832) (xy 243.9416 -56.0832) (xy 243.9416 -56.2864) (xy 244.1448 -56.2864)
			)
		)
		(polygon
			(pts
				(xy 242.189 -56.0832) (xy 241.9858 -56.0832) (xy 241.9858 -56.2864) (xy 242.189 -56.2864)
			)
		)
		(polygon
			(pts
				(xy 237.236 -56.07812) (xy 237.0328 -56.07812) (xy 237.0328 -56.28132) (xy 237.236 -56.28132)
			)
		)
		(polygon
			(pts
				(xy 235.204 -56.07812) (xy 235.0008 -56.07812) (xy 235.0008 -56.28132) (xy 235.204 -56.28132)
			)
		)
		(polygon
			(pts
				(xy 252.222 -56.075072) (xy 252.0188 -56.075072) (xy 252.0188 -56.278272) (xy 252.222 -56.278272)
			)
		)
		(polygon
			(pts
				(xy 229.2096 -56.075072) (xy 229.0064 -56.075072) (xy 229.0064 -56.278272) (xy 229.2096 -56.278272)
			)
		)
		(polygon
			(pts
				(xy 246.1514 -55.7276) (xy 245.9482 -55.7276) (xy 245.9482 -55.9308) (xy 246.1514 -55.9308)
			)
		)
		(polygon
			(pts
				(xy 244.1448 -55.7276) (xy 243.9416 -55.7276) (xy 243.9416 -55.9308) (xy 244.1448 -55.9308)
			)
		)
		(polygon
			(pts
				(xy 242.189 -55.7276) (xy 241.9858 -55.7276) (xy 241.9858 -55.9308) (xy 242.189 -55.9308)
			)
		)
		(polygon
			(pts
				(xy 237.236 -55.72252) (xy 237.0328 -55.72252) (xy 237.0328 -55.92572) (xy 237.236 -55.92572)
			)
		)
		(polygon
			(pts
				(xy 235.204 -55.72252) (xy 235.0008 -55.72252) (xy 235.0008 -55.92572) (xy 235.204 -55.92572)
			)
		)
		(polygon
			(pts
				(xy 252.222 -55.719472) (xy 252.0188 -55.719472) (xy 252.0188 -55.922672) (xy 252.222 -55.922672)
			)
		)
		(polygon
			(pts
				(xy 229.2096 -55.719472) (xy 229.0064 -55.719472) (xy 229.0064 -55.922672) (xy 229.2096 -55.922672)
			)
		)
		(polygon
			(pts
				(xy 234.1118 -55.0799) (xy 233.9086 -55.0799) (xy 233.9086 -55.2831) (xy 234.1118 -55.2831)
			)
		)
		(polygon
			(pts
				(xy 252.222 -55.071772) (xy 252.0188 -55.071772) (xy 252.0188 -55.274972) (xy 252.222 -55.274972)
			)
		)
		(polygon
			(pts
				(xy 229.2096 -55.071772) (xy 229.0064 -55.071772) (xy 229.0064 -55.274972) (xy 229.2096 -55.274972)
			)
		)
		(polygon
			(pts
				(xy 247.2563 -55.06974) (xy 247.0531 -55.06974) (xy 247.0531 -55.27294) (xy 247.2563 -55.27294)
			)
		)
		(polygon
			(pts
				(xy 250.1392 -55.06847) (xy 249.936 -55.06847) (xy 249.936 -55.27167) (xy 250.1392 -55.27167)
			)
		)
		(polygon
			(pts
				(xy 231.2162 -55.0672) (xy 231.013 -55.0672) (xy 231.013 -55.2704) (xy 231.2162 -55.2704)
			)
		)
		(polygon
			(pts
				(xy 234.1118 -54.7243) (xy 233.9086 -54.7243) (xy 233.9086 -54.9275) (xy 234.1118 -54.9275)
			)
		)
		(polygon
			(pts
				(xy 252.222 -54.716172) (xy 252.0188 -54.716172) (xy 252.0188 -54.919372) (xy 252.222 -54.919372)
			)
		)
		(polygon
			(pts
				(xy 229.2096 -54.716172) (xy 229.0064 -54.716172) (xy 229.0064 -54.919372) (xy 229.2096 -54.919372)
			)
		)
		(polygon
			(pts
				(xy 247.2563 -54.71414) (xy 247.0531 -54.71414) (xy 247.0531 -54.91734) (xy 247.2563 -54.91734)
			)
		)
		(polygon
			(pts
				(xy 250.1392 -54.71287) (xy 249.936 -54.71287) (xy 249.936 -54.91607) (xy 250.1392 -54.91607)
			)
		)
		(polygon
			(pts
				(xy 231.2162 -54.7116) (xy 231.013 -54.7116) (xy 231.013 -54.9148) (xy 231.2162 -54.9148)
			)
		)
		(polygon
			(pts
				(xy 247.65 -54.082696) (xy 247.4468 -54.082696) (xy 247.4468 -54.285896) (xy 247.65 -54.285896)
			)
		)
		(polygon
			(pts
				(xy 239.7506 -54.0766) (xy 239.5474 -54.0766) (xy 239.5474 -54.2798) (xy 239.7506 -54.2798)
			)
		)
		(polygon
			(pts
				(xy 252.222 -54.068472) (xy 252.0188 -54.068472) (xy 252.0188 -54.271672) (xy 252.222 -54.271672)
			)
		)
		(polygon
			(pts
				(xy 229.2096 -54.068472) (xy 229.0064 -54.068472) (xy 229.0064 -54.271672) (xy 229.2096 -54.271672)
			)
		)
		(polygon
			(pts
				(xy 236.7788 -53.721) (xy 236.5756 -53.721) (xy 236.5756 -53.9242) (xy 236.7788 -53.9242)
			)
		)
		(polygon
			(pts
				(xy 252.222 -53.712872) (xy 252.0188 -53.712872) (xy 252.0188 -53.916072) (xy 252.222 -53.916072)
			)
		)
		(polygon
			(pts
				(xy 229.2096 -53.712872) (xy 229.0064 -53.712872) (xy 229.0064 -53.916072) (xy 229.2096 -53.916072)
			)
		)
		(polygon
			(pts
				(xy 252.222 -53.077872) (xy 252.0188 -53.077872) (xy 252.0188 -53.281072) (xy 252.222 -53.281072)
			)
		)
		(polygon
			(pts
				(xy 229.2096 -53.077872) (xy 229.0064 -53.077872) (xy 229.0064 -53.281072) (xy 229.2096 -53.281072)
			)
		)
		(polygon
			(pts
				(xy 252.222 -52.722272) (xy 252.0188 -52.722272) (xy 252.0188 -52.925472) (xy 252.222 -52.925472)
			)
		)
		(polygon
			(pts
				(xy 229.2096 -52.722272) (xy 229.0064 -52.722272) (xy 229.0064 -52.925472) (xy 229.2096 -52.925472)
			)
		)
		(polygon
			(pts
				(xy 229.2096 -52.074572) (xy 229.0064 -52.074572) (xy 229.0064 -52.277772) (xy 229.2096 -52.277772)
			)
		)
		(polygon
			(pts
				(xy 252.222 -52.061872) (xy 252.0188 -52.061872) (xy 252.0188 -52.265072) (xy 252.222 -52.265072)
			)
		)
		(polygon
			(pts
				(xy 248.2723 -51.9303) (xy 248.0564 -51.9303) (xy 245.6307 -54.356) (xy 245.6307 -54.6227) (xy 245.8974 -54.8894)
				(xy 246.38 -54.8894) (xy 248.5644 -52.705) (xy 248.5644 -52.2224)
			)
		)
		(polygon
			(pts
				(xy 229.2096 -51.718972) (xy 229.0064 -51.718972) (xy 229.0064 -51.922172) (xy 229.2096 -51.922172)
			)
		)
		(polygon
			(pts
				(xy 238.7854 -51.7144) (xy 238.5822 -51.7144) (xy 238.5822 -51.9176) (xy 238.7854 -51.9176)
			)
		)
		(polygon
			(pts
				(xy 252.222 -51.706272) (xy 252.0188 -51.706272) (xy 252.0188 -51.909472) (xy 252.222 -51.909472)
			)
		)
		(polygon
			(pts
				(xy 252.222 -51.071272) (xy 252.0188 -51.071272) (xy 252.0188 -51.274472) (xy 252.222 -51.274472)
			)
		)
		(polygon
			(pts
				(xy 229.2096 -51.071272) (xy 229.0064 -51.071272) (xy 229.0064 -51.274472) (xy 229.2096 -51.274472)
			)
		)
		(polygon
			(pts
				(xy 252.222 -50.715672) (xy 252.0188 -50.715672) (xy 252.0188 -50.918872) (xy 252.222 -50.918872)
			)
		)
		(polygon
			(pts
				(xy 229.2096 -50.715672) (xy 229.0064 -50.715672) (xy 229.0064 -50.918872) (xy 229.2096 -50.918872)
			)
		)
		(polygon
			(pts
				(xy 248.2342 -50.165) (xy 247.777 -50.165) (xy 243.5733 -54.3687) (xy 243.5733 -54.5846) (xy 243.8273 -54.8386)
				(xy 244.4369 -54.8386) (xy 248.5517 -50.7238) (xy 248.5517 -50.4825)
			)
		)
		(polygon
			(pts
				(xy 252.222 -50.080672) (xy 252.0188 -50.080672) (xy 252.0188 -50.283872) (xy 252.222 -50.283872)
			)
		)
		(polygon
			(pts
				(xy 229.2096 -50.067972) (xy 229.0064 -50.067972) (xy 229.0064 -50.271172) (xy 229.2096 -50.271172)
			)
		)
		(polygon
			(pts
				(xy 252.222 -49.725072) (xy 252.0188 -49.725072) (xy 252.0188 -49.928272) (xy 252.222 -49.928272)
			)
		)
		(polygon
			(pts
				(xy 229.2096 -49.712372) (xy 229.0064 -49.712372) (xy 229.0064 -49.915572) (xy 229.2096 -49.915572)
			)
		)
		(polygon
			(pts
				(xy 229.2096 -49.077372) (xy 229.0064 -49.077372) (xy 229.0064 -49.280572) (xy 229.2096 -49.280572)
			)
		)
		(polygon
			(pts
				(xy 252.222 -49.064672) (xy 252.0188 -49.064672) (xy 252.0188 -49.267872) (xy 252.222 -49.267872)
			)
		)
		(polygon
			(pts
				(xy 229.2096 -48.721772) (xy 229.0064 -48.721772) (xy 229.0064 -48.924972) (xy 229.2096 -48.924972)
			)
		)
		(polygon
			(pts
				(xy 242.7478 -48.7172) (xy 242.5446 -48.7172) (xy 242.5446 -48.9204) (xy 242.7478 -48.9204)
			)
		)
		(polygon
			(pts
				(xy 252.222 -48.709072) (xy 252.0188 -48.709072) (xy 252.0188 -48.912272) (xy 252.222 -48.912272)
			)
		)
		(polygon
			(pts
				(xy 248.3104 -48.1711) (xy 247.7643 -48.1711) (xy 247.5611 -48.3743) (xy 247.5611 -48.387) (xy 241.681 -54.2671)
				(xy 241.681 -54.61) (xy 241.8842 -54.8132) (xy 242.4176 -54.8132) (xy 248.4247 -48.8061) (xy 248.4247 -48.2854)
			)
		)
		(polygon
			(pts
				(xy 252.222 -48.074072) (xy 252.0188 -48.074072) (xy 252.0188 -48.277272) (xy 252.222 -48.277272)
			)
		)
		(polygon
			(pts
				(xy 229.2096 -48.074072) (xy 229.0064 -48.074072) (xy 229.0064 -48.277272) (xy 229.2096 -48.277272)
			)
		)
		(polygon
			(pts
				(xy 252.222 -47.718472) (xy 252.0188 -47.718472) (xy 252.0188 -47.921672) (xy 252.222 -47.921672)
			)
		)
		(polygon
			(pts
				(xy 229.2096 -47.718472) (xy 229.0064 -47.718472) (xy 229.0064 -47.921672) (xy 229.2096 -47.921672)
			)
		)
		(polygon
			(pts
				(xy 250.952 -47.1932) (xy 250.7488 -47.1932) (xy 250.7488 -47.3964) (xy 250.952 -47.3964)
			)
		)
		(polygon
			(pts
				(xy 230.505 -47.117) (xy 230.3018 -47.117) (xy 230.3018 -47.3202) (xy 230.505 -47.3202)
			)
		)
		(polygon
			(pts
				(xy 244.7544 -47.108872) (xy 244.5512 -47.108872) (xy 244.5512 -47.312072) (xy 244.7544 -47.312072)
			)
		)
		(polygon
			(pts
				(xy 243.713 -47.108872) (xy 243.5098 -47.108872) (xy 243.5098 -47.312072) (xy 243.713 -47.312072)
			)
		)
		(polygon
			(pts
				(xy 234.7214 -47.108872) (xy 234.5182 -47.108872) (xy 234.5182 -47.312072) (xy 234.7214 -47.312072)
			)
		)
		(polygon
			(pts
				(xy 250.1265 -47.0789) (xy 249.9233 -47.0789) (xy 249.9233 -47.2821) (xy 250.1265 -47.2821)
			)
		)
		(polygon
			(pts
				(xy 250.1265 -46.7233) (xy 249.9233 -46.7233) (xy 249.9233 -46.9265) (xy 250.1265 -46.9265)
			)
		)
		(polygon
			(pts
				(xy 247.5611 -46.1772) (xy 246.9007 -46.1772) (xy 246.7483 -46.3296) (xy 246.7483 -46.6344) (xy 247.0023 -46.8884)
				(xy 247.0023 -47.0789) (xy 240.2332 -53.848) (xy 240.2332 -54.1147) (xy 240.3856 -54.2671) (xy 240.9698 -54.2671)
				(xy 246.9007 -48.3362) (xy 246.9007 -48.3235) (xy 247.8151 -47.4091) (xy 247.8151 -46.4312)
			)
		)
		(polygon
			(pts
				(xy 231.2162 -46.0756) (xy 231.013 -46.0756) (xy 231.013 -46.2788) (xy 231.2162 -46.2788)
			)
		)
		(polygon
			(pts
				(xy 231.2162 -45.72) (xy 231.013 -45.72) (xy 231.013 -45.9232) (xy 231.2162 -45.9232)
			)
		)
		(polygon
			(pts
				(xy 252.222 -45.711872) (xy 252.0188 -45.711872) (xy 252.0188 -45.915072) (xy 252.222 -45.915072)
			)
		)
		(polygon
			(pts
				(xy 229.2096 -45.711872) (xy 229.0064 -45.711872) (xy 229.0064 -45.915072) (xy 229.2096 -45.915072)
			)
		)
		(polygon
			(pts
				(xy 252.222 -45.076872) (xy 252.0188 -45.076872) (xy 252.0188 -45.280072) (xy 252.222 -45.280072)
			)
		)
		(polygon
			(pts
				(xy 229.2096 -45.076872) (xy 229.0064 -45.076872) (xy 229.0064 -45.280072) (xy 229.2096 -45.280072)
			)
		)
		(polygon
			(pts
				(xy 250.1646 -45.0723) (xy 249.9614 -45.0723) (xy 249.9614 -45.2755) (xy 250.1646 -45.2755)
			)
		)
		(polygon
			(pts
				(xy 232.884472 -44.873672) (xy 232.681272 -44.873672) (xy 232.681272 -45.076872) (xy 232.884472 -45.076872)
			)
		)
		(polygon
			(pts
				(xy 232.528872 -44.873672) (xy 232.325672 -44.873672) (xy 232.325672 -45.076872) (xy 232.528872 -45.076872)
			)
		)
		(polygon
			(pts
				(xy 252.222 -44.721272) (xy 252.0188 -44.721272) (xy 252.0188 -44.924472) (xy 252.222 -44.924472)
			)
		)
		(polygon
			(pts
				(xy 229.2096 -44.721272) (xy 229.0064 -44.721272) (xy 229.0064 -44.924472) (xy 229.2096 -44.924472)
			)
		)
		(polygon
			(pts
				(xy 250.1646 -44.7167) (xy 249.9614 -44.7167) (xy 249.9614 -44.9199) (xy 250.1646 -44.9199)
			)
		)
		(polygon
			(pts
				(xy 252.222 -44.086272) (xy 252.0188 -44.086272) (xy 252.0188 -44.289472) (xy 252.222 -44.289472)
			)
		)
		(polygon
			(pts
				(xy 239.7506 -44.073572) (xy 239.5474 -44.073572) (xy 239.5474 -44.276772) (xy 239.7506 -44.276772)
			)
		)
		(polygon
			(pts
				(xy 229.2096 -44.073572) (xy 229.0064 -44.073572) (xy 229.0064 -44.276772) (xy 229.2096 -44.276772)
			)
		)
		(polygon
			(pts
				(xy 252.222 -43.730672) (xy 252.0188 -43.730672) (xy 252.0188 -43.933872) (xy 252.222 -43.933872)
			)
		)
		(polygon
			(pts
				(xy 229.2096 -43.717972) (xy 229.0064 -43.717972) (xy 229.0064 -43.921172) (xy 229.2096 -43.921172)
			)
		)
		(polygon
			(pts
				(xy 247.9929 -43.18) (xy 247.7643 -43.18) (xy 247.1547 -43.7896) (xy 247.1547 -44.0055) (xy 244.7925 -46.3677)
				(xy 244.7925 -46.6598) (xy 245.0338 -46.9011) (xy 245.0338 -47.2059) (xy 243.6876 -48.5521) (xy 243.4082 -48.5521)
				(xy 243.078 -48.8823) (xy 243.078 -49.0982) (xy 240.8301 -51.3461) (xy 239.7125 -51.3461) (xy 236.4867 -54.5719)
				(xy 237.0455 -55.1307) (xy 238.9378 -55.1307) (xy 239.395 -54.6735) (xy 239.395 -54.3306) (xy 239.2934 -54.229)
				(xy 239.2934 -53.9242) (xy 240.6523 -52.5653) (xy 240.8047 -52.5653) (xy 246.1006 -47.2694) (xy 246.1006 -46.6852)
				(xy 245.9609 -46.5455) (xy 245.9609 -46.1772) (xy 248.4501 -43.688) (xy 248.4501 -43.6372)
			)
		)
		(polygon
			(pts
				(xy 252.222 -43.070272) (xy 252.0188 -43.070272) (xy 252.0188 -43.273472) (xy 252.222 -43.273472)
			)
		)
		(polygon
			(pts
				(xy 229.2096 -43.070272) (xy 229.0064 -43.070272) (xy 229.0064 -43.273472) (xy 229.2096 -43.273472)
			)
		)
		(polygon
			(pts
				(xy 252.222 -42.714672) (xy 252.0188 -42.714672) (xy 252.0188 -42.917872) (xy 252.222 -42.917872)
			)
		)
		(polygon
			(pts
				(xy 229.2096 -42.714672) (xy 229.0064 -42.714672) (xy 229.0064 -42.917872) (xy 229.2096 -42.917872)
			)
		)
		(polygon
			(pts
				(xy 251.206 -42.0878) (xy 251.0028 -42.0878) (xy 251.0028 -42.291) (xy 251.206 -42.291)
			)
		)
		(polygon
			(pts
				(xy 239.7506 -42.072052) (xy 239.5474 -42.072052) (xy 239.5474 -42.275252) (xy 239.7506 -42.275252)
			)
		)
		(polygon
			(pts
				(xy 234.7214 -42.072052) (xy 234.5182 -42.072052) (xy 234.5182 -42.275252) (xy 234.7214 -42.275252)
			)
		)
		(polygon
			(pts
				(xy 230.7336 -42.0624) (xy 230.5304 -42.0624) (xy 230.5304 -42.2656) (xy 230.7336 -42.2656)
			)
		)
		(polygon
			(pts
				(xy 242.7478 -41.716452) (xy 242.5446 -41.716452) (xy 242.5446 -41.919652) (xy 242.7478 -41.919652)
			)
		)
		(polygon
			(pts
				(xy 240.7158 -41.716452) (xy 240.5126 -41.716452) (xy 240.5126 -41.919652) (xy 240.7158 -41.919652)
			)
		)
		(polygon
			(pts
				(xy 240.665 -41.0972) (xy 240.4618 -41.0972) (xy 240.4618 -41.3004) (xy 240.665 -41.3004)
			)
		)
		(polygon
			(pts
				(xy 241.749072 -40.733472) (xy 241.545872 -40.733472) (xy 241.545872 -40.936672) (xy 241.749072 -40.936672)
			)
		)
		(polygon
			(pts
				(xy 252.222 -40.7162) (xy 252.0188 -40.7162) (xy 252.0188 -40.9194) (xy 252.222 -40.9194)
			)
		)
		(polygon
			(pts
				(xy 251.088906 -40.11041) (xy 250.885706 -40.11041) (xy 250.885706 -40.31361) (xy 251.088906 -40.31361)
			)
		)
		(polygon
			(pts
				(xy 252.1966 -40.0812) (xy 251.9934 -40.0812) (xy 251.9934 -40.2844) (xy 252.1966 -40.2844)
			)
		)
		(polygon
			(pts
				(xy 239.2045 -40.0812) (xy 239.0013 -40.0812) (xy 239.0013 -40.2844) (xy 239.2045 -40.2844)
			)
		)
		(polygon
			(pts
				(xy 241.749072 -40.073072) (xy 241.545872 -40.073072) (xy 241.545872 -40.276272) (xy 241.749072 -40.276272)
			)
		)
	)
	(zone
		(layer "B.Cu")
		(hatch none 0.5)
		(connect_pads
			(clearance 0)
		)
		(min_thickness 0.25)
		(keepout
			(tracks not_allowed)
			(vias allowed)
			(pads allowed)
			(copperpour not_allowed)
			(footprints allowed)
		)
		(placement
			(enabled no)
			(sheetname "")
		)
		(fill
			(thermal_gap 0.5)
			(thermal_bridge_width 0.5)
			(island_removal_mode 0)
		)
		(polygon
			(pts
				(arc
					(start 347.49994 -34.500058)
					(mid 345.60002 -32.600138)
					(end 343.7001 -34.500058)
				)
				(arc
					(start 343.7001 -34.500058)
					(mid 345.60002 -36.399978)
					(end 347.49994 -34.500058)
				)
			)
		)
	)
	(zone
		(layer "B.Cu")
		(hatch none 0.5)
		(connect_pads
			(clearance 0)
		)
		(min_thickness 0.25)
		(keepout
			(tracks allowed)
			(vias allowed)
			(pads allowed)
			(copperpour allowed)
			(footprints not_allowed)
		)
		(placement
			(enabled no)
			(sheetname "")
		)
		(fill
			(thermal_gap 0.5)
			(thermal_bridge_width 0.5)
			(island_removal_mode 0)
		)
		(polygon
			(pts
				(arc
					(start 343.7001 -34.500058)
					(mid 345.60002 -36.399978)
					(end 347.49994 -34.500058)
				)
				(arc
					(start 347.49994 -34.500058)
					(mid 345.60002 -32.600138)
					(end 343.7001 -34.500058)
				)
			)
		)
	)
	(zone
		(layer "B.Cu")
		(hatch none 0.5)
		(connect_pads
			(clearance 0)
		)
		(min_thickness 0.25)
		(keepout
			(tracks not_allowed)
			(vias allowed)
			(pads allowed)
			(copperpour not_allowed)
			(footprints allowed)
		)
		(placement
			(enabled no)
			(sheetname "")
		)
		(fill
			(thermal_gap 0.5)
			(thermal_bridge_width 0.5)
			(island_removal_mode 0)
		)
		(polygon
			(pts
				(arc
					(start 136.893554 -221.784164)
					(mid 136.383014 -222.294704)
					(end 136.893554 -222.805244)
				)
				(arc
					(start 137.059924 -222.805244)
					(mid 137.030557 -222.672837)
					(end 136.978898 -222.547434)
				)
				(arc
					(start 136.978898 -222.547434)
					(mid 136.734226 -222.081026)
					(end 137.11047 -222.449644)
				)
				(arc
					(start 137.11047 -222.449644)
					(mid 137.184381 -222.621858)
					(end 137.222992 -222.805244)
				)
				(arc
					(start 137.37717 -222.805244)
					(mid 137.415651 -222.621993)
					(end 137.489438 -222.449898)
				)
				(arc
					(start 137.489438 -222.449898)
					(mid 137.865147 -222.080409)
					(end 137.62101 -222.547434)
				)
				(arc
					(start 137.62101 -222.547434)
					(mid 137.569467 -222.672842)
					(end 137.540238 -222.805244)
				)
				(arc
					(start 137.7061 -222.805244)
					(mid 138.216894 -222.294831)
					(end 137.706354 -221.784164)
				)
			)
		)
	)
	(zone
		(net "DUT_AVD_PCIE")
		(layer "B.Cu")
		(hatch none 0.5)
		(connect_pads
			(clearance 0.5)
		)
		(min_thickness 0.25)
		(fill yes
			(thermal_gap 0.5)
			(thermal_bridge_width 0.5)
			(island_removal_mode 0)
		)
		(polygon
			(pts
				(xy 253.0602 -32.8422) (xy 252.857 -33.0454) (xy 252.857 -36.0172) (xy 252.1966 -36.6776) (xy 252.1966 -39.1668)
				(xy 252.6792 -39.6494) (xy 252.6792 -41.148) (xy 252.5522 -41.275) (xy 250.9266 -41.275) (xy 250.8504 -41.3512)
				(xy 250.8504 -41.6052) (xy 250.952 -41.7068) (xy 251.5108 -41.7068) (xy 251.6378 -41.8338) (xy 251.6378 -42.1386)
				(xy 251.6632 -42.164) (xy 252.5268 -42.164) (xy 252.6792 -42.3164) (xy 252.6792 -46.1264) (xy 252.5014 -46.3042)
				(xy 250.9774 -46.3042) (xy 250.9012 -46.3804) (xy 250.9012 -46.6852) (xy 250.952 -46.736) (xy 251.2314 -46.736)
				(xy 251.3838 -46.8884) (xy 251.3838 -47.2186) (xy 251.5108 -47.3456) (xy 252.476 -47.3456) (xy 252.6792 -47.5488)
				(xy 252.6792 -52.1208) (xy 252.603 -52.197) (xy 252.603 -52.7558) (xy 252.6792 -52.832) (xy 252.6792 -60.1472)
				(xy 252.5522 -60.2742) (xy 250.9012 -60.2742) (xy 250.7742 -60.1472) (xy 246.4816 -60.1472) (xy 246.4308 -60.198)
				(xy 246.4308 -62.738) (xy 246.888 -63.1952) (xy 256.9718 -63.1952) (xy 257.8862 -62.2808) (xy 257.8862 -33.147)
				(xy 257.6068 -32.8676) (xy 254.5334 -32.8676) (xy 254.1016 -33.2994) (xy 253.7206 -33.2994) (xy 253.5936 -33.1724)
				(xy 253.5936 -32.9184) (xy 253.5174 -32.8422)
			)
		)
		(polygon
			(pts
				(xy 250.8758 -60.452) (xy 250.6726 -60.452) (xy 250.6726 -60.6552) (xy 250.8758 -60.6552)
			)
		)
		(polygon
			(pts
				(xy 250.5202 -60.452) (xy 250.317 -60.452) (xy 250.317 -60.6552) (xy 250.5202 -60.6552)
			)
		)
		(polygon
			(pts
				(xy 249.884438 -60.452) (xy 249.681238 -60.452) (xy 249.681238 -60.6552) (xy 249.884438 -60.6552)
			)
		)
		(polygon
			(pts
				(xy 249.528838 -60.452) (xy 249.325638 -60.452) (xy 249.325638 -60.6552) (xy 249.528838 -60.6552)
			)
		)
		(polygon
			(pts
				(xy 248.88444 -60.452) (xy 248.68124 -60.452) (xy 248.68124 -60.6552) (xy 248.88444 -60.6552)
			)
		)
		(polygon
			(pts
				(xy 248.52884 -60.452) (xy 248.32564 -60.452) (xy 248.32564 -60.6552) (xy 248.52884 -60.6552)
			)
		)
		(polygon
			(pts
				(xy 247.8786 -60.452) (xy 247.6754 -60.452) (xy 247.6754 -60.6552) (xy 247.8786 -60.6552)
			)
		)
		(polygon
			(pts
				(xy 247.523 -60.452) (xy 247.3198 -60.452) (xy 247.3198 -60.6552) (xy 247.523 -60.6552)
			)
		)
		(polygon
			(pts
				(xy 246.87403 -60.452) (xy 246.67083 -60.452) (xy 246.67083 -60.6552) (xy 246.87403 -60.6552)
			)
		)
		(polygon
			(pts
				(xy 254.1778 -60.071) (xy 253.9746 -60.071) (xy 253.9746 -60.2742) (xy 254.1778 -60.2742)
			)
		)
		(polygon
			(pts
				(xy 253.1872 -60.071) (xy 252.984 -60.071) (xy 252.984 -60.2742) (xy 253.1872 -60.2742)
			)
		)
		(polygon
			(pts
				(xy 253.1872 -59.7154) (xy 252.984 -59.7154) (xy 252.984 -59.9186) (xy 253.1872 -59.9186)
			)
		)
		(polygon
			(pts
				(xy 253.1872 -59.072272) (xy 252.984 -59.072272) (xy 252.984 -59.275472) (xy 253.1872 -59.275472)
			)
		)
		(polygon
			(pts
				(xy 253.1872 -58.716672) (xy 252.984 -58.716672) (xy 252.984 -58.919872) (xy 253.1872 -58.919872)
			)
		)
		(polygon
			(pts
				(xy 253.1872 -58.081672) (xy 252.984 -58.081672) (xy 252.984 -58.284872) (xy 253.1872 -58.284872)
			)
		)
		(polygon
			(pts
				(xy 253.1872 -57.726072) (xy 252.984 -57.726072) (xy 252.984 -57.929272) (xy 253.1872 -57.929272)
			)
		)
		(polygon
			(pts
				(xy 253.1872 -57.065672) (xy 252.984 -57.065672) (xy 252.984 -57.268872) (xy 253.1872 -57.268872)
			)
		)
		(polygon
			(pts
				(xy 253.1872 -56.710072) (xy 252.984 -56.710072) (xy 252.984 -56.913272) (xy 253.1872 -56.913272)
			)
		)
		(polygon
			(pts
				(xy 253.1872 -56.075072) (xy 252.984 -56.075072) (xy 252.984 -56.278272) (xy 253.1872 -56.278272)
			)
		)
		(polygon
			(pts
				(xy 253.1872 -55.719472) (xy 252.984 -55.719472) (xy 252.984 -55.922672) (xy 253.1872 -55.922672)
			)
		)
		(polygon
			(pts
				(xy 253.1872 -55.071772) (xy 252.984 -55.071772) (xy 252.984 -55.274972) (xy 253.1872 -55.274972)
			)
		)
		(polygon
			(pts
				(xy 253.1872 -54.716172) (xy 252.984 -54.716172) (xy 252.984 -54.919372) (xy 253.1872 -54.919372)
			)
		)
		(polygon
			(pts
				(xy 253.1872 -54.068472) (xy 252.984 -54.068472) (xy 252.984 -54.271672) (xy 253.1872 -54.271672)
			)
		)
		(polygon
			(pts
				(xy 253.1872 -53.712872) (xy 252.984 -53.712872) (xy 252.984 -53.916072) (xy 253.1872 -53.916072)
			)
		)
		(polygon
			(pts
				(xy 253.1872 -53.077872) (xy 252.984 -53.077872) (xy 252.984 -53.281072) (xy 253.1872 -53.281072)
			)
		)
		(polygon
			(pts
				(xy 253.1872 -51.706272) (xy 252.984 -51.706272) (xy 252.984 -51.909472) (xy 253.1872 -51.909472)
			)
		)
		(polygon
			(pts
				(xy 253.1872 -51.071272) (xy 252.984 -51.071272) (xy 252.984 -51.274472) (xy 253.1872 -51.274472)
			)
		)
		(polygon
			(pts
				(xy 253.1872 -50.715672) (xy 252.984 -50.715672) (xy 252.984 -50.918872) (xy 253.1872 -50.918872)
			)
		)
		(polygon
			(pts
				(xy 253.1872 -50.080672) (xy 252.984 -50.080672) (xy 252.984 -50.283872) (xy 253.1872 -50.283872)
			)
		)
		(polygon
			(pts
				(xy 253.1872 -49.725072) (xy 252.984 -49.725072) (xy 252.984 -49.928272) (xy 253.1872 -49.928272)
			)
		)
		(polygon
			(pts
				(xy 253.1872 -49.064672) (xy 252.984 -49.064672) (xy 252.984 -49.267872) (xy 253.1872 -49.267872)
			)
		)
		(polygon
			(pts
				(xy 253.1872 -48.709072) (xy 252.984 -48.709072) (xy 252.984 -48.912272) (xy 253.1872 -48.912272)
			)
		)
		(polygon
			(pts
				(xy 253.1872 -48.074072) (xy 252.984 -48.074072) (xy 252.984 -48.277272) (xy 253.1872 -48.277272)
			)
		)
		(polygon
			(pts
				(xy 253.1872 -47.718472) (xy 252.984 -47.718472) (xy 252.984 -47.921672) (xy 253.1872 -47.921672)
			)
		)
		(polygon
			(pts
				(xy 251.9172 -46.8376) (xy 251.714 -46.8376) (xy 251.714 -47.0408) (xy 251.9172 -47.0408)
			)
		)
		(polygon
			(pts
				(xy 253.1872 -46.067472) (xy 252.984 -46.067472) (xy 252.984 -46.270672) (xy 253.1872 -46.270672)
			)
		)
		(polygon
			(pts
				(xy 253.1872 -45.711872) (xy 252.984 -45.711872) (xy 252.984 -45.915072) (xy 253.1872 -45.915072)
			)
		)
		(polygon
			(pts
				(xy 253.1872 -45.076872) (xy 252.984 -45.076872) (xy 252.984 -45.280072) (xy 253.1872 -45.280072)
			)
		)
		(polygon
			(pts
				(xy 253.1872 -44.721272) (xy 252.984 -44.721272) (xy 252.984 -44.924472) (xy 253.1872 -44.924472)
			)
		)
		(polygon
			(pts
				(xy 253.1872 -44.086272) (xy 252.984 -44.086272) (xy 252.984 -44.289472) (xy 253.1872 -44.289472)
			)
		)
		(polygon
			(pts
				(xy 253.1872 -43.730672) (xy 252.984 -43.730672) (xy 252.984 -43.933872) (xy 253.1872 -43.933872)
			)
		)
		(polygon
			(pts
				(xy 253.1872 -43.070272) (xy 252.984 -43.070272) (xy 252.984 -43.273472) (xy 253.1872 -43.273472)
			)
		)
		(polygon
			(pts
				(xy 253.1872 -42.714672) (xy 252.984 -42.714672) (xy 252.984 -42.917872) (xy 253.1872 -42.917872)
			)
		)
		(polygon
			(pts
				(xy 252.1712 -41.7322) (xy 251.968 -41.7322) (xy 251.968 -41.9354) (xy 252.1712 -41.9354)
			)
		)
		(polygon
			(pts
				(xy 253.687072 -41.089072) (xy 253.483872 -41.089072) (xy 253.483872 -41.292272) (xy 253.687072 -41.292272)
			)
		)
		(polygon
			(pts
				(xy 253.1872 -41.0718) (xy 252.984 -41.0718) (xy 252.984 -41.275) (xy 253.1872 -41.275)
			)
		)
		(polygon
			(pts
				(xy 253.687072 -40.733472) (xy 253.483872 -40.733472) (xy 253.483872 -40.936672) (xy 253.687072 -40.936672)
			)
		)
		(polygon
			(pts
				(xy 253.1872 -40.7162) (xy 252.984 -40.7162) (xy 252.984 -40.9194) (xy 253.1872 -40.9194)
			)
		)
		(polygon
			(pts
				(xy 253.1618 -40.0812) (xy 252.9586 -40.0812) (xy 252.9586 -40.2844) (xy 253.1618 -40.2844)
			)
		)
		(polygon
			(pts
				(xy 253.1618 -39.7256) (xy 252.9586 -39.7256) (xy 252.9586 -39.9288) (xy 253.1618 -39.9288)
			)
		)
		(polygon
			(pts
				(xy 253.2126 -39.0906) (xy 253.0094 -39.0906) (xy 253.0094 -39.2938) (xy 253.2126 -39.2938)
			)
		)
		(polygon
			(pts
				(xy 253.2126 -38.735) (xy 253.0094 -38.735) (xy 253.0094 -38.9382) (xy 253.2126 -38.9382)
			)
		)
		(polygon
			(pts
				(xy 253.2126 -38.079172) (xy 253.0094 -38.079172) (xy 253.0094 -38.282372) (xy 253.2126 -38.282372)
			)
		)
		(polygon
			(pts
				(xy 253.2126 -37.723572) (xy 253.0094 -37.723572) (xy 253.0094 -37.926772) (xy 253.2126 -37.926772)
			)
		)
		(polygon
			(pts
				(xy 253.2126 -37.075872) (xy 253.0094 -37.075872) (xy 253.0094 -37.279072) (xy 253.2126 -37.279072)
			)
		)
		(polygon
			(pts
				(xy 253.2126 -36.720272) (xy 253.0094 -36.720272) (xy 253.0094 -36.923472) (xy 253.2126 -36.923472)
			)
		)
		(polygon
			(pts
				(xy 253.2126 -36.085272) (xy 253.0094 -36.085272) (xy 253.0094 -36.288472) (xy 253.2126 -36.288472)
			)
		)
	)
	(zone
		(layer "B.Cu")
		(hatch none 0.5)
		(connect_pads
			(clearance 0)
		)
		(min_thickness 0.25)
		(keepout
			(tracks not_allowed)
			(vias allowed)
			(pads allowed)
			(copperpour not_allowed)
			(footprints allowed)
		)
		(placement
			(enabled no)
			(sheetname "")
		)
		(fill
			(thermal_gap 0.5)
			(thermal_bridge_width 0.5)
			(island_removal_mode 0)
		)
		(polygon
			(pts
				(arc
					(start 192.093596 -221.784164)
					(mid 191.583056 -222.294704)
					(end 192.093596 -222.805244)
				)
				(arc
					(start 192.259966 -222.805244)
					(mid 192.230599 -222.672837)
					(end 192.17894 -222.547434)
				)
				(arc
					(start 192.17894 -222.547434)
					(mid 191.934268 -222.081026)
					(end 192.310512 -222.449644)
				)
				(arc
					(start 192.310512 -222.449644)
					(mid 192.384423 -222.621858)
					(end 192.423034 -222.805244)
				)
				(arc
					(start 192.577212 -222.805244)
					(mid 192.615693 -222.621993)
					(end 192.68948 -222.449898)
				)
				(arc
					(start 192.68948 -222.449898)
					(mid 193.065189 -222.080409)
					(end 192.821052 -222.547434)
				)
				(arc
					(start 192.821052 -222.547434)
					(mid 192.769509 -222.672842)
					(end 192.74028 -222.805244)
				)
				(arc
					(start 192.906142 -222.805244)
					(mid 193.416936 -222.294831)
					(end 192.906396 -221.784164)
				)
			)
		)
	)
	(zone
		(layer "B.Cu")
		(hatch none 0.5)
		(connect_pads
			(clearance 0)
		)
		(min_thickness 0.25)
		(keepout
			(tracks not_allowed)
			(vias allowed)
			(pads allowed)
			(copperpour not_allowed)
			(footprints allowed)
		)
		(placement
			(enabled no)
			(sheetname "")
		)
		(fill
			(thermal_gap 0.5)
			(thermal_bridge_width 0.5)
			(island_removal_mode 0)
		)
		(polygon
			(pts
				(arc
					(start 291.935154 -12.825222)
					(mid 291.679478 -11.979321)
					(end 290.833556 -12.23518)
				)
				(xy 290.831524 -12.23391) (xy 290.081462 -13.633958)
				(arc
					(start 290.083494 -13.635228)
					(mid 290.21502 -14.393356)
					(end 290.9824 -14.449044)
				)
				(arc
					(start 290.9824 -14.449044)
					(mid 290.947832 -14.372461)
					(end 290.89604 -14.306296)
				)
				(arc
					(start 290.840414 -14.25067)
					(mid 290.36499 -13.660692)
					(end 290.954968 -14.136116)
				)
				(xy 291.010594 -14.191488) (xy 291.010594 -14.191742) (xy 291.034216 -14.215364)
				(arc
					(start 291.034216 -14.216888)
					(mid 291.076732 -14.272916)
					(end 291.111178 -14.334236)
				)
				(arc
					(start 291.111178 -14.334236)
					(mid 291.151146 -14.281585)
					(end 291.185346 -14.225016)
				)
				(xy 291.187378 -14.226286) (xy 291.303456 -14.009624)
				(arc
					(start 291.303456 -12.902438)
					(mid 291.384482 -12.148996)
					(end 291.465508 -12.902438)
				)
				(xy 291.465508 -13.70711) (xy 291.93744 -12.826492) (xy 291.937186 -12.826238)
			)
		)
	)
	(zone
		(layer "B.Cu")
		(hatch none 0.5)
		(connect_pads
			(clearance 0)
		)
		(min_thickness 0.25)
		(keepout
			(tracks not_allowed)
			(vias allowed)
			(pads allowed)
			(copperpour not_allowed)
			(footprints allowed)
		)
		(placement
			(enabled no)
			(sheetname "")
		)
		(fill
			(thermal_gap 0.5)
			(thermal_bridge_width 0.5)
			(island_removal_mode 0)
		)
		(polygon
			(pts
				(arc
					(start 314.893706 -221.784164)
					(mid 314.383166 -222.294704)
					(end 314.893706 -222.805244)
				)
				(arc
					(start 315.060076 -222.805244)
					(mid 315.030709 -222.672837)
					(end 314.97905 -222.547434)
				)
				(arc
					(start 314.97905 -222.547434)
					(mid 314.734378 -222.081026)
					(end 315.110622 -222.449644)
				)
				(arc
					(start 315.110622 -222.449644)
					(mid 315.184533 -222.621858)
					(end 315.223144 -222.805244)
				)
				(arc
					(start 315.377322 -222.805244)
					(mid 315.415803 -222.621993)
					(end 315.48959 -222.449898)
				)
				(arc
					(start 315.48959 -222.449898)
					(mid 315.865299 -222.080409)
					(end 315.621162 -222.547434)
				)
				(arc
					(start 315.621162 -222.547434)
					(mid 315.569619 -222.672842)
					(end 315.54039 -222.805244)
				)
				(arc
					(start 315.706252 -222.805244)
					(mid 316.217046 -222.294831)
					(end 315.706506 -221.784164)
				)
			)
		)
	)
	(zone
		(layer "B.Cu")
		(hatch none 0.5)
		(connect_pads
			(clearance 0)
		)
		(min_thickness 0.25)
		(keepout
			(tracks allowed)
			(vias allowed)
			(pads allowed)
			(copperpour allowed)
			(footprints not_allowed)
		)
		(placement
			(enabled no)
			(sheetname "")
		)
		(fill
			(thermal_gap 0.5)
			(thermal_bridge_width 0.5)
			(island_removal_mode 0)
		)
		(polygon
			(pts
				(arc
					(start 8.10006 -203.499974)
					(mid 9.99998 -205.399894)
					(end 11.8999 -203.499974)
				)
				(arc
					(start 11.8999 -203.499974)
					(mid 9.99998 -201.600054)
					(end 8.10006 -203.499974)
				)
			)
		)
	)
	(zone
		(layer "B.Cu")
		(hatch none 0.5)
		(connect_pads
			(clearance 0)
		)
		(min_thickness 0.25)
		(keepout
			(tracks not_allowed)
			(vias allowed)
			(pads allowed)
			(copperpour not_allowed)
			(footprints allowed)
		)
		(placement
			(enabled no)
			(sheetname "")
		)
		(fill
			(thermal_gap 0.5)
			(thermal_bridge_width 0.5)
			(island_removal_mode 0)
		)
		(polygon
			(pts
				(arc
					(start 196.622162 -72.00011)
					(mid 200.622154 -76.000102)
					(end 204.622146 -72.00011)
				)
				(arc
					(start 204.622146 -72.00011)
					(mid 200.622154 -68.000118)
					(end 196.622162 -72.00011)
				)
			)
		)
	)
	(zone
		(layer "B.Cu")
		(hatch none 0.5)
		(connect_pads
			(clearance 0)
		)
		(min_thickness 0.25)
		(keepout
			(tracks allowed)
			(vias allowed)
			(pads allowed)
			(copperpour allowed)
			(footprints not_allowed)
		)
		(placement
			(enabled no)
			(sheetname "")
		)
		(fill
			(thermal_gap 0.5)
			(thermal_bridge_width 0.5)
			(island_removal_mode 0)
		)
		(polygon
			(pts
				(arc
					(start 17.562068 -60.300108)
					(mid 13.812012 -56.550052)
					(end 10.061956 -60.300108)
				)
				(arc
					(start 10.061956 -60.300108)
					(mid 13.812012 -64.050164)
					(end 17.562068 -60.300108)
				)
			)
		)
	)
	(zone
		(layer "B.Cu")
		(hatch none 0.5)
		(connect_pads
			(clearance 0)
		)
		(min_thickness 0.25)
		(keepout
			(tracks not_allowed)
			(vias allowed)
			(pads allowed)
			(copperpour not_allowed)
			(footprints allowed)
		)
		(placement
			(enabled no)
			(sheetname "")
		)
		(fill
			(thermal_gap 0.5)
			(thermal_bridge_width 0.5)
			(island_removal_mode 0)
		)
		(polygon
			(pts
				(arc
					(start 83.849972 -22.999954)
					(mid 85.450172 -24.600154)
					(end 87.050118 -22.999954)
				)
				(arc
					(start 87.050118 -22.999954)
					(mid 85.450172 -21.400008)
					(end 83.849972 -22.999954)
				)
			)
		)
	)
	(zone
		(layer "B.Cu")
		(hatch none 0.5)
		(connect_pads
			(clearance 0)
		)
		(min_thickness 0.25)
		(keepout
			(tracks not_allowed)
			(vias allowed)
			(pads allowed)
			(copperpour not_allowed)
			(footprints allowed)
		)
		(placement
			(enabled no)
			(sheetname "")
		)
		(fill
			(thermal_gap 0.5)
			(thermal_bridge_width 0.5)
			(island_removal_mode 0)
		)
		(polygon
			(pts
				(arc
					(start 90.893392 -221.784164)
					(mid 90.382852 -222.294704)
					(end 90.893392 -222.805244)
				)
				(arc
					(start 91.059762 -222.805244)
					(mid 91.030395 -222.672837)
					(end 90.978736 -222.547434)
				)
				(arc
					(start 90.978736 -222.547434)
					(mid 90.734064 -222.081026)
					(end 91.110308 -222.449644)
				)
				(arc
					(start 91.110308 -222.449644)
					(mid 91.184219 -222.621858)
					(end 91.22283 -222.805244)
				)
				(arc
					(start 91.377008 -222.805244)
					(mid 91.415489 -222.621993)
					(end 91.489276 -222.449898)
				)
				(arc
					(start 91.489276 -222.449898)
					(mid 91.864985 -222.080409)
					(end 91.620848 -222.547434)
				)
				(arc
					(start 91.620848 -222.547434)
					(mid 91.569305 -222.672842)
					(end 91.540076 -222.805244)
				)
				(arc
					(start 91.705938 -222.805244)
					(mid 92.216732 -222.294831)
					(end 91.706192 -221.784164)
				)
			)
		)
	)
	(zone
		(net "P3V3_STBY")
		(layer "B.Cu")
		(hatch none 0.5)
		(connect_pads
			(clearance 0.5)
		)
		(min_thickness 0.25)
		(fill yes
			(thermal_gap 0.5)
			(thermal_bridge_width 0.5)
			(island_removal_mode 0)
		)
		(polygon
			(pts
				(xy 142.875 -191.516) (xy 140.081 -194.31) (xy 134.7978 -194.31) (xy 134.747 -194.3608) (xy 134.747 -195.5292)
				(xy 134.62 -195.6562) (xy 134.62 -196.9516) (xy 134.7724 -197.104) (xy 144.272 -197.104) (xy 147.828 -193.548)
				(xy 188.976 -193.548) (xy 201.041 -205.613) (xy 216.027 -205.613) (xy 217.043 -204.597) (xy 217.043 -202.565)
				(xy 216.789 -202.311) (xy 205.232 -202.311) (xy 194.437 -191.516)
			)
		)
	)
	(zone
		(layer "B.Cu")
		(hatch none 0.5)
		(connect_pads
			(clearance 0)
		)
		(min_thickness 0.25)
		(keepout
			(tracks not_allowed)
			(vias allowed)
			(pads allowed)
			(copperpour not_allowed)
			(footprints allowed)
		)
		(placement
			(enabled no)
			(sheetname "")
		)
		(fill
			(thermal_gap 0.5)
			(thermal_bridge_width 0.5)
			(island_removal_mode 0)
		)
		(polygon
			(pts
				(arc
					(start 321.293744 -221.784164)
					(mid 320.783204 -222.294704)
					(end 321.293744 -222.805244)
				)
				(arc
					(start 321.460114 -222.805244)
					(mid 321.430747 -222.672837)
					(end 321.379088 -222.547434)
				)
				(arc
					(start 321.379088 -222.547434)
					(mid 321.134416 -222.081026)
					(end 321.51066 -222.449644)
				)
				(arc
					(start 321.51066 -222.449644)
					(mid 321.584571 -222.621858)
					(end 321.623182 -222.805244)
				)
				(arc
					(start 321.77736 -222.805244)
					(mid 321.815841 -222.621993)
					(end 321.889628 -222.449898)
				)
				(arc
					(start 321.889628 -222.449898)
					(mid 322.265337 -222.080409)
					(end 322.0212 -222.547434)
				)
				(arc
					(start 322.0212 -222.547434)
					(mid 321.969657 -222.672842)
					(end 321.940428 -222.805244)
				)
				(arc
					(start 322.10629 -222.805244)
					(mid 322.617084 -222.294831)
					(end 322.106544 -221.784164)
				)
			)
		)
	)
	(zone
		(net "P1V53_STBY")
		(layer "B.Cu")
		(hatch none 0.5)
		(connect_pads
			(clearance 0.5)
		)
		(min_thickness 0.25)
		(fill yes
			(thermal_gap 0.5)
			(thermal_bridge_width 0.5)
			(island_removal_mode 0)
		)
		(polygon
			(pts
				(xy 39.755826 -155.75788) (xy 39.501826 -156.01188) (xy 39.501826 -156.71038) (xy 38.866826 -157.34538)
				(xy 36.644326 -157.34538) (xy 35.889946 -156.591) (xy 34.798 -156.591) (xy 34.796476 -156.589476)
				(xy 34.485326 -156.90088) (xy 34.167826 -157.21838) (xy 34.167572 -157.21838) (xy 34.032952 -157.353)
				(xy 30.619446 -157.353) (xy 30.611826 -157.34538) (xy 30.103826 -157.85338) (xy 30.103826 -159.31388)
				(xy 30.167326 -159.37738) (xy 33.374076 -159.37738) (xy 34.358326 -158.39313) (xy 35.533076 -158.39313)
				(xy 36.009326 -158.86938) (xy 42.549826 -158.86938) (xy 43.121326 -158.29788) (xy 43.121326 -157.21838)
				(xy 42.422826 -156.51988) (xy 40.771826 -156.51988) (xy 40.009826 -155.75788)
			)
		)
		(polygon
			(pts
				(xy 32.626554 -158.759144) (xy 32.423354 -158.759144) (xy 32.423354 -158.962344) (xy 32.626554 -158.962344)
			)
		)
		(polygon
			(pts
				(xy 32.016954 -158.759144) (xy 31.813754 -158.759144) (xy 31.813754 -158.962344) (xy 32.016954 -158.962344)
			)
		)
		(polygon
			(pts
				(xy 30.975554 -158.759144) (xy 30.772354 -158.759144) (xy 30.772354 -158.962344) (xy 30.975554 -158.962344)
			)
		)
		(polygon
			(pts
				(xy 42.532554 -158.124144) (xy 42.329354 -158.124144) (xy 42.329354 -158.327344) (xy 42.532554 -158.327344)
			)
		)
		(polygon
			(pts
				(xy 41.922954 -158.124144) (xy 41.719754 -158.124144) (xy 41.719754 -158.327344) (xy 41.922954 -158.327344)
			)
		)
		(polygon
			(pts
				(xy 41.262554 -158.124144) (xy 41.059354 -158.124144) (xy 41.059354 -158.327344) (xy 41.262554 -158.327344)
			)
		)
		(polygon
			(pts
				(xy 40.652954 -158.124144) (xy 40.449754 -158.124144) (xy 40.449754 -158.327344) (xy 40.652954 -158.327344)
			)
		)
		(polygon
			(pts
				(xy 39.992554 -158.124144) (xy 39.789354 -158.124144) (xy 39.789354 -158.327344) (xy 39.992554 -158.327344)
			)
		)
		(polygon
			(pts
				(xy 39.382954 -158.124144) (xy 39.179754 -158.124144) (xy 39.179754 -158.327344) (xy 39.382954 -158.327344)
			)
		)
		(polygon
			(pts
				(xy 38.468554 -158.124144) (xy 38.265354 -158.124144) (xy 38.265354 -158.327344) (xy 38.468554 -158.327344)
			)
		)
		(polygon
			(pts
				(xy 37.858954 -158.124144) (xy 37.655754 -158.124144) (xy 37.655754 -158.327344) (xy 37.858954 -158.327344)
			)
		)
		(polygon
			(pts
				(xy 35.344354 -157.616144) (xy 35.141154 -157.616144) (xy 35.141154 -157.819344) (xy 35.344354 -157.819344)
			)
		)
		(polygon
			(pts
				(xy 34.734754 -157.616144) (xy 34.531554 -157.616144) (xy 34.531554 -157.819344) (xy 34.734754 -157.819344)
			)
		)
	)
	(zone
		(layer "B.Cu")
		(hatch none 0.5)
		(connect_pads
			(clearance 0)
		)
		(min_thickness 0.25)
		(keepout
			(tracks allowed)
			(vias allowed)
			(pads allowed)
			(copperpour allowed)
			(footprints not_allowed)
		)
		(placement
			(enabled no)
			(sheetname "")
		)
		(fill
			(thermal_gap 0.5)
			(thermal_bridge_width 0.5)
			(island_removal_mode 0)
		)
		(polygon
			(pts
				(arc
					(start 345.74988 -22.999954)
					(mid 349.750126 -27.0002)
					(end 353.750118 -22.999954)
				)
				(arc
					(start 353.750118 -22.999954)
					(mid 349.750126 -18.999962)
					(end 345.74988 -22.999954)
				)
			)
		)
	)
	(zone
		(layer "B.Cu")
		(hatch none 0.5)
		(connect_pads
			(clearance 0)
		)
		(min_thickness 0.25)
		(keepout
			(tracks not_allowed)
			(vias allowed)
			(pads allowed)
			(copperpour not_allowed)
			(footprints allowed)
		)
		(placement
			(enabled no)
			(sheetname "")
		)
		(fill
			(thermal_gap 0.5)
			(thermal_bridge_width 0.5)
			(island_removal_mode 0)
		)
		(polygon
			(pts
				(arc
					(start 143.293592 -221.784164)
					(mid 142.783052 -222.294704)
					(end 143.293592 -222.805244)
				)
				(arc
					(start 143.459962 -222.805244)
					(mid 143.430595 -222.672837)
					(end 143.378936 -222.547434)
				)
				(arc
					(start 143.378936 -222.547434)
					(mid 143.134264 -222.081026)
					(end 143.510508 -222.449644)
				)
				(arc
					(start 143.510508 -222.449644)
					(mid 143.584419 -222.621858)
					(end 143.62303 -222.805244)
				)
				(arc
					(start 143.777208 -222.805244)
					(mid 143.815689 -222.621993)
					(end 143.889476 -222.449898)
				)
				(arc
					(start 143.889476 -222.449898)
					(mid 144.265185 -222.080409)
					(end 144.021048 -222.547434)
				)
				(arc
					(start 144.021048 -222.547434)
					(mid 143.969505 -222.672842)
					(end 143.940276 -222.805244)
				)
				(arc
					(start 144.106138 -222.805244)
					(mid 144.616932 -222.294831)
					(end 144.106392 -221.784164)
				)
			)
		)
	)
	(zone
		(layer "B.Cu")
		(hatch none 0.5)
		(connect_pads
			(clearance 0)
		)
		(min_thickness 0.25)
		(keepout
			(tracks allowed)
			(vias allowed)
			(pads allowed)
			(copperpour allowed)
			(footprints not_allowed)
		)
		(placement
			(enabled no)
			(sheetname "")
		)
		(fill
			(thermal_gap 0.5)
			(thermal_bridge_width 0.5)
			(island_removal_mode 0)
		)
		(polygon
			(pts
				(arc
					(start 87.050118 -22.999954)
					(mid 85.450172 -21.400008)
					(end 83.849972 -22.999954)
				)
				(arc
					(start 83.849972 -22.999954)
					(mid 85.450172 -24.600154)
					(end 87.050118 -22.999954)
				)
			)
		)
	)
	(zone
		(layer "B.Cu")
		(hatch none 0.5)
		(connect_pads
			(clearance 0)
		)
		(min_thickness 0.25)
		(keepout
			(tracks allowed)
			(vias allowed)
			(pads allowed)
			(copperpour allowed)
			(footprints not_allowed)
		)
		(placement
			(enabled no)
			(sheetname "")
		)
		(fill
			(thermal_gap 0.5)
			(thermal_bridge_width 0.5)
			(island_removal_mode 0)
		)
		(polygon
			(pts
				(arc
					(start 148.237448 -9.53008)
					(mid 147.137628 -8.43026)
					(end 146.037554 -9.53008)
				)
				(arc
					(start 146.037554 -9.53008)
					(mid 147.137628 -10.630154)
					(end 148.237448 -9.53008)
				)
			)
		)
	)
	(zone
		(layer "B.Cu")
		(hatch none 0.5)
		(connect_pads
			(clearance 0)
		)
		(min_thickness 0.25)
		(keepout
			(tracks allowed)
			(vias allowed)
			(pads allowed)
			(copperpour allowed)
			(footprints not_allowed)
		)
		(placement
			(enabled no)
			(sheetname "")
		)
		(fill
			(thermal_gap 0.5)
			(thermal_bridge_width 0.5)
			(island_removal_mode 0)
		)
		(polygon
			(pts
				(arc
					(start 89.44991 -5.40004)
					(mid 85.449918 -1.400048)
					(end 81.449926 -5.40004)
				)
				(arc
					(start 81.449926 -5.40004)
					(mid 85.449918 -9.400032)
					(end 89.44991 -5.40004)
				)
			)
		)
	)
	(zone
		(layer "B.Cu")
		(hatch none 0.5)
		(connect_pads
			(clearance 0)
		)
		(min_thickness 0.25)
		(keepout
			(tracks not_allowed)
			(vias allowed)
			(pads allowed)
			(copperpour not_allowed)
			(footprints allowed)
		)
		(placement
			(enabled no)
			(sheetname "")
		)
		(fill
			(thermal_gap 0.5)
			(thermal_bridge_width 0.5)
			(island_removal_mode 0)
		)
		(polygon
			(pts
				(arc
					(start 56.49341 -221.784164)
					(mid 55.98287 -222.294704)
					(end 56.49341 -222.805244)
				)
				(arc
					(start 56.65978 -222.805244)
					(mid 56.630413 -222.672837)
					(end 56.578754 -222.547434)
				)
				(arc
					(start 56.578754 -222.547434)
					(mid 56.334082 -222.081026)
					(end 56.710326 -222.449644)
				)
				(arc
					(start 56.710326 -222.449644)
					(mid 56.784237 -222.621858)
					(end 56.822848 -222.805244)
				)
				(arc
					(start 56.977026 -222.805244)
					(mid 57.015507 -222.621993)
					(end 57.089294 -222.449898)
				)
				(arc
					(start 57.089294 -222.449898)
					(mid 57.465003 -222.080409)
					(end 57.220866 -222.547434)
				)
				(arc
					(start 57.220866 -222.547434)
					(mid 57.169323 -222.672842)
					(end 57.140094 -222.805244)
				)
				(arc
					(start 57.305956 -222.805244)
					(mid 57.81675 -222.294831)
					(end 57.30621 -221.784164)
				)
			)
		)
	)
	(zone
		(layer "B.Cu")
		(hatch none 0.5)
		(connect_pads
			(clearance 0)
		)
		(min_thickness 0.25)
		(keepout
			(tracks not_allowed)
			(vias allowed)
			(pads allowed)
			(copperpour not_allowed)
			(footprints allowed)
		)
		(placement
			(enabled no)
			(sheetname "")
		)
		(fill
			(thermal_gap 0.5)
			(thermal_bridge_width 0.5)
			(island_removal_mode 0)
		)
		(polygon
			(pts
				(arc
					(start 159.29356 -221.784164)
					(mid 158.78302 -222.294704)
					(end 159.29356 -222.805244)
				)
				(arc
					(start 159.45993 -222.805244)
					(mid 159.430563 -222.672837)
					(end 159.378904 -222.547434)
				)
				(arc
					(start 159.378904 -222.547434)
					(mid 159.134232 -222.081026)
					(end 159.510476 -222.449644)
				)
				(arc
					(start 159.510476 -222.449644)
					(mid 159.584387 -222.621858)
					(end 159.622998 -222.805244)
				)
				(arc
					(start 159.777176 -222.805244)
					(mid 159.815657 -222.621993)
					(end 159.889444 -222.449898)
				)
				(arc
					(start 159.889444 -222.449898)
					(mid 160.265153 -222.080409)
					(end 160.021016 -222.547434)
				)
				(arc
					(start 160.021016 -222.547434)
					(mid 159.969473 -222.672842)
					(end 159.940244 -222.805244)
				)
				(arc
					(start 160.106106 -222.805244)
					(mid 160.6169 -222.294831)
					(end 160.10636 -221.784164)
				)
			)
		)
	)
	(zone
		(layer "B.Cu")
		(hatch none 0.5)
		(connect_pads
			(clearance 0)
		)
		(min_thickness 0.25)
		(keepout
			(tracks not_allowed)
			(vias allowed)
			(pads allowed)
			(copperpour not_allowed)
			(footprints allowed)
		)
		(placement
			(enabled no)
			(sheetname "")
		)
		(fill
			(thermal_gap 0.5)
			(thermal_bridge_width 0.5)
			(island_removal_mode 0)
		)
		(polygon
			(pts
				(arc
					(start 337.293712 -221.784164)
					(mid 336.783172 -222.294704)
					(end 337.293712 -222.805244)
				)
				(arc
					(start 337.460082 -222.805244)
					(mid 337.430715 -222.672837)
					(end 337.379056 -222.547434)
				)
				(arc
					(start 337.379056 -222.547434)
					(mid 337.134384 -222.081026)
					(end 337.510628 -222.449644)
				)
				(arc
					(start 337.510628 -222.449644)
					(mid 337.584539 -222.621858)
					(end 337.62315 -222.805244)
				)
				(arc
					(start 337.777328 -222.805244)
					(mid 337.815809 -222.621993)
					(end 337.889596 -222.449898)
				)
				(arc
					(start 337.889596 -222.449898)
					(mid 338.265305 -222.080409)
					(end 338.021168 -222.547434)
				)
				(arc
					(start 338.021168 -222.547434)
					(mid 337.969625 -222.672842)
					(end 337.940396 -222.805244)
				)
				(arc
					(start 338.106258 -222.805244)
					(mid 338.617052 -222.294831)
					(end 338.106512 -221.784164)
				)
			)
		)
	)
	(zone
		(layer "B.Cu")
		(hatch none 0.5)
		(connect_pads
			(clearance 0)
		)
		(min_thickness 0.25)
		(keepout
			(tracks not_allowed)
			(vias allowed)
			(pads allowed)
			(copperpour not_allowed)
			(footprints allowed)
		)
		(placement
			(enabled no)
			(sheetname "")
		)
		(fill
			(thermal_gap 0.5)
			(thermal_bridge_width 0.5)
			(island_removal_mode 0)
		)
		(polygon
			(pts
				(arc
					(start 81.449926 -22.999954)
					(mid 85.449918 -26.999946)
					(end 89.44991 -22.999954)
				)
				(arc
					(start 89.44991 -22.999954)
					(mid 85.449918 -18.999962)
					(end 81.449926 -22.999954)
				)
			)
		)
	)
	(zone
		(layer "B.Cu")
		(hatch none 0.5)
		(connect_pads
			(clearance 0)
		)
		(min_thickness 0.25)
		(keepout
			(tracks not_allowed)
			(vias allowed)
			(pads allowed)
			(copperpour not_allowed)
			(footprints allowed)
		)
		(placement
			(enabled no)
			(sheetname "")
		)
		(fill
			(thermal_gap 0.5)
			(thermal_bridge_width 0.5)
			(island_removal_mode 0)
		)
		(polygon
			(pts
				(arc
					(start 288.493708 -221.784164)
					(mid 287.983168 -222.294704)
					(end 288.493708 -222.805244)
				)
				(arc
					(start 288.660078 -222.805244)
					(mid 288.630711 -222.672837)
					(end 288.579052 -222.547434)
				)
				(arc
					(start 288.579052 -222.547434)
					(mid 288.33438 -222.081026)
					(end 288.710624 -222.449644)
				)
				(arc
					(start 288.710624 -222.449644)
					(mid 288.784535 -222.621858)
					(end 288.823146 -222.805244)
				)
				(arc
					(start 288.977324 -222.805244)
					(mid 289.015805 -222.621993)
					(end 289.089592 -222.449898)
				)
				(arc
					(start 289.089592 -222.449898)
					(mid 289.465301 -222.080409)
					(end 289.221164 -222.547434)
				)
				(arc
					(start 289.221164 -222.547434)
					(mid 289.169621 -222.672842)
					(end 289.140392 -222.805244)
				)
				(arc
					(start 289.306254 -222.805244)
					(mid 289.817048 -222.294831)
					(end 289.306508 -221.784164)
				)
			)
		)
	)
	(zone
		(layer "B.Cu")
		(hatch none 0.5)
		(connect_pads
			(clearance 0)
		)
		(min_thickness 0.25)
		(keepout
			(tracks allowed)
			(vias allowed)
			(pads allowed)
			(copperpour allowed)
			(footprints not_allowed)
		)
		(placement
			(enabled no)
			(sheetname "")
		)
		(fill
			(thermal_gap 0.5)
			(thermal_bridge_width 0.5)
			(island_removal_mode 0)
		)
		(polygon
			(pts
				(arc
					(start 286.637476 -9.53008)
					(mid 289.137598 -12.030202)
					(end 291.637466 -9.53008)
				)
				(arc
					(start 291.637466 -9.53008)
					(mid 289.137598 -7.030212)
					(end 286.637476 -9.53008)
				)
			)
		)
	)
	(zone
		(net "P3V3_STBY_VIN")
		(layer "B.Cu")
		(hatch none 0.5)
		(connect_pads
			(clearance 0.5)
		)
		(min_thickness 0.25)
		(fill yes
			(thermal_gap 0.5)
			(thermal_bridge_width 0.5)
			(island_removal_mode 0)
		)
		(polygon
			(pts
				(xy 60.325 -39.116) (xy 60.071 -39.37) (xy 60.071 -48.006) (xy 60.325 -48.26) (xy 63.5 -48.26) (xy 63.627 -48.133)
				(xy 63.627 -44.45) (xy 62.865 -43.688) (xy 62.865 -39.37) (xy 62.611 -39.116)
			)
		)
	)
	(zone
		(net "GND")
		(layer "B.Cu")
		(hatch none 0.5)
		(connect_pads
			(clearance 0.5)
		)
		(min_thickness 0.25)
		(fill yes
			(thermal_gap 0.5)
			(thermal_bridge_width 0.5)
			(island_removal_mode 0)
		)
		(polygon
			(pts
				(xy 221.5896 -31.115) (xy 221.4626 -31.242) (xy 221.4626 -41.8084) (xy 221.615 -41.9608) (xy 226.3394 -41.9608)
				(xy 226.568 -41.7322) (xy 226.568 -41.2242) (xy 226.6442 -41.148) (xy 227.5332 -41.148) (xy 227.584 -41.0972)
				(xy 227.584 -31.4706) (xy 227.2284 -31.115)
			)
		)
		(polygon
			(pts
				(xy 227.3046 -39.725346) (xy 227.1014 -39.725346) (xy 227.1014 -39.928546) (xy 227.3046 -39.928546)
			)
		)
		(polygon
			(pts
				(xy 227.3046 -39.080948) (xy 227.1014 -39.080948) (xy 227.1014 -39.284148) (xy 227.3046 -39.284148)
			)
		)
		(polygon
			(pts
				(xy 227.3046 -37.719) (xy 227.1014 -37.719) (xy 227.1014 -37.9222) (xy 227.3046 -37.9222)
			)
		)
		(polygon
			(pts
				(xy 227.3046 -37.080952) (xy 227.1014 -37.080952) (xy 227.1014 -37.284152) (xy 227.3046 -37.284152)
			)
		)
		(polygon
			(pts
				(xy 227.3046 -35.715956) (xy 227.1014 -35.715956) (xy 227.1014 -35.919156) (xy 227.3046 -35.919156)
			)
		)
		(polygon
			(pts
				(xy 227.3046 -35.0774) (xy 227.1014 -35.0774) (xy 227.1014 -35.2806) (xy 227.3046 -35.2806)
			)
		)
		(polygon
			(pts
				(xy 227.3046 -32.715962) (xy 227.1014 -32.715962) (xy 227.1014 -32.919162) (xy 227.3046 -32.919162)
			)
		)
	)
	(zone
		(net "GND")
		(layer "B.Cu")
		(hatch none 0.5)
		(connect_pads
			(clearance 0.5)
		)
		(min_thickness 0.25)
		(fill yes
			(thermal_gap 0.5)
			(thermal_bridge_width 0.5)
			(island_removal_mode 0)
		)
		(polygon
			(pts
				(xy 324.382892 -174.735236) (xy 309.337202 -189.780926) (xy 309.337202 -208.6864) (xy 309.845202 -209.1944)
				(xy 336.4992 -209.1944) (xy 336.8294 -208.8642) (xy 336.8294 -201.2442) (xy 339.8266 -198.247) (xy 339.8266 -191.666368)
				(xy 337.960716 -189.800484) (xy 337.960716 -188.888116) (xy 337.016598 -187.943998) (xy 328.538078 -187.943998)
				(xy 327.00722 -186.41314) (xy 327.00722 -175.435006) (xy 326.30745 -174.735236)
			)
		)
		(polygon
			(pts
				(xy 335.9404 -207.9498) (xy 335.7372 -207.9498) (xy 335.7372 -208.153) (xy 335.9404 -208.153)
			)
		)
		(polygon
			(pts
				(xy 335.9404 -207.0862) (xy 335.7372 -207.0862) (xy 335.7372 -207.2894) (xy 335.9404 -207.2894)
			)
		)
	)
	(zone
		(net "P1V8_CLKGEN")
		(layer "B.Cu")
		(hatch none 0.5)
		(connect_pads
			(clearance 0.5)
		)
		(min_thickness 0.25)
		(fill yes
			(thermal_gap 0.5)
			(thermal_bridge_width 0.5)
			(island_removal_mode 0)
		)
		(polygon
			(pts
				(xy 156.464 -85.725) (xy 155.956 -86.233) (xy 155.956 -94.234) (xy 157.226 -95.504) (xy 163.322 -95.504)
				(xy 163.703 -95.123) (xy 163.703 -93.218) (xy 163.322 -92.837) (xy 160.92932 -92.837) (xy 160.67024 -93.09608)
				(xy 158.757874 -93.09608) (xy 158.496 -92.834206) (xy 158.496 -88.646) (xy 158.877 -88.265) (xy 163.576 -88.265)
				(xy 163.83 -88.011) (xy 163.83 -85.979) (xy 163.576 -85.725)
			)
		)
		(polygon
			(pts
				(xy 162.1028 -93.3958) (xy 161.6202 -93.3958) (xy 161.6202 -93.599) (xy 162.1028 -93.599)
			)
		)
		(polygon
			(pts
				(xy 161.2138 -93.3958) (xy 161.0106 -93.3958) (xy 161.0106 -93.599) (xy 161.2138 -93.599)
			)
		)
		(polygon
			(pts
				(xy 157.9626 -90.2716) (xy 157.7594 -90.2716) (xy 157.7594 -90.4748) (xy 157.9626 -90.4748)
			)
		)
		(polygon
			(pts
				(xy 157.9626 -89.662) (xy 157.7594 -89.662) (xy 157.7594 -89.8652) (xy 157.9626 -89.8652)
			)
		)
		(polygon
			(pts
				(xy 161.8234 -87.5538) (xy 161.6202 -87.5538) (xy 161.6202 -87.757) (xy 161.8234 -87.757)
			)
		)
		(polygon
			(pts
				(xy 161.2138 -87.5538) (xy 161.0106 -87.5538) (xy 161.0106 -87.757) (xy 161.2138 -87.757)
			)
		)
		(polygon
			(pts
				(xy 160.5534 -87.5538) (xy 160.3502 -87.5538) (xy 160.3502 -87.757) (xy 160.5534 -87.757)
			)
		)
		(polygon
			(pts
				(xy 159.9438 -87.5538) (xy 159.4612 -87.5538) (xy 159.4612 -87.757) (xy 159.9438 -87.757)
			)
		)
		(polygon
			(pts
				(xy 159.0548 -87.5538) (xy 158.8516 -87.5538) (xy 158.8516 -87.757) (xy 159.0548 -87.757)
			)
		)
	)
	(zone
		(layer "B.Cu")
		(hatch none 0.5)
		(connect_pads
			(clearance 0)
		)
		(min_thickness 0.25)
		(keepout
			(tracks not_allowed)
			(vias allowed)
			(pads allowed)
			(copperpour not_allowed)
			(footprints allowed)
		)
		(placement
			(enabled no)
			(sheetname "")
		)
		(fill
			(thermal_gap 0.5)
			(thermal_bridge_width 0.5)
			(island_removal_mode 0)
		)
		(polygon
			(pts
				(arc
					(start 93.38945 -183.13146)
					(mid 92.87891 -183.642)
					(end 93.38945 -184.15254)
				)
				(xy 93.517974 -184.15254)
				(arc
					(start 93.517974 -184.147968)
					(mid 93.504985 -184.019986)
					(end 93.466412 -183.89727)
				)
				(arc
					(start 93.466412 -183.89727)
					(mid 93.237882 -183.422368)
					(end 93.601794 -183.803544)
				)
				(arc
					(start 93.601794 -183.803544)
					(mid 93.656246 -183.954685)
					(end 93.679264 -184.113678)
				)
				(xy 93.680026 -184.11444) (xy 93.680026 -184.15254)
				(arc
					(start 93.843094 -184.15254)
					(mid 93.896653 -183.966318)
					(end 93.982032 -183.792368)
				)
				(arc
					(start 93.982032 -183.792368)
					(mid 94.366334 -183.431339)
					(end 94.111064 -183.892698)
				)
				(arc
					(start 94.111064 -183.892698)
					(mid 94.050155 -184.018787)
					(end 94.008702 -184.15254)
				)
				(arc
					(start 94.201996 -184.15254)
					(mid 94.71279 -183.642127)
					(end 94.20225 -183.13146)
				)
			)
		)
	)
	(zone
		(layer "B.Cu")
		(hatch none 0.5)
		(connect_pads
			(clearance 0)
		)
		(min_thickness 0.25)
		(keepout
			(tracks not_allowed)
			(vias allowed)
			(pads allowed)
			(copperpour not_allowed)
			(footprints allowed)
		)
		(placement
			(enabled no)
			(sheetname "")
		)
		(fill
			(thermal_gap 0.5)
			(thermal_bridge_width 0.5)
			(island_removal_mode 0)
		)
		(polygon
			(pts
				(arc
					(start 345.74988 -5.40004)
					(mid 349.750126 -9.400286)
					(end 353.750118 -5.40004)
				)
				(arc
					(start 353.750118 -5.40004)
					(mid 349.750126 -1.400048)
					(end 345.74988 -5.40004)
				)
			)
		)
	)
	(zone
		(layer "B.Cu")
		(hatch none 0.5)
		(connect_pads
			(clearance 0)
		)
		(min_thickness 0.25)
		(keepout
			(tracks not_allowed)
			(vias allowed)
			(pads allowed)
			(copperpour not_allowed)
			(footprints allowed)
		)
		(placement
			(enabled no)
			(sheetname "")
		)
		(fill
			(thermal_gap 0.5)
			(thermal_bridge_width 0.5)
			(island_removal_mode 0)
		)
		(polygon
			(pts
				(arc
					(start 330.893674 -221.784164)
					(mid 330.383134 -222.294704)
					(end 330.893674 -222.805244)
				)
				(arc
					(start 331.060044 -222.805244)
					(mid 331.030677 -222.672837)
					(end 330.979018 -222.547434)
				)
				(arc
					(start 330.979018 -222.547434)
					(mid 330.734346 -222.081026)
					(end 331.11059 -222.449644)
				)
				(arc
					(start 331.11059 -222.449644)
					(mid 331.184501 -222.621858)
					(end 331.223112 -222.805244)
				)
				(arc
					(start 331.37729 -222.805244)
					(mid 331.415771 -222.621993)
					(end 331.489558 -222.449898)
				)
				(arc
					(start 331.489558 -222.449898)
					(mid 331.865267 -222.080409)
					(end 331.62113 -222.547434)
				)
				(arc
					(start 331.62113 -222.547434)
					(mid 331.569587 -222.672842)
					(end 331.540358 -222.805244)
				)
				(arc
					(start 331.70622 -222.805244)
					(mid 332.217014 -222.294831)
					(end 331.706474 -221.784164)
				)
			)
		)
	)
	(zone
		(layer "B.Cu")
		(hatch none 0.5)
		(connect_pads
			(clearance 0)
		)
		(min_thickness 0.25)
		(keepout
			(tracks not_allowed)
			(vias allowed)
			(pads allowed)
			(copperpour not_allowed)
			(footprints allowed)
		)
		(placement
			(enabled no)
			(sheetname "")
		)
		(fill
			(thermal_gap 0.5)
			(thermal_bridge_width 0.5)
			(island_removal_mode 0)
		)
		(polygon
			(pts
				(arc
					(start 87.050118 -5.40004)
					(mid 85.450172 -3.800094)
					(end 83.849972 -5.40004)
				)
				(arc
					(start 83.849972 -5.40004)
					(mid 85.450172 -7.00024)
					(end 87.050118 -5.40004)
				)
			)
		)
	)
	(zone
		(layer "B.Cu")
		(hatch none 0.5)
		(connect_pads
			(clearance 0)
		)
		(min_thickness 0.25)
		(keepout
			(tracks not_allowed)
			(vias allowed)
			(pads allowed)
			(copperpour not_allowed)
			(footprints allowed)
		)
		(placement
			(enabled no)
			(sheetname "")
		)
		(fill
			(thermal_gap 0.5)
			(thermal_bridge_width 0.5)
			(island_removal_mode 0)
		)
		(polygon
			(pts
				(arc
					(start 290.237418 -9.53008)
					(mid 289.137598 -8.43026)
					(end 288.037524 -9.53008)
				)
				(arc
					(start 288.037524 -9.53008)
					(mid 289.137598 -10.630154)
					(end 290.237418 -9.53008)
				)
			)
		)
	)
	(zone
		(layer "B.Cu")
		(hatch none 0.5)
		(connect_pads
			(clearance 0)
		)
		(min_thickness 0.25)
		(keepout
			(tracks not_allowed)
			(vias allowed)
			(pads allowed)
			(copperpour not_allowed)
			(footprints allowed)
		)
		(placement
			(enabled no)
			(sheetname "")
		)
		(fill
			(thermal_gap 0.5)
			(thermal_bridge_width 0.5)
			(island_removal_mode 0)
		)
		(polygon
			(pts
				(arc
					(start 311.69356 -221.784164)
					(mid 311.18302 -222.294704)
					(end 311.69356 -222.805244)
				)
				(arc
					(start 311.85993 -222.805244)
					(mid 311.830563 -222.672837)
					(end 311.778904 -222.547434)
				)
				(arc
					(start 311.778904 -222.547434)
					(mid 311.534232 -222.081026)
					(end 311.910476 -222.449644)
				)
				(arc
					(start 311.910476 -222.449644)
					(mid 311.984387 -222.621858)
					(end 312.022998 -222.805244)
				)
				(arc
					(start 312.177176 -222.805244)
					(mid 312.215657 -222.621993)
					(end 312.289444 -222.449898)
				)
				(arc
					(start 312.289444 -222.449898)
					(mid 312.665153 -222.080409)
					(end 312.421016 -222.547434)
				)
				(arc
					(start 312.421016 -222.547434)
					(mid 312.369473 -222.672842)
					(end 312.340244 -222.805244)
				)
				(arc
					(start 312.506106 -222.805244)
					(mid 313.0169 -222.294831)
					(end 312.50636 -221.784164)
				)
			)
		)
	)
	(zone
		(layer "B.Cu")
		(hatch none 0.5)
		(connect_pads
			(clearance 0)
		)
		(min_thickness 0.25)
		(keepout
			(tracks not_allowed)
			(vias allowed)
			(pads allowed)
			(copperpour not_allowed)
			(footprints allowed)
		)
		(placement
			(enabled no)
			(sheetname "")
		)
		(fill
			(thermal_gap 0.5)
			(thermal_bridge_width 0.5)
			(island_removal_mode 0)
		)
		(polygon
			(pts
				(arc
					(start 15.912084 -60.300108)
					(mid 13.812266 -58.20029)
					(end 11.712194 -60.300108)
				)
				(arc
					(start 11.712194 -60.300108)
					(mid 13.812266 -62.40018)
					(end 15.912084 -60.300108)
				)
			)
		)
	)
	(zone
		(layer "B.Cu")
		(hatch none 0.5)
		(connect_pads
			(clearance 0)
		)
		(min_thickness 0.25)
		(keepout
			(tracks allowed)
			(vias allowed)
			(pads allowed)
			(copperpour allowed)
			(footprints not_allowed)
		)
		(placement
			(enabled no)
			(sheetname "")
		)
		(fill
			(thermal_gap 0.5)
			(thermal_bridge_width 0.5)
			(island_removal_mode 0)
		)
		(polygon
			(pts
				(arc
					(start 349.600012 -34.500058)
					(mid 345.60002 -30.500066)
					(end 341.600028 -34.500058)
				)
				(arc
					(start 341.600028 -34.500058)
					(mid 345.60002 -38.50005)
					(end 349.600012 -34.500058)
				)
			)
		)
	)
	(zone
		(net "GND")
		(layer "B.Cu")
		(hatch none 0.5)
		(connect_pads
			(clearance 0.5)
		)
		(min_thickness 0.25)
		(fill yes
			(thermal_gap 0.5)
			(thermal_bridge_width 0.5)
			(island_removal_mode 0)
		)
		(polygon
			(pts
				(xy 166.607236 -55.708296) (xy 166.353236 -55.962296) (xy 166.353236 -60.026296) (xy 168.714166 -62.387226)
				(xy 176.8094 -62.387226) (xy 176.9618 -62.234826) (xy 176.9618 -61.6712) (xy 177.0761 -61.5569)
				(xy 187.2615 -61.5569) (xy 187.706 -61.1124) (xy 187.706 -56.3118) (xy 187.102496 -55.708296)
			)
		)
	)
	(zone
		(layer "B.Cu")
		(hatch none 0.5)
		(connect_pads
			(clearance 0)
		)
		(min_thickness 0.25)
		(keepout
			(tracks not_allowed)
			(vias allowed)
			(pads allowed)
			(copperpour not_allowed)
			(footprints allowed)
		)
		(placement
			(enabled no)
			(sheetname "")
		)
		(fill
			(thermal_gap 0.5)
			(thermal_bridge_width 0.5)
			(island_removal_mode 0)
		)
		(polygon
			(pts
				(arc
					(start 286.08274 -13.552678)
					(mid 286.019688 -13.292288)
					(end 285.889954 -13.057886)
				)
				(xy 285.581344 -13.633958)
				(arc
					(start 285.583376 -13.635228)
					(mid 285.839408 -14.481048)
					(end 286.685228 -14.225016)
				)
				(xy 286.68726 -14.226286) (xy 287.437322 -12.826492) (xy 287.437068 -12.826238)
				(arc
					(start 287.435036 -12.825222)
					(mid 287.17936 -11.979321)
					(end 286.333438 -12.23518)
				)
				(xy 286.331406 -12.23391)
				(arc
					(start 286.13735 -12.596114)
					(mid 286.325271 -12.657755)
					(end 286.522922 -12.650724)
				)
				(arc
					(start 286.522922 -12.650724)
					(mid 287.210009 -12.332205)
					(end 286.610806 -12.79525)
				)
				(arc
					(start 286.610806 -12.79525)
					(mid 286.330272 -12.821465)
					(end 286.060896 -12.738862)
				)
				(arc
					(start 285.973266 -12.902438)
					(mid 286.162398 -13.212708)
					(end 286.246824 -13.56614)
				)
				(arc
					(start 286.246824 -13.56614)
					(mid 286.103086 -14.309819)
					(end 286.08274 -13.552678)
				)
			)
		)
	)
	(zone
		(net "GND")
		(layer "B.Cu")
		(hatch none 0.5)
		(connect_pads
			(clearance 0.5)
		)
		(min_thickness 0.25)
		(fill yes
			(thermal_gap 0.5)
			(thermal_bridge_width 0.5)
			(island_removal_mode 0)
		)
		(polygon
			(pts
				(xy 272.247868 -22.09165) (xy 271.41678 -22.922738) (xy 271.41678 -71.90867) (xy 275.440648 -75.932538)
				(xy 292.432486 -75.932538) (xy 293.897812 -74.467212) (xy 293.897812 -50.302414) (xy 296.347134 -47.853092)
				(xy 322.057522 -47.853092) (xy 323.408548 -46.502066) (xy 323.408548 -40.079676) (xy 323.408548 -39.459916)
				(xy 322.996052 -39.04742) (xy 320.56832 -39.04742) (xy 320.48323 -39.04742) (xy 320.482976 -39.047674)
				(xy 320.107056 -38.671754) (xy 320.107056 -38.586156) (xy 320.105024 -38.584124) (xy 320.105024 -37.79266)
				(xy 320.109596 -37.788088) (xy 320.109596 -37.414708) (xy 320.137536 -37.386768) (xy 320.137536 -37.076888)
				(xy 320.364612 -36.849812) (xy 323.02196 -36.849812) (xy 324.315328 -36.849812) (xy 325.1835 -35.98164)
				(xy 325.51624 -35.6489) (xy 328.975212 -32.189928) (xy 328.975212 -31.996126) (xy 328.975212 -29.439616)
				(xy 328.275442 -28.739846) (xy 284.625796 -28.739846) (xy 277.9776 -22.09165)
			)
		)
		(polygon
			(pts
				(xy 322.334636 -39.557198) (xy 321.876928 -39.557198) (xy 321.876928 -39.760398) (xy 322.334636 -39.760398)
			)
		)
		(polygon
			(pts
				(xy 321.470528 -39.557198) (xy 321.267328 -39.557198) (xy 321.267328 -39.760398) (xy 321.470528 -39.760398)
			)
		)
		(polygon
			(pts
				(xy 315.546486 -36.868862) (xy 315.343286 -36.868862) (xy 315.343286 -37.072062) (xy 315.546486 -37.072062)
			)
		)
		(polygon
			(pts
				(xy 314.936886 -36.868862) (xy 314.479432 -36.868862) (xy 314.479432 -37.072062) (xy 314.936886 -37.072062)
			)
		)
		(polygon
			(pts
				(xy 314.073032 -36.868862) (xy 313.869832 -36.868862) (xy 313.869832 -37.072062) (xy 314.073032 -37.072062)
			)
		)
		(polygon
			(pts
				(xy 322.944236 -36.127436) (xy 322.741036 -36.127436) (xy 322.741036 -36.330636) (xy 322.944236 -36.330636)
			)
		)
		(polygon
			(pts
				(xy 322.334636 -36.127436) (xy 321.876928 -36.127436) (xy 321.876928 -36.330636) (xy 322.334636 -36.330636)
			)
		)
		(polygon
			(pts
				(xy 321.470528 -36.127436) (xy 321.267328 -36.127436) (xy 321.267328 -36.330636) (xy 321.470528 -36.330636)
			)
		)
		(polygon
			(pts
				(xy 305.69789 -35.379914) (xy 305.49469 -35.379914) (xy 305.49469 -35.583114) (xy 305.69789 -35.583114)
			)
		)
		(polygon
			(pts
				(xy 307.17363 -35.37966) (xy 306.97043 -35.37966) (xy 306.97043 -35.58286) (xy 307.17363 -35.58286)
			)
		)
		(polygon
			(pts
				(xy 306.56403 -35.37966) (xy 306.36083 -35.37966) (xy 306.30749 -35.379914) (xy 306.10429 -35.379914)
				(xy 306.10429 -35.583114) (xy 306.30749 -35.583114) (xy 306.36083 -35.58286) (xy 306.56403 -35.58286)
			)
		)
		(polygon
			(pts
				(xy 297.998388 -34.195512) (xy 297.795188 -34.195512) (xy 297.795188 -34.398712) (xy 297.998388 -34.398712)
			)
		)
		(polygon
			(pts
				(xy 297.130978 -34.195004) (xy 296.927778 -34.195004) (xy 296.927778 -34.398204) (xy 297.130978 -34.398204)
				(xy 297.185588 -34.398712) (xy 297.388788 -34.398712) (xy 297.388788 -34.195512) (xy 297.185588 -34.195512)
			)
		)
		(polygon
			(pts
				(xy 296.521378 -34.195004) (xy 296.318178 -34.195004) (xy 296.318178 -34.398204) (xy 296.521378 -34.398204)
			)
		)
		(polygon
			(pts
				(xy 298.286424 -33.761426) (xy 298.083224 -33.761426) (xy 298.083224 -33.964626) (xy 298.286424 -33.964626)
			)
		)
		(polygon
			(pts
				(xy 299.760132 -33.761172) (xy 299.556932 -33.761172) (xy 299.556932 -33.964372) (xy 299.760132 -33.964372)
			)
		)
		(polygon
			(pts
				(xy 299.150532 -33.761172) (xy 298.947332 -33.761172) (xy 298.896024 -33.761426) (xy 298.692824 -33.761426)
				(xy 298.692824 -33.964626) (xy 298.896024 -33.964626) (xy 298.947332 -33.964372) (xy 299.150532 -33.964372)
			)
		)
	)
	(zone
		(net "P0V9_VIN")
		(layer "B.Cu")
		(hatch none 0.5)
		(connect_pads
			(clearance 0.5)
		)
		(min_thickness 0.25)
		(fill yes
			(thermal_gap 0.5)
			(thermal_bridge_width 0.5)
			(island_removal_mode 0)
		)
		(polygon
			(pts
				(xy 147.926806 -62.149736) (xy 147.782534 -62.294008) (xy 147.782534 -62.561724) (xy 147.578826 -62.765432)
				(xy 146.320002 -62.765432) (xy 145.939002 -63.146432) (xy 145.939002 -66.829432) (xy 143.780002 -68.988432)
				(xy 143.780002 -79.275432) (xy 144.161002 -79.656432) (xy 149.850602 -79.656432) (xy 150.892002 -78.615032)
				(xy 150.892002 -62.544452) (xy 150.497286 -62.149736)
			)
		)
	)
	(zone
		(layer "B.Cu")
		(hatch none 0.5)
		(connect_pads
			(clearance 0)
		)
		(min_thickness 0.25)
		(keepout
			(tracks allowed)
			(vias allowed)
			(pads allowed)
			(copperpour allowed)
			(footprints not_allowed)
		)
		(placement
			(enabled no)
			(sheetname "")
		)
		(fill
			(thermal_gap 0.5)
			(thermal_bridge_width 0.5)
			(island_removal_mode 0)
		)
		(polygon
			(pts
				(arc
					(start 149.637496 -9.53008)
					(mid 147.137628 -7.030212)
					(end 144.637506 -9.53008)
				)
				(arc
					(start 144.637506 -9.53008)
					(mid 147.137628 -12.030202)
					(end 149.637496 -9.53008)
				)
			)
		)
	)
	(zone
		(net "GND")
		(layer "B.Cu")
		(hatch none 0.5)
		(connect_pads
			(clearance 0.5)
		)
		(min_thickness 0.25)
		(fill yes
			(thermal_gap 0.5)
			(thermal_bridge_width 0.5)
			(island_removal_mode 0)
		)
		(polygon
			(pts
				(xy 245.3386 -0.865124) (xy 245.3386 -4.13512) (xy 249.338592 -4.13512) (xy 249.338592 -0.865124)
			)
		)
	)
	(zone
		(layer "B.Cu")
		(hatch none 0.5)
		(connect_pads
			(clearance 0)
		)
		(min_thickness 0.25)
		(keepout
			(tracks not_allowed)
			(vias allowed)
			(pads allowed)
			(copperpour not_allowed)
			(footprints allowed)
		)
		(placement
			(enabled no)
			(sheetname "")
		)
		(fill
			(thermal_gap 0.5)
			(thermal_bridge_width 0.5)
			(island_removal_mode 0)
		)
		(polygon
			(pts
				(arc
					(start 341.600028 -203.499974)
					(mid 345.60002 -207.499966)
					(end 349.600012 -203.499974)
				)
				(arc
					(start 349.600012 -203.499974)
					(mid 345.60002 -199.499982)
					(end 341.600028 -203.499974)
				)
			)
		)
	)
	(zone
		(layer "B.Cu")
		(hatch none 0.5)
		(connect_pads
			(clearance 0)
		)
		(min_thickness 0.25)
		(keepout
			(tracks not_allowed)
			(vias allowed)
			(pads allowed)
			(copperpour not_allowed)
			(footprints allowed)
		)
		(placement
			(enabled no)
			(sheetname "")
		)
		(fill
			(thermal_gap 0.5)
			(thermal_bridge_width 0.5)
			(island_removal_mode 0)
		)
		(polygon
			(pts
				(arc
					(start 174.493682 -221.784164)
					(mid 173.983142 -222.294704)
					(end 174.493682 -222.805244)
				)
				(arc
					(start 174.660052 -222.805244)
					(mid 174.630685 -222.672837)
					(end 174.579026 -222.547434)
				)
				(arc
					(start 174.579026 -222.547434)
					(mid 174.334354 -222.081026)
					(end 174.710598 -222.449644)
				)
				(arc
					(start 174.710598 -222.449644)
					(mid 174.784509 -222.621858)
					(end 174.82312 -222.805244)
				)
				(arc
					(start 174.977298 -222.805244)
					(mid 175.015779 -222.621993)
					(end 175.089566 -222.449898)
				)
				(arc
					(start 175.089566 -222.449898)
					(mid 175.465275 -222.080409)
					(end 175.221138 -222.547434)
				)
				(arc
					(start 175.221138 -222.547434)
					(mid 175.169595 -222.672842)
					(end 175.140366 -222.805244)
				)
				(arc
					(start 175.306228 -222.805244)
					(mid 175.817022 -222.294831)
					(end 175.306482 -221.784164)
				)
			)
		)
	)
	(zone
		(layer "B.Cu")
		(hatch none 0.5)
		(connect_pads
			(clearance 0)
		)
		(min_thickness 0.25)
		(keepout
			(tracks allowed)
			(vias allowed)
			(pads allowed)
			(copperpour allowed)
			(footprints not_allowed)
		)
		(placement
			(enabled no)
			(sheetname "")
		)
		(fill
			(thermal_gap 0.5)
			(thermal_bridge_width 0.5)
			(island_removal_mode 0)
		)
		(polygon
			(pts
				(xy 351.600008 -213.499954) (xy 351.600008 -77.0001) (xy 355.6 -77.0001) (xy 355.6 -29.99994)
				(arc
					(start 355.6 -19.200114)
					(mid 355.453516 -18.846472)
					(end 355.099874 -18.699988)
				)
				(arc
					(start 354.750116 -18.699988)
					(mid 354.396489 -18.553669)
					(end 354.24999 -18.200116)
				)
				(arc
					(start 354.24999 -10.199878)
					(mid 354.396563 -9.8464)
					(end 354.750116 -9.700006)
				)
				(arc
					(start 355.099874 -9.700006)
					(mid 355.453516 -9.553522)
					(end 355.6 -9.19988)
				)
				(arc
					(start 355.6 -0.999998)
					(mid 355.307107 -0.292893)
					(end 354.600002 0)
				)
				(arc
					(start 332.749906 0)
					(mid 332.042801 0.292893)
					(end 331.749908 0.999998)
				)
				(arc
					(start 331.749908 3.999992)
					(mid 331.457015 4.707097)
					(end 330.74991 4.99999)
				)
				(arc
					(start 123.637548 4.99999)
					(mid 122.223337 4.414205)
					(end 121.637552 2.999994)
				)
				(arc
					(start 121.637552 1.999996)
					(mid 121.051767 0.585785)
					(end 119.637556 0)
				)
				(xy 93.449902 0) (xy 67.449954 0)
				(arc
					(start 53.950108 0)
					(mid 52.535897 -0.585785)
					(end 51.950112 -1.999996)
				)
				(arc
					(start 51.950112 -24.010112)
					(mid 51.364327 -25.424323)
					(end 49.950116 -26.010108)
				)
				(arc
					(start 1.999996 -26.010108)
					(mid 0.585785 -26.595893)
					(end 0 -28.010104)
				)
				(xy 0 -77.0001) (xy 3.999992 -77.0001) (xy 3.999992 -213.499954) (xy 229.142036 -213.499954) (xy 229.142036 -158.999936)
				(xy 256.141982 -158.999936) (xy 256.141982 -213.499954)
			)
		)
	)
	(zone
		(net "DUT_VDD")
		(layer "B.Cu")
		(hatch none 0.5)
		(connect_pads
			(clearance 0.5)
		)
		(min_thickness 0.25)
		(fill yes
			(thermal_gap 0.5)
			(thermal_bridge_width 0.5)
			(island_removal_mode 0)
		)
		(polygon
			(pts
				(xy 246.04345 -41.23055) (xy 233.8451 -53.4289) (xy 233.8451 -53.5559) (xy 234.0356 -53.7464) (xy 234.2388 -53.7464)
				(xy 240.2967 -47.6885) (xy 240.2967 -47.6758) (xy 246.3927 -41.5798) (xy 246.3927 -41.4655) (xy 246.15775 -41.23055)
			)
		)
	)
	(zone
		(layer "B.Cu")
		(hatch none 0.5)
		(connect_pads
			(clearance 0)
		)
		(min_thickness 0.25)
		(keepout
			(tracks not_allowed)
			(vias allowed)
			(pads allowed)
			(copperpour not_allowed)
			(footprints allowed)
		)
		(placement
			(enabled no)
			(sheetname "")
		)
		(fill
			(thermal_gap 0.5)
			(thermal_bridge_width 0.5)
			(island_removal_mode 0)
		)
		(polygon
			(pts
				(arc
					(start 294.893746 -221.784164)
					(mid 294.383206 -222.294704)
					(end 294.893746 -222.805244)
				)
				(arc
					(start 295.060116 -222.805244)
					(mid 295.030749 -222.672837)
					(end 294.97909 -222.547434)
				)
				(arc
					(start 294.97909 -222.547434)
					(mid 294.734418 -222.081026)
					(end 295.110662 -222.449644)
				)
				(arc
					(start 295.110662 -222.449644)
					(mid 295.184573 -222.621858)
					(end 295.223184 -222.805244)
				)
				(arc
					(start 295.377362 -222.805244)
					(mid 295.415843 -222.621993)
					(end 295.48963 -222.449898)
				)
				(arc
					(start 295.48963 -222.449898)
					(mid 295.865339 -222.080409)
					(end 295.621202 -222.547434)
				)
				(arc
					(start 295.621202 -222.547434)
					(mid 295.569659 -222.672842)
					(end 295.54043 -222.805244)
				)
				(arc
					(start 295.706292 -222.805244)
					(mid 296.217086 -222.294831)
					(end 295.706546 -221.784164)
				)
			)
		)
	)
	(zone
		(layer "B.Cu")
		(hatch none 0.5)
		(connect_pads
			(clearance 0)
		)
		(min_thickness 0.25)
		(keepout
			(tracks not_allowed)
			(vias allowed)
			(pads allowed)
			(copperpour not_allowed)
			(footprints allowed)
		)
		(placement
			(enabled no)
			(sheetname "")
		)
		(fill
			(thermal_gap 0.5)
			(thermal_bridge_width 0.5)
			(island_removal_mode 0)
		)
		(polygon
			(pts
				(arc
					(start 271.19834 -8.353806)
					(mid 270.687927 -7.843012)
					(end 270.17726 -8.353552)
				)
				(arc
					(start 270.17726 -9.166352)
					(mid 270.6878 -9.676892)
					(end 271.19834 -9.166352)
				)
				(xy 271.19834 -8.993378) (xy 270.975328 -8.993378)
				(arc
					(start 270.924782 -9.043924)
					(mid 270.499188 -9.354964)
					(end 270.810228 -8.92937)
				)
				(xy 270.908272 -8.831326) (xy 271.19834 -8.831326) (xy 271.19834 -8.688578) (xy 270.908272 -8.688578)
				(arc
					(start 270.810228 -8.590534)
					(mid 270.499188 -8.16494)
					(end 270.924782 -8.47598)
				)
				(xy 270.975328 -8.526526) (xy 271.19834 -8.526526)
			)
		)
	)
	(zone
		(layer "B.Cu")
		(hatch none 0.5)
		(connect_pads
			(clearance 0)
		)
		(min_thickness 0.25)
		(keepout
			(tracks allowed)
			(vias allowed)
			(pads allowed)
			(copperpour allowed)
			(footprints not_allowed)
		)
		(placement
			(enabled no)
			(sheetname "")
		)
		(fill
			(thermal_gap 0.5)
			(thermal_bridge_width 0.5)
			(island_removal_mode 0)
		)
		(polygon
			(pts
				(arc
					(start 76.049886 -14.200124)
					(mid 74.44994 -12.600178)
					(end 72.849994 -14.200124)
				)
				(arc
					(start 72.849994 -14.200124)
					(mid 74.44994 -15.80007)
					(end 76.049886 -14.200124)
				)
			)
		)
	)
	(zone
		(layer "B.Cu")
		(hatch none 0.5)
		(connect_pads
			(clearance 0)
		)
		(min_thickness 0.25)
		(keepout
			(tracks allowed)
			(vias allowed)
			(pads allowed)
			(copperpour allowed)
			(footprints not_allowed)
		)
		(placement
			(enabled no)
			(sheetname "")
		)
		(fill
			(thermal_gap 0.5)
			(thermal_bridge_width 0.5)
			(island_removal_mode 0)
		)
		(polygon
			(pts
				(arc
					(start 348.149926 -22.999954)
					(mid 349.750126 -24.600154)
					(end 351.350072 -22.999954)
				)
				(arc
					(start 351.350072 -22.999954)
					(mid 349.750126 -21.400008)
					(end 348.149926 -22.999954)
				)
			)
		)
	)
	(zone
		(layer "B.Cu")
		(hatch none 0.5)
		(connect_pads
			(clearance 0)
		)
		(min_thickness 0.25)
		(keepout
			(tracks not_allowed)
			(vias allowed)
			(pads allowed)
			(copperpour not_allowed)
			(footprints allowed)
		)
		(placement
			(enabled no)
			(sheetname "")
		)
		(fill
			(thermal_gap 0.5)
			(thermal_bridge_width 0.5)
			(island_removal_mode 0)
		)
		(polygon
			(pts
				(arc
					(start 102.893368 -221.784164)
					(mid 102.382828 -222.294704)
					(end 102.893368 -222.805244)
				)
				(arc
					(start 103.059738 -222.805244)
					(mid 103.030371 -222.672837)
					(end 102.978712 -222.547434)
				)
				(arc
					(start 102.978712 -222.547434)
					(mid 102.73404 -222.081026)
					(end 103.110284 -222.449644)
				)
				(arc
					(start 103.110284 -222.449644)
					(mid 103.184195 -222.621858)
					(end 103.222806 -222.805244)
				)
				(arc
					(start 103.376984 -222.805244)
					(mid 103.415465 -222.621993)
					(end 103.489252 -222.449898)
				)
				(arc
					(start 103.489252 -222.449898)
					(mid 103.864961 -222.080409)
					(end 103.620824 -222.547434)
				)
				(arc
					(start 103.620824 -222.547434)
					(mid 103.569281 -222.672842)
					(end 103.540052 -222.805244)
				)
				(arc
					(start 103.705914 -222.805244)
					(mid 104.216708 -222.294831)
					(end 103.706168 -221.784164)
				)
			)
		)
	)
	(zone
		(layer "B.Cu")
		(hatch none 0.5)
		(connect_pads
			(clearance 0)
		)
		(min_thickness 0.25)
		(keepout
			(tracks not_allowed)
			(vias allowed)
			(pads allowed)
			(copperpour not_allowed)
			(footprints allowed)
		)
		(placement
			(enabled no)
			(sheetname "")
		)
		(fill
			(thermal_gap 0.5)
			(thermal_bridge_width 0.5)
			(island_removal_mode 0)
		)
		(polygon
			(pts
				(arc
					(start 152.893776 -221.784164)
					(mid 152.383236 -222.294704)
					(end 152.893776 -222.805244)
				)
				(arc
					(start 153.060146 -222.805244)
					(mid 153.030779 -222.672837)
					(end 152.97912 -222.547434)
				)
				(arc
					(start 152.97912 -222.547434)
					(mid 152.734448 -222.081026)
					(end 153.110692 -222.449644)
				)
				(arc
					(start 153.110692 -222.449644)
					(mid 153.184603 -222.621858)
					(end 153.223214 -222.805244)
				)
				(arc
					(start 153.377392 -222.805244)
					(mid 153.415873 -222.621993)
					(end 153.48966 -222.449898)
				)
				(arc
					(start 153.48966 -222.449898)
					(mid 153.865369 -222.080409)
					(end 153.621232 -222.547434)
				)
				(arc
					(start 153.621232 -222.547434)
					(mid 153.569689 -222.672842)
					(end 153.54046 -222.805244)
				)
				(arc
					(start 153.706322 -222.805244)
					(mid 154.217116 -222.294831)
					(end 153.706576 -221.784164)
				)
			)
		)
	)
	(zone
		(layer "B.Cu")
		(hatch none 0.5)
		(connect_pads
			(clearance 0)
		)
		(min_thickness 0.25)
		(keepout
			(tracks allowed)
			(vias allowed)
			(pads allowed)
			(copperpour allowed)
			(footprints not_allowed)
		)
		(placement
			(enabled no)
			(sheetname "")
		)
		(fill
			(thermal_gap 0.5)
			(thermal_bridge_width 0.5)
			(island_removal_mode 0)
		)
		(polygon
			(pts
				(arc
					(start 166.637462 -9.53008)
					(mid 169.137584 -12.030202)
					(end 171.637452 -9.53008)
				)
				(arc
					(start 171.637452 -9.53008)
					(mid 169.137584 -7.030212)
					(end 166.637462 -9.53008)
				)
			)
		)
	)
	(zone
		(layer "B.Cu")
		(hatch none 0.5)
		(connect_pads
			(clearance 0)
		)
		(min_thickness 0.25)
		(keepout
			(tracks not_allowed)
			(vias allowed)
			(pads allowed)
			(copperpour not_allowed)
			(footprints allowed)
		)
		(placement
			(enabled no)
			(sheetname "")
		)
		(fill
			(thermal_gap 0.5)
			(thermal_bridge_width 0.5)
			(island_removal_mode 0)
		)
		(polygon
			(pts
				(arc
					(start 183.63057 -7.89559)
					(mid 183.12003 -8.40613)
					(end 183.63057 -8.91667)
				)
				(arc
					(start 184.443116 -8.91667)
					(mid 184.95391 -8.406257)
					(end 184.44337 -7.89559)
				)
				(xy 184.268872 -7.89559) (xy 184.270142 -7.923022) (xy 184.27065 -7.92353) (xy 184.27065 -7.990586)
				(xy 184.270396 -7.99084) (xy 184.270396 -8.118602)
				(arc
					(start 184.320942 -8.169148)
					(mid 184.631982 -8.594742)
					(end 184.206388 -8.283702)
				)
				(xy 184.108344 -8.185658) (xy 184.108344 -7.935976) (xy 184.106312 -7.89559) (xy 183.963056 -7.89559)
				(xy 183.964834 -7.922768) (xy 183.965596 -7.92353) (xy 183.965596 -8.185658)
				(arc
					(start 183.867552 -8.283702)
					(mid 183.441958 -8.594742)
					(end 183.752998 -8.169148)
				)
				(xy 183.803544 -8.118602)
				(arc
					(start 183.803544 -7.95655)
					(mid 183.802742 -7.926024)
					(end 183.800242 -7.89559)
				)
			)
		)
	)
	(zone
		(layer "B.Cu")
		(hatch none 0.5)
		(connect_pads
			(clearance 0)
		)
		(min_thickness 0.25)
		(keepout
			(tracks allowed)
			(vias allowed)
			(pads allowed)
			(copperpour allowed)
			(footprints not_allowed)
		)
		(placement
			(enabled no)
			(sheetname "")
		)
		(fill
			(thermal_gap 0.5)
			(thermal_bridge_width 0.5)
			(island_removal_mode 0)
		)
		(polygon
			(pts
				(arc
					(start 319.63741 -9.53008)
					(mid 322.137532 -12.030202)
					(end 324.6374 -9.53008)
				)
				(arc
					(start 324.6374 -9.53008)
					(mid 322.137532 -7.030212)
					(end 319.63741 -9.53008)
				)
			)
		)
	)
	(zone
		(net "DUT_AVD_PCIE_Q")
		(layer "B.Cu")
		(hatch none 0.5)
		(connect_pads
			(clearance 0.5)
		)
		(min_thickness 0.25)
		(fill yes
			(thermal_gap 0.5)
			(thermal_bridge_width 0.5)
			(island_removal_mode 0)
		)
		(polygon
			(pts
				(xy 183.346598 -49.527968) (xy 183.092598 -49.781968) (xy 183.092598 -53.693568) (xy 184.083198 -54.684168)
				(xy 191.017398 -54.684168) (xy 191.461898 -54.239668) (xy 191.461898 -49.896268) (xy 191.093598 -49.527968)
			)
		)
		(polygon
			(pts
				(xy 183.892698 -51.623468) (xy 183.689498 -51.623468) (xy 183.689498 -51.826668) (xy 183.892698 -51.826668)
			)
		)
		(polygon
			(pts
				(xy 183.892698 -50.759868) (xy 183.689498 -50.759868) (xy 183.689498 -50.963068) (xy 183.892698 -50.963068)
			)
		)
	)
	(zone
		(layer "B.Cu")
		(hatch none 0.5)
		(connect_pads
			(clearance 0)
		)
		(min_thickness 0.25)
		(keepout
			(tracks allowed)
			(vias allowed)
			(pads allowed)
			(copperpour allowed)
			(footprints allowed)
		)
		(placement
			(enabled no)
			(sheetname "")
		)
		(fill
			(thermal_gap 0.5)
			(thermal_bridge_width 0.5)
			(island_removal_mode 0)
		)
		(polygon
			(pts
				(xy 270.12011 -5.706364) (xy 270.12011 -4.687824) (xy 272.001996 -4.687824) (xy 272.001996 -5.706364)
			)
		)
	)
	(zone
		(layer "B.Cu")
		(hatch none 0.5)
		(connect_pads
			(clearance 0)
		)
		(min_thickness 0.25)
		(keepout
			(tracks allowed)
			(vias allowed)
			(pads allowed)
			(copperpour allowed)
			(footprints allowed)
		)
		(placement
			(enabled no)
			(sheetname "")
		)
		(fill
			(thermal_gap 0.5)
			(thermal_bridge_width 0.5)
			(island_removal_mode 0)
		)
		(polygon
			(pts
				(xy 219.7862 -68.3768) (xy 219.7862 -27.2288) (xy 234.3404 -27.2288) (xy 234.3404 -25.781) (xy 234.3912 -25.7302)
				(xy 241.427 -25.7302) (xy 241.5286 -25.8318) (xy 241.5286 -27.2288) (xy 261.0866 -27.2288) (xy 261.0866 -68.3768)
			)
		)
	)
	(zone
		(layer "B.Cu")
		(hatch none 0.5)
		(connect_pads
			(clearance 0)
		)
		(min_thickness 0.25)
		(keepout
			(tracks not_allowed)
			(vias allowed)
			(pads allowed)
			(copperpour not_allowed)
			(footprints allowed)
		)
		(placement
			(enabled no)
			(sheetname "")
		)
		(fill
			(thermal_gap 0.5)
			(thermal_bridge_width 0.5)
			(island_removal_mode 0)
		)
		(polygon
			(pts
				(arc
					(start 168.03751 -9.53008)
					(mid 169.137584 -10.630154)
					(end 170.237404 -9.53008)
				)
				(arc
					(start 170.237404 -9.53008)
					(mid 169.137584 -8.43026)
					(end 168.03751 -9.53008)
				)
			)
		)
	)
	(zone
		(layer "B.Cu")
		(hatch none 0.5)
		(connect_pads
			(clearance 0)
		)
		(min_thickness 0.25)
		(keepout
			(tracks not_allowed)
			(vias allowed)
			(pads allowed)
			(copperpour not_allowed)
			(footprints allowed)
		)
		(placement
			(enabled no)
			(sheetname "")
		)
		(fill
			(thermal_gap 0.5)
			(thermal_bridge_width 0.5)
			(island_removal_mode 0)
		)
		(polygon
			(pts
				(arc
					(start 164.893752 -221.784164)
					(mid 164.383212 -222.294704)
					(end 164.893752 -222.805244)
				)
				(arc
					(start 165.060122 -222.805244)
					(mid 165.030755 -222.672837)
					(end 164.979096 -222.547434)
				)
				(arc
					(start 164.979096 -222.547434)
					(mid 164.734424 -222.081026)
					(end 165.110668 -222.449644)
				)
				(arc
					(start 165.110668 -222.449644)
					(mid 165.184579 -222.621858)
					(end 165.22319 -222.805244)
				)
				(arc
					(start 165.377368 -222.805244)
					(mid 165.415849 -222.621993)
					(end 165.489636 -222.449898)
				)
				(arc
					(start 165.489636 -222.449898)
					(mid 165.865345 -222.080409)
					(end 165.621208 -222.547434)
				)
				(arc
					(start 165.621208 -222.547434)
					(mid 165.569665 -222.672842)
					(end 165.540436 -222.805244)
				)
				(arc
					(start 165.706298 -222.805244)
					(mid 166.217092 -222.294831)
					(end 165.706552 -221.784164)
				)
			)
		)
	)
	(zone
		(layer "B.Cu")
		(hatch none 0.5)
		(connect_pads
			(clearance 0)
		)
		(min_thickness 0.25)
		(keepout
			(tracks not_allowed)
			(vias allowed)
			(pads allowed)
			(copperpour not_allowed)
			(footprints allowed)
		)
		(placement
			(enabled no)
			(sheetname "")
		)
		(fill
			(thermal_gap 0.5)
			(thermal_bridge_width 0.5)
			(island_removal_mode 0)
		)
		(polygon
			(pts
				(arc
					(start 188.893704 -221.784164)
					(mid 188.383164 -222.294704)
					(end 188.893704 -222.805244)
				)
				(arc
					(start 189.060074 -222.805244)
					(mid 189.030707 -222.672837)
					(end 188.979048 -222.547434)
				)
				(arc
					(start 188.979048 -222.547434)
					(mid 188.734376 -222.081026)
					(end 189.11062 -222.449644)
				)
				(arc
					(start 189.11062 -222.449644)
					(mid 189.184531 -222.621858)
					(end 189.223142 -222.805244)
				)
				(arc
					(start 189.37732 -222.805244)
					(mid 189.415801 -222.621993)
					(end 189.489588 -222.449898)
				)
				(arc
					(start 189.489588 -222.449898)
					(mid 189.865297 -222.080409)
					(end 189.62116 -222.547434)
				)
				(arc
					(start 189.62116 -222.547434)
					(mid 189.569617 -222.672842)
					(end 189.540388 -222.805244)
				)
				(arc
					(start 189.70625 -222.805244)
					(mid 190.217044 -222.294831)
					(end 189.706504 -221.784164)
				)
			)
		)
	)
	(zone
		(layer "B.Cu")
		(hatch none 0.5)
		(connect_pads
			(clearance 0)
		)
		(min_thickness 0.25)
		(keepout
			(tracks allowed)
			(vias allowed)
			(pads allowed)
			(copperpour allowed)
			(footprints not_allowed)
		)
		(placement
			(enabled no)
			(sheetname "")
		)
		(fill
			(thermal_gap 0.5)
			(thermal_bridge_width 0.5)
			(island_removal_mode 0)
		)
		(polygon
			(pts
				(arc
					(start 249.871992 -163.999926)
					(mid 250.770018 -164.3719)
					(end 251.141992 -165.269926)
				)
				(arc
					(start 251.141992 -208.499964)
					(mid 252.606455 -212.035491)
					(end 256.141982 -213.499954)
				)
				(xy 256.141982 -158.999936) (xy 229.142036 -158.999936)
				(arc
					(start 229.142036 -213.499954)
					(mid 232.677563 -212.035491)
					(end 234.142026 -208.499964)
				)
				(arc
					(start 234.142026 -165.269926)
					(mid 234.514 -164.3719)
					(end 235.412026 -163.999926)
				)
			)
		)
	)
	(zone
		(layer "B.Cu")
		(hatch none 0.5)
		(connect_pads
			(clearance 0)
		)
		(min_thickness 0.25)
		(keepout
			(tracks allowed)
			(vias allowed)
			(pads allowed)
			(copperpour allowed)
			(footprints allowed)
		)
		(placement
			(enabled no)
			(sheetname "")
		)
		(fill
			(thermal_gap 0.5)
			(thermal_bridge_width 0.5)
			(island_removal_mode 0)
		)
		(polygon
			(pts
				(xy 181.356 -8.763) (xy 181.356 -7.1882) (xy 182.0418 -7.1882) (xy 182.0418 -8.763)
			)
		)
	)
	(zone
		(net "DUT_VDD")
		(layer "B.Cu")
		(hatch none 0.5)
		(connect_pads
			(clearance 0.5)
		)
		(min_thickness 0.25)
		(fill yes
			(thermal_gap 0.5)
			(thermal_bridge_width 0.5)
			(island_removal_mode 0)
		)
		(polygon
			(pts
				(xy 248.031 -50.2412) (xy 243.8146 -54.4576) (xy 243.8146 -54.5846) (xy 244.0051 -54.7751) (xy 244.221 -54.7751)
				(xy 248.3612 -50.6349) (xy 248.3612 -50.4698) (xy 248.1326 -50.2412)
			)
		)
	)
	(zone
		(layer "B.Cu")
		(hatch none 0.5)
		(connect_pads
			(clearance 0)
		)
		(min_thickness 0.25)
		(keepout
			(tracks allowed)
			(vias allowed)
			(pads allowed)
			(copperpour allowed)
			(footprints not_allowed)
		)
		(placement
			(enabled no)
			(sheetname "")
		)
		(fill
			(thermal_gap 0.5)
			(thermal_bridge_width 0.5)
			(island_removal_mode 0)
		)
		(polygon
			(pts
				(arc
					(start 334.749902 -14.200124)
					(mid 338.749894 -18.200116)
					(end 342.749886 -14.200124)
				)
				(arc
					(start 342.749886 -14.200124)
					(mid 338.749894 -10.200132)
					(end 334.749902 -14.200124)
				)
			)
		)
	)
	(zone
		(layer "B.Cu")
		(hatch none 0.5)
		(connect_pads
			(clearance 0)
		)
		(min_thickness 0.25)
		(keepout
			(tracks not_allowed)
			(vias allowed)
			(pads allowed)
			(copperpour not_allowed)
			(footprints allowed)
		)
		(placement
			(enabled no)
			(sheetname "")
		)
		(fill
			(thermal_gap 0.5)
			(thermal_bridge_width 0.5)
			(island_removal_mode 0)
		)
		(polygon
			(pts
				(arc
					(start 312.237374 -9.53008)
					(mid 311.137554 -8.43026)
					(end 310.03748 -9.53008)
				)
				(arc
					(start 310.03748 -9.53008)
					(mid 311.137554 -10.630154)
					(end 312.237374 -9.53008)
				)
			)
		)
	)
	(zone
		(net "DUT_AVD_TX")
		(layer "B.Cu")
		(hatch none 0.5)
		(connect_pads
			(clearance 0.5)
		)
		(min_thickness 0.25)
		(fill yes
			(thermal_gap 0.5)
			(thermal_bridge_width 0.5)
			(island_removal_mode 0)
		)
		(polygon
			(pts
				(xy 235.712 -55.88) (xy 235.712 -56.515) (xy 235.331 -56.896) (xy 235.077 -56.896) (xy 234.95 -57.023)
				(xy 234.95 -57.531) (xy 235.077 -57.658) (xy 235.458 -57.658) (xy 235.712 -57.912) (xy 235.712 -58.4454)
				(xy 235.3564 -58.801) (xy 235.204 -58.801) (xy 234.95 -59.055) (xy 234.95 -59.69) (xy 235.077 -59.817)
				(xy 235.585 -59.817) (xy 235.712 -59.944) (xy 235.712 -61.087) (xy 235.331 -61.468) (xy 235.331 -74.93)
				(xy 229.87 -80.391) (xy 181.229 -80.391) (xy 177.9778 -77.1398) (xy 177.9778 -71.5264) (xy 177.8254 -71.374)
				(xy 175.274986 -71.374) (xy 174.480474 -72.168512) (xy 174.480474 -80.246474) (xy 184.277 -90.043)
				(xy 241.3 -90.043) (xy 245.872 -85.471) (xy 245.872 -60.833) (xy 245.491 -60.452) (xy 245.491 -59.8678)
				(xy 245.364 -59.7408) (xy 245.364 -58.7502) (xy 245.491 -58.6232) (xy 245.491 -57.8612) (xy 245.3894 -57.7596)
				(xy 245.3894 -56.6674) (xy 245.491 -56.5658) (xy 245.491 -55.88) (xy 245.11 -55.88) (xy 244.983 -56.007)
				(xy 244.983 -56.515) (xy 244.602 -56.896) (xy 243.713 -56.896) (xy 243.459 -56.642) (xy 243.459 -55.88)
				(xy 243.078 -55.88) (xy 242.951 -56.007) (xy 242.951 -56.515) (xy 242.697 -56.769) (xy 241.681 -56.769)
				(xy 241.427 -56.515) (xy 241.427 -55.88) (xy 237.744 -55.88) (xy 237.617 -56.007) (xy 237.617 -56.515)
				(xy 237.236 -56.896) (xy 236.728 -56.896) (xy 236.347 -56.515) (xy 236.347 -56.134) (xy 236.093 -55.88)
			)
		)
		(polygon
			(pts
				(xy 243.205 -60.07354) (xy 243.0018 -60.07354) (xy 243.0018 -60.27674) (xy 243.205 -60.27674)
			)
		)
		(polygon
			(pts
				(xy 241.2238 -60.07354) (xy 241.0206 -60.07354) (xy 241.0206 -60.27674) (xy 241.2238 -60.27674)
			)
		)
		(polygon
			(pts
				(xy 238.2012 -60.07354) (xy 237.998 -60.07354) (xy 237.998 -60.27674) (xy 238.2012 -60.27674)
			)
		)
		(polygon
			(pts
				(xy 236.1692 -60.07354) (xy 235.966 -60.07354) (xy 235.966 -60.27674) (xy 236.1692 -60.27674)
			)
		)
		(polygon
			(pts
				(xy 245.2116 -60.071) (xy 245.0084 -60.071) (xy 245.0084 -60.2742) (xy 245.2116 -60.2742)
			)
		)
		(polygon
			(pts
				(xy 244.1702 -59.0804) (xy 243.967 -59.0804) (xy 243.967 -59.2836) (xy 244.1702 -59.2836)
			)
		)
		(polygon
			(pts
				(xy 242.189 -59.0804) (xy 241.9858 -59.0804) (xy 241.9858 -59.2836) (xy 242.189 -59.2836)
			)
		)
		(polygon
			(pts
				(xy 239.4966 -59.0804) (xy 239.2934 -59.0804) (xy 239.2934 -59.2836) (xy 239.4966 -59.2836)
			)
		)
		(polygon
			(pts
				(xy 237.236 -59.0804) (xy 237.0328 -59.0804) (xy 237.0328 -59.2836) (xy 237.236 -59.2836)
			)
		)
		(polygon
			(pts
				(xy 243.205 -58.071258) (xy 243.0018 -58.071258) (xy 243.0018 -58.274458) (xy 243.205 -58.274458)
			)
		)
		(polygon
			(pts
				(xy 241.2238 -58.071258) (xy 241.0206 -58.071258) (xy 241.0206 -58.274458) (xy 241.2238 -58.274458)
			)
		)
		(polygon
			(pts
				(xy 238.2012 -58.071258) (xy 237.998 -58.071258) (xy 237.998 -58.274458) (xy 238.2012 -58.274458)
			)
		)
		(polygon
			(pts
				(xy 236.1692 -58.071258) (xy 235.966 -58.071258) (xy 235.966 -58.274458) (xy 236.1692 -58.274458)
			)
		)
		(polygon
			(pts
				(xy 245.2116 -58.0644) (xy 245.0084 -58.0644) (xy 245.0084 -58.2676) (xy 245.2116 -58.2676)
			)
		)
		(polygon
			(pts
				(xy 244.1702 -57.0738) (xy 243.967 -57.0738) (xy 243.967 -57.277) (xy 244.1702 -57.277)
			)
		)
		(polygon
			(pts
				(xy 242.189 -57.0738) (xy 241.9858 -57.0738) (xy 241.9858 -57.277) (xy 242.189 -57.277)
			)
		)
		(polygon
			(pts
				(xy 239.4966 -57.0738) (xy 239.2934 -57.0738) (xy 239.2934 -57.277) (xy 239.4966 -57.277)
			)
		)
		(polygon
			(pts
				(xy 237.236 -57.0738) (xy 237.0328 -57.0738) (xy 237.0328 -57.277) (xy 237.236 -57.277)
			)
		)
		(polygon
			(pts
				(xy 241.2238 -56.0832) (xy 241.0206 -56.0832) (xy 241.0206 -56.2864) (xy 241.2238 -56.2864)
			)
		)
		(polygon
			(pts
				(xy 238.2012 -56.07812) (xy 237.998 -56.07812) (xy 237.998 -56.28132) (xy 238.2012 -56.28132)
			)
		)
	)
	(zone
		(layer "B.Cu")
		(hatch none 0.5)
		(connect_pads
			(clearance 0)
		)
		(min_thickness 0.25)
		(keepout
			(tracks not_allowed)
			(vias allowed)
			(pads allowed)
			(copperpour not_allowed)
			(footprints allowed)
		)
		(placement
			(enabled no)
			(sheetname "")
		)
		(fill
			(thermal_gap 0.5)
			(thermal_bridge_width 0.5)
			(island_removal_mode 0)
		)
		(polygon
			(pts
				(arc
					(start 323.237606 -9.53008)
					(mid 322.137532 -8.430006)
					(end 321.037458 -9.53008)
				)
				(arc
					(start 321.037458 -9.53008)
					(mid 322.137532 -10.630154)
					(end 323.237606 -9.53008)
				)
			)
		)
	)
	(zone
		(net "DUT_AVD_PCIE")
		(layer "B.Cu")
		(hatch none 0.5)
		(connect_pads
			(clearance 0.5)
		)
		(min_thickness 0.25)
		(fill yes
			(thermal_gap 0.5)
			(thermal_bridge_width 0.5)
			(island_removal_mode 0)
		)
		(polygon
			(pts
				(xy 177.885598 -49.273968) (xy 177.758598 -49.400968) (xy 177.758598 -54.099968) (xy 178.266598 -54.607968)
				(xy 181.797198 -54.607968) (xy 182.076598 -54.328568) (xy 182.076598 -49.400968) (xy 181.949598 -49.273968)
			)
		)
		(polygon
			(pts
				(xy 181.606698 -51.623468) (xy 181.403498 -51.623468) (xy 181.403498 -51.826668) (xy 181.606698 -51.826668)
			)
		)
		(polygon
			(pts
				(xy 181.606698 -50.759868) (xy 181.403498 -50.759868) (xy 181.403498 -50.963068) (xy 181.606698 -50.963068)
			)
		)
	)
	(zone
		(net "DUT_VDD")
		(layer "B.Cu")
		(hatch none 0.5)
		(connect_pads
			(clearance 0.5)
		)
		(min_thickness 0.25)
		(fill yes
			(thermal_gap 0.5)
			(thermal_bridge_width 0.5)
			(island_removal_mode 0)
		)
		(polygon
			(pts
				(xy 295.656 -55.88) (xy 295.275 -56.261) (xy 295.275 -67.691) (xy 295.656 -68.072) (xy 309.626 -68.072)
				(xy 309.88 -67.818) (xy 309.88 -56.261) (xy 309.499 -55.88)
			)
		)
	)
	(zone
		(layer "B.Cu")
		(hatch none 0.5)
		(connect_pads
			(clearance 0)
		)
		(min_thickness 0.25)
		(keepout
			(tracks not_allowed)
			(vias allowed)
			(pads allowed)
			(copperpour not_allowed)
			(footprints allowed)
		)
		(placement
			(enabled no)
			(sheetname "")
		)
		(fill
			(thermal_gap 0.5)
			(thermal_bridge_width 0.5)
			(island_removal_mode 0)
		)
		(polygon
			(pts
				(arc
					(start 52.399692 -47.366428)
					(mid 51.888898 -47.876841)
					(end 52.399438 -48.387508)
				)
				(xy 52.608734 -48.387508) (xy 52.608734 -48.200818)
				(arc
					(start 52.521866 -48.11395)
					(mid 52.210826 -47.688356)
					(end 52.63642 -47.999396)
				)
				(xy 52.770786 -48.133762) (xy 52.770786 -48.387508) (xy 52.913534 -48.387508) (xy 52.913534 -48.154844)
				(arc
					(start 53.068982 -47.999396)
					(mid 53.494576 -47.688356)
					(end 53.183536 -48.11395)
				)
				(xy 53.075586 -48.2219) (xy 53.075586 -48.387508)
				(arc
					(start 53.305964 -48.387508)
					(mid 53.816504 -47.876968)
					(end 53.305964 -47.366428)
				)
			)
		)
	)
	(zone
		(layer "B.Cu")
		(hatch none 0.5)
		(connect_pads
			(clearance 0)
		)
		(min_thickness 0.25)
		(keepout
			(tracks not_allowed)
			(vias allowed)
			(pads allowed)
			(copperpour not_allowed)
			(footprints allowed)
		)
		(placement
			(enabled no)
			(sheetname "")
		)
		(fill
			(thermal_gap 0.5)
			(thermal_bridge_width 0.5)
			(island_removal_mode 0)
		)
		(polygon
			(pts
				(arc
					(start 65.330832 -127.168656)
					(mid 64.820038 -127.679069)
					(end 65.330578 -128.189736)
				)
				(xy 65.50787 -128.189736) (xy 65.50787 -127.971042)
				(arc
					(start 65.453006 -127.916178)
					(mid 65.141966 -127.490584)
					(end 65.56756 -127.801624)
				)
				(xy 65.669922 -127.903986) (xy 65.669922 -128.189736) (xy 65.81267 -128.189736) (xy 65.81267 -127.89535)
				(arc
					(start 65.906396 -127.801624)
					(mid 66.33199 -127.490584)
					(end 66.02095 -127.916178)
				)
				(xy 65.974722 -127.962406) (xy 65.974722 -128.189736)
				(arc
					(start 66.143378 -128.189736)
					(mid 66.653918 -127.679196)
					(end 66.143378 -127.168656)
				)
			)
		)
	)
	(zone
		(layer "B.Cu")
		(hatch none 0.5)
		(connect_pads
			(clearance 0)
		)
		(min_thickness 0.25)
		(keepout
			(tracks allowed)
			(vias allowed)
			(pads allowed)
			(copperpour allowed)
			(footprints not_allowed)
		)
		(placement
			(enabled no)
			(sheetname "")
		)
		(fill
			(thermal_gap 0.5)
			(thermal_bridge_width 0.5)
			(island_removal_mode 0)
		)
		(polygon
			(pts
				(arc
					(start 343.7001 -203.499974)
					(mid 345.60002 -205.399894)
					(end 347.49994 -203.499974)
				)
				(arc
					(start 347.49994 -203.499974)
					(mid 345.60002 -201.600054)
					(end 343.7001 -203.499974)
				)
			)
		)
	)
	(zone
		(layer "B.Cu")
		(hatch none 0.5)
		(connect_pads
			(clearance 0)
		)
		(min_thickness 0.25)
		(keepout
			(tracks not_allowed)
			(vias allowed)
			(pads allowed)
			(copperpour not_allowed)
			(footprints allowed)
		)
		(placement
			(enabled no)
			(sheetname "")
		)
		(fill
			(thermal_gap 0.5)
			(thermal_bridge_width 0.5)
			(island_removal_mode 0)
		)
		(polygon
			(pts
				(arc
					(start 201.69378 -221.784164)
					(mid 201.18324 -222.294704)
					(end 201.69378 -222.805244)
				)
				(arc
					(start 201.86015 -222.805244)
					(mid 201.830783 -222.672837)
					(end 201.779124 -222.547434)
				)
				(arc
					(start 201.779124 -222.547434)
					(mid 201.534452 -222.081026)
					(end 201.910696 -222.449644)
				)
				(arc
					(start 201.910696 -222.449644)
					(mid 201.984607 -222.621858)
					(end 202.023218 -222.805244)
				)
				(arc
					(start 202.177396 -222.805244)
					(mid 202.215877 -222.621993)
					(end 202.289664 -222.449898)
				)
				(arc
					(start 202.289664 -222.449898)
					(mid 202.665373 -222.080409)
					(end 202.421236 -222.547434)
				)
				(arc
					(start 202.421236 -222.547434)
					(mid 202.369693 -222.672842)
					(end 202.340464 -222.805244)
				)
				(arc
					(start 202.506326 -222.805244)
					(mid 203.01712 -222.294831)
					(end 202.50658 -221.784164)
				)
			)
		)
	)
	(zone
		(layer "B.Cu")
		(hatch none 0.5)
		(connect_pads
			(clearance 0)
		)
		(min_thickness 0.25)
		(keepout
			(tracks not_allowed)
			(vias allowed)
			(pads allowed)
			(copperpour not_allowed)
			(footprints allowed)
		)
		(placement
			(enabled no)
			(sheetname "")
		)
		(fill
			(thermal_gap 0.5)
			(thermal_bridge_width 0.5)
			(island_removal_mode 0)
		)
		(polygon
			(pts
				(arc
					(start 272.49374 -221.784164)
					(mid 271.9832 -222.294704)
					(end 272.49374 -222.805244)
				)
				(arc
					(start 272.66011 -222.805244)
					(mid 272.630743 -222.672837)
					(end 272.579084 -222.547434)
				)
				(arc
					(start 272.579084 -222.547434)
					(mid 272.334412 -222.081026)
					(end 272.710656 -222.449644)
				)
				(arc
					(start 272.710656 -222.449644)
					(mid 272.784567 -222.621858)
					(end 272.823178 -222.805244)
				)
				(arc
					(start 272.977356 -222.805244)
					(mid 273.015837 -222.621993)
					(end 273.089624 -222.449898)
				)
				(arc
					(start 273.089624 -222.449898)
					(mid 273.465333 -222.080409)
					(end 273.221196 -222.547434)
				)
				(arc
					(start 273.221196 -222.547434)
					(mid 273.169653 -222.672842)
					(end 273.140424 -222.805244)
				)
				(arc
					(start 273.306286 -222.805244)
					(mid 273.81708 -222.294831)
					(end 273.30654 -221.784164)
				)
			)
		)
	)
	(zone
		(layer "B.Cu")
		(hatch none 0.5)
		(connect_pads
			(clearance 0)
		)
		(min_thickness 0.25)
		(keepout
			(tracks not_allowed)
			(vias allowed)
			(pads allowed)
			(copperpour not_allowed)
			(footprints allowed)
		)
		(placement
			(enabled no)
			(sheetname "")
		)
		(fill
			(thermal_gap 0.5)
			(thermal_bridge_width 0.5)
			(island_removal_mode 0)
		)
		(polygon
			(pts
				(arc
					(start 65.293494 -221.784164)
					(mid 64.782954 -222.294704)
					(end 65.293494 -222.805244)
				)
				(arc
					(start 65.459864 -222.805244)
					(mid 65.430497 -222.672837)
					(end 65.378838 -222.547434)
				)
				(arc
					(start 65.378838 -222.547434)
					(mid 65.134166 -222.081026)
					(end 65.51041 -222.449644)
				)
				(arc
					(start 65.51041 -222.449644)
					(mid 65.584321 -222.621858)
					(end 65.622932 -222.805244)
				)
				(arc
					(start 65.77711 -222.805244)
					(mid 65.815591 -222.621993)
					(end 65.889378 -222.449898)
				)
				(arc
					(start 65.889378 -222.449898)
					(mid 66.265087 -222.080409)
					(end 66.02095 -222.547434)
				)
				(arc
					(start 66.02095 -222.547434)
					(mid 65.969407 -222.672842)
					(end 65.940178 -222.805244)
				)
				(arc
					(start 66.10604 -222.805244)
					(mid 66.616834 -222.294831)
					(end 66.106294 -221.784164)
				)
			)
		)
	)
	(zone
		(layer "B.Cu")
		(hatch none 0.5)
		(connect_pads
			(clearance 0)
		)
		(min_thickness 0.25)
		(keepout
			(tracks allowed)
			(vias allowed)
			(pads allowed)
			(copperpour allowed)
			(footprints not_allowed)
		)
		(placement
			(enabled no)
			(sheetname "")
		)
		(fill
			(thermal_gap 0.5)
			(thermal_bridge_width 0.5)
			(island_removal_mode 0)
		)
		(polygon
			(pts
				(arc
					(start 349.600012 -203.499974)
					(mid 345.60002 -199.499982)
					(end 341.600028 -203.499974)
				)
				(arc
					(start 341.600028 -203.499974)
					(mid 345.60002 -207.499966)
					(end 349.600012 -203.499974)
				)
			)
		)
	)
	(zone
		(layer "B.Cu")
		(hatch none 0.5)
		(connect_pads
			(clearance 0)
		)
		(min_thickness 0.25)
		(keepout
			(tracks not_allowed)
			(vias allowed)
			(pads allowed)
			(copperpour not_allowed)
			(footprints allowed)
		)
		(placement
			(enabled no)
			(sheetname "")
		)
		(fill
			(thermal_gap 0.5)
			(thermal_bridge_width 0.5)
			(island_removal_mode 0)
		)
		(polygon
			(pts
				(arc
					(start 334.093566 -221.784164)
					(mid 333.583026 -222.294704)
					(end 334.093566 -222.805244)
				)
				(arc
					(start 334.259936 -222.805244)
					(mid 334.230569 -222.672837)
					(end 334.17891 -222.547434)
				)
				(arc
					(start 334.17891 -222.547434)
					(mid 333.934238 -222.081026)
					(end 334.310482 -222.449644)
				)
				(arc
					(start 334.310482 -222.449644)
					(mid 334.384393 -222.621858)
					(end 334.423004 -222.805244)
				)
				(arc
					(start 334.577182 -222.805244)
					(mid 334.615663 -222.621993)
					(end 334.68945 -222.449898)
				)
				(arc
					(start 334.68945 -222.449898)
					(mid 335.065159 -222.080409)
					(end 334.821022 -222.547434)
				)
				(arc
					(start 334.821022 -222.547434)
					(mid 334.769479 -222.672842)
					(end 334.74025 -222.805244)
				)
				(arc
					(start 334.906112 -222.805244)
					(mid 335.416906 -222.294831)
					(end 334.906366 -221.784164)
				)
			)
		)
	)
	(zone
		(net "GND")
		(layer "B.Cu")
		(hatch none 0.5)
		(connect_pads
			(clearance 0.5)
		)
		(min_thickness 0.25)
		(fill yes
			(thermal_gap 0.5)
			(thermal_bridge_width 0.5)
			(island_removal_mode 0)
		)
		(polygon
			(pts
				(xy 346.964 -53.086) (xy 346.456 -53.594) (xy 346.456 -61.468) (xy 347.345 -62.357) (xy 347.345 -63.5)
				(xy 347.599 -63.754) (xy 349.377 -63.754) (xy 350.012 -63.119) (xy 350.012 -53.467) (xy 349.631 -53.086)
			)
		)
	)
	(zone
		(net "GND")
		(layer "B.Cu")
		(hatch none 0.5)
		(connect_pads
			(clearance 0.5)
		)
		(min_thickness 0.25)
		(fill yes
			(thermal_gap 0.5)
			(thermal_bridge_width 0.5)
			(island_removal_mode 0)
		)
		(polygon
			(pts
				(xy 143.018002 -62.511432) (xy 142.637002 -62.892432) (xy 142.637002 -66.702432) (xy 142.891002 -66.956432)
				(xy 145.050002 -66.956432) (xy 145.304002 -66.702432) (xy 145.304002 -62.892432) (xy 144.923002 -62.511432)
			)
		)
	)
	(zone
		(net "GND")
		(layer "B.Cu")
		(hatch none 0.5)
		(connect_pads
			(clearance 0.5)
		)
		(min_thickness 0.25)
		(fill yes
			(thermal_gap 0.5)
			(thermal_bridge_width 0.5)
			(island_removal_mode 0)
		)
		(polygon
			(pts
				(xy 250.378976 -83.192874) (xy 242.41887 -91.15298) (xy 184.291986 -91.15298) (xy 176.594262 -83.455256)
				(xy 173.22673 -83.455256) (xy 171.4754 -85.206586) (xy 171.4754 -102.567232) (xy 174.188628 -105.28046)
				(xy 316.10554 -105.28046) (xy 319.6336 -101.7524) (xy 319.6336 -88.94064) (xy 317.559944 -86.866984)
				(xy 317.559944 -86.8426) (xy 313.910218 -83.192874)
			)
		)
	)
	(zone
		(layer "B.Cu")
		(hatch none 0.5)
		(connect_pads
			(clearance 0)
		)
		(min_thickness 0.25)
		(keepout
			(tracks allowed)
			(vias allowed)
			(pads allowed)
			(copperpour allowed)
			(footprints not_allowed)
		)
		(placement
			(enabled no)
			(sheetname "")
		)
		(fill
			(thermal_gap 0.5)
			(thermal_bridge_width 0.5)
			(island_removal_mode 0)
		)
		(polygon
			(pts
				(arc
					(start 341.600028 -203.499974)
					(mid 345.60002 -207.499966)
					(end 349.600012 -203.499974)
				)
				(arc
					(start 349.600012 -203.499974)
					(mid 345.60002 -199.499982)
					(end 341.600028 -203.499974)
				)
			)
		)
	)
	(zone
		(layer "B.Cu")
		(hatch none 0.5)
		(connect_pads
			(clearance 0)
		)
		(min_thickness 0.25)
		(keepout
			(tracks not_allowed)
			(vias allowed)
			(pads allowed)
			(copperpour not_allowed)
			(footprints allowed)
		)
		(placement
			(enabled no)
			(sheetname "")
		)
		(fill
			(thermal_gap 0.5)
			(thermal_bridge_width 0.5)
			(island_removal_mode 0)
		)
		(polygon
			(pts
				(arc
					(start 345.74988 -22.999954)
					(mid 349.750126 -27.0002)
					(end 353.750118 -22.999954)
				)
				(arc
					(start 353.750118 -22.999954)
					(mid 349.750126 -18.999962)
					(end 345.74988 -22.999954)
				)
			)
		)
	)
	(zone
		(layer "B.Cu")
		(hatch none 0.5)
		(connect_pads
			(clearance 0)
		)
		(min_thickness 0.25)
		(keepout
			(tracks not_allowed)
			(vias allowed)
			(pads allowed)
			(copperpour not_allowed)
			(footprints allowed)
		)
		(placement
			(enabled no)
			(sheetname "")
		)
		(fill
			(thermal_gap 0.5)
			(thermal_bridge_width 0.5)
			(island_removal_mode 0)
		)
		(polygon
			(pts
				(arc
					(start 204.893672 -221.784164)
					(mid 204.383132 -222.294704)
					(end 204.893672 -222.805244)
				)
				(arc
					(start 205.060042 -222.805244)
					(mid 205.030675 -222.672837)
					(end 204.979016 -222.547434)
				)
				(arc
					(start 204.979016 -222.547434)
					(mid 204.734344 -222.081026)
					(end 205.110588 -222.449644)
				)
				(arc
					(start 205.110588 -222.449644)
					(mid 205.184499 -222.621858)
					(end 205.22311 -222.805244)
				)
				(arc
					(start 205.377288 -222.805244)
					(mid 205.415769 -222.621993)
					(end 205.489556 -222.449898)
				)
				(arc
					(start 205.489556 -222.449898)
					(mid 205.865265 -222.080409)
					(end 205.621128 -222.547434)
				)
				(arc
					(start 205.621128 -222.547434)
					(mid 205.569585 -222.672842)
					(end 205.540356 -222.805244)
				)
				(arc
					(start 205.706218 -222.805244)
					(mid 206.217012 -222.294831)
					(end 205.706472 -221.784164)
				)
			)
		)
	)
	(zone
		(layer "B.Cu")
		(hatch none 0.5)
		(connect_pads
			(clearance 0)
		)
		(min_thickness 0.25)
		(keepout
			(tracks allowed)
			(vias allowed)
			(pads allowed)
			(copperpour allowed)
			(footprints not_allowed)
		)
		(placement
			(enabled no)
			(sheetname "")
		)
		(fill
			(thermal_gap 0.5)
			(thermal_bridge_width 0.5)
			(island_removal_mode 0)
		)
		(polygon
			(pts
				(arc
					(start 133.637528 -9.53008)
					(mid 136.13765 -12.030202)
					(end 138.637518 -9.53008)
				)
				(arc
					(start 138.637518 -9.53008)
					(mid 136.13765 -7.030212)
					(end 133.637528 -9.53008)
				)
			)
		)
	)
	(zone
		(layer "B.Cu")
		(hatch none 0.5)
		(connect_pads
			(clearance 0)
		)
		(min_thickness 0.25)
		(keepout
			(tracks not_allowed)
			(vias allowed)
			(pads allowed)
			(copperpour not_allowed)
			(footprints allowed)
		)
		(placement
			(enabled no)
			(sheetname "")
		)
		(fill
			(thermal_gap 0.5)
			(thermal_bridge_width 0.5)
			(island_removal_mode 0)
		)
		(polygon
			(pts
				(arc
					(start 202.946254 -49.27346)
					(mid 202.43546 -49.783873)
					(end 202.946 -50.29454)
				)
				(arc
					(start 203.7588 -50.29454)
					(mid 204.26934 -49.784)
					(end 203.7588 -49.27346)
				)
				(arc
					(start 203.59243 -49.27346)
					(mid 203.621797 -49.405867)
					(end 203.673456 -49.53127)
				)
				(arc
					(start 203.673456 -49.53127)
					(mid 203.918128 -49.997678)
					(end 203.541884 -49.62906)
				)
				(arc
					(start 203.541884 -49.62906)
					(mid 203.467973 -49.456846)
					(end 203.429362 -49.27346)
				)
				(arc
					(start 203.275438 -49.27346)
					(mid 203.236843 -49.456851)
					(end 203.162916 -49.62906)
				)
				(arc
					(start 203.162916 -49.62906)
					(mid 202.786651 -49.997707)
					(end 203.031344 -49.53127)
				)
				(arc
					(start 203.031344 -49.53127)
					(mid 203.083035 -49.405877)
					(end 203.11237 -49.27346)
				)
			)
		)
	)
	(zone
		(net "P12V_PCIE")
		(layer "B.Cu")
		(hatch none 0.5)
		(connect_pads
			(clearance 0.5)
		)
		(min_thickness 0.25)
		(fill yes
			(thermal_gap 0.5)
			(thermal_bridge_width 0.5)
			(island_removal_mode 0)
		)
		(polygon
			(pts
				(xy 25.9842 -207.772) (xy 25.654 -208.1022) (xy 25.654 -212.0646) (xy 27.559 -213.9696) (xy 27.559 -220.345)
				(arc
					(start 28.425648 -221.211648)
					(mid 28.892602 -221.507456)
					(end 29.18841 -221.97441)
				)
				(xy 29.337 -222.123) (xy 29.337 -223.901) (xy 29.4259 -223.9899) (xy 33.4391 -223.9899) (xy 33.528 -223.901)
				(xy 33.528 -223.774) (xy 33.274 -223.52) (xy 33.274 -209.677) (xy 31.369 -207.772)
			)
		)
	)
	(zone
		(layer "B.Cu")
		(hatch none 0.5)
		(connect_pads
			(clearance 0)
		)
		(min_thickness 0.25)
		(keepout
			(tracks allowed)
			(vias allowed)
			(pads allowed)
			(copperpour allowed)
			(footprints not_allowed)
		)
		(placement
			(enabled no)
			(sheetname "")
		)
		(fill
			(thermal_gap 0.5)
			(thermal_bridge_width 0.5)
			(island_removal_mode 0)
		)
		(polygon
			(pts
				(arc
					(start 13.999972 -203.499974)
					(mid 9.99998 -199.499982)
					(end 5.999988 -203.499974)
				)
				(arc
					(start 5.999988 -203.499974)
					(mid 9.99998 -207.499966)
					(end 13.999972 -203.499974)
				)
			)
		)
	)
	(zone
		(layer "B.Cu")
		(hatch none 0.5)
		(connect_pads
			(clearance 0)
		)
		(min_thickness 0.25)
		(keepout
			(tracks allowed)
			(vias allowed)
			(pads allowed)
			(copperpour allowed)
			(footprints not_allowed)
		)
		(placement
			(enabled no)
			(sheetname "")
		)
		(fill
			(thermal_gap 0.5)
			(thermal_bridge_width 0.5)
			(island_removal_mode 0)
		)
		(polygon
			(pts
				(arc
					(start 347.49994 -34.500058)
					(mid 345.60002 -32.600138)
					(end 343.7001 -34.500058)
				)
				(arc
					(start 343.7001 -34.500058)
					(mid 345.60002 -36.399978)
					(end 347.49994 -34.500058)
				)
			)
		)
	)
	(zone
		(layer "B.Cu")
		(hatch none 0.5)
		(connect_pads
			(clearance 0)
		)
		(min_thickness 0.25)
		(keepout
			(tracks not_allowed)
			(vias allowed)
			(pads allowed)
			(copperpour not_allowed)
			(footprints allowed)
		)
		(placement
			(enabled no)
			(sheetname "")
		)
		(fill
			(thermal_gap 0.5)
			(thermal_bridge_width 0.5)
			(island_removal_mode 0)
		)
		(polygon
			(pts
				(arc
					(start 198.493634 -221.784164)
					(mid 197.983094 -222.294704)
					(end 198.493634 -222.805244)
				)
				(arc
					(start 198.660004 -222.805244)
					(mid 198.630637 -222.672837)
					(end 198.578978 -222.547434)
				)
				(arc
					(start 198.578978 -222.547434)
					(mid 198.334306 -222.081026)
					(end 198.71055 -222.449644)
				)
				(arc
					(start 198.71055 -222.449644)
					(mid 198.784461 -222.621858)
					(end 198.823072 -222.805244)
				)
				(arc
					(start 198.97725 -222.805244)
					(mid 199.015731 -222.621993)
					(end 199.089518 -222.449898)
				)
				(arc
					(start 199.089518 -222.449898)
					(mid 199.465227 -222.080409)
					(end 199.22109 -222.547434)
				)
				(arc
					(start 199.22109 -222.547434)
					(mid 199.169547 -222.672842)
					(end 199.140318 -222.805244)
				)
				(arc
					(start 199.30618 -222.805244)
					(mid 199.816974 -222.294831)
					(end 199.306434 -221.784164)
				)
			)
		)
	)
	(zone
		(net "DUT_VDDO_REF")
		(layer "B.Cu")
		(hatch none 0.5)
		(connect_pads
			(clearance 0.5)
		)
		(min_thickness 0.25)
		(fill yes
			(thermal_gap 0.5)
			(thermal_bridge_width 0.5)
			(island_removal_mode 0)
		)
		(polygon
			(pts
				(xy 234.315 -9.652) (xy 233.934 -10.033) (xy 233.934 -12.954) (xy 234.188 -13.208) (xy 240.411 -13.208)
				(xy 240.665 -12.954) (xy 240.665 -10.033) (xy 240.284 -9.652)
			)
		)
		(polygon
			(pts
				(xy 240.1062 -11.5316) (xy 239.903 -11.5316) (xy 239.903 -11.7348) (xy 240.1062 -11.7348)
			)
		)
		(polygon
			(pts
				(xy 240.1062 -10.668) (xy 239.903 -10.668) (xy 239.903 -10.8712) (xy 240.1062 -10.8712)
			)
		)
	)
	(zone
		(layer "B.Cu")
		(hatch none 0.5)
		(connect_pads
			(clearance 0)
		)
		(min_thickness 0.25)
		(keepout
			(tracks not_allowed)
			(vias allowed)
			(pads allowed)
			(copperpour not_allowed)
			(footprints allowed)
		)
		(placement
			(enabled no)
			(sheetname "")
		)
		(fill
			(thermal_gap 0.5)
			(thermal_bridge_width 0.5)
			(island_removal_mode 0)
		)
		(polygon
			(pts
				(arc
					(start 334.749902 -14.200124)
					(mid 338.749894 -18.200116)
					(end 342.749886 -14.200124)
				)
				(arc
					(start 342.749886 -14.200124)
					(mid 338.749894 -10.200132)
					(end 334.749902 -14.200124)
				)
			)
		)
	)
	(zone
		(layer "B.Cu")
		(hatch none 0.5)
		(connect_pads
			(clearance 0)
		)
		(min_thickness 0.25)
		(keepout
			(tracks not_allowed)
			(vias allowed)
			(pads allowed)
			(copperpour not_allowed)
			(footprints allowed)
		)
		(placement
			(enabled no)
			(sheetname "")
		)
		(fill
			(thermal_gap 0.5)
			(thermal_bridge_width 0.5)
			(island_removal_mode 0)
		)
		(polygon
			(pts
				(arc
					(start 262.893556 -221.784164)
					(mid 262.383016 -222.294704)
					(end 262.893556 -222.805244)
				)
				(arc
					(start 263.059926 -222.805244)
					(mid 263.030559 -222.672837)
					(end 262.9789 -222.547434)
				)
				(arc
					(start 262.9789 -222.547434)
					(mid 262.734228 -222.081026)
					(end 263.110472 -222.449644)
				)
				(arc
					(start 263.110472 -222.449644)
					(mid 263.184383 -222.621858)
					(end 263.222994 -222.805244)
				)
				(arc
					(start 263.377172 -222.805244)
					(mid 263.415653 -222.621993)
					(end 263.48944 -222.449898)
				)
				(arc
					(start 263.48944 -222.449898)
					(mid 263.865149 -222.080409)
					(end 263.621012 -222.547434)
				)
				(arc
					(start 263.621012 -222.547434)
					(mid 263.569469 -222.672842)
					(end 263.54024 -222.805244)
				)
				(arc
					(start 263.706102 -222.805244)
					(mid 264.216896 -222.294831)
					(end 263.706356 -221.784164)
				)
			)
		)
	)
	(zone
		(net "GND")
		(layer "B.Cu")
		(hatch none 0.5)
		(connect_pads
			(clearance 0.5)
		)
		(min_thickness 0.25)
		(fill yes
			(thermal_gap 0.5)
			(thermal_bridge_width 0.5)
			(island_removal_mode 0)
		)
		(polygon
			(pts
				(xy 159.004 -88.519) (xy 158.877 -88.646) (xy 158.877 -92.512896) (xy 159.129222 -92.765118) (xy 160.319466 -92.765118)
				(xy 160.501584 -92.583) (xy 162.433 -92.583) (xy 162.687 -92.329) (xy 162.687 -88.9) (xy 162.306 -88.519)
			)
		)
		(polygon
			(pts
				(xy 162.1028 -91.8718) (xy 161.6202 -91.8718) (xy 161.6202 -92.075) (xy 162.1028 -92.075)
			)
		)
		(polygon
			(pts
				(xy 161.2138 -91.8718) (xy 161.0106 -91.8718) (xy 161.0106 -92.075) (xy 161.2138 -92.075)
			)
		)
		(polygon
			(pts
				(xy 162.2806 -91.5416) (xy 162.0774 -91.5416) (xy 162.0774 -91.7448) (xy 162.2806 -91.7448)
			)
		)
		(polygon
			(pts
				(xy 162.2806 -90.932) (xy 162.0774 -90.932) (xy 162.0774 -91.1352) (xy 162.2806 -91.1352)
			)
		)
		(polygon
			(pts
				(xy 162.2806 -90.5256) (xy 162.0774 -90.5256) (xy 162.0774 -90.7288) (xy 162.2806 -90.7288)
			)
		)
		(polygon
			(pts
				(xy 159.4866 -90.2716) (xy 159.2834 -90.2716) (xy 159.2834 -90.4748) (xy 159.4866 -90.4748)
			)
		)
		(polygon
			(pts
				(xy 162.2806 -89.916) (xy 162.0774 -89.916) (xy 162.0774 -90.1192) (xy 162.2806 -90.1192)
			)
		)
		(polygon
			(pts
				(xy 159.4866 -89.662) (xy 159.2834 -89.662) (xy 159.2834 -89.8652) (xy 159.4866 -89.8652)
			)
		)
		(polygon
			(pts
				(xy 162.1028 -89.0778) (xy 161.6202 -89.0778) (xy 161.6202 -89.281) (xy 162.1028 -89.281)
			)
		)
		(polygon
			(pts
				(xy 161.2138 -89.0778) (xy 161.0106 -89.0778) (xy 161.0106 -89.281) (xy 161.2138 -89.281)
			)
		)
		(polygon
			(pts
				(xy 160.5534 -89.0778) (xy 160.3502 -89.0778) (xy 160.3502 -89.281) (xy 160.5534 -89.281)
			)
		)
		(polygon
			(pts
				(xy 159.9438 -89.0778) (xy 159.4612 -89.0778) (xy 159.4612 -89.281) (xy 159.9438 -89.281)
			)
		)
	)
	(zone
		(layer "B.Cu")
		(hatch none 0.5)
		(connect_pads
			(clearance 0)
		)
		(min_thickness 0.25)
		(keepout
			(tracks not_allowed)
			(vias allowed)
			(pads allowed)
			(copperpour not_allowed)
			(footprints allowed)
		)
		(placement
			(enabled no)
			(sheetname "")
		)
		(fill
			(thermal_gap 0.5)
			(thermal_bridge_width 0.5)
			(island_removal_mode 0)
		)
		(polygon
			(pts
				(arc
					(start 168.093644 -221.784164)
					(mid 167.583104 -222.294704)
					(end 168.093644 -222.805244)
				)
				(arc
					(start 168.260014 -222.805244)
					(mid 168.230647 -222.672837)
					(end 168.178988 -222.547434)
				)
				(arc
					(start 168.178988 -222.547434)
					(mid 167.934316 -222.081026)
					(end 168.31056 -222.449644)
				)
				(arc
					(start 168.31056 -222.449644)
					(mid 168.384471 -222.621858)
					(end 168.423082 -222.805244)
				)
				(arc
					(start 168.57726 -222.805244)
					(mid 168.615741 -222.621993)
					(end 168.689528 -222.449898)
				)
				(arc
					(start 168.689528 -222.449898)
					(mid 169.065237 -222.080409)
					(end 168.8211 -222.547434)
				)
				(arc
					(start 168.8211 -222.547434)
					(mid 168.769557 -222.672842)
					(end 168.740328 -222.805244)
				)
				(arc
					(start 168.90619 -222.805244)
					(mid 169.416984 -222.294831)
					(end 168.906444 -221.784164)
				)
			)
		)
	)
	(zone
		(net "DUT_VDDO")
		(layer "B.Cu")
		(hatch none 0.5)
		(connect_pads
			(clearance 0.5)
		)
		(min_thickness 0.25)
		(fill yes
			(thermal_gap 0.5)
			(thermal_bridge_width 0.5)
			(island_removal_mode 0)
		)
		(polygon
			(pts
				(xy 241.751358 -9.537954) (xy 241.427 -9.862312) (xy 241.427 -12.7) (xy 240.3221 -13.8049) (xy 231.9909 -13.8049)
				(xy 231.1908 -14.605) (xy 222.753936 -14.605) (xy 222.446342 -14.912594) (xy 221.084648 -14.912594)
				(xy 220.769688 -14.597634) (xy 220.769688 -14.267688) (xy 219.733368 -13.231368) (xy 219.458286 -13.231368)
				(xy 218.741244 -12.514326) (xy 217.93835 -12.514326) (xy 217.799412 -12.375388) (xy 217.1954 -12.9794)
				(xy 195.4784 -12.9794) (xy 194.01409 -11.51509) (xy 187.66409 -11.51509) (xy 186.39282 -12.78636)
				(xy 186.39282 -14.4653) (xy 184.29859 -16.55953) (xy 181.81447 -16.55953) (xy 178.95316 -19.42084)
				(xy 178.95316 -26.19502) (xy 160.11398 -45.0342) (xy 131.191 -45.0342) (xy 127.6096 -48.6156) (xy 127.6096 -50.6984)
				(xy 125.1458 -53.1622) (xy 125.1458 -61.0108) (xy 127.6096 -63.4746) (xy 127.6096 -75.936856) (xy 130.119374 -78.44663)
				(xy 136.559544 -78.44663) (xy 136.935718 -78.070456) (xy 136.935718 -75.933554) (xy 133.65099 -72.648826)
				(xy 131.950714 -72.648826) (xy 131.602226 -72.300338) (xy 131.602226 -62.2554) (xy 136.55294 -57.30494)
				(xy 136.55294 -56.38546) (xy 138.3792 -54.5592) (xy 138.3792 -54.109874) (xy 138.814302 -53.674772)
				(xy 142.019528 -53.674772) (xy 145.433796 -50.260504) (xy 145.437352 -50.260504) (xy 146.696176 -49.00168)
				(xy 162.85972 -49.00168) (xy 182.03799 -29.82341) (xy 182.03799 -19.89963) (xy 183.37149 -18.56613)
				(xy 186.16422 -18.56613) (xy 189.94374 -14.78661) (xy 193.7766 -14.78661) (xy 195.09359 -16.1036)
				(xy 213.6394 -16.1036) (xy 213.759796 -15.983204) (xy 213.778846 -16.002) (xy 219.71 -16.002) (xy 220.6498 -16.9418)
				(xy 233.54792 -16.9418) (xy 234.36326 -17.75714) (xy 238.35106 -17.75714) (xy 240.2078 -15.9004)
				(xy 241.3762 -15.9004) (xy 243.513356 -13.763244) (xy 250.693682 -13.763244) (xy 251.079 -13.377926)
				(xy 251.079 -9.851136) (xy 250.790202 -9.562338) (xy 250.790202 -9.560306) (xy 250.76785 -9.537954)
			)
		)
		(polygon
			(pts
				(xy 242.3922 -11.5316) (xy 242.189 -11.5316) (xy 242.189 -11.7348) (xy 242.3922 -11.7348)
			)
		)
		(polygon
			(pts
				(xy 242.3922 -10.668) (xy 242.189 -10.668) (xy 242.189 -10.8712) (xy 242.3922 -10.8712)
			)
		)
	)
	(zone
		(layer "B.Cu")
		(hatch none 0.5)
		(connect_pads
			(clearance 0)
		)
		(min_thickness 0.25)
		(keepout
			(tracks allowed)
			(vias allowed)
			(pads allowed)
			(copperpour allowed)
			(footprints not_allowed)
		)
		(placement
			(enabled no)
			(sheetname "")
		)
		(fill
			(thermal_gap 0.5)
			(thermal_bridge_width 0.5)
			(island_removal_mode 0)
		)
		(polygon
			(pts
				(arc
					(start 324.6374 -9.53008)
					(mid 322.137532 -7.030212)
					(end 319.63741 -9.53008)
				)
				(arc
					(start 319.63741 -9.53008)
					(mid 322.137532 -12.030202)
					(end 324.6374 -9.53008)
				)
			)
		)
	)
	(zone
		(layer "B.Cu")
		(hatch none 0.5)
		(connect_pads
			(clearance 0)
		)
		(min_thickness 0.25)
		(keepout
			(tracks allowed)
			(vias allowed)
			(pads allowed)
			(copperpour allowed)
			(footprints not_allowed)
		)
		(placement
			(enabled no)
			(sheetname "")
		)
		(fill
			(thermal_gap 0.5)
			(thermal_bridge_width 0.5)
			(island_removal_mode 0)
		)
		(polygon
			(pts
				(arc
					(start 11.8999 -203.499974)
					(mid 9.99998 -201.600054)
					(end 8.10006 -203.499974)
				)
				(arc
					(start 8.10006 -203.499974)
					(mid 9.99998 -205.399894)
					(end 11.8999 -203.499974)
				)
			)
		)
	)
	(zone
		(layer "B.Cu")
		(hatch none 0.5)
		(connect_pads
			(clearance 0)
		)
		(min_thickness 0.25)
		(keepout
			(tracks not_allowed)
			(vias allowed)
			(pads allowed)
			(copperpour not_allowed)
			(footprints allowed)
		)
		(placement
			(enabled no)
			(sheetname "")
		)
		(fill
			(thermal_gap 0.5)
			(thermal_bridge_width 0.5)
			(island_removal_mode 0)
		)
		(polygon
			(pts
				(arc
					(start 282.09367 -221.784164)
					(mid 281.58313 -222.294704)
					(end 282.09367 -222.805244)
				)
				(arc
					(start 282.26004 -222.805244)
					(mid 282.230673 -222.672837)
					(end 282.179014 -222.547434)
				)
				(arc
					(start 282.179014 -222.547434)
					(mid 281.934342 -222.081026)
					(end 282.310586 -222.449644)
				)
				(arc
					(start 282.310586 -222.449644)
					(mid 282.384497 -222.621858)
					(end 282.423108 -222.805244)
				)
				(arc
					(start 282.577286 -222.805244)
					(mid 282.615767 -222.621993)
					(end 282.689554 -222.449898)
				)
				(arc
					(start 282.689554 -222.449898)
					(mid 283.065263 -222.080409)
					(end 282.821126 -222.547434)
				)
				(arc
					(start 282.821126 -222.547434)
					(mid 282.769583 -222.672842)
					(end 282.740354 -222.805244)
				)
				(arc
					(start 282.906216 -222.805244)
					(mid 283.41701 -222.294831)
					(end 282.90647 -221.784164)
				)
			)
		)
	)
	(zone
		(layer "B.Cu")
		(hatch none 0.5)
		(connect_pads
			(clearance 0)
		)
		(min_thickness 0.25)
		(keepout
			(tracks not_allowed)
			(vias allowed)
			(pads allowed)
			(copperpour not_allowed)
			(footprints allowed)
		)
		(placement
			(enabled no)
			(sheetname "")
		)
		(fill
			(thermal_gap 0.5)
			(thermal_bridge_width 0.5)
			(island_removal_mode 0)
		)
		(polygon
			(pts
				(arc
					(start 319.63741 -9.53008)
					(mid 322.137532 -12.030202)
					(end 324.6374 -9.53008)
				)
				(arc
					(start 324.6374 -9.53008)
					(mid 322.137532 -7.030212)
					(end 319.63741 -9.53008)
				)
			)
		)
	)
	(zone
		(layer "B.Cu")
		(hatch none 0.5)
		(connect_pads
			(clearance 0)
		)
		(min_thickness 0.25)
		(keepout
			(tracks not_allowed)
			(vias allowed)
			(pads allowed)
			(copperpour not_allowed)
			(footprints allowed)
		)
		(placement
			(enabled no)
			(sheetname "")
		)
		(fill
			(thermal_gap 0.5)
			(thermal_bridge_width 0.5)
			(island_removal_mode 0)
		)
		(polygon
			(pts
				(arc
					(start 280.75128 -18.612104)
					(mid 280.617952 -18.63775)
					(end 280.491438 -18.687034)
				)
				(arc
					(start 280.491438 -18.687034)
					(mid 280.022914 -18.927968)
					(end 280.394664 -18.5547)
				)
				(arc
					(start 280.394664 -18.5547)
					(mid 280.568772 -18.483364)
					(end 280.75382 -18.44929)
				)
				(arc
					(start 280.756106 -18.298922)
					(mid 280.570503 -18.258974)
					(end 280.397712 -18.180304)
				)
				(arc
					(start 280.397712 -18.180304)
					(mid 280.042326 -17.791249)
					(end 280.500074 -18.052288)
				)
				(arc
					(start 280.500074 -18.052288)
					(mid 280.625371 -18.106506)
					(end 280.758646 -18.136108)
				)
				(arc
					(start 280.761186 -17.965928)
					(mid 280.258647 -17.447516)
					(end 279.740106 -17.949926)
				)
				(arc
					(start 279.72766 -18.762726)
					(mid 280.230326 -19.28114)
					(end 280.74874 -18.778474)
				)
			)
		)
	)
	(zone
		(layer "B.Cu")
		(hatch none 0.5)
		(connect_pads
			(clearance 0)
		)
		(min_thickness 0.25)
		(keepout
			(tracks allowed)
			(vias allowed)
			(pads allowed)
			(copperpour allowed)
			(footprints not_allowed)
		)
		(placement
			(enabled no)
			(sheetname "")
		)
		(fill
			(thermal_gap 0.5)
			(thermal_bridge_width 0.5)
			(island_removal_mode 0)
		)
		(polygon
			(pts
				(arc
					(start 290.237418 -9.53008)
					(mid 289.137598 -8.43026)
					(end 288.037524 -9.53008)
				)
				(arc
					(start 288.037524 -9.53008)
					(mid 289.137598 -10.630154)
					(end 290.237418 -9.53008)
				)
			)
		)
	)
	(zone
		(layer "B.Cu")
		(hatch none 0.5)
		(connect_pads
			(clearance 0)
		)
		(min_thickness 0.25)
		(keepout
			(tracks allowed)
			(vias allowed)
			(pads allowed)
			(copperpour allowed)
			(footprints not_allowed)
		)
		(placement
			(enabled no)
			(sheetname "")
		)
		(fill
			(thermal_gap 0.5)
			(thermal_bridge_width 0.5)
			(island_removal_mode 0)
		)
		(polygon
			(pts
				(arc
					(start 0 -212.499956)
					(mid 0.292893 -213.207061)
					(end 0.999998 -213.499954)
				)
				(xy 3.999992 -213.499954) (xy 3.999992 -77.0001) (xy 0 -77.0001)
			)
		)
	)
	(zone
		(layer "B.Cu")
		(hatch none 0.5)
		(connect_pads
			(clearance 0)
		)
		(min_thickness 0.25)
		(keepout
			(tracks not_allowed)
			(vias allowed)
			(pads allowed)
			(copperpour not_allowed)
			(footprints allowed)
		)
		(placement
			(enabled no)
			(sheetname "")
		)
		(fill
			(thermal_gap 0.5)
			(thermal_bridge_width 0.5)
			(island_removal_mode 0)
		)
		(polygon
			(pts
				(arc
					(start 274.118578 -28.480004)
					(mid 272.081497 -28.481274)
					(end 274.118578 -28.482544)
				)
				(arc
					(start 273.823938 -28.482544)
					(mid 273.100038 -29.203908)
					(end 272.376138 -28.482544)
				)
				(arc
					(start 272.376138 -28.480004)
					(mid 273.100038 -27.756104)
					(end 273.823938 -28.480004)
				)
			)
		)
	)
	(zone
		(net "GND")
		(layer "B.Cu")
		(hatch none 0.5)
		(connect_pads
			(clearance 0.5)
		)
		(min_thickness 0.25)
		(fill yes
			(thermal_gap 0.5)
			(thermal_bridge_width 0.5)
			(island_removal_mode 0)
		)
		(polygon
			(pts
				(xy 309.4228 -48.768) (xy 306.5526 -51.6382) (xy 296.9768 -51.6382) (xy 295.783 -52.832) (xy 295.783 -55.118)
				(xy 296.0116 -55.3466) (xy 320.8274 -55.3466) (xy 321.31 -54.864) (xy 321.31 -49.403) (xy 320.675 -48.768)
			)
		)
	)
	(zone
		(net "DUT_VDD")
		(layer "B.Cu")
		(hatch none 0.5)
		(connect_pads
			(clearance 0.5)
		)
		(min_thickness 0.25)
		(fill yes
			(thermal_gap 0.5)
			(thermal_bridge_width 0.5)
			(island_removal_mode 0)
		)
		(polygon
			(pts
				(xy 241.3 -41.8719) (xy 240.4618 -42.7101) (xy 239.5474 -42.7101) (xy 235.24845 -47.00905) (xy 235.24845 -48.01235)
				(xy 232.8291 -50.4317) (xy 232.8291 -50.5587) (xy 233.0196 -50.7492) (xy 233.2228 -50.7492) (xy 237.0074 -46.9646)
				(xy 237.0074 -46.863) (xy 236.7788 -46.6344) (xy 236.7788 -46.2661) (xy 238.887 -44.1579) (xy 238.9886 -44.1579)
				(xy 239.0648 -44.0817) (xy 239.0648 -43.9039) (xy 239.4077 -43.561) (xy 240.3094 -43.561) (xy 241.5921 -42.2783)
				(xy 241.5921 -42.0116) (xy 241.4524 -41.8719)
			)
		)
		(polygon
			(pts
				(xy 235.6866 -47.108872) (xy 235.4834 -47.108872) (xy 235.4834 -47.312072) (xy 235.6866 -47.312072)
			)
		)
	)
	(zone
		(layer "B.Cu")
		(hatch none 0.5)
		(connect_pads
			(clearance 0)
		)
		(min_thickness 0.25)
		(keepout
			(tracks not_allowed)
			(vias allowed)
			(pads allowed)
			(copperpour not_allowed)
			(footprints allowed)
		)
		(placement
			(enabled no)
			(sheetname "")
		)
		(fill
			(thermal_gap 0.5)
			(thermal_bridge_width 0.5)
			(island_removal_mode 0)
		)
		(polygon
			(pts
				(arc
					(start 278.893778 -221.784164)
					(mid 278.383238 -222.294704)
					(end 278.893778 -222.805244)
				)
				(arc
					(start 279.060148 -222.805244)
					(mid 279.030781 -222.672837)
					(end 278.979122 -222.547434)
				)
				(arc
					(start 278.979122 -222.547434)
					(mid 278.73445 -222.081026)
					(end 279.110694 -222.449644)
				)
				(arc
					(start 279.110694 -222.449644)
					(mid 279.184605 -222.621858)
					(end 279.223216 -222.805244)
				)
				(arc
					(start 279.377394 -222.805244)
					(mid 279.415875 -222.621993)
					(end 279.489662 -222.449898)
				)
				(arc
					(start 279.489662 -222.449898)
					(mid 279.865371 -222.080409)
					(end 279.621234 -222.547434)
				)
				(arc
					(start 279.621234 -222.547434)
					(mid 279.569691 -222.672842)
					(end 279.540462 -222.805244)
				)
				(arc
					(start 279.706324 -222.805244)
					(mid 280.217118 -222.294831)
					(end 279.706578 -221.784164)
				)
			)
		)
	)
	(zone
		(layer "B.Cu")
		(hatch none 0.5)
		(connect_pads
			(clearance 0)
		)
		(min_thickness 0.25)
		(keepout
			(tracks not_allowed)
			(vias allowed)
			(pads allowed)
			(copperpour not_allowed)
			(footprints allowed)
		)
		(placement
			(enabled no)
			(sheetname "")
		)
		(fill
			(thermal_gap 0.5)
			(thermal_bridge_width 0.5)
			(island_removal_mode 0)
		)
		(polygon
			(pts
				(arc
					(start 78.16977 -219.371164)
					(mid 77.65923 -219.881704)
					(end 78.16977 -220.392244)
				)
				(xy 78.266544 -220.392244)
				(arc
					(start 78.266544 -220.310964)
					(mid 78.259314 -220.224048)
					(end 78.237842 -220.139514)
				)
				(arc
					(start 78.237842 -220.139514)
					(mid 78.024971 -219.6578)
					(end 78.377034 -220.049598)
				)
				(arc
					(start 78.377034 -220.049598)
					(mid 78.412073 -220.16085)
					(end 78.427834 -220.27642)
				)
				(xy 78.428596 -220.277436) (xy 78.428596 -220.392244) (xy 78.571598 -220.392244) (xy 78.571598 -220.387672)
				(arc
					(start 78.572614 -220.386656)
					(mid 78.616257 -220.19662)
					(end 78.71968 -220.03131)
				)
				(xy 78.71968 -220.029786)
				(arc
					(start 78.745588 -220.003878)
					(mid 79.171753 -219.693673)
					(end 78.860142 -220.118686)
				)
				(arc
					(start 78.85811 -220.120718)
					(mid 78.771766 -220.24529)
					(end 78.734666 -220.392244)
				)
				(arc
					(start 78.982316 -220.392244)
					(mid 79.49311 -219.881831)
					(end 78.98257 -219.371164)
				)
			)
		)
	)
	(zone
		(layer "B.Cu")
		(hatch none 0.5)
		(connect_pads
			(clearance 0)
		)
		(min_thickness 0.25)
		(keepout
			(tracks allowed)
			(vias allowed)
			(pads allowed)
			(copperpour allowed)
			(footprints not_allowed)
		)
		(placement
			(enabled no)
			(sheetname "")
		)
		(fill
			(thermal_gap 0.5)
			(thermal_bridge_width 0.5)
			(island_removal_mode 0)
		)
		(polygon
			(pts
				(arc
					(start 70.449948 -14.200124)
					(mid 74.44994 -18.200116)
					(end 78.449932 -14.200124)
				)
				(arc
					(start 78.449932 -14.200124)
					(mid 74.44994 -10.200132)
					(end 70.449948 -14.200124)
				)
			)
		)
	)
	(zone
		(layer "B.Cu")
		(hatch none 0.5)
		(connect_pads
			(clearance 0)
		)
		(min_thickness 0.25)
		(keepout
			(tracks not_allowed)
			(vias allowed)
			(pads allowed)
			(copperpour not_allowed)
			(footprints allowed)
		)
		(placement
			(enabled no)
			(sheetname "")
		)
		(fill
			(thermal_gap 0.5)
			(thermal_bridge_width 0.5)
			(island_removal_mode 0)
		)
		(polygon
			(pts
				(arc
					(start 71.7042 -219.50426)
					(mid 71.19366 -220.0148)
					(end 71.7042 -220.52534)
				)
				(arc
					(start 71.862442 -220.52534)
					(mid 71.836689 -220.393327)
					(end 71.787766 -220.268038)
				)
				(arc
					(start 71.787766 -220.268038)
					(mid 71.547203 -219.798974)
					(end 71.920354 -220.171264)
				)
				(arc
					(start 71.920354 -220.171264)
					(mid 71.990939 -220.342932)
					(end 72.025256 -220.52534)
				)
				(arc
					(start 72.179942 -220.52534)
					(mid 72.22229 -220.34128)
					(end 72.299068 -220.168724)
				)
				(arc
					(start 72.299068 -220.168724)
					(mid 72.677143 -219.801396)
					(end 72.430132 -220.267022)
				)
				(arc
					(start 72.430132 -220.267022)
					(mid 72.376029 -220.392562)
					(end 72.343518 -220.52534)
				)
				(arc
					(start 72.516746 -220.52534)
					(mid 73.02754 -220.014927)
					(end 72.517 -219.50426)
				)
			)
		)
	)
	(zone
		(layer "B.Cu")
		(hatch none 0.5)
		(connect_pads
			(clearance 0)
		)
		(min_thickness 0.25)
		(keepout
			(tracks allowed)
			(vias allowed)
			(pads allowed)
			(copperpour allowed)
			(footprints not_allowed)
		)
		(placement
			(enabled no)
			(sheetname "")
		)
		(fill
			(thermal_gap 0.5)
			(thermal_bridge_width 0.5)
			(island_removal_mode 0)
		)
		(polygon
			(pts
				(arc
					(start 308.637432 -9.53008)
					(mid 311.137554 -12.030202)
					(end 313.637422 -9.53008)
				)
				(arc
					(start 313.637422 -9.53008)
					(mid 311.137554 -7.030212)
					(end 308.637432 -9.53008)
				)
			)
		)
	)
	(zone
		(net "GND")
		(layer "B.Cu")
		(hatch none 0.5)
		(connect_pads
			(clearance 0.5)
		)
		(min_thickness 0.25)
		(fill yes
			(thermal_gap 0.5)
			(thermal_bridge_width 0.5)
			(island_removal_mode 0)
		)
		(polygon
			(pts
				(xy 295.91 -68.961) (xy 295.529 -69.342) (xy 295.529 -75.311) (xy 295.783 -75.565) (xy 320.802 -75.565)
				(xy 321.31 -75.057) (xy 321.31 -69.469) (xy 320.802 -68.961)
			)
		)
	)
	(zone
		(layer "B.Cu")
		(hatch none 0.5)
		(connect_pads
			(clearance 0)
		)
		(min_thickness 0.25)
		(keepout
			(tracks not_allowed)
			(vias allowed)
			(pads allowed)
			(copperpour not_allowed)
			(footprints allowed)
		)
		(placement
			(enabled no)
			(sheetname "")
		)
		(fill
			(thermal_gap 0.5)
			(thermal_bridge_width 0.5)
			(island_removal_mode 0)
		)
		(polygon
			(pts
				(arc
					(start 286.637476 -9.53008)
					(mid 289.137598 -12.030202)
					(end 291.637466 -9.53008)
				)
				(arc
					(start 291.637466 -9.53008)
					(mid 289.137598 -7.030212)
					(end 286.637476 -9.53008)
				)
			)
		)
	)
	(zone
		(layer "B.Cu")
		(hatch none 0.5)
		(connect_pads
			(clearance 0)
		)
		(min_thickness 0.25)
		(keepout
			(tracks allowed)
			(vias allowed)
			(pads allowed)
			(copperpour allowed)
			(footprints not_allowed)
		)
		(placement
			(enabled no)
			(sheetname "")
		)
		(fill
			(thermal_gap 0.5)
			(thermal_bridge_width 0.5)
			(island_removal_mode 0)
		)
		(polygon
			(pts
				(arc
					(start 347.49994 -203.499974)
					(mid 345.60002 -201.600054)
					(end 343.7001 -203.499974)
				)
				(arc
					(start 343.7001 -203.499974)
					(mid 345.60002 -205.399894)
					(end 347.49994 -203.499974)
				)
			)
		)
	)
	(zone
		(layer "B.Cu")
		(hatch none 0.5)
		(connect_pads
			(clearance 0)
		)
		(min_thickness 0.25)
		(keepout
			(tracks not_allowed)
			(vias allowed)
			(pads allowed)
			(copperpour not_allowed)
			(footprints allowed)
		)
		(placement
			(enabled no)
			(sheetname "")
		)
		(fill
			(thermal_gap 0.5)
			(thermal_bridge_width 0.5)
			(island_removal_mode 0)
		)
		(polygon
			(pts
				(arc
					(start 318.093598 -221.784164)
					(mid 317.583058 -222.294704)
					(end 318.093598 -222.805244)
				)
				(arc
					(start 318.259968 -222.805244)
					(mid 318.230601 -222.672837)
					(end 318.178942 -222.547434)
				)
				(arc
					(start 318.178942 -222.547434)
					(mid 317.93427 -222.081026)
					(end 318.310514 -222.449644)
				)
				(arc
					(start 318.310514 -222.449644)
					(mid 318.384425 -222.621858)
					(end 318.423036 -222.805244)
				)
				(arc
					(start 318.577214 -222.805244)
					(mid 318.615695 -222.621993)
					(end 318.689482 -222.449898)
				)
				(arc
					(start 318.689482 -222.449898)
					(mid 319.065191 -222.080409)
					(end 318.821054 -222.547434)
				)
				(arc
					(start 318.821054 -222.547434)
					(mid 318.769511 -222.672842)
					(end 318.740282 -222.805244)
				)
				(arc
					(start 318.906144 -222.805244)
					(mid 319.416938 -222.294831)
					(end 318.906398 -221.784164)
				)
			)
		)
	)
	(zone
		(net "GND")
		(layer "B.Cu")
		(hatch none 0.5)
		(connect_pads
			(clearance 0.5)
		)
		(min_thickness 0.25)
		(fill yes
			(thermal_gap 0.5)
			(thermal_bridge_width 0.5)
			(island_removal_mode 0)
		)
		(polygon
			(pts
				(arc
					(start 115.599972 -211.467954)
					(mid 113.243912 -212.443866)
					(end 112.268 -214.799926)
				)
				(xy 112.268 -219.907612) (xy 113.536984 -219.907612)
				(arc
					(start 113.536984 -214.799926)
					(mid 114.141219 -213.341173)
					(end 115.599972 -212.736938)
				)
				(arc
					(start 131.400042 -212.736938)
					(mid 132.858795 -213.341173)
					(end 133.46303 -214.799926)
				)
				(xy 133.46303 -219.8116) (xy 134.732014 -219.8116)
				(arc
					(start 134.732014 -214.799926)
					(mid 133.756102 -212.443866)
					(end 131.400042 -211.467954)
				)
			)
		)
	)
	(zone
		(layer "B.Cu")
		(hatch none 0.5)
		(connect_pads
			(clearance 0)
		)
		(min_thickness 0.25)
		(keepout
			(tracks allowed)
			(vias allowed)
			(pads allowed)
			(copperpour allowed)
			(footprints not_allowed)
		)
		(placement
			(enabled no)
			(sheetname "")
		)
		(fill
			(thermal_gap 0.5)
			(thermal_bridge_width 0.5)
			(island_removal_mode 0)
		)
		(polygon
			(pts
				(arc
					(start 144.637506 -9.53008)
					(mid 147.137628 -12.030202)
					(end 149.637496 -9.53008)
				)
				(arc
					(start 149.637496 -9.53008)
					(mid 147.137628 -7.030212)
					(end 144.637506 -9.53008)
				)
			)
		)
	)
	(zone
		(layer "B.Cu")
		(hatch none 0.5)
		(connect_pads
			(clearance 0)
		)
		(min_thickness 0.25)
		(keepout
			(tracks not_allowed)
			(vias allowed)
			(pads allowed)
			(copperpour not_allowed)
			(footprints allowed)
		)
		(placement
			(enabled no)
			(sheetname "")
		)
		(fill
			(thermal_gap 0.5)
			(thermal_bridge_width 0.5)
			(island_removal_mode 0)
		)
		(polygon
			(pts
				(arc
					(start 138.637518 -9.53008)
					(mid 136.13765 -7.030212)
					(end 133.637528 -9.53008)
				)
				(arc
					(start 133.637528 -9.53008)
					(mid 136.13765 -12.030202)
					(end 138.637518 -9.53008)
				)
			)
		)
	)
	(zone
		(net "DUT_VDD")
		(layer "B.Cu")
		(hatch none 0.5)
		(connect_pads
			(clearance 0.5)
		)
		(min_thickness 0.25)
		(fill yes
			(thermal_gap 0.5)
			(thermal_bridge_width 0.5)
			(island_removal_mode 0)
		)
		(polygon
			(pts
				(xy 247.9802 -48.2854) (xy 241.8588 -54.4068) (xy 241.8588 -54.5338) (xy 242.0493 -54.7243) (xy 242.2525 -54.7243)
				(xy 248.3104 -48.6664) (xy 248.3104 -48.4124) (xy 248.1834 -48.2854)
			)
		)
	)
	(zone
		(net "GND")
		(layer "B.Cu")
		(hatch none 0.5)
		(connect_pads
			(clearance 0.5)
		)
		(min_thickness 0.25)
		(fill yes
			(thermal_gap 0.5)
			(thermal_bridge_width 0.5)
			(island_removal_mode 0)
		)
		(polygon
			(pts
				(xy 20.10918 -73.154794) (xy 20.010374 -73.2536) (xy 20.010374 -73.627742) (xy 19.805904 -73.832212)
				(xy 16.380206 -73.832212) (xy 16.2814 -73.931018) (xy 16.2814 -74.633836) (xy 16.32458 -74.677016)
				(xy 16.32458 -75.40879) (xy 16.107918 -75.625452) (xy 14.439392 -75.625452) (xy 14.272768 -75.458828)
				(xy 14.272768 -74.669904) (xy 14.205966 -74.603102) (xy 13.716762 -74.603102) (xy 13.666216 -74.653648)
				(xy 13.666216 -77.704696) (xy 13.6144 -77.756512) (xy 13.6144 -78.232) (xy 13.6906 -78.3082) (xy 14.189964 -78.3082)
				(xy 15.104364 -77.3938) (xy 16.002 -77.3938) (xy 16.256 -77.6478) (xy 16.256 -78.3082) (xy 15.8623 -78.7019)
				(xy 15.8623 -80.7466) (xy 16.9926 -80.7466) (xy 17.9832 -79.756) (xy 18.7198 -79.756) (xy 19.2786 -79.1972)
				(xy 19.2786 -77.9907) (xy 20.30984 -76.95946) (xy 20.30984 -74.98334) (xy 20.451572 -74.841608)
				(xy 20.713192 -74.841608) (xy 20.7264 -74.8284) (xy 21.3614 -74.8284) (xy 21.485352 -74.704448)
				(xy 21.485352 -73.186798) (xy 21.453348 -73.154794)
			)
		)
		(polygon
			(pts
				(xy 14.3256 -77.597) (xy 14.1224 -77.597) (xy 14.1224 -77.8002) (xy 14.3256 -77.8002)
			)
		)
		(polygon
			(pts
				(xy 14.36878 -76.864464) (xy 14.16558 -76.864464) (xy 14.16558 -77.067664) (xy 14.36878 -77.067664)
			)
		)
		(polygon
			(pts
				(xy 14.370558 -75.989434) (xy 14.167358 -75.989434) (xy 14.167358 -76.192634) (xy 14.16558 -76.254864)
				(xy 14.16558 -76.458064) (xy 14.36878 -76.458064) (xy 14.36878 -76.254864) (xy 14.370558 -76.192634)
			)
		)
		(polygon
			(pts
				(xy 17.013428 -75.185778) (xy 16.810228 -75.185778) (xy 16.810228 -75.388978) (xy 17.013428 -75.388978)
			)
		)
		(polygon
			(pts
				(xy 17.013428 -74.576178) (xy 16.810228 -74.576178) (xy 16.810228 -74.779378) (xy 17.013428 -74.779378)
			)
		)
	)
	(zone
		(layer "B.Cu")
		(hatch none 0.5)
		(connect_pads
			(clearance 0)
		)
		(min_thickness 0.25)
		(keepout
			(tracks not_allowed)
			(vias allowed)
			(pads allowed)
			(copperpour not_allowed)
			(footprints allowed)
		)
		(placement
			(enabled no)
			(sheetname "")
		)
		(fill
			(thermal_gap 0.5)
			(thermal_bridge_width 0.5)
			(island_removal_mode 0)
		)
		(polygon
			(pts
				(arc
					(start 59.693302 -221.784164)
					(mid 59.182762 -222.294704)
					(end 59.693302 -222.805244)
				)
				(arc
					(start 59.859672 -222.805244)
					(mid 59.830305 -222.672837)
					(end 59.778646 -222.547434)
				)
				(arc
					(start 59.778646 -222.547434)
					(mid 59.533974 -222.081026)
					(end 59.910218 -222.449644)
				)
				(arc
					(start 59.910218 -222.449644)
					(mid 59.984129 -222.621858)
					(end 60.02274 -222.805244)
				)
				(arc
					(start 60.176918 -222.805244)
					(mid 60.215399 -222.621993)
					(end 60.289186 -222.449898)
				)
				(arc
					(start 60.289186 -222.449898)
					(mid 60.664895 -222.080409)
					(end 60.420758 -222.547434)
				)
				(arc
					(start 60.420758 -222.547434)
					(mid 60.369215 -222.672842)
					(end 60.339986 -222.805244)
				)
				(arc
					(start 60.505848 -222.805244)
					(mid 61.016642 -222.294831)
					(end 60.506102 -221.784164)
				)
			)
		)
	)
	(zone
		(layer "B.Cu")
		(hatch none 0.5)
		(connect_pads
			(clearance 0)
		)
		(min_thickness 0.25)
		(keepout
			(tracks not_allowed)
			(vias allowed)
			(pads allowed)
			(copperpour not_allowed)
			(footprints allowed)
		)
		(placement
			(enabled no)
			(sheetname "")
		)
		(fill
			(thermal_gap 0.5)
			(thermal_bridge_width 0.5)
			(island_removal_mode 0)
		)
		(polygon
			(pts
				(arc
					(start 137.23747 -9.53008)
					(mid 136.13765 -8.43026)
					(end 135.037576 -9.53008)
				)
				(arc
					(start 135.037576 -9.53008)
					(mid 136.13765 -10.630154)
					(end 137.23747 -9.53008)
				)
			)
		)
	)
	(zone
		(layer "B.Cu")
		(hatch none 0.5)
		(connect_pads
			(clearance 0)
		)
		(min_thickness 0.25)
		(keepout
			(tracks not_allowed)
			(vias allowed)
			(pads allowed)
			(copperpour not_allowed)
			(footprints allowed)
		)
		(placement
			(enabled no)
			(sheetname "")
		)
		(fill
			(thermal_gap 0.5)
			(thermal_bridge_width 0.5)
			(island_removal_mode 0)
		)
		(polygon
			(pts
				(arc
					(start 171.637452 -9.53008)
					(mid 169.137584 -7.030212)
					(end 166.637462 -9.53008)
				)
				(arc
					(start 166.637462 -9.53008)
					(mid 169.137584 -12.030202)
					(end 171.637452 -9.53008)
				)
			)
		)
	)
	(zone
		(net "GND")
		(layer "B.Cu")
		(hatch none 0.5)
		(connect_pads
			(clearance 0.5)
		)
		(min_thickness 0.25)
		(fill yes
			(thermal_gap 0.5)
			(thermal_bridge_width 0.5)
			(island_removal_mode 0)
		)
		(polygon
			(pts
				(xy 152.4 -58.447432) (xy 152.376632 -58.4708) (xy 151.7142 -58.4708) (xy 151.4094 -58.7756) (xy 151.4094 -63.661798)
				(xy 151.781002 -64.0334) (xy 151.781002 -75.694032) (xy 152.390602 -76.303632) (xy 154.371802 -76.303632)
				(xy 155.718002 -74.957432) (xy 155.718002 -58.828432) (xy 155.337002 -58.447432)
			)
		)
		(polygon
			(pts
				(xy 155.311602 -64.492632) (xy 155.108402 -64.492632) (xy 155.108402 -64.695832) (xy 155.311602 -64.695832)
			)
		)
		(polygon
			(pts
				(xy 155.311602 -63.883032) (xy 155.108402 -63.883032) (xy 155.108402 -64.086232) (xy 155.311602 -64.086232)
			)
		)
	)
	(zone
		(net "P3V3_STBY")
		(layer "B.Cu")
		(hatch none 0.5)
		(connect_pads
			(clearance 0.5)
		)
		(min_thickness 0.25)
		(fill yes
			(thermal_gap 0.5)
			(thermal_bridge_width 0.5)
			(island_removal_mode 0)
		)
		(polygon
			(pts
				(xy 323.948552 -37.162994) (xy 320.55181 -37.162994) (xy 320.442844 -37.27196) (xy 320.442844 -38.53688)
				(xy 320.651124 -38.74516) (xy 324.81012 -38.74516) (xy 325.28129 -38.27399) (xy 325.28129 -37.555932)
				(xy 324.888352 -37.162994)
			)
		)
		(polygon
			(pts
				(xy 322.944236 -38.033198) (xy 322.741036 -38.033198) (xy 322.741036 -38.236398) (xy 322.944236 -38.236398)
			)
		)
		(polygon
			(pts
				(xy 322.334636 -38.033198) (xy 321.876928 -38.033198) (xy 321.876928 -38.236398) (xy 322.334636 -38.236398)
			)
		)
		(polygon
			(pts
				(xy 321.470528 -38.033198) (xy 321.267328 -38.033198) (xy 321.267328 -38.236398) (xy 321.470528 -38.236398)
			)
		)
		(polygon
			(pts
				(xy 322.944236 -37.651436) (xy 322.741036 -37.651436) (xy 322.741036 -37.854636) (xy 322.944236 -37.854636)
			)
		)
		(polygon
			(pts
				(xy 322.334636 -37.651436) (xy 321.876928 -37.651436) (xy 321.876928 -37.854636) (xy 322.334636 -37.854636)
			)
		)
		(polygon
			(pts
				(xy 321.470528 -37.651436) (xy 321.267328 -37.651436) (xy 321.267328 -37.854636) (xy 321.470528 -37.854636)
			)
		)
	)
	(zone
		(layer "B.Cu")
		(hatch none 0.5)
		(connect_pads
			(clearance 0)
		)
		(min_thickness 0.25)
		(keepout
			(tracks not_allowed)
			(vias allowed)
			(pads allowed)
			(copperpour not_allowed)
			(footprints allowed)
		)
		(placement
			(enabled no)
			(sheetname "")
		)
		(fill
			(thermal_gap 0.5)
			(thermal_bridge_width 0.5)
			(island_removal_mode 0)
		)
		(polygon
			(pts
				(arc
					(start 300.493684 -221.784164)
					(mid 299.983144 -222.294704)
					(end 300.493684 -222.805244)
				)
				(arc
					(start 300.660054 -222.805244)
					(mid 300.630687 -222.672837)
					(end 300.579028 -222.547434)
				)
				(arc
					(start 300.579028 -222.547434)
					(mid 300.334356 -222.081026)
					(end 300.7106 -222.449644)
				)
				(arc
					(start 300.7106 -222.449644)
					(mid 300.784511 -222.621858)
					(end 300.823122 -222.805244)
				)
				(arc
					(start 300.9773 -222.805244)
					(mid 301.015781 -222.621993)
					(end 301.089568 -222.449898)
				)
				(arc
					(start 301.089568 -222.449898)
					(mid 301.465277 -222.080409)
					(end 301.22114 -222.547434)
				)
				(arc
					(start 301.22114 -222.547434)
					(mid 301.169597 -222.672842)
					(end 301.140368 -222.805244)
				)
				(arc
					(start 301.30623 -222.805244)
					(mid 301.817024 -222.294831)
					(end 301.306484 -221.784164)
				)
			)
		)
	)
	(zone
		(layer "B.Cu")
		(hatch none 0.5)
		(connect_pads
			(clearance 0)
		)
		(min_thickness 0.25)
		(keepout
			(tracks allowed)
			(vias allowed)
			(pads allowed)
			(copperpour allowed)
			(footprints not_allowed)
		)
		(placement
			(enabled no)
			(sheetname "")
		)
		(fill
			(thermal_gap 0.5)
			(thermal_bridge_width 0.5)
			(island_removal_mode 0)
		)
		(polygon
			(pts
				(arc
					(start 171.637452 -9.53008)
					(mid 169.137584 -7.030212)
					(end 166.637462 -9.53008)
				)
				(arc
					(start 166.637462 -9.53008)
					(mid 169.137584 -12.030202)
					(end 171.637452 -9.53008)
				)
			)
		)
	)
	(zone
		(layer "B.Cu")
		(hatch none 0.5)
		(connect_pads
			(clearance 0)
		)
		(min_thickness 0.25)
		(keepout
			(tracks allowed)
			(vias allowed)
			(pads allowed)
			(copperpour allowed)
			(footprints not_allowed)
		)
		(placement
			(enabled no)
			(sheetname "")
		)
		(fill
			(thermal_gap 0.5)
			(thermal_bridge_width 0.5)
			(island_removal_mode 0)
		)
		(polygon
			(pts
				(arc
					(start 15.912084 -60.300108)
					(mid 13.812266 -58.20029)
					(end 11.712194 -60.300108)
				)
				(arc
					(start 11.712194 -60.300108)
					(mid 13.812266 -62.40018)
					(end 15.912084 -60.300108)
				)
			)
		)
	)
	(zone
		(layer "B.Cu")
		(hatch none 0.5)
		(connect_pads
			(clearance 0)
		)
		(min_thickness 0.25)
		(keepout
			(tracks not_allowed)
			(vias allowed)
			(pads allowed)
			(copperpour not_allowed)
			(footprints allowed)
		)
		(placement
			(enabled no)
			(sheetname "")
		)
		(fill
			(thermal_gap 0.5)
			(thermal_bridge_width 0.5)
			(island_removal_mode 0)
		)
		(polygon
			(pts
				(arc
					(start 53.293518 -221.784164)
					(mid 52.782978 -222.294704)
					(end 53.293518 -222.805244)
				)
				(arc
					(start 53.459888 -222.805244)
					(mid 53.430521 -222.672837)
					(end 53.378862 -222.547434)
				)
				(arc
					(start 53.378862 -222.547434)
					(mid 53.13419 -222.081026)
					(end 53.510434 -222.449644)
				)
				(arc
					(start 53.510434 -222.449644)
					(mid 53.584345 -222.621858)
					(end 53.622956 -222.805244)
				)
				(arc
					(start 53.777134 -222.805244)
					(mid 53.815615 -222.621993)
					(end 53.889402 -222.449898)
				)
				(arc
					(start 53.889402 -222.449898)
					(mid 54.265111 -222.080409)
					(end 54.020974 -222.547434)
				)
				(arc
					(start 54.020974 -222.547434)
					(mid 53.969431 -222.672842)
					(end 53.940202 -222.805244)
				)
				(arc
					(start 54.106064 -222.805244)
					(mid 54.616858 -222.294831)
					(end 54.106318 -221.784164)
				)
			)
		)
	)
	(zone
		(layer "B.Cu")
		(hatch none 0.5)
		(connect_pads
			(clearance 0)
		)
		(min_thickness 0.25)
		(keepout
			(tracks not_allowed)
			(vias allowed)
			(pads allowed)
			(copperpour not_allowed)
			(footprints allowed)
		)
		(placement
			(enabled no)
			(sheetname "")
		)
		(fill
			(thermal_gap 0.5)
			(thermal_bridge_width 0.5)
			(island_removal_mode 0)
		)
		(polygon
			(pts
				(arc
					(start 133.63702 -12.819888)
					(mid 134.064033 -12.193866)
					(end 133.779768 -12.896342)
				)
				(xy 133.701028 -13.043408)
				(arc
					(start 133.69671 -13.044678)
					(mid 133.587832 -13.119142)
					(end 133.455918 -13.117068)
				)
				(xy 133.451346 -13.118592) (xy 133.439916 -13.112242) (xy 133.426708 -13.112242) (xy 133.411468 -13.097002)
				(xy 132.990336 -12.870688) (xy 132.922772 -12.996672) (xy 133.328664 -13.214604) (xy 133.332982 -13.213588)
				(xy 133.341364 -13.219176) (xy 133.350254 -13.219176) (xy 133.365494 -13.234162) (xy 133.383782 -13.244068)
				(xy 133.385052 -13.248386) (xy 133.385814 -13.248894) (xy 133.389624 -13.251434)
				(arc
					(start 133.389624 -13.251942)
					(mid 133.461531 -13.36011)
					(end 133.458966 -13.48994)
				)
				(xy 133.460236 -13.494004)
				(arc
					(start 133.38175 -13.640308)
					(mid 132.954737 -14.26633)
					(end 133.239002 -13.563854)
				)
				(arc
					(start 133.301486 -13.447014)
					(mid 133.307413 -13.412592)
					(end 133.29158 -13.381482)
				)
				(xy 133.283452 -13.381482) (xy 133.267704 -13.365734) (xy 132.846318 -13.13942) (xy 132.581396 -13.633958)
				(arc
					(start 132.583428 -13.635228)
					(mid 132.83946 -14.481048)
					(end 133.68528 -14.225016)
				)
				(xy 133.687312 -14.226286) (xy 134.437374 -12.826492) (xy 134.43712 -12.826238)
				(arc
					(start 134.435088 -12.825222)
					(mid 134.179412 -11.979321)
					(end 133.33349 -12.23518)
				)
				(xy 133.331458 -12.23391) (xy 133.06679 -12.72794) (xy 133.480556 -12.95019) (xy 133.494018 -12.95019)
				(arc
					(start 133.50748 -12.963652)
					(mid 133.545555 -12.962551)
					(end 133.574028 -12.937236)
				)
			)
		)
	)
	(zone
		(layer "B.Cu")
		(hatch none 0.5)
		(connect_pads
			(clearance 0)
		)
		(min_thickness 0.25)
		(keepout
			(tracks not_allowed)
			(vias allowed)
			(pads allowed)
			(copperpour not_allowed)
			(footprints allowed)
		)
		(placement
			(enabled no)
			(sheetname "")
		)
		(fill
			(thermal_gap 0.5)
			(thermal_bridge_width 0.5)
			(island_removal_mode 0)
		)
		(polygon
			(pts
				(arc
					(start 347.49994 -203.499974)
					(mid 345.60002 -201.600054)
					(end 343.7001 -203.499974)
				)
				(arc
					(start 343.7001 -203.499974)
					(mid 345.60002 -205.399894)
					(end 347.49994 -203.499974)
				)
			)
		)
	)
	(zone
		(layer "B.Cu")
		(hatch none 0.5)
		(connect_pads
			(clearance 0)
		)
		(min_thickness 0.25)
		(keepout
			(tracks not_allowed)
			(vias allowed)
			(pads allowed)
			(copperpour not_allowed)
			(footprints allowed)
		)
		(placement
			(enabled no)
			(sheetname "")
		)
		(fill
			(thermal_gap 0.5)
			(thermal_bridge_width 0.5)
			(island_removal_mode 0)
		)
		(polygon
			(pts
				(arc
					(start 156.093668 -221.784164)
					(mid 155.583128 -222.294704)
					(end 156.093668 -222.805244)
				)
				(arc
					(start 156.260038 -222.805244)
					(mid 156.230671 -222.672837)
					(end 156.179012 -222.547434)
				)
				(arc
					(start 156.179012 -222.547434)
					(mid 155.93434 -222.081026)
					(end 156.310584 -222.449644)
				)
				(arc
					(start 156.310584 -222.449644)
					(mid 156.384495 -222.621858)
					(end 156.423106 -222.805244)
				)
				(xy 156.571696 -222.805244) (xy 156.571696 -222.572072)
				(arc
					(start 156.574744 -222.569024)
					(mid 156.588324 -222.521831)
					(end 156.612082 -222.478854)
				)
				(xy 156.612082 -222.474536)
				(arc
					(start 156.669486 -222.417132)
					(mid 157.09508 -222.106092)
					(end 156.78404 -222.531686)
				)
				(arc
					(start 156.750512 -222.565468)
					(mid 156.738126 -222.583866)
					(end 156.733748 -222.6056)
				)
				(xy 156.733748 -222.805244)
				(arc
					(start 156.906214 -222.805244)
					(mid 157.417008 -222.294831)
					(end 156.906468 -221.784164)
				)
			)
		)
	)
	(zone
		(layer "B.Cu")
		(hatch none 0.5)
		(connect_pads
			(clearance 0)
		)
		(min_thickness 0.25)
		(keepout
			(tracks not_allowed)
			(vias allowed)
			(pads allowed)
			(copperpour not_allowed)
			(footprints allowed)
		)
		(placement
			(enabled no)
			(sheetname "")
		)
		(fill
			(thermal_gap 0.5)
			(thermal_bridge_width 0.5)
			(island_removal_mode 0)
		)
		(polygon
			(pts
				(arc
					(start 96.493584 -221.784164)
					(mid 95.983044 -222.294704)
					(end 96.493584 -222.805244)
				)
				(arc
					(start 96.659954 -222.805244)
					(mid 96.630587 -222.672837)
					(end 96.578928 -222.547434)
				)
				(arc
					(start 96.578928 -222.547434)
					(mid 96.334256 -222.081026)
					(end 96.7105 -222.449644)
				)
				(arc
					(start 96.7105 -222.449644)
					(mid 96.784411 -222.621858)
					(end 96.823022 -222.805244)
				)
				(arc
					(start 96.9772 -222.805244)
					(mid 97.015681 -222.621993)
					(end 97.089468 -222.449898)
				)
				(arc
					(start 97.089468 -222.449898)
					(mid 97.465177 -222.080409)
					(end 97.22104 -222.547434)
				)
				(arc
					(start 97.22104 -222.547434)
					(mid 97.169497 -222.672842)
					(end 97.140268 -222.805244)
				)
				(arc
					(start 97.30613 -222.805244)
					(mid 97.816924 -222.294831)
					(end 97.306384 -221.784164)
				)
			)
		)
	)
	(zone
		(layer "B.Cu")
		(hatch none 0.5)
		(connect_pads
			(clearance 0)
		)
		(min_thickness 0.25)
		(keepout
			(tracks allowed)
			(vias allowed)
			(pads allowed)
			(copperpour allowed)
			(footprints not_allowed)
		)
		(placement
			(enabled no)
			(sheetname "")
		)
		(fill
			(thermal_gap 0.5)
			(thermal_bridge_width 0.5)
			(island_removal_mode 0)
		)
		(polygon
			(pts
				(arc
					(start 81.449926 -22.999954)
					(mid 85.449918 -26.999946)
					(end 89.44991 -22.999954)
				)
				(arc
					(start 89.44991 -22.999954)
					(mid 85.449918 -18.999962)
					(end 81.449926 -22.999954)
				)
			)
		)
	)
	(zone
		(layer "B.Cu")
		(hatch none 0.5)
		(connect_pads
			(clearance 0)
		)
		(min_thickness 0.25)
		(keepout
			(tracks not_allowed)
			(vias allowed)
			(pads allowed)
			(copperpour not_allowed)
			(footprints allowed)
		)
		(placement
			(enabled no)
			(sheetname "")
		)
		(fill
			(thermal_gap 0.5)
			(thermal_bridge_width 0.5)
			(island_removal_mode 0)
		)
		(polygon
			(pts
				(arc
					(start 11.8999 -203.499974)
					(mid 9.99998 -201.600054)
					(end 8.10006 -203.499974)
				)
				(arc
					(start 8.10006 -203.499974)
					(mid 9.99998 -205.399894)
					(end 11.8999 -203.499974)
				)
			)
		)
	)
	(zone
		(layer "B.Cu")
		(hatch none 0.5)
		(connect_pads
			(clearance 0)
		)
		(min_thickness 0.25)
		(keepout
			(tracks not_allowed)
			(vias allowed)
			(pads allowed)
			(copperpour not_allowed)
			(footprints allowed)
		)
		(placement
			(enabled no)
			(sheetname "")
		)
		(fill
			(thermal_gap 0.5)
			(thermal_bridge_width 0.5)
			(island_removal_mode 0)
		)
		(polygon
			(pts
				(arc
					(start 159.237426 -9.53008)
					(mid 158.137606 -8.43026)
					(end 157.037532 -9.53008)
				)
				(arc
					(start 157.037532 -9.53008)
					(mid 158.137606 -10.630154)
					(end 159.237426 -9.53008)
				)
			)
		)
	)
	(zone
		(net "GND")
		(layer "B.Cu")
		(hatch none 0.5)
		(connect_pads
			(clearance 0.5)
		)
		(min_thickness 0.25)
		(fill yes
			(thermal_gap 0.5)
			(thermal_bridge_width 0.5)
			(island_removal_mode 0)
		)
		(polygon
			(pts
				(xy 246.634 -67.183) (xy 246.38 -67.437) (xy 246.38 -72.771) (xy 246.507 -72.898) (xy 249.428 -72.898)
				(xy 250.063 -72.263) (xy 250.063 -67.437) (xy 249.809 -67.183)
			)
		)
	)
	(zone
		(layer "B.Cu")
		(hatch none 0.5)
		(connect_pads
			(clearance 0)
		)
		(min_thickness 0.25)
		(keepout
			(tracks not_allowed)
			(vias allowed)
			(pads allowed)
			(copperpour not_allowed)
			(footprints allowed)
		)
		(placement
			(enabled no)
			(sheetname "")
		)
		(fill
			(thermal_gap 0.5)
			(thermal_bridge_width 0.5)
			(island_removal_mode 0)
		)
		(polygon
			(pts
				(xy 304.028856 -220.794072) (xy 304.028856 -220.79839) (xy 304.171858 -220.793818)
				(arc
					(start 304.172366 -220.79331)
					(mid 304.212158 -220.582625)
					(end 304.309272 -220.391482)
				)
				(arc
					(start 304.309272 -220.391482)
					(mid 304.733205 -220.078944)
					(end 304.42662 -220.507306)
				)
				(arc
					(start 304.42662 -220.507306)
					(mid 304.363112 -220.642264)
					(end 304.334926 -220.788738)
				)
				(xy 304.561748 -220.781626) (xy 304.562002 -220.781372)
				(arc
					(start 304.562002 -220.779086)
					(mid 305.056286 -220.252798)
					(end 304.529998 -219.758514)
				)
				(xy 304.529998 -219.755974) (xy 303.717198 -219.781374)
				(arc
					(start 303.717198 -219.783914)
					(mid 303.222914 -220.310202)
					(end 303.749202 -220.804486)
				)
				(xy 303.749202 -220.807026)
				(arc
					(start 303.866296 -220.80347)
					(mid 303.84942 -220.673963)
					(end 303.808384 -220.549978)
				)
				(arc
					(start 303.808384 -220.549978)
					(mid 303.582935 -220.073983)
					(end 303.94402 -220.457522)
				)
				(arc
					(start 303.94402 -220.457522)
					(mid 304.003317 -220.621095)
					(end 304.028094 -220.79331)
				)
			)
		)
	)
	(zone
		(layer "B.Cu")
		(hatch none 0.5)
		(connect_pads
			(clearance 0)
		)
		(min_thickness 0.25)
		(keepout
			(tracks not_allowed)
			(vias allowed)
			(pads allowed)
			(copperpour not_allowed)
			(footprints allowed)
		)
		(placement
			(enabled no)
			(sheetname "")
		)
		(fill
			(thermal_gap 0.5)
			(thermal_bridge_width 0.5)
			(island_removal_mode 0)
		)
		(polygon
			(pts
				(arc
					(start 299.037502 -9.53008)
					(mid 300.137576 -10.630154)
					(end 301.237396 -9.53008)
				)
				(arc
					(start 301.237396 -9.53008)
					(mid 300.137576 -8.43026)
					(end 299.037502 -9.53008)
				)
			)
		)
	)
	(zone
		(layer "B.Cu")
		(hatch none 0.5)
		(connect_pads
			(clearance 0)
		)
		(min_thickness 0.25)
		(keepout
			(tracks not_allowed)
			(vias allowed)
			(pads allowed)
			(copperpour not_allowed)
			(footprints allowed)
		)
		(placement
			(enabled no)
			(sheetname "")
		)
		(fill
			(thermal_gap 0.5)
			(thermal_bridge_width 0.5)
			(island_removal_mode 0)
		)
		(polygon
			(pts
				(arc
					(start 68.493386 -221.784164)
					(mid 67.982846 -222.294704)
					(end 68.493386 -222.805244)
				)
				(arc
					(start 68.659756 -222.805244)
					(mid 68.630389 -222.672837)
					(end 68.57873 -222.547434)
				)
				(arc
					(start 68.57873 -222.547434)
					(mid 68.334058 -222.081026)
					(end 68.710302 -222.449644)
				)
				(arc
					(start 68.710302 -222.449644)
					(mid 68.784213 -222.621858)
					(end 68.822824 -222.805244)
				)
				(arc
					(start 68.977002 -222.805244)
					(mid 69.015483 -222.621993)
					(end 69.08927 -222.449898)
				)
				(arc
					(start 69.08927 -222.449898)
					(mid 69.464979 -222.080409)
					(end 69.220842 -222.547434)
				)
				(arc
					(start 69.220842 -222.547434)
					(mid 69.169299 -222.672842)
					(end 69.14007 -222.805244)
				)
				(arc
					(start 69.305932 -222.805244)
					(mid 69.816726 -222.294831)
					(end 69.306186 -221.784164)
				)
			)
		)
	)
	(zone
		(layer "B.Cu")
		(hatch none 0.5)
		(connect_pads
			(clearance 0)
		)
		(min_thickness 0.25)
		(keepout
			(tracks not_allowed)
			(vias allowed)
			(pads allowed)
			(copperpour not_allowed)
			(footprints allowed)
		)
		(placement
			(enabled no)
			(sheetname "")
		)
		(fill
			(thermal_gap 0.5)
			(thermal_bridge_width 0.5)
			(island_removal_mode 0)
		)
		(polygon
			(pts
				(arc
					(start 291.6936 -221.784164)
					(mid 291.18306 -222.294704)
					(end 291.6936 -222.805244)
				)
				(arc
					(start 291.85997 -222.805244)
					(mid 291.830603 -222.672837)
					(end 291.778944 -222.547434)
				)
				(arc
					(start 291.778944 -222.547434)
					(mid 291.534272 -222.081026)
					(end 291.910516 -222.449644)
				)
				(arc
					(start 291.910516 -222.449644)
					(mid 291.984427 -222.621858)
					(end 292.023038 -222.805244)
				)
				(arc
					(start 292.177216 -222.805244)
					(mid 292.215697 -222.621993)
					(end 292.289484 -222.449898)
				)
				(arc
					(start 292.289484 -222.449898)
					(mid 292.665193 -222.080409)
					(end 292.421056 -222.547434)
				)
				(arc
					(start 292.421056 -222.547434)
					(mid 292.369513 -222.672842)
					(end 292.340284 -222.805244)
				)
				(arc
					(start 292.506146 -222.805244)
					(mid 293.01694 -222.294831)
					(end 292.5064 -221.784164)
				)
			)
		)
	)
	(zone
		(layer "B.Cu")
		(hatch none 0.5)
		(connect_pads
			(clearance 0)
		)
		(min_thickness 0.25)
		(keepout
			(tracks allowed)
			(vias allowed)
			(pads allowed)
			(copperpour allowed)
			(footprints not_allowed)
		)
		(placement
			(enabled no)
			(sheetname "")
		)
		(fill
			(thermal_gap 0.5)
			(thermal_bridge_width 0.5)
			(island_removal_mode 0)
		)
		(polygon
			(pts
				(arc
					(start 199.021954 -72.00011)
					(mid 200.622154 -73.60031)
					(end 202.2221 -72.00011)
				)
				(arc
					(start 202.2221 -72.00011)
					(mid 200.622154 -70.400164)
					(end 199.021954 -72.00011)
				)
			)
		)
	)
	(zone
		(net "DUT_VDD")
		(layer "B.Cu")
		(hatch none 0.5)
		(connect_pads
			(clearance 0.5)
		)
		(min_thickness 0.25)
		(fill yes
			(thermal_gap 0.5)
			(thermal_bridge_width 0.5)
			(island_removal_mode 0)
		)
		(polygon
			(pts
				(xy 239.0902 -41.1607) (xy 233.7943 -46.4566) (xy 233.7943 -46.5836) (xy 233.9848 -46.7741) (xy 234.188 -46.7741)
				(xy 239.4331 -41.529) (xy 239.4331 -41.4147) (xy 239.1791 -41.1607)
			)
		)
	)
	(zone
		(net "GND")
		(layer "B.Cu")
		(hatch none 0.5)
		(connect_pads
			(clearance 0.5)
		)
		(min_thickness 0.25)
		(fill yes
			(thermal_gap 0.5)
			(thermal_bridge_width 0.5)
			(island_removal_mode 0)
		)
		(polygon
			(pts
				(xy 263.675368 -156.584396) (xy 261.970012 -158.289752) (xy 261.970012 -208.5594) (xy 262.554212 -209.1436)
				(xy 293.9288 -209.1436) (xy 293.9542 -209.169) (xy 296.391076 -209.169) (xy 296.391076 -197.697598)
				(xy 324.03288 -170.055794) (xy 324.03288 -160.60801) (xy 320.009266 -156.584396)
			)
		)
		(polygon
			(pts
				(xy 295.886378 -208.51114) (xy 295.683178 -208.51114) (xy 295.683178 -208.71434) (xy 295.886378 -208.71434)
			)
		)
		(polygon
			(pts
				(xy 295.022778 -208.51114) (xy 294.819578 -208.51114) (xy 294.819578 -208.71434) (xy 295.022778 -208.71434)
			)
		)
	)
	(zone
		(layer "B.Cu")
		(hatch none 0.5)
		(connect_pads
			(clearance 0)
		)
		(min_thickness 0.25)
		(keepout
			(tracks not_allowed)
			(vias allowed)
			(pads allowed)
			(copperpour not_allowed)
			(footprints allowed)
		)
		(placement
			(enabled no)
			(sheetname "")
		)
		(fill
			(thermal_gap 0.5)
			(thermal_bridge_width 0.5)
			(island_removal_mode 0)
		)
		(polygon
			(pts
				(arc
					(start 87.6935 -221.784164)
					(mid 87.18296 -222.294704)
					(end 87.6935 -222.805244)
				)
				(arc
					(start 87.85987 -222.805244)
					(mid 87.830503 -222.672837)
					(end 87.778844 -222.547434)
				)
				(arc
					(start 87.778844 -222.547434)
					(mid 87.534172 -222.081026)
					(end 87.910416 -222.449644)
				)
				(arc
					(start 87.910416 -222.449644)
					(mid 87.984327 -222.621858)
					(end 88.022938 -222.805244)
				)
				(arc
					(start 88.177116 -222.805244)
					(mid 88.215597 -222.621993)
					(end 88.289384 -222.449898)
				)
				(arc
					(start 88.289384 -222.449898)
					(mid 88.665093 -222.080409)
					(end 88.420956 -222.547434)
				)
				(arc
					(start 88.420956 -222.547434)
					(mid 88.369413 -222.672842)
					(end 88.340184 -222.805244)
				)
				(arc
					(start 88.506046 -222.805244)
					(mid 89.01684 -222.294831)
					(end 88.5063 -221.784164)
				)
			)
		)
	)
	(zone
		(layer "B.Cu")
		(hatch none 0.5)
		(connect_pads
			(clearance 0)
		)
		(min_thickness 0.25)
		(keepout
			(tracks not_allowed)
			(vias allowed)
			(pads allowed)
			(copperpour not_allowed)
			(footprints allowed)
		)
		(placement
			(enabled no)
			(sheetname "")
		)
		(fill
			(thermal_gap 0.5)
			(thermal_bridge_width 0.5)
			(island_removal_mode 0)
		)
		(polygon
			(pts
				(arc
					(start 5.999988 -203.499974)
					(mid 9.99998 -207.499966)
					(end 13.999972 -203.499974)
				)
				(arc
					(start 13.999972 -203.499974)
					(mid 9.99998 -199.499982)
					(end 5.999988 -203.499974)
				)
			)
		)
	)
	(zone
		(net "P12V")
		(layer "B.Cu")
		(hatch none 0.5)
		(connect_pads
			(clearance 0.5)
		)
		(min_thickness 0.25)
		(fill yes
			(thermal_gap 0.5)
			(thermal_bridge_width 0.5)
			(island_removal_mode 0)
		)
		(polygon
			(pts
				(xy 26.162 -194.056) (xy 25.908 -194.31) (xy 25.908 -197.866) (xy 26.416 -198.374) (xy 28.829 -198.374)
				(xy 29.083 -198.12) (xy 29.083 -194.31) (xy 28.829 -194.056)
			)
		)
	)
	(zone
		(layer "B.Cu")
		(hatch none 0.5)
		(connect_pads
			(clearance 0)
		)
		(min_thickness 0.25)
		(keepout
			(tracks not_allowed)
			(vias allowed)
			(pads allowed)
			(copperpour not_allowed)
			(footprints allowed)
		)
		(placement
			(enabled no)
			(sheetname "")
		)
		(fill
			(thermal_gap 0.5)
			(thermal_bridge_width 0.5)
			(island_removal_mode 0)
		)
		(polygon
			(pts
				(arc
					(start 140.0937 -221.784164)
					(mid 139.58316 -222.294704)
					(end 140.0937 -222.805244)
				)
				(arc
					(start 140.26007 -222.805244)
					(mid 140.230703 -222.672837)
					(end 140.179044 -222.547434)
				)
				(arc
					(start 140.179044 -222.547434)
					(mid 139.934372 -222.081026)
					(end 140.310616 -222.449644)
				)
				(arc
					(start 140.310616 -222.449644)
					(mid 140.384527 -222.621858)
					(end 140.423138 -222.805244)
				)
				(arc
					(start 140.577316 -222.805244)
					(mid 140.615797 -222.621993)
					(end 140.689584 -222.449898)
				)
				(arc
					(start 140.689584 -222.449898)
					(mid 141.065293 -222.080409)
					(end 140.821156 -222.547434)
				)
				(arc
					(start 140.821156 -222.547434)
					(mid 140.769613 -222.672842)
					(end 140.740384 -222.805244)
				)
				(arc
					(start 140.906246 -222.805244)
					(mid 141.41704 -222.294831)
					(end 140.9065 -221.784164)
				)
			)
		)
	)
	(zone
		(layer "B.Cu")
		(hatch none 0.5)
		(connect_pads
			(clearance 0)
		)
		(min_thickness 0.25)
		(keepout
			(tracks allowed)
			(vias allowed)
			(pads allowed)
			(copperpour allowed)
			(footprints not_allowed)
		)
		(placement
			(enabled no)
			(sheetname "")
		)
		(fill
			(thermal_gap 0.5)
			(thermal_bridge_width 0.5)
			(island_removal_mode 0)
		)
		(polygon
			(pts
				(arc
					(start 87.050118 -5.40004)
					(mid 85.450172 -3.800094)
					(end 83.849972 -5.40004)
				)
				(arc
					(start 83.849972 -5.40004)
					(mid 85.450172 -7.00024)
					(end 87.050118 -5.40004)
				)
			)
		)
	)
	(zone
		(net "GND")
		(layer "B.Cu")
		(hatch none 0.5)
		(connect_pads
			(clearance 0.5)
		)
		(min_thickness 0.25)
		(fill yes
			(thermal_gap 0.5)
			(thermal_bridge_width 0.5)
			(island_removal_mode 0)
		)
		(polygon
			(pts
				(xy 133.425184 -171.148756) (xy 133.162802 -171.411138) (xy 133.162802 -182.12689) (xy 134.212584 -183.176672)
				(xy 216.438734 -183.176672) (xy 217.00744 -182.607966) (xy 217.00744 -173.685454) (xy 214.470742 -171.148756)
			)
		)
	)
	(zone
		(net "GND")
		(layer "B.Cu")
		(hatch none 0.5)
		(connect_pads
			(clearance 0.5)
		)
		(min_thickness 0.25)
		(fill yes
			(thermal_gap 0.5)
			(thermal_bridge_width 0.5)
			(island_removal_mode 0)
		)
		(polygon
			(pts
				(xy 196.39153 -54.5592) (xy 195.072 -55.87873) (xy 191.300862 -55.87873) (xy 190.546228 -56.633364)
				(xy 190.546228 -70.200266) (xy 190.76162 -70.415658) (xy 190.76162 -76.23556) (xy 191.814704 -77.28839)
				(xy 226.148646 -77.28839) (xy 227.111052 -76.325984) (xy 227.111052 -62.2427) (xy 225.536506 -60.668154)
				(xy 225.536506 -55.222902) (xy 225.383344 -55.06974) (xy 204.724 -55.06974) (xy 204.21346 -54.5592)
			)
		)
		(polygon
			(pts
				(arc
					(start 200.6219 -67.619372)
					(mid 200.6219 -76.38034)
					(end 200.6219 -67.619372)
				)
			)
		)
		(polygon
			(pts
				(arc
					(start 200.6219 -55.589678)
					(mid 200.6219 -64.410082)
					(end 200.6219 -55.589678)
				)
			)
		)
	)
	(zone
		(layer "B.Cu")
		(hatch none 0.5)
		(connect_pads
			(clearance 0)
		)
		(min_thickness 0.25)
		(keepout
			(tracks not_allowed)
			(vias allowed)
			(pads allowed)
			(copperpour not_allowed)
			(footprints allowed)
		)
		(placement
			(enabled no)
			(sheetname "")
		)
		(fill
			(thermal_gap 0.5)
			(thermal_bridge_width 0.5)
			(island_removal_mode 0)
		)
		(polygon
			(pts
				(arc
					(start 149.69363 -221.784164)
					(mid 149.18309 -222.294704)
					(end 149.69363 -222.805244)
				)
				(arc
					(start 149.86 -222.805244)
					(mid 149.830633 -222.672837)
					(end 149.778974 -222.547434)
				)
				(arc
					(start 149.778974 -222.547434)
					(mid 149.534302 -222.081026)
					(end 149.910546 -222.449644)
				)
				(arc
					(start 149.910546 -222.449644)
					(mid 149.984457 -222.621858)
					(end 150.023068 -222.805244)
				)
				(arc
					(start 150.177246 -222.805244)
					(mid 150.215727 -222.621993)
					(end 150.289514 -222.449898)
				)
				(arc
					(start 150.289514 -222.449898)
					(mid 150.665223 -222.080409)
					(end 150.421086 -222.547434)
				)
				(arc
					(start 150.421086 -222.547434)
					(mid 150.369543 -222.672842)
					(end 150.340314 -222.805244)
				)
				(arc
					(start 150.506176 -222.805244)
					(mid 151.01697 -222.294831)
					(end 150.50643 -221.784164)
				)
			)
		)
	)
	(zone
		(layer "B.Cu")
		(hatch none 0.5)
		(connect_pads
			(clearance 0)
		)
		(min_thickness 0.25)
		(keepout
			(tracks not_allowed)
			(vias allowed)
			(pads allowed)
			(copperpour not_allowed)
			(footprints allowed)
		)
		(placement
			(enabled no)
			(sheetname "")
		)
		(fill
			(thermal_gap 0.5)
			(thermal_bridge_width 0.5)
			(island_removal_mode 0)
		)
		(polygon
			(pts
				(arc
					(start 300.6852 -12.824968)
					(mid 300.429168 -11.979148)
					(end 299.583348 -12.23518)
				)
				(arc
					(start 298.837604 -13.627608)
					(mid 299.04293 -14.453501)
					(end 299.881544 -14.308836)
				)
				(xy 299.881544 -14.06144) (xy 299.88129 -14.061186)
				(arc
					(start 299.88129 -14.027658)
					(mid 299.879605 -13.959761)
					(end 299.874686 -13.892022)
				)
				(arc
					(start 299.874686 -13.892022)
					(mid 299.864869 -13.812305)
					(end 299.850556 -13.733272)
				)
				(arc
					(start 299.782992 -13.415264)
					(mid 299.701991 -13.290638)
					(end 299.558456 -13.251942)
				)
				(xy 299.553122 -13.257276)
				(arc
					(start 299.528484 -13.257276)
					(mid 299.402908 -13.348958)
					(end 299.376084 -13.502132)
				)
				(arc
					(start 299.386244 -13.549122)
					(mid 299.464253 -14.302731)
					(end 299.227748 -13.582904)
				)
				(xy 299.210476 -13.502894)
				(arc
					(start 299.212 -13.500862)
					(mid 299.271971 -13.253189)
					(end 299.477938 -13.103098)
				)
				(xy 299.485812 -13.095224)
				(arc
					(start 299.511466 -13.095224)
					(mid 299.769864 -13.141437)
					(end 299.932598 -13.347446)
				)
				(xy 299.93463 -13.348716) (xy 300.01591 -13.73251)
				(arc
					(start 300.015656 -13.733018)
					(mid 300.027588 -13.804664)
					(end 300.03623 -13.876782)
				)
				(arc
					(start 300.03623 -13.876782)
					(mid 300.040735 -13.935012)
					(end 300.043088 -13.993368)
				)
				(xy 300.043596 -13.99413) (xy 300.043596 -14.023086)
				(arc
					(start 300.16958 -13.787628)
					(mid 300.160317 -13.728521)
					(end 300.149006 -13.669772)
				)
				(arc
					(start 300.149006 -13.669772)
					(mid 300.085604 -13.2884)
					(end 300.055788 -12.902946)
				)
				(arc
					(start 300.055788 -12.902946)
					(mid 300.131155 -12.149094)
					(end 300.21784 -12.901676)
				)
				(arc
					(start 300.21784 -12.901676)
					(mid 300.242124 -13.231923)
					(end 300.292008 -13.559282)
				)
			)
		)
	)
	(zone
		(layer "B.Cu")
		(hatch none 0.5)
		(connect_pads
			(clearance 0)
		)
		(min_thickness 0.25)
		(keepout
			(tracks not_allowed)
			(vias allowed)
			(pads allowed)
			(copperpour not_allowed)
			(footprints allowed)
		)
		(placement
			(enabled no)
			(sheetname "")
		)
		(fill
			(thermal_gap 0.5)
			(thermal_bridge_width 0.5)
			(island_removal_mode 0)
		)
		(polygon
			(pts
				(arc
					(start 351.350072 -5.40004)
					(mid 349.750126 -3.800094)
					(end 348.149926 -5.40004)
				)
				(arc
					(start 348.149926 -5.40004)
					(mid 349.750126 -7.00024)
					(end 351.350072 -5.40004)
				)
			)
		)
	)
	(zone
		(net "P1V5_I210")
		(layer "B.Cu")
		(hatch none 0.5)
		(connect_pads
			(clearance 0.5)
		)
		(min_thickness 0.25)
		(fill yes
			(thermal_gap 0.5)
			(thermal_bridge_width 0.5)
			(island_removal_mode 0)
		)
		(polygon
			(pts
				(xy 9.8933 -65.5955) (xy 9.3218 -66.167) (xy 9.3218 -71.755) (xy 9.5758 -72.009) (xy 9.5758 -72.5678)
				(xy 9.568942 -72.574658) (xy 9.568942 -74.015854) (xy 10.4394 -74.886312) (xy 10.4394 -77.1906)
				(xy 10.1092 -77.5208) (xy 9.5504 -77.5208) (xy 9.4488 -77.6224) (xy 9.4488 -78.994) (xy 9.7409 -79.2861)
				(xy 10.7569 -79.2861) (xy 11.301476 -78.741524) (xy 11.301476 -77.03693) (xy 11.66368 -76.674726)
				(xy 11.77417 -76.564236) (xy 12.45743 -76.564236) (xy 12.547854 -76.65466) (xy 12.547854 -76.815442)
				(xy 12.788392 -77.05598) (xy 13.292328 -77.05598) (xy 13.39342 -76.954888) (xy 13.39342 -75.538838)
				(xy 13.331952 -75.47737) (xy 12.794234 -75.47737) (xy 12.628118 -75.643486) (xy 11.901932 -75.643486)
				(xy 11.623802 -75.365356) (xy 11.623802 -73.262998) (xy 12.9794 -71.9074) (xy 12.9794 -71.247) (xy 12.7254 -70.993)
				(xy 12.7254 -70.5866) (xy 13.1318 -70.1802) (xy 13.1318 -65.7225) (xy 13.0048 -65.5955)
			)
		)
		(polygon
			(pts
				(xy 12.846558 -75.989434) (xy 12.643358 -75.989434) (xy 12.643358 -76.192634) (xy 12.64158 -76.254864)
				(xy 12.64158 -76.458064) (xy 12.84478 -76.458064) (xy 12.84478 -76.254864) (xy 12.846558 -76.192634)
			)
		)
	)
	(zone
		(layer "B.Cu")
		(hatch none 0.5)
		(connect_pads
			(clearance 0)
		)
		(min_thickness 0.25)
		(keepout
			(tracks not_allowed)
			(vias allowed)
			(pads allowed)
			(copperpour not_allowed)
			(footprints allowed)
		)
		(placement
			(enabled no)
			(sheetname "")
		)
		(fill
			(thermal_gap 0.5)
			(thermal_bridge_width 0.5)
			(island_removal_mode 0)
		)
		(polygon
			(pts
				(arc
					(start 177.5968 -220.16466)
					(mid 177.08626 -220.6752)
					(end 177.5968 -221.18574)
				)
				(arc
					(start 177.858166 -221.18574)
					(mid 177.808779 -221.038681)
					(end 177.718974 -220.912182)
				)
				(arc
					(start 177.718974 -220.912182)
					(mid 177.408769 -220.486017)
					(end 177.833782 -220.797628)
				)
				(xy 177.84953 -220.813376)
				(arc
					(start 177.84953 -220.814646)
					(mid 177.963914 -220.987145)
					(end 178.02225 -221.18574)
				)
				(xy 178.171602 -221.18574) (xy 178.171602 -221.02064)
				(arc
					(start 178.172618 -221.019624)
					(mid 178.183669 -220.932805)
					(end 178.206908 -220.848428)
				)
				(arc
					(start 178.206908 -220.848428)
					(mid 178.548502 -220.447227)
					(end 178.349402 -220.935042)
				)
				(arc
					(start 178.349402 -220.935042)
					(mid 178.337583 -220.994083)
					(end 178.333654 -221.054168)
				)
				(xy 178.333654 -221.18574)
				(arc
					(start 178.409346 -221.18574)
					(mid 178.92014 -220.675327)
					(end 178.4096 -220.16466)
				)
			)
		)
	)
	(zone
		(layer "B.Cu")
		(hatch none 0.5)
		(connect_pads
			(clearance 0)
		)
		(min_thickness 0.25)
		(keepout
			(tracks not_allowed)
			(vias allowed)
			(pads allowed)
			(copperpour not_allowed)
			(footprints allowed)
		)
		(placement
			(enabled no)
			(sheetname "")
		)
		(fill
			(thermal_gap 0.5)
			(thermal_bridge_width 0.5)
			(island_removal_mode 0)
		)
		(polygon
			(pts
				(arc
					(start 81.293462 -221.784164)
					(mid 80.782922 -222.294704)
					(end 81.293462 -222.805244)
				)
				(arc
					(start 81.459832 -222.805244)
					(mid 81.430465 -222.672837)
					(end 81.378806 -222.547434)
				)
				(arc
					(start 81.378806 -222.547434)
					(mid 81.134134 -222.081026)
					(end 81.510378 -222.449644)
				)
				(arc
					(start 81.510378 -222.449644)
					(mid 81.584289 -222.621858)
					(end 81.6229 -222.805244)
				)
				(arc
					(start 81.777078 -222.805244)
					(mid 81.815559 -222.621993)
					(end 81.889346 -222.449898)
				)
				(arc
					(start 81.889346 -222.449898)
					(mid 82.265055 -222.080409)
					(end 82.020918 -222.547434)
				)
				(arc
					(start 82.020918 -222.547434)
					(mid 81.969375 -222.672842)
					(end 81.940146 -222.805244)
				)
				(arc
					(start 82.106008 -222.805244)
					(mid 82.616802 -222.294831)
					(end 82.106262 -221.784164)
				)
			)
		)
	)
	(zone
		(net "DUT_VDD")
		(layer "B.Cu")
		(hatch none 0.5)
		(connect_pads
			(clearance 0.5)
		)
		(min_thickness 0.25)
		(fill yes
			(thermal_gap 0.5)
			(thermal_bridge_width 0.5)
			(island_removal_mode 0)
		)
		(polygon
			(pts
				(xy 244.08765 -41.15435) (xy 239.9919 -45.2501) (xy 239.0648 -45.2501) (xy 237.9091 -46.4058) (xy 237.9091 -47.3329)
				(xy 232.8037 -52.4383) (xy 232.8037 -52.5653) (xy 232.9942 -52.7558) (xy 233.1974 -52.7558) (xy 239.2553 -46.6979)
				(xy 239.2553 -46.6852) (xy 244.3988 -41.5417) (xy 244.3988 -41.4655)
			)
		)
		(polygon
			(pts
				(xy 238.7854 -46.753272) (xy 238.5822 -46.753272) (xy 238.5822 -46.956472) (xy 238.7854 -46.956472)
			)
		)
	)
	(zone
		(layer "B.Cu")
		(hatch none 0.5)
		(connect_pads
			(clearance 0)
		)
		(min_thickness 0.25)
		(keepout
			(tracks not_allowed)
			(vias allowed)
			(pads allowed)
			(copperpour not_allowed)
			(footprints allowed)
		)
		(placement
			(enabled no)
			(sheetname "")
		)
		(fill
			(thermal_gap 0.5)
			(thermal_bridge_width 0.5)
			(island_removal_mode 0)
		)
		(polygon
			(pts
				(arc
					(start 285.293562 -221.784164)
					(mid 284.783022 -222.294704)
					(end 285.293562 -222.805244)
				)
				(arc
					(start 285.459932 -222.805244)
					(mid 285.430565 -222.672837)
					(end 285.378906 -222.547434)
				)
				(arc
					(start 285.378906 -222.547434)
					(mid 285.134234 -222.081026)
					(end 285.510478 -222.449644)
				)
				(arc
					(start 285.510478 -222.449644)
					(mid 285.584389 -222.621858)
					(end 285.623 -222.805244)
				)
				(arc
					(start 285.777178 -222.805244)
					(mid 285.815659 -222.621993)
					(end 285.889446 -222.449898)
				)
				(arc
					(start 285.889446 -222.449898)
					(mid 286.265155 -222.080409)
					(end 286.021018 -222.547434)
				)
				(arc
					(start 286.021018 -222.547434)
					(mid 285.969475 -222.672842)
					(end 285.940246 -222.805244)
				)
				(arc
					(start 286.106108 -222.805244)
					(mid 286.616902 -222.294831)
					(end 286.106362 -221.784164)
				)
			)
		)
	)
	(zone
		(net "DUT_VDD")
		(layer "B.Cu")
		(hatch none 0.5)
		(connect_pads
			(clearance 0.5)
		)
		(min_thickness 0.25)
		(fill yes
			(thermal_gap 0.5)
			(thermal_bridge_width 0.5)
			(island_removal_mode 0)
		)
		(polygon
			(pts
				(xy 247.7516 -43.3324) (xy 247.2436 -43.8404) (xy 247.2436 -44.0309) (xy 244.9195 -46.355) (xy 244.9195 -46.5201)
				(xy 245.237 -46.8376) (xy 245.237 -47.2059) (xy 243.6495 -48.7934) (xy 243.4082 -48.7934) (xy 243.2685 -48.9331)
				(xy 243.2685 -49.1744) (xy 240.88725 -51.55565) (xy 239.73155 -51.55565) (xy 236.8931 -54.3941)
				(xy 236.8931 -54.7116) (xy 237.2106 -55.0291) (xy 238.8616 -55.0291) (xy 239.24895 -54.64175) (xy 239.24895 -54.356)
				(xy 239.0775 -54.18455) (xy 239.0775 -53.8607) (xy 240.81105 -52.12715) (xy 241.02695 -52.12715)
				(xy 245.0084 -48.1457) (xy 245.0084 -48.133) (xy 245.8085 -47.3329) (xy 245.8085 -46.1645) (xy 248.3104 -43.6626)
				(xy 248.3104 -43.434) (xy 248.2088 -43.3324)
			)
		)
		(polygon
			(pts
				(xy 238.7854 -54.0766) (xy 238.5822 -54.0766) (xy 238.5822 -54.2798) (xy 238.7854 -54.2798)
			)
		)
		(polygon
			(pts
				(xy 238.7854 -53.721) (xy 238.5822 -53.721) (xy 238.5822 -53.9242) (xy 238.7854 -53.9242)
			)
		)
		(polygon
			(pts
				(xy 239.7506 -52.07) (xy 239.5474 -52.07) (xy 239.5474 -52.2732) (xy 239.7506 -52.2732)
			)
		)
		(polygon
			(pts
				(xy 240.7158 -51.7144) (xy 240.5126 -51.7144) (xy 240.5126 -51.9176) (xy 240.7158 -51.9176)
			)
		)
		(polygon
			(pts
				(xy 243.713 -49.0728) (xy 243.5098 -49.0728) (xy 243.5098 -49.276) (xy 243.713 -49.276)
			)
		)
	)
	(zone
		(net "GND")
		(layer "B.Cu")
		(hatch none 0.5)
		(connect_pads
			(clearance 0.5)
		)
		(min_thickness 0.25)
		(fill yes
			(thermal_gap 0.5)
			(thermal_bridge_width 0.5)
			(island_removal_mode 0)
		)
		(polygon
			(pts
				(xy 63.881 -35.179) (xy 63.5 -35.56) (xy 63.5 -42.672) (xy 64.516 -43.688) (xy 64.516 -48.514) (xy 64.529716 -48.527716)
				(xy 64.529716 -48.997108) (xy 65.227962 -49.695354) (xy 67.760596 -49.695354) (xy 68.834 -48.62195)
				(xy 68.834 -48.598074) (xy 69.293994 -48.13808) (xy 69.293994 -46.771052) (xy 68.834 -46.311058)
				(xy 68.834 -35.306) (xy 68.707 -35.179)
			)
		)
	)
	(zone
		(layer "B.Cu")
		(hatch none 0.5)
		(connect_pads
			(clearance 0)
		)
		(min_thickness 0.25)
		(keepout
			(tracks allowed)
			(vias allowed)
			(pads allowed)
			(copperpour allowed)
			(footprints not_allowed)
		)
		(placement
			(enabled no)
			(sheetname "")
		)
		(fill
			(thermal_gap 0.5)
			(thermal_bridge_width 0.5)
			(island_removal_mode 0)
		)
		(polygon
			(pts
				(arc
					(start 10.061956 -60.300108)
					(mid 13.812012 -64.050164)
					(end 17.562068 -60.300108)
				)
				(arc
					(start 17.562068 -60.300108)
					(mid 13.812012 -56.550052)
					(end 10.061956 -60.300108)
				)
			)
		)
	)
	(zone
		(layer "B.Cu")
		(hatch none 0.5)
		(connect_pads
			(clearance 0)
		)
		(min_thickness 0.25)
		(keepout
			(tracks allowed)
			(vias allowed)
			(pads allowed)
			(copperpour allowed)
			(footprints allowed)
		)
		(placement
			(enabled no)
			(sheetname "")
		)
		(fill
			(thermal_gap 0.5)
			(thermal_bridge_width 0.5)
			(island_removal_mode 0)
		)
		(polygon
			(pts
				(xy 56.109616 -128.517396) (xy 56.109616 -130.549396) (xy 53.569616 -130.549396) (xy 53.569616 -128.517396)
			)
		)
	)
	(zone
		(layer "B.Cu")
		(hatch none 0.5)
		(connect_pads
			(clearance 0)
		)
		(min_thickness 0.25)
		(keepout
			(tracks allowed)
			(vias allowed)
			(pads allowed)
			(copperpour allowed)
			(footprints not_allowed)
		)
		(placement
			(enabled no)
			(sheetname "")
		)
		(fill
			(thermal_gap 0.5)
			(thermal_bridge_width 0.5)
			(island_removal_mode 0)
		)
		(polygon
			(pts
				(xy 351.600008 -213.499954)
				(arc
					(start 354.600002 -213.499954)
					(mid 355.307107 -213.207061)
					(end 355.6 -212.499956)
				)
				(xy 355.6 -77.0001) (xy 351.600008 -77.0001)
			)
		)
	)
	(zone
		(layer "B.Cu")
		(hatch none 0.5)
		(connect_pads
			(clearance 0)
		)
		(min_thickness 0.25)
		(keepout
			(tracks not_allowed)
			(vias allowed)
			(pads allowed)
			(copperpour not_allowed)
			(footprints allowed)
		)
		(placement
			(enabled no)
			(sheetname "")
		)
		(fill
			(thermal_gap 0.5)
			(thermal_bridge_width 0.5)
			(island_removal_mode 0)
		)
		(polygon
			(pts
				(arc
					(start 146.037554 -9.53008)
					(mid 147.137628 -10.630154)
					(end 148.237448 -9.53008)
				)
				(arc
					(start 148.237448 -9.53008)
					(mid 147.137628 -8.43026)
					(end 146.037554 -9.53008)
				)
			)
		)
	)
	(zone
		(layer "B.Cu")
		(hatch none 0.5)
		(connect_pads
			(clearance 0)
		)
		(min_thickness 0.25)
		(keepout
			(tracks not_allowed)
			(vias allowed)
			(pads allowed)
			(copperpour not_allowed)
			(footprints allowed)
		)
		(placement
			(enabled no)
			(sheetname "")
		)
		(fill
			(thermal_gap 0.5)
			(thermal_bridge_width 0.5)
			(island_removal_mode 0)
		)
		(polygon
			(pts
				(arc
					(start 195.293742 -221.784164)
					(mid 194.783202 -222.294704)
					(end 195.293742 -222.805244)
				)
				(arc
					(start 195.460112 -222.805244)
					(mid 195.430745 -222.672837)
					(end 195.379086 -222.547434)
				)
				(arc
					(start 195.379086 -222.547434)
					(mid 195.134414 -222.081026)
					(end 195.510658 -222.449644)
				)
				(arc
					(start 195.510658 -222.449644)
					(mid 195.584569 -222.621858)
					(end 195.62318 -222.805244)
				)
				(arc
					(start 195.777358 -222.805244)
					(mid 195.815839 -222.621993)
					(end 195.889626 -222.449898)
				)
				(arc
					(start 195.889626 -222.449898)
					(mid 196.265335 -222.080409)
					(end 196.021198 -222.547434)
				)
				(arc
					(start 196.021198 -222.547434)
					(mid 195.969655 -222.672842)
					(end 195.940426 -222.805244)
				)
				(arc
					(start 196.106288 -222.805244)
					(mid 196.617082 -222.294831)
					(end 196.106542 -221.784164)
				)
			)
		)
	)
	(zone
		(layer "B.Cu")
		(hatch none 0.5)
		(connect_pads
			(clearance 0)
		)
		(min_thickness 0.25)
		(keepout
			(tracks not_allowed)
			(vias allowed)
			(pads allowed)
			(copperpour not_allowed)
			(footprints allowed)
		)
		(placement
			(enabled no)
			(sheetname "")
		)
		(fill
			(thermal_gap 0.5)
			(thermal_bridge_width 0.5)
			(island_removal_mode 0)
		)
		(polygon
			(pts
				(arc
					(start 76.049886 -14.200124)
					(mid 74.44994 -12.600178)
					(end 72.849994 -14.200124)
				)
				(arc
					(start 72.849994 -14.200124)
					(mid 74.44994 -15.80007)
					(end 76.049886 -14.200124)
				)
			)
		)
	)
	(zone
		(net "GND")
		(layer "B.Cu")
		(hatch none 0.5)
		(connect_pads
			(clearance 0.5)
		)
		(min_thickness 0.25)
		(fill yes
			(thermal_gap 0.5)
			(thermal_bridge_width 0.5)
			(island_removal_mode 0)
		)
		(polygon
			(pts
				(xy 26.34996 -77.2287) (xy 26.24836 -77.3303) (xy 26.24836 -78.7527) (xy 26.259028 -78.763368) (xy 26.259028 -79.047594)
				(xy 26.26614 -79.05496) (xy 26.26614 -79.798926) (xy 26.61793 -80.150716) (xy 27.7368 -80.150716)
				(xy 28.10256 -79.784956) (xy 28.10256 -77.4827) (xy 27.84856 -77.2287)
			)
		)
	)
	(zone
		(layer "B.Cu")
		(hatch none 0.5)
		(connect_pads
			(clearance 0)
		)
		(min_thickness 0.25)
		(keepout
			(tracks allowed)
			(vias allowed)
			(pads allowed)
			(copperpour allowed)
			(footprints not_allowed)
		)
		(placement
			(enabled no)
			(sheetname "")
		)
		(fill
			(thermal_gap 0.5)
			(thermal_bridge_width 0.5)
			(island_removal_mode 0)
		)
		(polygon
			(pts
				(arc
					(start 159.237426 -9.53008)
					(mid 158.137606 -8.43026)
					(end 157.037532 -9.53008)
				)
				(arc
					(start 157.037532 -9.53008)
					(mid 158.137606 -10.630154)
					(end 159.237426 -9.53008)
				)
			)
		)
	)
	(zone
		(net "GND")
		(layer "B.Cu")
		(hatch none 0.5)
		(connect_pads
			(clearance 0.5)
		)
		(min_thickness 0.25)
		(fill yes
			(thermal_gap 0.5)
			(thermal_bridge_width 0.5)
			(island_removal_mode 0)
		)
		(polygon
			(pts
				(xy 34.8996 -208.9404) (xy 34.417 -209.423) (xy 34.417 -223.1644) (xy 33.909 -223.6724) (xy 33.909 -223.8756)
				(xy 38.354 -223.8756) (xy 38.354 -209.7532) (xy 37.5412 -208.9404)
			)
		)
	)
	(zone
		(layer "B.Cu")
		(hatch none 0.5)
		(connect_pads
			(clearance 0)
		)
		(min_thickness 0.25)
		(keepout
			(tracks allowed)
			(vias allowed)
			(pads allowed)
			(copperpour allowed)
			(footprints allowed)
		)
		(placement
			(enabled no)
			(sheetname "")
		)
		(fill
			(thermal_gap 0.5)
			(thermal_bridge_width 0.5)
			(island_removal_mode 0)
		)
		(polygon
			(pts
				(xy 133.2484 -228.2952) (xy 133.2484 -222.0722) (xy 218.8464 -222.0722) (xy 218.8464 -228.2952)
			)
		)
	)
	(zone
		(layer "B.Cu")
		(hatch none 0.5)
		(connect_pads
			(clearance 0)
		)
		(min_thickness 0.25)
		(keepout
			(tracks allowed)
			(vias allowed)
			(pads allowed)
			(copperpour allowed)
			(footprints not_allowed)
		)
		(placement
			(enabled no)
			(sheetname "")
		)
		(fill
			(thermal_gap 0.5)
			(thermal_bridge_width 0.5)
			(island_removal_mode 0)
		)
		(polygon
			(pts
				(arc
					(start 341.600028 -34.500058)
					(mid 345.60002 -38.50005)
					(end 349.600012 -34.500058)
				)
				(arc
					(start 349.600012 -34.500058)
					(mid 345.60002 -30.500066)
					(end 341.600028 -34.500058)
				)
			)
		)
	)
	(zone
		(net "DUT_VDD")
		(layer "B.Cu")
		(hatch none 0.5)
		(connect_pads
			(clearance 0.5)
		)
		(min_thickness 0.25)
		(fill yes
			(thermal_gap 0.5)
			(thermal_bridge_width 0.5)
			(island_removal_mode 0)
		)
		(polygon
			(pts
				(xy 248.0056 -52.2732) (xy 245.8212 -54.4576) (xy 245.8212 -54.5592) (xy 246.0244 -54.7624) (xy 246.1768 -54.7624)
				(xy 248.3612 -52.578) (xy 248.3612 -52.4256) (xy 248.2088 -52.2732)
			)
		)
	)
	(zone
		(layer "B.Cu")
		(hatch none 0.5)
		(connect_pads
			(clearance 0)
		)
		(min_thickness 0.25)
		(keepout
			(tracks not_allowed)
			(vias allowed)
			(pads allowed)
			(copperpour not_allowed)
			(footprints allowed)
		)
		(placement
			(enabled no)
			(sheetname "")
		)
		(fill
			(thermal_gap 0.5)
			(thermal_bridge_width 0.5)
			(island_removal_mode 0)
		)
		(polygon
			(pts
				(arc
					(start 341.600028 -34.500058)
					(mid 345.60002 -38.50005)
					(end 349.600012 -34.500058)
				)
				(arc
					(start 349.600012 -34.500058)
					(mid 345.60002 -30.500066)
					(end 341.600028 -34.500058)
				)
			)
		)
	)
	(zone
		(net "GND")
		(layer "B.Cu")
		(hatch none 0.5)
		(connect_pads
			(clearance 0.5)
		)
		(min_thickness 0.25)
		(fill yes
			(thermal_gap 0.5)
			(thermal_bridge_width 0.5)
			(island_removal_mode 0)
		)
		(polygon
			(pts
				(arc
					(start 123.637548 4.236974)
					(mid 122.762871 3.874671)
					(end 122.400568 2.999994)
				)
				(arc
					(start 122.400568 1.999996)
					(mid 121.591301 0.046251)
					(end 119.637556 -0.763016)
				)
				(arc
					(start 53.950108 -0.763016)
					(mid 53.075431 -1.125319)
					(end 52.713128 -1.999996)
				)
				(arc
					(start 52.713128 -24.010112)
					(mid 51.903861 -25.963857)
					(end 49.950116 -26.773124)
				)
				(arc
					(start 1.999996 -26.773124)
					(mid 1.125319 -27.135427)
					(end 0.763016 -28.010104)
				)
				(arc
					(start 0.763016 -212.499956)
					(mid 0.832426 -212.667528)
					(end 0.999998 -212.736938)
				)
				(xy 24.751792 -212.736938) (xy 24.751792 -211.467954) (xy 10.25398 -211.467954) (xy 6.368034 -207.582008)
				(xy 6.368034 -188.556392) (xy 11.879072 -183.045354) (xy 31.386018 -183.045354) (xy 32.041846 -182.389526)
				(xy 32.041846 -176.310036) (xy 31.298134 -175.566324) (xy 21.209 -175.566324) (xy 20.343876 -174.7012)
				(xy 13.7414 -174.7012) (xy 12.876276 -175.566324) (xy 6.586474 -175.566324) (xy 5.099558 -174.079408)
				(xy 5.099558 -166.6875) (xy 7.286498 -164.50056) (xy 22.113494 -164.50056) (xy 25.131268 -161.482786)
				(xy 25.131268 -144.517872) (xy 24.262842 -143.649446) (xy 23.184358 -143.649446) (xy 22.709886 -144.123918)
				(xy 22.709886 -144.92224) (xy 20.17268 -144.92224) (xy 19.26082 -144.01038) (xy 15.91564 -144.01038)
				(xy 15.43558 -143.53032) (xy 15.43558 -138.994134) (xy 14.699996 -138.25855) (xy 14.699996 -129.182876)
				(xy 11.69416 -126.17704) (xy 11.54684 -126.17704) (xy 10.3124 -124.9426) (xy 10.3124 -114.5794)
				(xy 15.0368 -109.855) (xy 15.0368 -98.09226) (xy 15.779242 -97.349818) (xy 15.779242 -96.103186)
				(xy 14.32814 -94.652084) (xy 14.32814 -90.52306) (xy 15.4813 -89.3699) (xy 15.4813 -86.5124) (xy 15.5194 -86.5124)
				(xy 15.6718 -86.36) (xy 21.1328 -86.36) (xy 23.0632 -84.4296) (xy 23.0632 -82.1944) (xy 22.8092 -81.9404)
				(xy 21.59 -81.9404) (xy 21.58746 -81.94294) (xy 19.27352 -81.94294) (xy 18.33626 -82.8802) (xy 17.8816 -82.8802)
				(xy 17.8308 -82.8294) (xy 11.5316 -82.8294) (xy 10.5156 -81.8134) (xy 10.5156 -80.4418) (xy 10.16 -80.0862)
				(xy 9.42594 -80.0862) (xy 8.95477 -79.61503) (xy 8.95477 -77.83957) (xy 8.6106 -77.4954) (xy 7.6708 -77.4954)
				(xy 7.5438 -77.3684) (xy 7.5438 -76.7842) (xy 9.2964 -75.0316) (xy 9.2964 -71.501) (xy 9.0932 -71.2978)
				(xy 9.0932 -68.8594) (xy 8.6868 -68.453) (xy 8.6868 -66.2686) (xy 9.5758 -65.3796) (xy 13.3858 -65.3796)
				(xy 13.843 -65.8368) (xy 16.3322 -65.8368) (xy 16.7894 -65.3796) (xy 16.7894 -64.9732) (xy 17.0434 -64.7192)
				(xy 17.6784 -64.7192) (xy 17.8054 -64.8462) (xy 17.8054 -66.2178) (xy 18.7198 -67.1322) (xy 22.606 -67.1322)
				(xy 23.137114 -66.601086) (xy 24.661114 -66.601086) (xy 26.3906 -64.8716) (xy 26.3906 -60.895738)
				(xy 41.516046 -45.770292) (xy 41.516046 -32.662622) (xy 44.586398 -29.59227) (xy 54.07406 -29.59227)
				(xy 54.69128 -28.97505) (xy 54.69128 -17.95018) (xy 57.51322 -15.12824) (xy 65.89268 -15.12824)
				(xy 67.74434 -16.9799) (xy 67.74434 -28.57754) (xy 69.3928 -30.226) (xy 104.627426 -30.226) (xy 106.575098 -28.278328)
				(xy 110.7948 -28.278328) (xy 115.400328 -23.6728) (xy 117.89283 -23.6728) (xy 118.19255 -23.37308)
				(xy 118.239286 -23.37308) (xy 126.2634 -15.348966) (xy 126.2634 -5.461) (xy 129.2352 -2.4892) (xy 130.586226 -2.4892)
				(xy 132.367528 -0.707898) (xy 139.54887 -0.707898) (xy 139.724892 -0.88392) (xy 178.46548 -0.88392)
				(xy 183.3118 3.9624) (xy 228.36759 3.9624) (xy 229.362 2.96799) (xy 278.154384 2.96799) (xy 282.832302 -1.709928)
				(xy 328.450448 -1.709928) (xy 331.99324 -5.25272) (xy 331.99324 -34.66592) (xy 336.498184 -39.170864)
				(xy 346.183204 -39.170864) (xy 346.423996 -39.411656) (xy 351.916238 -39.411656) (xy 353.568 -41.063418)
				(xy 353.568 -94.596204) (xy 334.223868 -113.940336) (xy 145.803112 -113.940336) (xy 137.536682 -105.673906)
				(xy 94.586552 -105.673906) (xy 89.075514 -111.184944) (xy 89.075514 -124.481082) (xy 84.745576 -128.81102)
				(xy 84.745576 -138.345672) (xy 82.121248 -140.97) (xy 78.18501 -140.97) (xy 73.592436 -136.377426)
				(xy 69.656198 -136.377426) (xy 67.381882 -138.651742) (xy 62.089538 -138.651742) (xy 52.20462 -148.53666)
				(xy 50.10531 -148.53666) (xy 45.469302 -153.172668) (xy 45.469302 -161.832798) (xy 48.596296 -164.959792)
				(xy 65.9384 -164.959792) (xy 68.671948 -162.226244) (xy 69.327776 -162.226244) (xy 70.159118 -163.057586)
				(xy 70.159118 -165.506654) (xy 70.771512 -166.119048) (xy 200.343516 -166.119048) (xy 218.450922 -148.011642)
				(xy 323.683122 -148.011642) (xy 346.776294 -171.104814)
				(arc
					(start 346.776294 -211.571332)
					(mid 344.968762 -212.755705)
					(end 344.268044 -214.799926)
				)
				(arc
					(start 344.268044 -219.976192)
					(mid 344.174327 -220.006509)
					(end 344.081862 -220.040454)
				)
				(xy 345.537028 -220.040454)
				(arc
					(start 345.537028 -214.799926)
					(mid 346.141263 -213.341173)
					(end 347.600016 -212.736938)
				)
				(arc
					(start 354.600002 -212.736938)
					(mid 354.767574 -212.667528)
					(end 354.836984 -212.499956)
				)
				(arc
					(start 354.836984 -19.459956)
					(mid 353.888159 -19.123385)
					(end 353.486974 -18.200116)
				)
				(arc
					(start 353.486974 -10.199878)
					(mid 353.888305 -9.276765)
					(end 354.836984 -8.940038)
				)
				(xy 354.836984 -1.446784) (xy 354.2792 -0.889) (xy 332.0034 -0.889) (xy 330.9366 0.1778) (xy 330.9366 3.932174)
				(xy 330.6318 4.236974)
			)
		)
		(polygon
			(pts
				(arc
					(start 74.5744 -148.666708)
					(mid 74.363333 -148.607687)
					(end 74.213466 -148.44776)
				)
				(arc
					(start 74.074274 -148.44776)
					(mid 73.687933 -148.678982)
					(end 73.256394 -148.55063)
				)
				(arc
					(start 73.256394 -148.55063)
					(mid 73.183335 -148.526727)
					(end 73.114408 -148.56079)
				)
				(arc
					(start 73.114408 -148.56079)
					(mid 73.062678 -148.613228)
					(end 73.005442 -148.659596)
				)
				(arc
					(start 73.005442 -148.659596)
					(mid 72.963238 -148.746201)
					(end 73.0123 -148.829014)
				)
				(arc
					(start 73.0123 -148.829014)
					(mid 73.083005 -148.878468)
					(end 73.146666 -148.93671)
				)
				(arc
					(start 73.146666 -148.93671)
					(mid 73.211967 -148.967708)
					(end 73.281286 -148.947378)
				)
				(arc
					(start 73.281286 -148.947378)
					(mid 73.728919 -148.84569)
					(end 74.10196 -149.11324)
				)
				(arc
					(start 74.213466 -149.11324)
					(mid 74.363315 -148.953284)
					(end 74.5744 -148.894292)
				)
				(xy 74.93 -148.894292)
				(arc
					(start 74.960226 -148.895562)
					(mid 75.03679 -148.868626)
					(end 75.069192 -148.794216)
				)
				(arc
					(start 75.069192 -148.766784)
					(mid 75.036781 -148.692384)
					(end 74.960226 -148.665438)
				)
				(xy 74.93 -148.666708)
			)
		)
		(polygon
			(pts
				(xy 73.236074 -147.219416) (xy 73.11898 -147.219416)
				(arc
					(start 73.10374 -147.240498)
					(mid 73.035175 -147.321031)
					(end 72.954642 -147.389596)
				)
				(arc
					(start 72.954642 -147.389596)
					(mid 72.912438 -147.476201)
					(end 72.9615 -147.559014)
				)
				(arc
					(start 72.9615 -147.559014)
					(mid 73.04281 -147.617221)
					(end 73.114408 -147.68703)
				)
				(arc
					(start 73.114408 -147.68703)
					(mid 73.183332 -147.721131)
					(end 73.256394 -147.69719)
				)
				(arc
					(start 73.256394 -147.69719)
					(mid 73.632392 -147.564706)
					(end 74.001122 -147.71624)
				)
				(arc
					(start 74.213466 -147.71624)
					(mid 74.258834 -147.647481)
					(end 74.317098 -147.58924)
				)
				(arc
					(start 74.317098 -147.58924)
					(mid 74.354471 -147.5105)
					(end 74.317098 -147.43176)
				)
				(arc
					(start 74.317098 -147.43176)
					(mid 74.2588 -147.373547)
					(end 74.213466 -147.30476)
				)
				(xy 73.99147 -147.30476)
				(arc
					(start 73.978516 -147.31365)
					(mid 73.600392 -147.410022)
					(end 73.251314 -147.235672)
				)
			)
		)
		(polygon
			(pts
				(xy 23.84044 -144.12214) (xy 23.63724 -144.12214) (xy 23.63724 -144.32534) (xy 23.84044 -144.32534)
			)
		)
		(polygon
			(pts
				(xy 23.28164 -144.12214) (xy 23.07844 -144.12214) (xy 23.07844 -144.32534) (xy 23.28164 -144.32534)
			)
		)
		(polygon
			(pts
				(xy 11.7856 -108.4072) (xy 11.5824 -108.4072) (xy 11.5824 -108.6104) (xy 11.7856 -108.6104)
			)
		)
		(polygon
			(pts
				(xy 11.7856 -107.7976) (xy 11.5824 -107.7976) (xy 11.5824 -108.0008) (xy 11.7856 -108.0008)
			)
		)
		(polygon
			(pts
				(xy 11.7856 -107.3912) (xy 11.5824 -107.3912) (xy 11.5824 -107.5944) (xy 11.7856 -107.5944)
			)
		)
		(polygon
			(pts
				(arc
					(start 349.749872 -18.692368)
					(mid 349.749872 -27.30754)
					(end 349.749872 -18.692368)
				)
			)
		)
		(polygon
			(pts
				(arc
					(start 85.449918 -18.575528)
					(mid 85.449918 -27.42438)
					(end 85.449918 -18.575528)
				)
			)
		)
		(polygon
			(pts
				(arc
					(start 74.44994 -9.83615)
					(mid 74.44994 -18.564098)
					(end 74.44994 -9.83615)
				)
			)
		)
		(polygon
			(pts
				(arc
					(start 338.749894 -9.809226)
					(mid 338.749894 -18.591022)
					(end 338.749894 -9.809226)
				)
			)
		)
		(polygon
			(pts
				(arc
					(start 349.749872 -1.090168)
					(mid 349.749872 -9.709912)
					(end 349.749872 -1.090168)
				)
			)
		)
		(polygon
			(pts
				(arc
					(start 85.449918 -1.058672)
					(mid 85.449918 -9.741408)
					(end 85.449918 -1.058672)
				)
			)
		)
	)
	(zone
		(layer "B.Cu")
		(hatch none 0.5)
		(connect_pads
			(clearance 0)
		)
		(min_thickness 0.25)
		(keepout
			(tracks not_allowed)
			(vias allowed)
			(pads allowed)
			(copperpour not_allowed)
			(footprints allowed)
		)
		(placement
			(enabled no)
			(sheetname "")
		)
		(fill
			(thermal_gap 0.5)
			(thermal_bridge_width 0.5)
			(island_removal_mode 0)
		)
		(polygon
			(pts
				(arc
					(start 275.693632 -221.784164)
					(mid 275.183092 -222.294704)
					(end 275.693632 -222.805244)
				)
				(arc
					(start 275.860002 -222.805244)
					(mid 275.830635 -222.672837)
					(end 275.778976 -222.547434)
				)
				(arc
					(start 275.778976 -222.547434)
					(mid 275.534304 -222.081026)
					(end 275.910548 -222.449644)
				)
				(arc
					(start 275.910548 -222.449644)
					(mid 275.984459 -222.621858)
					(end 276.02307 -222.805244)
				)
				(arc
					(start 276.177248 -222.805244)
					(mid 276.215729 -222.621993)
					(end 276.289516 -222.449898)
				)
				(arc
					(start 276.289516 -222.449898)
					(mid 276.665225 -222.080409)
					(end 276.421088 -222.547434)
				)
				(arc
					(start 276.421088 -222.547434)
					(mid 276.369545 -222.672842)
					(end 276.340316 -222.805244)
				)
				(arc
					(start 276.506178 -222.805244)
					(mid 277.016972 -222.294831)
					(end 276.506432 -221.784164)
				)
			)
		)
	)
	(zone
		(layer "B.Cu")
		(hatch none 0.5)
		(connect_pads
			(clearance 0)
		)
		(min_thickness 0.25)
		(keepout
			(tracks allowed)
			(vias allowed)
			(pads allowed)
			(copperpour allowed)
			(footprints not_allowed)
		)
		(placement
			(enabled no)
			(sheetname "")
		)
		(fill
			(thermal_gap 0.5)
			(thermal_bridge_width 0.5)
			(island_removal_mode 0)
		)
		(polygon
			(pts
				(arc
					(start 196.622162 -72.00011)
					(mid 200.622154 -76.000102)
					(end 204.622146 -72.00011)
				)
				(arc
					(start 204.622146 -72.00011)
					(mid 200.622154 -68.000118)
					(end 196.622162 -72.00011)
				)
			)
		)
	)
	(zone
		(layer "B.Cu")
		(hatch none 0.5)
		(connect_pads
			(clearance 0)
		)
		(min_thickness 0.25)
		(keepout
			(tracks not_allowed)
			(vias allowed)
			(pads allowed)
			(copperpour not_allowed)
			(footprints allowed)
		)
		(placement
			(enabled no)
			(sheetname "")
		)
		(fill
			(thermal_gap 0.5)
			(thermal_bridge_width 0.5)
			(island_removal_mode 0)
		)
		(polygon
			(pts
				(arc
					(start 10.061956 -60.300108)
					(mid 13.812012 -64.050164)
					(end 17.562068 -60.300108)
				)
				(arc
					(start 17.562068 -60.300108)
					(mid 13.812012 -56.550052)
					(end 10.061956 -60.300108)
				)
			)
		)
	)
	(zone
		(net "DUT_AVD_PCIE")
		(layer "B.Cu")
		(hatch none 0.5)
		(connect_pads
			(clearance 0.5)
		)
		(min_thickness 0.25)
		(fill yes
			(thermal_gap 0.5)
			(thermal_bridge_width 0.5)
			(island_removal_mode 0)
		)
		(polygon
			(pts
				(xy 178.926998 -62.048136) (xy 178.393598 -62.581536) (xy 178.393598 -69.924168) (xy 178.010566 -70.3072)
				(xy 178.010566 -71.819262) (xy 178.245262 -72.053958) (xy 187.45454 -72.053958) (xy 188.043566 -71.464932)
				(xy 188.043566 -62.683136) (xy 187.408566 -62.048136)
			)
		)
	)
	(zone
		(layer "B.Cu")
		(hatch none 0.5)
		(connect_pads
			(clearance 0)
		)
		(min_thickness 0.25)
		(keepout
			(tracks not_allowed)
			(vias allowed)
			(pads allowed)
			(copperpour not_allowed)
			(footprints allowed)
		)
		(placement
			(enabled no)
			(sheetname "")
		)
		(fill
			(thermal_gap 0.5)
			(thermal_bridge_width 0.5)
			(island_removal_mode 0)
		)
		(polygon
			(pts
				(arc
					(start 99.693476 -221.784164)
					(mid 99.182936 -222.294704)
					(end 99.693476 -222.805244)
				)
				(arc
					(start 99.859846 -222.805244)
					(mid 99.830479 -222.672837)
					(end 99.77882 -222.547434)
				)
				(arc
					(start 99.77882 -222.547434)
					(mid 99.534148 -222.081026)
					(end 99.910392 -222.449644)
				)
				(arc
					(start 99.910392 -222.449644)
					(mid 99.984303 -222.621858)
					(end 100.022914 -222.805244)
				)
				(arc
					(start 100.177092 -222.805244)
					(mid 100.215573 -222.621993)
					(end 100.28936 -222.449898)
				)
				(arc
					(start 100.28936 -222.449898)
					(mid 100.665069 -222.080409)
					(end 100.420932 -222.547434)
				)
				(arc
					(start 100.420932 -222.547434)
					(mid 100.369389 -222.672842)
					(end 100.34016 -222.805244)
				)
				(arc
					(start 100.506022 -222.805244)
					(mid 101.016816 -222.294831)
					(end 100.506276 -221.784164)
				)
			)
		)
	)
	(zone
		(layer "B.Cu")
		(hatch none 0.5)
		(connect_pads
			(clearance 0)
		)
		(min_thickness 0.25)
		(keepout
			(tracks not_allowed)
			(vias allowed)
			(pads allowed)
			(copperpour not_allowed)
			(footprints allowed)
		)
		(placement
			(enabled no)
			(sheetname "")
		)
		(fill
			(thermal_gap 0.5)
			(thermal_bridge_width 0.5)
			(island_removal_mode 0)
		)
		(polygon
			(pts
				(arc
					(start 196.622162 -59.99988)
					(mid 200.622154 -63.999872)
					(end 204.622146 -59.99988)
				)
				(arc
					(start 204.622146 -59.99988)
					(mid 200.622154 -55.999888)
					(end 196.622162 -59.99988)
				)
			)
		)
	)
	(zone
		(layer "B.Cu")
		(hatch none 0.5)
		(connect_pads
			(clearance 0)
		)
		(min_thickness 0.25)
		(keepout
			(tracks allowed)
			(vias allowed)
			(pads allowed)
			(copperpour allowed)
			(footprints not_allowed)
		)
		(placement
			(enabled no)
			(sheetname "")
		)
		(fill
			(thermal_gap 0.5)
			(thermal_bridge_width 0.5)
			(island_removal_mode 0)
		)
		(polygon
			(pts
				(arc
					(start 301.237396 -9.53008)
					(mid 300.137576 -8.43026)
					(end 299.037502 -9.53008)
				)
				(arc
					(start 299.037502 -9.53008)
					(mid 300.137576 -10.630154)
					(end 301.237396 -9.53008)
				)
			)
		)
	)
	(zone
		(layer "B.Cu")
		(hatch none 0.5)
		(connect_pads
			(clearance 0)
		)
		(min_thickness 0.25)
		(keepout
			(tracks not_allowed)
			(vias allowed)
			(pads allowed)
			(copperpour not_allowed)
			(footprints allowed)
		)
		(placement
			(enabled no)
			(sheetname "")
		)
		(fill
			(thermal_gap 0.5)
			(thermal_bridge_width 0.5)
			(island_removal_mode 0)
		)
		(polygon
			(pts
				(arc
					(start 185.069226 -11.697208)
					(mid 184.558813 -11.186414)
					(end 184.048146 -11.696954)
				)
				(arc
					(start 184.048146 -11.88339)
					(mid 184.090567 -11.875443)
					(end 184.13349 -11.870944)
				)
				(xy 184.134506 -11.869928) (xy 184.271158 -11.869928)
				(arc
					(start 184.321704 -11.819382)
					(mid 184.747298 -11.508342)
					(end 184.436258 -11.933936)
				)
				(xy 184.338214 -12.03198)
				(arc
					(start 184.167526 -12.03198)
					(mid 184.10704 -12.036902)
					(end 184.048146 -12.051538)
				)
				(arc
					(start 184.048146 -12.208256)
					(mid 184.088317 -12.188867)
					(end 184.131458 -12.177522)
				)
				(xy 184.134506 -12.174728) (xy 184.338214 -12.174728)
				(arc
					(start 184.436258 -12.272772)
					(mid 184.747298 -12.698366)
					(end 184.321704 -12.387326)
				)
				(xy 184.271158 -12.33678)
				(arc
					(start 184.168034 -12.33678)
					(mid 184.141498 -12.342058)
					(end 184.119012 -12.3571)
				)
				(xy 184.056782 -12.41933) (xy 184.056782 -12.419584) (xy 184.048146 -12.42822)
				(arc
					(start 184.048146 -12.509754)
					(mid 184.558686 -13.020294)
					(end 185.069226 -12.509754)
				)
			)
		)
	)
	(zone
		(net "P0V9")
		(layer "B.Cu")
		(hatch none 0.5)
		(connect_pads
			(clearance 0.5)
		)
		(min_thickness 0.25)
		(fill yes
			(thermal_gap 0.5)
			(thermal_bridge_width 0.5)
			(island_removal_mode 0)
		)
		(polygon
			(pts
				(xy 169.351706 -62.728094) (xy 168.916096 -63.163704) (xy 168.916096 -69.87667) (xy 169.76852 -70.729094)
				(xy 177.673 -70.729094) (xy 177.8762 -70.525894) (xy 177.8762 -68.4276) (xy 178.1048 -68.199) (xy 178.1048 -63.246)
				(xy 177.3936 -63.246) (xy 176.9364 -62.7888) (xy 176.9364 -62.728094)
			)
		)
	)
	(zone
		(layer "B.Cu")
		(hatch none 0.5)
		(connect_pads
			(clearance 0)
		)
		(min_thickness 0.25)
		(keepout
			(tracks not_allowed)
			(vias allowed)
			(pads allowed)
			(copperpour not_allowed)
			(footprints allowed)
		)
		(placement
			(enabled no)
			(sheetname "")
		)
		(fill
			(thermal_gap 0.5)
			(thermal_bridge_width 0.5)
			(island_removal_mode 0)
		)
		(polygon
			(pts
				(arc
					(start 146.493738 -221.784164)
					(mid 145.983198 -222.294704)
					(end 146.493738 -222.805244)
				)
				(arc
					(start 146.660108 -222.805244)
					(mid 146.630741 -222.672837)
					(end 146.579082 -222.547434)
				)
				(arc
					(start 146.579082 -222.547434)
					(mid 146.33441 -222.081026)
					(end 146.710654 -222.449644)
				)
				(arc
					(start 146.710654 -222.449644)
					(mid 146.784565 -222.621858)
					(end 146.823176 -222.805244)
				)
				(arc
					(start 146.977354 -222.805244)
					(mid 147.015835 -222.621993)
					(end 147.089622 -222.449898)
				)
				(arc
					(start 147.089622 -222.449898)
					(mid 147.465331 -222.080409)
					(end 147.221194 -222.547434)
				)
				(arc
					(start 147.221194 -222.547434)
					(mid 147.169651 -222.672842)
					(end 147.140422 -222.805244)
				)
				(arc
					(start 147.306284 -222.805244)
					(mid 147.817078 -222.294831)
					(end 147.306538 -221.784164)
				)
			)
		)
	)
	(zone
		(net "DUT_VDD")
		(layer "B.Cu")
		(hatch none 0.5)
		(connect_pads
			(clearance 0.5)
		)
		(min_thickness 0.25)
		(fill yes
			(thermal_gap 0.5)
			(thermal_bridge_width 0.5)
			(island_removal_mode 0)
		)
		(polygon
			(pts
				(xy 247.9548 -41.3004) (xy 234.8357 -54.4195) (xy 234.8357 -54.5465) (xy 235.0262 -54.737) (xy 235.2294 -54.737)
				(xy 240.20145 -49.76495) (xy 241.16665 -49.76495) (xy 241.3 -49.6316) (xy 241.3 -49.3903) (xy 241.0968 -49.1871)
				(xy 241.0968 -48.8696) (xy 241.2619 -48.7045) (xy 242.2271 -48.7045) (xy 242.4049 -48.5267) (xy 242.4049 -47.5488)
				(xy 248.285 -41.6687) (xy 248.285 -41.4274) (xy 248.158 -41.3004)
			)
		)
		(polygon
			(pts
				(xy 240.7158 -49.0728) (xy 240.5126 -49.0728) (xy 240.5126 -49.276) (xy 240.7158 -49.276)
			)
		)
	)
	(zone
		(layer "B.Cu")
		(hatch none 0.5)
		(connect_pads
			(clearance 0)
		)
		(min_thickness 0.25)
		(keepout
			(tracks not_allowed)
			(vias allowed)
			(pads allowed)
			(copperpour not_allowed)
			(footprints allowed)
		)
		(placement
			(enabled no)
			(sheetname "")
		)
		(fill
			(thermal_gap 0.5)
			(thermal_bridge_width 0.5)
			(island_removal_mode 0)
		)
		(polygon
			(pts
				(arc
					(start 337.149948 -14.200124)
					(mid 338.750148 -15.800324)
					(end 340.350094 -14.200124)
				)
				(arc
					(start 340.350094 -14.200124)
					(mid 338.750148 -12.600178)
					(end 337.149948 -14.200124)
				)
			)
		)
	)
	(zone
		(layer "B.Cu")
		(hatch none 0.5)
		(connect_pads
			(clearance 0)
		)
		(min_thickness 0.25)
		(keepout
			(tracks not_allowed)
			(vias allowed)
			(pads allowed)
			(copperpour not_allowed)
			(footprints allowed)
		)
		(placement
			(enabled no)
			(sheetname "")
		)
		(fill
			(thermal_gap 0.5)
			(thermal_bridge_width 0.5)
			(island_removal_mode 0)
		)
		(polygon
			(pts
				(arc
					(start 313.637422 -9.53008)
					(mid 311.137554 -7.030212)
					(end 308.637432 -9.53008)
				)
				(arc
					(start 308.637432 -9.53008)
					(mid 311.137554 -12.030202)
					(end 313.637422 -9.53008)
				)
			)
		)
	)
	(zone
		(layer "B.Cu")
		(hatch none 0.5)
		(connect_pads
			(clearance 0)
		)
		(min_thickness 0.25)
		(keepout
			(tracks not_allowed)
			(vias allowed)
			(pads allowed)
			(copperpour not_allowed)
			(footprints allowed)
		)
		(placement
			(enabled no)
			(sheetname "")
		)
		(fill
			(thermal_gap 0.5)
			(thermal_bridge_width 0.5)
			(island_removal_mode 0)
		)
		(polygon
			(pts
				(arc
					(start 340.493858 -221.784164)
					(mid 339.983064 -222.294577)
					(end 340.493604 -222.805244)
				)
				(arc
					(start 340.659974 -222.805244)
					(mid 340.630607 -222.672837)
					(end 340.578948 -222.547434)
				)
				(arc
					(start 340.578948 -222.547434)
					(mid 340.334276 -222.081026)
					(end 340.71052 -222.449644)
				)
				(arc
					(start 340.71052 -222.449644)
					(mid 340.784431 -222.621858)
					(end 340.823042 -222.805244)
				)
				(arc
					(start 340.97722 -222.805244)
					(mid 341.015701 -222.621993)
					(end 341.089488 -222.449898)
				)
				(arc
					(start 341.089488 -222.449898)
					(mid 341.465197 -222.080409)
					(end 341.22106 -222.547434)
				)
				(arc
					(start 341.22106 -222.547434)
					(mid 341.169517 -222.672842)
					(end 341.140288 -222.805244)
				)
				(arc
					(start 341.306404 -222.805244)
					(mid 341.816944 -222.294704)
					(end 341.306404 -221.784164)
				)
			)
		)
	)
	(zone
		(layer "B.Cu")
		(hatch none 0.5)
		(connect_pads
			(clearance 0)
		)
		(min_thickness 0.25)
		(keepout
			(tracks allowed)
			(vias allowed)
			(pads allowed)
			(copperpour allowed)
			(footprints allowed)
		)
		(placement
			(enabled no)
			(sheetname "")
		)
		(fill
			(thermal_gap 0.5)
			(thermal_bridge_width 0.5)
			(island_removal_mode 0)
		)
		(polygon
			(pts
				(xy 38.9382 -114.5032) (xy 38.9382 -113.4872) (xy 39.9542 -113.4872) (xy 39.9542 -114.5032)
			)
		)
	)
	(zone
		(layer "B.Cu")
		(hatch none 0.5)
		(connect_pads
			(clearance 0)
		)
		(min_thickness 0.25)
		(keepout
			(tracks not_allowed)
			(vias allowed)
			(pads allowed)
			(copperpour not_allowed)
			(footprints allowed)
		)
		(placement
			(enabled no)
			(sheetname "")
		)
		(fill
			(thermal_gap 0.5)
			(thermal_bridge_width 0.5)
			(island_removal_mode 0)
		)
		(polygon
			(pts
				(arc
					(start 50.144934 -208.201514)
					(mid 49.63414 -208.711927)
					(end 50.14468 -209.222594)
				)
				(xy 50.33772 -209.222594)
				(arc
					(start 50.33772 -209.175096)
					(mid 50.318589 -209.056956)
					(end 50.263298 -208.950814)
				)
				(arc
					(start 50.263298 -208.950814)
					(mid 49.958792 -208.520946)
					(end 50.380138 -208.837276)
				)
				(arc
					(start 50.380138 -208.837276)
					(mid 50.462998 -208.979969)
					(end 50.498756 -209.14106)
				)
				(xy 50.499772 -209.142076) (xy 50.499772 -209.222594) (xy 50.64252 -209.222594) (xy 50.64252 -209.142076)
				(xy 50.642774 -209.141822) (xy 50.642774 -209.110072)
				(arc
					(start 50.64379 -209.109056)
					(mid 50.66939 -208.973023)
					(end 50.72761 -208.847436)
				)
				(arc
					(start 50.72761 -208.847436)
					(mid 51.134069 -208.512092)
					(end 50.851562 -208.95691)
				)
				(arc
					(start 50.851562 -208.95691)
					(mid 50.818519 -209.040498)
					(end 50.80508 -209.129376)
				)
				(xy 50.80508 -209.177128) (xy 50.804826 -209.177382) (xy 50.804826 -209.208624) (xy 50.804572 -209.208878)
				(xy 50.804572 -209.222594)
				(arc
					(start 50.95748 -209.222594)
					(mid 51.46802 -208.712054)
					(end 50.95748 -208.201514)
				)
			)
		)
	)
	(zone
		(net "P3V3_STBY")
		(layer "B.Cu")
		(hatch none 0.5)
		(connect_pads
			(clearance 0.5)
		)
		(min_thickness 0.25)
		(fill yes
			(thermal_gap 0.5)
			(thermal_bridge_width 0.5)
			(island_removal_mode 0)
		)
		(polygon
			(pts
				(xy 77.47 -171.196) (xy 77.216 -171.45) (xy 77.216 -172.339) (xy 85.852 -180.975) (xy 97.79 -180.975)
				(xy 114.681 -197.866) (xy 121.539 -197.866) (xy 122.428 -196.977) (xy 123.063 -196.977) (xy 123.698 -196.342)
				(xy 123.952 -196.342) (xy 124.079 -196.215) (xy 124.079 -195.707) (xy 123.698 -195.326) (xy 115.57 -195.326)
				(xy 99.949 -179.705) (xy 87.249 -179.705) (xy 78.74 -171.196)
			)
		)
	)
	(zone
		(layer "B.Cu")
		(hatch none 0.5)
		(connect_pads
			(clearance 0)
		)
		(min_thickness 0.25)
		(keepout
			(tracks not_allowed)
			(vias allowed)
			(pads allowed)
			(copperpour not_allowed)
			(footprints allowed)
		)
		(placement
			(enabled no)
			(sheetname "")
		)
		(fill
			(thermal_gap 0.5)
			(thermal_bridge_width 0.5)
			(island_removal_mode 0)
		)
		(polygon
			(pts
				(arc
					(start 185.693812 -221.784164)
					(mid 185.183018 -222.294577)
					(end 185.693558 -222.805244)
				)
				(arc
					(start 185.859928 -222.805244)
					(mid 185.830561 -222.672837)
					(end 185.778902 -222.547434)
				)
				(arc
					(start 185.778902 -222.547434)
					(mid 185.53423 -222.081026)
					(end 185.910474 -222.449644)
				)
				(arc
					(start 185.910474 -222.449644)
					(mid 185.984385 -222.621858)
					(end 186.022996 -222.805244)
				)
				(arc
					(start 186.177174 -222.805244)
					(mid 186.215655 -222.621993)
					(end 186.289442 -222.449898)
				)
				(arc
					(start 186.289442 -222.449898)
					(mid 186.665151 -222.080409)
					(end 186.421014 -222.547434)
				)
				(arc
					(start 186.421014 -222.547434)
					(mid 186.369471 -222.672842)
					(end 186.340242 -222.805244)
				)
				(arc
					(start 186.506358 -222.805244)
					(mid 187.016898 -222.294704)
					(end 186.506358 -221.784164)
				)
			)
		)
	)
	(zone
		(layer "B.Cu")
		(hatch none 0.5)
		(connect_pads
			(clearance 0)
		)
		(min_thickness 0.25)
		(keepout
			(tracks not_allowed)
			(vias allowed)
			(pads allowed)
			(copperpour not_allowed)
			(footprints allowed)
		)
		(placement
			(enabled no)
			(sheetname "")
		)
		(fill
			(thermal_gap 0.5)
			(thermal_bridge_width 0.5)
			(island_removal_mode 0)
		)
		(polygon
			(pts
				(arc
					(start 211.29371 -221.784164)
					(mid 210.78317 -222.294704)
					(end 211.29371 -222.805244)
				)
				(arc
					(start 211.46008 -222.805244)
					(mid 211.430713 -222.672837)
					(end 211.379054 -222.547434)
				)
				(arc
					(start 211.379054 -222.547434)
					(mid 211.134382 -222.081026)
					(end 211.510626 -222.449644)
				)
				(arc
					(start 211.510626 -222.449644)
					(mid 211.584537 -222.621858)
					(end 211.623148 -222.805244)
				)
				(arc
					(start 211.777326 -222.805244)
					(mid 211.815807 -222.621993)
					(end 211.889594 -222.449898)
				)
				(arc
					(start 211.889594 -222.449898)
					(mid 212.265303 -222.080409)
					(end 212.021166 -222.547434)
				)
				(arc
					(start 212.021166 -222.547434)
					(mid 211.969623 -222.672842)
					(end 211.940394 -222.805244)
				)
				(arc
					(start 212.106256 -222.805244)
					(mid 212.61705 -222.294831)
					(end 212.10651 -221.784164)
				)
			)
		)
	)
	(zone
		(net "DUT_VDD")
		(layer "B.Cu")
		(hatch none 0.5)
		(connect_pads
			(clearance 0.5)
		)
		(min_thickness 0.25)
		(fill yes
			(thermal_gap 0.5)
			(thermal_bridge_width 0.5)
			(island_removal_mode 0)
		)
		(polygon
			(pts
				(xy 237.0836 -41.1734) (xy 233.8197 -44.4373) (xy 233.8197 -44.5643) (xy 234.0102 -44.7548) (xy 234.2261 -44.7548)
				(xy 237.43285 -41.54805) (xy 237.43285 -41.43375) (xy 237.1725 -41.1734)
			)
		)
	)
	(zone
		(layer "B.Cu")
		(hatch none 0.5)
		(connect_pads
			(clearance 0)
		)
		(min_thickness 0.25)
		(keepout
			(tracks not_allowed)
			(vias allowed)
			(pads allowed)
			(copperpour not_allowed)
			(footprints allowed)
		)
		(placement
			(enabled no)
			(sheetname "")
		)
		(fill
			(thermal_gap 0.5)
			(thermal_bridge_width 0.5)
			(island_removal_mode 0)
		)
		(polygon
			(pts
				(arc
					(start 144.637506 -9.53008)
					(mid 147.137628 -12.030202)
					(end 149.637496 -9.53008)
				)
				(arc
					(start 149.637496 -9.53008)
					(mid 147.137628 -7.030212)
					(end 144.637506 -9.53008)
				)
			)
		)
	)
	(zone
		(layer "B.Cu")
		(hatch none 0.5)
		(connect_pads
			(clearance 0)
		)
		(min_thickness 0.25)
		(keepout
			(tracks allowed)
			(vias allowed)
			(pads allowed)
			(copperpour allowed)
			(footprints not_allowed)
		)
		(placement
			(enabled no)
			(sheetname "")
		)
		(fill
			(thermal_gap 0.5)
			(thermal_bridge_width 0.5)
			(island_removal_mode 0)
		)
		(polygon
			(pts
				(arc
					(start 81.449926 -5.40004)
					(mid 85.449918 -9.400032)
					(end 89.44991 -5.40004)
				)
				(arc
					(start 89.44991 -5.40004)
					(mid 85.449918 -1.400048)
					(end 81.449926 -5.40004)
				)
			)
		)
	)
	(zone
		(layer "B.Cu")
		(hatch none 0.5)
		(connect_pads
			(clearance 0)
		)
		(min_thickness 0.25)
		(keepout
			(tracks allowed)
			(vias allowed)
			(pads allowed)
			(copperpour allowed)
			(footprints not_allowed)
		)
		(placement
			(enabled no)
			(sheetname "")
		)
		(fill
			(thermal_gap 0.5)
			(thermal_bridge_width 0.5)
			(island_removal_mode 0)
		)
		(polygon
			(pts
				(arc
					(start 137.23747 -9.53008)
					(mid 136.13765 -8.43026)
					(end 135.037576 -9.53008)
				)
				(arc
					(start 135.037576 -9.53008)
					(mid 136.13765 -10.630154)
					(end 137.23747 -9.53008)
				)
			)
		)
	)
	(zone
		(layer "B.Cu")
		(hatch none 0.5)
		(connect_pads
			(clearance 0)
		)
		(min_thickness 0.25)
		(keepout
			(tracks allowed)
			(vias allowed)
			(pads allowed)
			(copperpour allowed)
			(footprints not_allowed)
		)
		(placement
			(enabled no)
			(sheetname "")
		)
		(fill
			(thermal_gap 0.5)
			(thermal_bridge_width 0.5)
			(island_removal_mode 0)
		)
		(polygon
			(pts
				(arc
					(start 345.74988 -5.40004)
					(mid 349.750126 -9.400286)
					(end 353.750118 -5.40004)
				)
				(arc
					(start 353.750118 -5.40004)
					(mid 349.750126 -1.400048)
					(end 345.74988 -5.40004)
				)
			)
		)
	)
	(zone
		(layer "B.Cu")
		(hatch none 0.5)
		(connect_pads
			(clearance 0)
		)
		(min_thickness 0.25)
		(keepout
			(tracks allowed)
			(vias allowed)
			(pads allowed)
			(copperpour allowed)
			(footprints allowed)
		)
		(placement
			(enabled no)
			(sheetname "")
		)
		(fill
			(thermal_gap 0.5)
			(thermal_bridge_width 0.5)
			(island_removal_mode 0)
		)
		(polygon
			(pts
				(xy 27.1272 -227.9142) (xy 27.1272 -221.6912) (xy 112.7252 -221.6912) (xy 112.7252 -227.9142)
			)
		)
	)
	(zone
		(layer "B.Cu")
		(hatch none 0.5)
		(connect_pads
			(clearance 0)
		)
		(min_thickness 0.25)
		(keepout
			(tracks not_allowed)
			(vias allowed)
			(pads allowed)
			(copperpour not_allowed)
			(footprints allowed)
		)
		(placement
			(enabled no)
			(sheetname "")
		)
		(fill
			(thermal_gap 0.5)
			(thermal_bridge_width 0.5)
			(island_removal_mode 0)
		)
		(polygon
			(pts
				(arc
					(start 327.693782 -221.784164)
					(mid 327.183242 -222.294704)
					(end 327.693782 -222.805244)
				)
				(arc
					(start 327.860152 -222.805244)
					(mid 327.830785 -222.672837)
					(end 327.779126 -222.547434)
				)
				(arc
					(start 327.779126 -222.547434)
					(mid 327.534454 -222.081026)
					(end 327.910698 -222.449644)
				)
				(arc
					(start 327.910698 -222.449644)
					(mid 327.984609 -222.621858)
					(end 328.02322 -222.805244)
				)
				(arc
					(start 328.177398 -222.805244)
					(mid 328.215879 -222.621993)
					(end 328.289666 -222.449898)
				)
				(arc
					(start 328.289666 -222.449898)
					(mid 328.665375 -222.080409)
					(end 328.421238 -222.547434)
				)
				(arc
					(start 328.421238 -222.547434)
					(mid 328.369695 -222.672842)
					(end 328.340466 -222.805244)
				)
				(arc
					(start 328.506328 -222.805244)
					(mid 329.017122 -222.294831)
					(end 328.506582 -221.784164)
				)
			)
		)
	)
	(zone
		(layer "B.Cu")
		(hatch none 0.5)
		(connect_pads
			(clearance 0)
		)
		(min_thickness 0.25)
		(keepout
			(tracks not_allowed)
			(vias allowed)
			(pads allowed)
			(copperpour not_allowed)
			(footprints allowed)
		)
		(placement
			(enabled no)
			(sheetname "")
		)
		(fill
			(thermal_gap 0.5)
			(thermal_bridge_width 0.5)
			(island_removal_mode 0)
		)
		(polygon
			(pts
				(arc
					(start 202.2221 -59.99988)
					(mid 200.622154 -58.399934)
					(end 199.021954 -59.99988)
				)
				(arc
					(start 199.021954 -59.99988)
					(mid 200.622154 -61.60008)
					(end 202.2221 -59.99988)
				)
			)
		)
	)
	(zone
		(layer "B.Cu")
		(hatch none 0.5)
		(connect_pads
			(clearance 0)
		)
		(min_thickness 0.25)
		(keepout
			(tracks allowed)
			(vias allowed)
			(pads allowed)
			(copperpour allowed)
			(footprints not_allowed)
		)
		(placement
			(enabled no)
			(sheetname "")
		)
		(fill
			(thermal_gap 0.5)
			(thermal_bridge_width 0.5)
			(island_removal_mode 0)
		)
		(polygon
			(pts
				(arc
					(start 302.637444 -9.53008)
					(mid 300.137576 -7.030212)
					(end 297.637454 -9.53008)
				)
				(arc
					(start 297.637454 -9.53008)
					(mid 300.137576 -12.030202)
					(end 302.637444 -9.53008)
				)
			)
		)
	)
	(zone
		(net "GND")
		(layer "B.Cu")
		(hatch none 0.5)
		(connect_pads
			(clearance 0.5)
		)
		(min_thickness 0.25)
		(fill yes
			(thermal_gap 0.5)
			(thermal_bridge_width 0.5)
			(island_removal_mode 0)
		)
		(polygon
			(pts
				(xy 169.8752 -71.882) (xy 169.7482 -72.009) (xy 169.7482 -76.7588) (xy 169.914062 -76.924662) (xy 173.881034 -76.924662)
				(xy 174.008034 -76.797662) (xy 174.008034 -72.225662) (xy 173.664372 -71.882)
			)
		)
	)
	(zone
		(layer "B.Cu")
		(hatch none 0.5)
		(connect_pads
			(clearance 0)
		)
		(min_thickness 0.25)
		(keepout
			(tracks allowed)
			(vias allowed)
			(pads allowed)
			(copperpour allowed)
			(footprints not_allowed)
		)
		(placement
			(enabled no)
			(sheetname "")
		)
		(fill
			(thermal_gap 0.5)
			(thermal_bridge_width 0.5)
			(island_removal_mode 0)
		)
		(polygon
			(pts
				(arc
					(start 155.637484 -9.53008)
					(mid 158.137606 -12.030202)
					(end 160.637474 -9.53008)
				)
				(arc
					(start 160.637474 -9.53008)
					(mid 158.137606 -7.030212)
					(end 155.637484 -9.53008)
				)
			)
		)
	)
	(zone
		(net "GND")
		(layer "B.Cu")
		(hatch none 0.5)
		(connect_pads
			(clearance 0.5)
		)
		(min_thickness 0.25)
		(fill yes
			(thermal_gap 0.5)
			(thermal_bridge_width 0.5)
			(island_removal_mode 0)
		)
		(polygon
			(pts
				(xy 337.489292 -59.385708) (xy 336.84083 -60.03417) (xy 336.84083 -69.47408) (xy 337.08975 -69.723)
				(xy 341.249 -69.723) (xy 341.376 -69.596) (xy 341.376 -64.643) (xy 340.487 -63.754) (xy 340.487 -59.63031)
				(xy 340.242398 -59.385708)
			)
		)
		(polygon
			(pts
				(xy 337.6676 -63.7032) (xy 337.4644 -63.7032) (xy 337.4644 -63.9064) (xy 337.6676 -63.9064)
			)
		)
		(polygon
			(pts
				(xy 337.6676 -63.0936) (xy 337.4644 -63.0936) (xy 337.4644 -63.2968) (xy 337.6676 -63.2968)
			)
		)
	)
	(zone
		(layer "B.Cu")
		(hatch none 0.5)
		(connect_pads
			(clearance 0)
		)
		(min_thickness 0.25)
		(keepout
			(tracks not_allowed)
			(vias allowed)
			(pads allowed)
			(copperpour not_allowed)
			(footprints allowed)
		)
		(placement
			(enabled no)
			(sheetname "")
		)
		(fill
			(thermal_gap 0.5)
			(thermal_bridge_width 0.5)
			(island_removal_mode 0)
		)
		(polygon
			(pts
				(arc
					(start 199.021954 -72.00011)
					(mid 200.622154 -73.60031)
					(end 202.2221 -72.00011)
				)
				(arc
					(start 202.2221 -72.00011)
					(mid 200.622154 -70.400164)
					(end 199.021954 -72.00011)
				)
			)
		)
	)
	(zone
		(layer "B.Cu")
		(hatch none 0.5)
		(connect_pads
			(clearance 0)
		)
		(min_thickness 0.25)
		(keepout
			(tracks not_allowed)
			(vias allowed)
			(pads allowed)
			(copperpour not_allowed)
			(footprints allowed)
		)
		(placement
			(enabled no)
			(sheetname "")
		)
		(fill
			(thermal_gap 0.5)
			(thermal_bridge_width 0.5)
			(island_removal_mode 0)
		)
		(polygon
			(pts
				(arc
					(start 84.493354 -221.784164)
					(mid 83.982814 -222.294704)
					(end 84.493354 -222.805244)
				)
				(arc
					(start 84.659724 -222.805244)
					(mid 84.630357 -222.672837)
					(end 84.578698 -222.547434)
				)
				(arc
					(start 84.578698 -222.547434)
					(mid 84.334026 -222.081026)
					(end 84.71027 -222.449644)
				)
				(arc
					(start 84.71027 -222.449644)
					(mid 84.784181 -222.621858)
					(end 84.822792 -222.805244)
				)
				(arc
					(start 84.97697 -222.805244)
					(mid 85.015451 -222.621993)
					(end 85.089238 -222.449898)
				)
				(arc
					(start 85.089238 -222.449898)
					(mid 85.464947 -222.080409)
					(end 85.22081 -222.547434)
				)
				(arc
					(start 85.22081 -222.547434)
					(mid 85.169267 -222.672842)
					(end 85.140038 -222.805244)
				)
				(arc
					(start 85.3059 -222.805244)
					(mid 85.816694 -222.294831)
					(end 85.306154 -221.784164)
				)
			)
		)
	)
	(zone
		(net "GND")
		(layer "B.Cu")
		(hatch none 0.5)
		(connect_pads
			(clearance 0.5)
		)
		(min_thickness 0.25)
		(fill yes
			(thermal_gap 0.5)
			(thermal_bridge_width 0.5)
			(island_removal_mode 0)
		)
		(polygon
			(pts
				(xy 230.632 -67.056) (xy 230.378 -67.31) (xy 230.378 -72.517) (xy 230.632 -72.771) (xy 234.569 -72.771)
				(xy 234.95 -72.39) (xy 234.95 -67.183) (xy 234.823 -67.056)
			)
		)
	)
	(zone
		(layer "B.Cu")
		(hatch none 0.5)
		(connect_pads
			(clearance 0)
		)
		(min_thickness 0.25)
		(keepout
			(tracks not_allowed)
			(vias allowed)
			(pads allowed)
			(copperpour not_allowed)
			(footprints allowed)
		)
		(placement
			(enabled no)
			(sheetname "")
		)
		(fill
			(thermal_gap 0.5)
			(thermal_bridge_width 0.5)
			(island_removal_mode 0)
		)
		(polygon
			(pts
				(arc
					(start 214.493602 -221.784164)
					(mid 213.983062 -222.294704)
					(end 214.493602 -222.805244)
				)
				(arc
					(start 214.659972 -222.805244)
					(mid 214.630605 -222.672837)
					(end 214.578946 -222.547434)
				)
				(arc
					(start 214.578946 -222.547434)
					(mid 214.334274 -222.081026)
					(end 214.710518 -222.449644)
				)
				(arc
					(start 214.710518 -222.449644)
					(mid 214.784429 -222.621858)
					(end 214.82304 -222.805244)
				)
				(arc
					(start 214.977218 -222.805244)
					(mid 215.015699 -222.621993)
					(end 215.089486 -222.449898)
				)
				(arc
					(start 215.089486 -222.449898)
					(mid 215.465195 -222.080409)
					(end 215.221058 -222.547434)
				)
				(arc
					(start 215.221058 -222.547434)
					(mid 215.169515 -222.672842)
					(end 215.140286 -222.805244)
				)
				(arc
					(start 215.306148 -222.805244)
					(mid 215.816942 -222.294831)
					(end 215.306402 -221.784164)
				)
			)
		)
	)
	(zone
		(layer "B.Cu")
		(hatch none 0.5)
		(connect_pads
			(clearance 0)
		)
		(min_thickness 0.25)
		(keepout
			(tracks allowed)
			(vias allowed)
			(pads allowed)
			(copperpour allowed)
			(footprints allowed)
		)
		(placement
			(enabled no)
			(sheetname "")
		)
		(fill
			(thermal_gap 0.5)
			(thermal_bridge_width 0.5)
			(island_removal_mode 0)
		)
		(polygon
			(pts
				(xy 270.117824 -6.71322) (xy 270.117824 -5.730748) (xy 272.017744 -5.730748) (xy 272.017744 -6.71322)
			)
		)
	)
	(zone
		(net "GND")
		(layer "B.Cu")
		(hatch none 0.5)
		(connect_pads
			(clearance 0.5)
		)
		(min_thickness 0.25)
		(fill yes
			(thermal_gap 0.5)
			(thermal_bridge_width 0.5)
			(island_removal_mode 0)
		)
		(polygon
			(pts
				(xy 140.97 -90.297) (xy 140.843 -90.424) (xy 140.843 -91.821) (xy 141.097 -92.075) (xy 143.51 -92.075)
				(xy 143.637 -91.948) (xy 143.637 -90.424) (xy 143.51 -90.297)
			)
		)
		(polygon
			(pts
				(xy 142.781274 -91.35872) (xy 142.578074 -91.35872) (xy 142.578074 -91.56192) (xy 142.781274 -91.56192)
			)
		)
		(polygon
			(pts
				(xy 142.171674 -91.35872) (xy 141.968474 -91.35872) (xy 141.968474 -91.56192) (xy 142.171674 -91.56192)
			)
		)
		(polygon
			(pts
				(xy 141.765274 -91.35872) (xy 141.562074 -91.35872) (xy 141.562074 -91.56192) (xy 141.765274 -91.56192)
			)
		)
		(polygon
			(pts
				(xy 141.155674 -91.35872) (xy 140.952474 -91.35872) (xy 140.952474 -91.56192) (xy 141.155674 -91.56192)
			)
		)
	)
	(zone
		(layer "B.Cu")
		(hatch none 0.5)
		(connect_pads
			(clearance 0)
		)
		(min_thickness 0.25)
		(keepout
			(tracks not_allowed)
			(vias allowed)
			(pads allowed)
			(copperpour not_allowed)
			(footprints allowed)
		)
		(placement
			(enabled no)
			(sheetname "")
		)
		(fill
			(thermal_gap 0.5)
			(thermal_bridge_width 0.5)
			(island_removal_mode 0)
		)
		(polygon
			(pts
				(arc
					(start 160.637474 -9.53008)
					(mid 158.137606 -7.030212)
					(end 155.637484 -9.53008)
				)
				(arc
					(start 155.637484 -9.53008)
					(mid 158.137606 -12.030202)
					(end 160.637474 -9.53008)
				)
			)
		)
	)
	(zone
		(net "P0V9_I210")
		(layer "B.Cu")
		(hatch none 0.5)
		(connect_pads
			(clearance 0.5)
		)
		(min_thickness 0.25)
		(fill yes
			(thermal_gap 0.5)
			(thermal_bridge_width 0.5)
			(island_removal_mode 0)
		)
		(polygon
			(pts
				(xy 18.10258 -68.67398) (xy 17.03197 -69.74459) (xy 16.19885 -69.74459) (xy 12.74826 -73.19518)
				(xy 12.74826 -74.140822) (xy 12.864084 -74.256646) (xy 14.388846 -74.256646) (xy 14.579854 -74.447654)
				(xy 14.579854 -75.209654) (xy 14.674342 -75.304142) (xy 15.936468 -75.304142) (xy 16.01216 -75.22845)
				(xy 16.01216 -74.2696) (xy 15.60576 -73.8632) (xy 14.6304 -73.8632) (xy 14.3764 -73.6092) (xy 14.3764 -72.9488)
				(xy 15.34414 -71.98106) (xy 20.80006 -71.98106) (xy 21.7932 -72.9742) (xy 21.7932 -75.042522) (xy 21.701252 -75.13447)
				(xy 20.872958 -75.13447) (xy 20.70354 -75.303888) (xy 20.70354 -77.28966) (xy 20.7264 -77.28966)
				(xy 19.685 -78.33106) (xy 19.685 -79.2226) (xy 17.8308 -81.0768) (xy 15.3416 -81.0768) (xy 15.113 -80.8482)
				(xy 15.113 -78.9686) (xy 14.859 -78.7146) (xy 13.6652 -78.7146) (xy 13.335 -78.3844) (xy 13.335 -77.597)
				(xy 12.827 -77.089) (xy 12.526264 -77.089) (xy 12.345924 -76.90866) (xy 11.713972 -76.90866) (xy 11.6078 -77.014832)
				(xy 11.6078 -77.1398) (xy 11.6078 -81.4324) (xy 12.3698 -82.1944) (xy 14.3764 -82.1944) (xy 14.3891 -82.1817)
				(xy 14.6304 -82.423) (xy 17.7546 -82.423) (xy 18.8976 -81.28) (xy 21.59 -81.28) (xy 21.6154 -81.3054)
				(xy 22.86 -81.3054) (xy 22.86 -75.86472) (xy 23.375874 -75.348846) (xy 23.375874 -72.458326) (xy 19.591528 -68.67398)
			)
		)
		(polygon
			(pts
				(xy 12.8016 -77.597) (xy 12.5984 -77.597) (xy 12.5984 -77.8002) (xy 12.8016 -77.8002)
			)
		)
		(polygon
			(pts
				(xy 15.489428 -74.576178) (xy 15.286228 -74.576178) (xy 15.286228 -74.779378) (xy 15.489428 -74.779378)
			)
		)
	)
	(zone
		(net "P0V9_E")
		(layer "B.Cu")
		(hatch none 0.5)
		(connect_pads
			(clearance 0.5)
		)
		(min_thickness 0.25)
		(fill yes
			(thermal_gap 0.5)
			(thermal_bridge_width 0.5)
			(island_removal_mode 0)
		)
		(polygon
			(pts
				(xy 310.642 -55.88) (xy 310.261 -56.261) (xy 310.261 -68.072) (xy 310.388 -68.199) (xy 321.2338 -68.199)
				(xy 321.4624 -67.9704) (xy 321.4624 -56.134) (xy 321.2084 -55.88)
			)
		)
	)
	(zone
		(layer "B.Cu")
		(hatch none 0.5)
		(connect_pads
			(clearance 0)
		)
		(min_thickness 0.25)
		(keepout
			(tracks not_allowed)
			(vias allowed)
			(pads allowed)
			(copperpour not_allowed)
			(footprints allowed)
		)
		(placement
			(enabled no)
			(sheetname "")
		)
		(fill
			(thermal_gap 0.5)
			(thermal_bridge_width 0.5)
			(island_removal_mode 0)
		)
		(polygon
			(pts
				(arc
					(start 106.093514 -221.784164)
					(mid 105.582974 -222.294704)
					(end 106.093514 -222.805244)
				)
				(arc
					(start 106.259884 -222.805244)
					(mid 106.230517 -222.672837)
					(end 106.178858 -222.547434)
				)
				(arc
					(start 106.178858 -222.547434)
					(mid 105.934186 -222.081026)
					(end 106.31043 -222.449644)
				)
				(arc
					(start 106.31043 -222.449644)
					(mid 106.384341 -222.621858)
					(end 106.422952 -222.805244)
				)
				(arc
					(start 106.57713 -222.805244)
					(mid 106.615611 -222.621993)
					(end 106.689398 -222.449898)
				)
				(arc
					(start 106.689398 -222.449898)
					(mid 107.065107 -222.080409)
					(end 106.82097 -222.547434)
				)
				(arc
					(start 106.82097 -222.547434)
					(mid 106.769427 -222.672842)
					(end 106.740198 -222.805244)
				)
				(arc
					(start 106.90606 -222.805244)
					(mid 107.416854 -222.294831)
					(end 106.906314 -221.784164)
				)
			)
		)
	)
	(zone
		(layer "B.Cu")
		(hatch none 0.5)
		(connect_pads
			(clearance 0)
		)
		(min_thickness 0.25)
		(keepout
			(tracks not_allowed)
			(vias allowed)
			(pads allowed)
			(copperpour not_allowed)
			(footprints allowed)
		)
		(placement
			(enabled no)
			(sheetname "")
		)
		(fill
			(thermal_gap 0.5)
			(thermal_bridge_width 0.5)
			(island_removal_mode 0)
		)
		(polygon
			(pts
				(arc
					(start 348.149926 -22.999954)
					(mid 349.750126 -24.600154)
					(end 351.350072 -22.999954)
				)
				(arc
					(start 351.350072 -22.999954)
					(mid 349.750126 -21.400008)
					(end 348.149926 -22.999954)
				)
			)
		)
	)
	(zone
		(layer "B.Cu")
		(hatch none 0.5)
		(connect_pads
			(clearance 0)
		)
		(min_thickness 0.25)
		(keepout
			(tracks allowed)
			(vias allowed)
			(pads allowed)
			(copperpour allowed)
			(footprints not_allowed)
		)
		(placement
			(enabled no)
			(sheetname "")
		)
		(fill
			(thermal_gap 0.5)
			(thermal_bridge_width 0.5)
			(island_removal_mode 0)
		)
		(polygon
			(pts
				(arc
					(start 351.350072 -5.40004)
					(mid 349.750126 -3.800094)
					(end 348.149926 -5.40004)
				)
				(arc
					(start 348.149926 -5.40004)
					(mid 349.750126 -7.00024)
					(end 351.350072 -5.40004)
				)
			)
		)
	)
	(zone
		(layer "B.Cu")
		(hatch none 0.5)
		(connect_pads
			(clearance 0)
		)
		(min_thickness 0.25)
		(keepout
			(tracks allowed)
			(vias allowed)
			(pads allowed)
			(copperpour allowed)
			(footprints not_allowed)
		)
		(placement
			(enabled no)
			(sheetname "")
		)
		(fill
			(thermal_gap 0.5)
			(thermal_bridge_width 0.5)
			(island_removal_mode 0)
		)
		(polygon
			(pts
				(arc
					(start 337.149948 -14.200124)
					(mid 338.750148 -15.800324)
					(end 340.350094 -14.200124)
				)
				(arc
					(start 340.350094 -14.200124)
					(mid 338.750148 -12.600178)
					(end 337.149948 -14.200124)
				)
			)
		)
	)
	(zone
		(layer "B.Cu")
		(hatch none 0.5)
		(connect_pads
			(clearance 0)
		)
		(min_thickness 0.25)
		(keepout
			(tracks allowed)
			(vias allowed)
			(pads allowed)
			(copperpour allowed)
			(footprints not_allowed)
		)
		(placement
			(enabled no)
			(sheetname "")
		)
		(fill
			(thermal_gap 0.5)
			(thermal_bridge_width 0.5)
			(island_removal_mode 0)
		)
		(polygon
			(pts
				(arc
					(start 5.999988 -203.499974)
					(mid 9.99998 -207.499966)
					(end 13.999972 -203.499974)
				)
				(arc
					(start 13.999972 -203.499974)
					(mid 9.99998 -199.499982)
					(end 5.999988 -203.499974)
				)
			)
		)
	)
	(zone
		(layer "B.Cu")
		(hatch none 0.5)
		(connect_pads
			(clearance 0)
		)
		(min_thickness 0.25)
		(keepout
			(tracks not_allowed)
			(vias allowed)
			(pads allowed)
			(copperpour not_allowed)
			(footprints allowed)
		)
		(placement
			(enabled no)
			(sheetname "")
		)
		(fill
			(thermal_gap 0.5)
			(thermal_bridge_width 0.5)
			(island_removal_mode 0)
		)
		(polygon
			(pts
				(arc
					(start 282.908756 -21.04771)
					(mid 283.435023 -21.073537)
					(end 282.926028 -21.209762)
				)
				(arc
					(start 282.926028 -21.209762)
					(mid 282.819027 -21.239216)
					(end 282.715462 -21.279104)
				)
				(xy 282.67533 -21.319236) (xy 282.788614 -21.44522)
				(arc
					(start 282.790646 -21.443442)
					(mid 283.511498 -21.481034)
					(end 283.54909 -20.760182)
				)
				(xy 283.551122 -20.758404) (xy 283.007308 -20.154646) (xy 283.0068 -20.154646)
				(arc
					(start 283.005276 -20.15617)
					(mid 282.284107 -20.118381)
					(end 282.246578 -20.83943)
				)
				(xy 282.244546 -20.841208) (xy 282.362148 -20.971764)
				(arc
					(start 282.414472 -20.919694)
					(mid 282.46653 -20.831028)
					(end 282.505912 -20.736052)
				)
				(arc
					(start 282.505912 -20.736052)
					(mid 282.666643 -20.23423)
					(end 282.667964 -20.761198)
				)
				(arc
					(start 282.667964 -20.761198)
					(mid 282.621435 -20.882881)
					(end 282.557982 -20.996656)
				)
				(xy 282.557982 -21.005292) (xy 282.47086 -21.092414) (xy 282.566618 -21.19884) (xy 282.635198 -21.13026)
				(arc
					(start 282.651454 -21.13026)
					(mid 282.777925 -21.082188)
					(end 282.908756 -21.04771)
				)
			)
		)
	)
	(zone
		(layer "B.Cu")
		(hatch none 0.5)
		(connect_pads
			(clearance 0)
		)
		(min_thickness 0.25)
		(keepout
			(tracks not_allowed)
			(vias allowed)
			(pads allowed)
			(copperpour not_allowed)
			(footprints allowed)
		)
		(placement
			(enabled no)
			(sheetname "")
		)
		(fill
			(thermal_gap 0.5)
			(thermal_bridge_width 0.5)
			(island_removal_mode 0)
		)
		(polygon
			(pts
				(arc
					(start 171.29379 -221.784164)
					(mid 170.78325 -222.294704)
					(end 171.29379 -222.805244)
				)
				(arc
					(start 171.46016 -222.805244)
					(mid 171.430793 -222.672837)
					(end 171.379134 -222.547434)
				)
				(arc
					(start 171.379134 -222.547434)
					(mid 171.134462 -222.081026)
					(end 171.510706 -222.449644)
				)
				(arc
					(start 171.510706 -222.449644)
					(mid 171.584617 -222.621858)
					(end 171.623228 -222.805244)
				)
				(arc
					(start 171.777406 -222.805244)
					(mid 171.815887 -222.621993)
					(end 171.889674 -222.449898)
				)
				(arc
					(start 171.889674 -222.449898)
					(mid 172.265383 -222.080409)
					(end 172.021246 -222.547434)
				)
				(arc
					(start 172.021246 -222.547434)
					(mid 171.969703 -222.672842)
					(end 171.940474 -222.805244)
				)
				(arc
					(start 172.106336 -222.805244)
					(mid 172.61713 -222.294831)
					(end 172.10659 -221.784164)
				)
			)
		)
	)
	(zone
		(layer "B.Cu")
		(hatch none 0.5)
		(connect_pads
			(clearance 0)
		)
		(min_thickness 0.25)
		(keepout
			(tracks not_allowed)
			(vias allowed)
			(pads allowed)
			(copperpour not_allowed)
			(footprints allowed)
		)
		(placement
			(enabled no)
			(sheetname "")
		)
		(fill
			(thermal_gap 0.5)
			(thermal_bridge_width 0.5)
			(island_removal_mode 0)
		)
		(polygon
			(pts
				(arc
					(start 297.637454 -9.53008)
					(mid 300.137576 -12.030202)
					(end 302.637444 -9.53008)
				)
				(arc
					(start 302.637444 -9.53008)
					(mid 300.137576 -7.030212)
					(end 297.637454 -9.53008)
				)
			)
		)
	)
	(zone
		(layer "B.Cu")
		(hatch none 0.5)
		(connect_pads
			(clearance 0)
		)
		(min_thickness 0.25)
		(keepout
			(tracks allowed)
			(vias allowed)
			(pads allowed)
			(copperpour allowed)
			(footprints not_allowed)
		)
		(placement
			(enabled no)
			(sheetname "")
		)
		(fill
			(thermal_gap 0.5)
			(thermal_bridge_width 0.5)
			(island_removal_mode 0)
		)
		(polygon
			(pts
				(arc
					(start 11.712194 -60.300108)
					(mid 13.812266 -62.40018)
					(end 15.912084 -60.300108)
				)
				(arc
					(start 15.912084 -60.300108)
					(mid 13.812266 -58.20029)
					(end 11.712194 -60.300108)
				)
			)
		)
	)
	(zone
		(layer "B.Cu")
		(hatch none 0.5)
		(connect_pads
			(clearance 0)
		)
		(min_thickness 0.25)
		(keepout
			(tracks allowed)
			(vias allowed)
			(pads allowed)
			(copperpour allowed)
			(footprints not_allowed)
		)
		(placement
			(enabled no)
			(sheetname "")
		)
		(fill
			(thermal_gap 0.5)
			(thermal_bridge_width 0.5)
			(island_removal_mode 0)
		)
		(polygon
			(pts
				(arc
					(start 297.637454 -9.53008)
					(mid 300.137576 -12.030202)
					(end 302.637444 -9.53008)
				)
				(arc
					(start 302.637444 -9.53008)
					(mid 300.137576 -7.030212)
					(end 297.637454 -9.53008)
				)
			)
		)
	)
	(zone
		(layer "B.Cu")
		(hatch none 0.5)
		(connect_pads
			(clearance 0)
		)
		(min_thickness 0.25)
		(keepout
			(tracks not_allowed)
			(vias allowed)
			(pads allowed)
			(copperpour not_allowed)
			(footprints allowed)
		)
		(placement
			(enabled no)
			(sheetname "")
		)
		(fill
			(thermal_gap 0.5)
			(thermal_bridge_width 0.5)
			(island_removal_mode 0)
		)
		(polygon
			(pts
				(arc
					(start 309.435246 -12.824968)
					(mid 309.179214 -11.979148)
					(end 308.333394 -12.23518)
				)
				(arc
					(start 308.11343 -12.645898)
					(mid 308.324081 -12.739258)
					(end 308.553612 -12.719304)
				)
				(arc
					(start 308.553612 -12.719304)
					(mid 309.162964 -12.270359)
					(end 308.671214 -12.845796)
				)
				(arc
					(start 308.671214 -12.845796)
					(mid 308.345983 -12.905313)
					(end 308.03596 -12.790424)
				)
				(xy 307.961538 -12.92987) (xy 308.26583 -13.234162)
				(arc
					(start 308.26583 -13.235686)
					(mid 308.372075 -13.427931)
					(end 308.389274 -13.646912)
				)
				(arc
					(start 308.389274 -13.646912)
					(mid 307.95342 -14.26526)
					(end 308.231794 -13.561822)
				)
				(arc
					(start 308.231794 -13.561822)
					(mid 308.201822 -13.433656)
					(end 308.1274 -13.325094)
				)
				(xy 307.881528 -13.078968)
				(arc
					(start 307.58765 -13.627608)
					(mid 307.835784 -14.479061)
					(end 308.685438 -14.225016)
				)
			)
		)
	)
	(zone
		(layer "B.Cu")
		(hatch none 0.5)
		(connect_pads
			(clearance 0)
		)
		(min_thickness 0.25)
		(keepout
			(tracks allowed)
			(vias allowed)
			(pads allowed)
			(copperpour allowed)
			(footprints not_allowed)
		)
		(placement
			(enabled no)
			(sheetname "")
		)
		(fill
			(thermal_gap 0.5)
			(thermal_bridge_width 0.5)
			(island_removal_mode 0)
		)
		(polygon
			(pts
				(arc
					(start 196.622162 -59.99988)
					(mid 200.622154 -63.999872)
					(end 204.622146 -59.99988)
				)
				(arc
					(start 204.622146 -59.99988)
					(mid 200.622154 -55.999888)
					(end 196.622162 -59.99988)
				)
			)
		)
	)
	(zone
		(layer "B.Cu")
		(hatch none 0.5)
		(connect_pads
			(clearance 0)
		)
		(min_thickness 0.25)
		(keepout
			(tracks not_allowed)
			(vias allowed)
			(pads allowed)
			(copperpour not_allowed)
			(footprints allowed)
		)
		(placement
			(enabled no)
			(sheetname "")
		)
		(fill
			(thermal_gap 0.5)
			(thermal_bridge_width 0.5)
			(island_removal_mode 0)
		)
		(polygon
			(pts
				(arc
					(start 270.05534 -5.305806)
					(mid 269.544927 -4.795012)
					(end 269.03426 -5.305552)
				)
				(arc
					(start 269.03426 -6.118352)
					(mid 269.5448 -6.628892)
					(end 270.05534 -6.118352)
				)
				(xy 270.05534 -5.945378) (xy 269.832328 -5.945378)
				(arc
					(start 269.781782 -5.995924)
					(mid 269.356188 -6.306964)
					(end 269.667228 -5.88137)
				)
				(xy 269.765272 -5.783326) (xy 270.05534 -5.783326) (xy 270.05534 -5.640578) (xy 269.765272 -5.640578)
				(arc
					(start 269.667228 -5.542534)
					(mid 269.356188 -5.11694)
					(end 269.781782 -5.42798)
				)
				(xy 269.832328 -5.478526) (xy 270.05534 -5.478526)
			)
		)
	)
	(zone
		(layer "B.Cu")
		(hatch none 0.5)
		(connect_pads
			(clearance 0)
		)
		(min_thickness 0.25)
		(keepout
			(tracks allowed)
			(vias allowed)
			(pads allowed)
			(copperpour allowed)
			(footprints not_allowed)
		)
		(placement
			(enabled no)
			(sheetname "")
		)
		(fill
			(thermal_gap 0.5)
			(thermal_bridge_width 0.5)
			(island_removal_mode 0)
		)
		(polygon
			(pts
				(arc
					(start 323.237606 -9.53008)
					(mid 322.137532 -8.430006)
					(end 321.037458 -9.53008)
				)
				(arc
					(start 321.037458 -9.53008)
					(mid 322.137532 -10.630154)
					(end 323.237606 -9.53008)
				)
			)
		)
	)
	(zone
		(layer "B.Cu")
		(hatch none 0.5)
		(connect_pads
			(clearance 0)
		)
		(min_thickness 0.25)
		(keepout
			(tracks allowed)
			(vias allowed)
			(pads allowed)
			(copperpour allowed)
			(footprints not_allowed)
		)
		(placement
			(enabled no)
			(sheetname "")
		)
		(fill
			(thermal_gap 0.5)
			(thermal_bridge_width 0.5)
			(island_removal_mode 0)
		)
		(polygon
			(pts
				(arc
					(start 312.237374 -9.53008)
					(mid 311.137554 -8.43026)
					(end 310.03748 -9.53008)
				)
				(arc
					(start 310.03748 -9.53008)
					(mid 311.137554 -10.630154)
					(end 312.237374 -9.53008)
				)
			)
		)
	)
	(zone
		(layer "B.Cu")
		(hatch none 0.5)
		(connect_pads
			(clearance 0)
		)
		(min_thickness 0.25)
		(keepout
			(tracks allowed)
			(vias allowed)
			(pads allowed)
			(copperpour allowed)
			(footprints not_allowed)
		)
		(placement
			(enabled no)
			(sheetname "")
		)
		(fill
			(thermal_gap 0.5)
			(thermal_bridge_width 0.5)
			(island_removal_mode 0)
		)
		(polygon
			(pts
				(arc
					(start 202.2221 -59.99988)
					(mid 200.622154 -58.399934)
					(end 199.021954 -59.99988)
				)
				(arc
					(start 199.021954 -59.99988)
					(mid 200.622154 -61.60008)
					(end 202.2221 -59.99988)
				)
			)
		)
	)
	(zone
		(net "GND")
		(layer "B.Cu")
		(hatch none 0.5)
		(connect_pads
			(clearance 0.5)
		)
		(min_thickness 0.25)
		(fill yes
			(thermal_gap 0.5)
			(thermal_bridge_width 0.5)
			(island_removal_mode 0)
		)
		(polygon
			(pts
				(xy 178.432968 -71.882) (xy 178.305968 -72.009) (xy 178.305968 -75.916536) (xy 178.689 -76.299568)
				(xy 187.475368 -76.299568) (xy 187.856368 -75.918568) (xy 187.856368 -72.057768) (xy 187.6806 -71.882)
			)
		)
	)
	(zone
		(net "GND")
		(layer "B.Cu")
		(hatch none 0.5)
		(connect_pads
			(clearance 0.5)
		)
		(min_thickness 0.25)
		(fill yes
			(thermal_gap 0.5)
			(thermal_bridge_width 0.5)
			(island_removal_mode 0)
		)
		(polygon
			(pts
				(xy 35.433 -127.127) (xy 35.306 -127.254) (xy 35.306 -130.302) (xy 35.814 -130.81) (xy 35.814 -132.842)
				(xy 36.068 -133.096) (xy 41.275 -133.096) (xy 41.529 -132.842) (xy 41.529 -127.381) (xy 41.275 -127.127)
			)
		)
		(polygon
			(pts
				(xy 41.000426 -132.72008) (xy 40.797226 -132.72008) (xy 40.797226 -132.92328) (xy 41.000426 -132.92328)
			)
		)
		(polygon
			(pts
				(xy 40.6654 -132.3594) (xy 40.4622 -132.3594) (xy 40.4622 -132.5626) (xy 40.6654 -132.5626)
			)
		)
		(polygon
			(pts
				(xy 40.0558 -132.3594) (xy 39.8526 -132.3594) (xy 39.8526 -132.5626) (xy 40.0558 -132.5626)
			)
		)
		(polygon
			(pts
				(xy 36.5506 -132.1816) (xy 36.3474 -132.1816) (xy 36.3474 -132.3848) (xy 36.5506 -132.3848)
			)
		)
		(polygon
			(pts
				(xy 41.000426 -132.11048) (xy 40.797226 -132.11048) (xy 40.797226 -132.31368) (xy 41.000426 -132.31368)
			)
		)
		(polygon
			(pts
				(xy 38.1254 -132.1054) (xy 37.9222 -132.1054) (xy 37.9222 -132.3086) (xy 38.1254 -132.3086)
			)
		)
		(polygon
			(pts
				(xy 37.5158 -132.1054) (xy 37.3126 -132.1054) (xy 37.3126 -132.3086) (xy 37.5158 -132.3086)
			)
		)
		(polygon
			(pts
				(xy 36.427664 -131.55168) (xy 36.224464 -131.55168) (xy 36.224464 -131.75488) (xy 36.427664 -131.75488)
			)
		)
		(polygon
			(pts
				(xy 40.9956 -131.2672) (xy 40.7924 -131.2672) (xy 40.7924 -131.4704) (xy 40.9956 -131.4704)
			)
		)
		(polygon
			(pts
				(xy 36.427664 -130.94208) (xy 36.224464 -130.94208) (xy 36.224464 -131.14528) (xy 36.427664 -131.14528)
			)
		)
		(polygon
			(pts
				(xy 40.9956 -130.3782) (xy 40.7924 -130.3782) (xy 40.7924 -130.8608) (xy 40.9956 -130.8608)
			)
		)
		(polygon
			(pts
				(xy 36.1696 -129.8702) (xy 35.9664 -129.8702) (xy 35.9664 -130.0734) (xy 36.1696 -130.0734)
			)
		)
		(polygon
			(pts
				(xy 40.9956 -129.4892) (xy 40.7924 -129.4892) (xy 40.7924 -129.9718) (xy 40.9956 -129.9718)
			)
		)
		(polygon
			(pts
				(xy 36.1696 -129.2606) (xy 35.9664 -129.2606) (xy 35.9664 -129.4638) (xy 36.1696 -129.4638)
			)
		)
		(polygon
			(pts
				(xy 40.9956 -128.6002) (xy 40.7924 -128.6002) (xy 40.7924 -129.0828) (xy 40.9956 -129.0828)
			)
		)
		(polygon
			(pts
				(xy 36.111688 -128.591818) (xy 35.908488 -128.591818) (xy 35.908488 -128.795018) (xy 36.111688 -128.795018)
			)
		)
		(polygon
			(pts
				(xy 40.9956 -127.9906) (xy 40.7924 -127.9906) (xy 40.7924 -128.1938) (xy 40.9956 -128.1938)
			)
		)
		(polygon
			(pts
				(xy 36.111688 -127.982218) (xy 35.908488 -127.982218) (xy 35.908488 -128.185418) (xy 36.111688 -128.185418)
			)
		)
		(polygon
			(pts
				(xy 40.249348 -127.663194) (xy 40.046148 -127.663194) (xy 40.046148 -127.866394) (xy 40.249348 -127.866394)
			)
		)
		(polygon
			(pts
				(xy 39.639748 -127.663194) (xy 39.436548 -127.663194) (xy 39.436548 -127.866394) (xy 39.639748 -127.866394)
			)
		)
		(polygon
			(pts
				(xy 36.783518 -127.65024) (xy 36.580318 -127.65024) (xy 36.580318 -127.85344) (xy 36.783518 -127.85344)
			)
		)
		(polygon
			(pts
				(xy 36.173918 -127.65024) (xy 35.970718 -127.65024) (xy 35.970718 -127.85344) (xy 36.173918 -127.85344)
			)
		)
		(polygon
			(pts
				(xy 37.73424 -127.61722) (xy 37.53104 -127.61722) (xy 37.53104 -127.82042) (xy 37.73424 -127.82042)
			)
		)
		(polygon
			(pts
				(xy 37.12464 -127.61722) (xy 36.92144 -127.61722) (xy 36.92144 -127.82042) (xy 37.12464 -127.82042)
			)
		)
		(polygon
			(pts
				(xy 41.402 -127.6096) (xy 41.1988 -127.6096) (xy 41.1988 -127.8128) (xy 41.402 -127.8128)
			)
		)
		(polygon
			(pts
				(xy 40.8432 -127.6096) (xy 40.64 -127.6096) (xy 40.64 -127.8128) (xy 40.8432 -127.8128)
			)
		)
		(polygon
			(pts
				(xy 39.247064 -127.593344) (xy 39.043864 -127.593344) (xy 39.043864 -127.796544) (xy 39.247064 -127.796544)
			)
		)
		(polygon
			(pts
				(xy 38.637464 -127.593344) (xy 38.434264 -127.593344) (xy 38.434264 -127.796544) (xy 38.637464 -127.796544)
			)
		)
	)
	(zone
		(layer "B.Cu")
		(hatch none 0.5)
		(connect_pads
			(clearance 0)
		)
		(min_thickness 0.25)
		(keepout
			(tracks not_allowed)
			(vias allowed)
			(pads allowed)
			(copperpour not_allowed)
			(footprints allowed)
		)
		(placement
			(enabled no)
			(sheetname "")
		)
		(fill
			(thermal_gap 0.5)
			(thermal_bridge_width 0.5)
			(island_removal_mode 0)
		)
		(polygon
			(pts
				(arc
					(start 266.093702 -221.784164)
					(mid 265.583162 -222.294704)
					(end 266.093702 -222.805244)
				)
				(arc
					(start 266.260072 -222.805244)
					(mid 266.230705 -222.672837)
					(end 266.179046 -222.547434)
				)
				(arc
					(start 266.179046 -222.547434)
					(mid 265.934374 -222.081026)
					(end 266.310618 -222.449644)
				)
				(arc
					(start 266.310618 -222.449644)
					(mid 266.384529 -222.621858)
					(end 266.42314 -222.805244)
				)
				(arc
					(start 266.577318 -222.805244)
					(mid 266.615799 -222.621993)
					(end 266.689586 -222.449898)
				)
				(arc
					(start 266.689586 -222.449898)
					(mid 267.065295 -222.080409)
					(end 266.821158 -222.547434)
				)
				(arc
					(start 266.821158 -222.547434)
					(mid 266.769615 -222.672842)
					(end 266.740386 -222.805244)
				)
				(arc
					(start 266.906248 -222.805244)
					(mid 267.417042 -222.294831)
					(end 266.906502 -221.784164)
				)
			)
		)
	)
	(zone
		(layers "B.Cu" "In2.Cu")
		(hatch none 0.5)
		(connect_pads
			(clearance 0)
		)
		(min_thickness 0.25)
		(keepout
			(tracks not_allowed)
			(vias allowed)
			(pads allowed)
			(copperpour not_allowed)
			(footprints allowed)
		)
		(placement
			(enabled no)
			(sheetname "")
		)
		(fill yes
			(thermal_gap 0.5)
			(thermal_bridge_width 0.5)
			(island_removal_mode 0)
		)
		(polygon
			(pts
				(arc
					(start 161.7853 -37.50056)
					(mid 161.27476 -38.0111)
					(end 161.7853 -38.52164)
				)
				(arc
					(start 162.597846 -38.52164)
					(mid 162.958117 -38.373093)
					(end 163.10864 -38.01364)
				)
				(arc
					(start 162.8648 -38.01364)
					(mid 162.5981 -38.277812)
					(end 162.3314 -38.01364)
				)
				(arc
					(start 162.052 -38.01364)
					(mid 161.7853 -38.277812)
					(end 161.5186 -38.01364)
				)
				(arc
					(start 161.5186 -38.0111)
					(mid 161.7853 -37.7444)
					(end 162.052 -38.0111)
				)
				(arc
					(start 162.3314 -38.0111)
					(mid 162.5981 -37.7444)
					(end 162.8648 -38.0111)
				)
				(arc
					(start 163.10864 -38.0111)
					(mid 162.959106 -37.650094)
					(end 162.5981 -37.50056)
				)
			)
		)
	)
	(zone
		(layers "B.Cu" "In2.Cu")
		(hatch none 0.5)
		(connect_pads
			(clearance 0)
		)
		(min_thickness 0.25)
		(keepout
			(tracks not_allowed)
			(vias allowed)
			(pads allowed)
			(copperpour not_allowed)
			(footprints allowed)
		)
		(placement
			(enabled no)
			(sheetname "")
		)
		(fill yes
			(thermal_gap 0.5)
			(thermal_bridge_width 0.5)
			(island_removal_mode 0)
		)
		(polygon
			(pts
				(arc
					(start 183.59374 -23.6601)
					(mid 183.0832 -23.14956)
					(end 182.57266 -23.6601)
				)
				(arc
					(start 182.57266 -24.472646)
					(mid 183.081803 -24.983438)
					(end 183.59374 -24.47544)
				)
				(arc
					(start 183.3499 -24.47544)
					(mid 183.0832 -24.739612)
					(end 182.8165 -24.47544)
				)
				(arc
					(start 182.8165 -24.4729)
					(mid 183.0832 -24.2062)
					(end 183.3499 -24.4729)
				)
				(xy 183.59374 -24.4729) (xy 183.59374 -23.66264)
				(arc
					(start 183.3499 -23.66264)
					(mid 183.0832 -23.926812)
					(end 182.8165 -23.66264)
				)
				(arc
					(start 182.8165 -23.6601)
					(mid 183.0832 -23.3934)
					(end 183.3499 -23.6601)
				)
			)
		)
	)
	(zone
		(layers "B.Cu" "In2.Cu")
		(hatch none 0.5)
		(connect_pads
			(clearance 0)
		)
		(min_thickness 0.25)
		(keepout
			(tracks not_allowed)
			(vias allowed)
			(pads allowed)
			(copperpour not_allowed)
			(footprints allowed)
		)
		(placement
			(enabled no)
			(sheetname "")
		)
		(fill yes
			(thermal_gap 0.5)
			(thermal_bridge_width 0.5)
			(island_removal_mode 0)
		)
		(polygon
			(pts
				(arc
					(start 92.493846 -210.385914)
					(mid 91.983052 -210.896327)
					(end 92.493592 -211.406994)
				)
				(arc
					(start 93.306392 -211.406994)
					(mid 93.666499 -211.258357)
					(end 93.816932 -210.898994)
				)
				(arc
					(start 93.573092 -210.898994)
					(mid 93.306392 -211.163166)
					(end 93.039692 -210.898994)
				)
				(arc
					(start 92.760292 -210.898994)
					(mid 92.493592 -211.163166)
					(end 92.226892 -210.898994)
				)
				(arc
					(start 92.226892 -210.896454)
					(mid 92.493592 -210.629754)
					(end 92.760292 -210.896454)
				)
				(arc
					(start 93.039692 -210.896454)
					(mid 93.306392 -210.629754)
					(end 93.573092 -210.896454)
				)
				(arc
					(start 93.816932 -210.896454)
					(mid 93.667398 -210.535448)
					(end 93.306392 -210.385914)
				)
			)
		)
	)
	(zone
		(layers "B.Cu" "In2.Cu")
		(hatch none 0.5)
		(connect_pads
			(clearance 0)
		)
		(min_thickness 0.25)
		(keepout
			(tracks not_allowed)
			(vias allowed)
			(pads allowed)
			(copperpour not_allowed)
			(footprints allowed)
		)
		(placement
			(enabled no)
			(sheetname "")
		)
		(fill yes
			(thermal_gap 0.5)
			(thermal_bridge_width 0.5)
			(island_removal_mode 0)
		)
		(polygon
			(pts
				(arc
					(start 183.59374 -19.8501)
					(mid 183.0832 -19.33956)
					(end 182.57266 -19.8501)
				)
				(arc
					(start 182.57266 -20.6629)
					(mid 183.08193 -21.173438)
					(end 183.59374 -20.66544)
				)
				(arc
					(start 183.3499 -20.66544)
					(mid 183.0832 -20.929612)
					(end 182.8165 -20.66544)
				)
				(arc
					(start 182.8165 -20.6629)
					(mid 183.0832 -20.3962)
					(end 183.3499 -20.6629)
				)
				(xy 183.59374 -20.6629) (xy 183.59374 -19.85264)
				(arc
					(start 183.3499 -19.85264)
					(mid 183.0832 -20.116812)
					(end 182.8165 -19.85264)
				)
				(arc
					(start 182.8165 -19.8501)
					(mid 183.0832 -19.5834)
					(end 183.3499 -19.8501)
				)
			)
		)
	)
	(zone
		(layers "B.Cu" "In2.Cu")
		(hatch none 0.5)
		(connect_pads
			(clearance 0)
		)
		(min_thickness 0.25)
		(keepout
			(tracks not_allowed)
			(vias allowed)
			(pads allowed)
			(copperpour not_allowed)
			(footprints allowed)
		)
		(placement
			(enabled no)
			(sheetname "")
		)
		(fill yes
			(thermal_gap 0.5)
			(thermal_bridge_width 0.5)
			(island_removal_mode 0)
		)
		(polygon
			(pts
				(arc
					(start 274.09394 -210.385914)
					(mid 273.583146 -210.896327)
					(end 274.093686 -211.406994)
				)
				(arc
					(start 274.906486 -211.406994)
					(mid 275.266593 -211.258357)
					(end 275.417026 -210.898994)
				)
				(arc
					(start 275.173186 -210.898994)
					(mid 274.906486 -211.163166)
					(end 274.639786 -210.898994)
				)
				(arc
					(start 274.360386 -210.898994)
					(mid 274.093686 -211.163166)
					(end 273.826986 -210.898994)
				)
				(arc
					(start 273.826986 -210.896454)
					(mid 274.093686 -210.629754)
					(end 274.360386 -210.896454)
				)
				(arc
					(start 274.639786 -210.896454)
					(mid 274.906486 -210.629754)
					(end 275.173186 -210.896454)
				)
				(arc
					(start 275.417026 -210.896454)
					(mid 275.267492 -210.535448)
					(end 274.906486 -210.385914)
				)
			)
		)
	)
	(zone
		(layers "B.Cu" "In2.Cu")
		(hatch none 0.5)
		(connect_pads
			(clearance 0)
		)
		(min_thickness 0.25)
		(keepout
			(tracks not_allowed)
			(vias allowed)
			(pads allowed)
			(copperpour not_allowed)
			(footprints allowed)
		)
		(placement
			(enabled no)
			(sheetname "")
		)
		(fill yes
			(thermal_gap 0.5)
			(thermal_bridge_width 0.5)
			(island_removal_mode 0)
		)
		(polygon
			(pts
				(arc
					(start 303.8348 -35.773614)
					(mid 303.32426 -36.284154)
					(end 303.8348 -36.794694)
				)
				(arc
					(start 304.647346 -36.794694)
					(mid 305.007617 -36.646147)
					(end 305.15814 -36.286694)
				)
				(arc
					(start 304.9143 -36.286694)
					(mid 304.6476 -36.550866)
					(end 304.3809 -36.286694)
				)
				(arc
					(start 304.1015 -36.286694)
					(mid 303.8348 -36.550866)
					(end 303.5681 -36.286694)
				)
				(arc
					(start 303.5681 -36.284154)
					(mid 303.8348 -36.017454)
					(end 304.1015 -36.284154)
				)
				(arc
					(start 304.3809 -36.284154)
					(mid 304.6476 -36.017454)
					(end 304.9143 -36.284154)
				)
				(arc
					(start 305.15814 -36.284154)
					(mid 305.008606 -35.923148)
					(end 304.6476 -35.773614)
				)
			)
		)
	)
	(zone
		(layers "B.Cu" "In2.Cu")
		(hatch none 0.5)
		(connect_pads
			(clearance 0)
		)
		(min_thickness 0.25)
		(keepout
			(tracks not_allowed)
			(vias allowed)
			(pads allowed)
			(copperpour not_allowed)
			(footprints allowed)
		)
		(placement
			(enabled no)
			(sheetname "")
		)
		(fill yes
			(thermal_gap 0.5)
			(thermal_bridge_width 0.5)
			(island_removal_mode 0)
		)
		(polygon
			(pts
				(arc
					(start 131.089654 -34.762694)
					(mid 130.57886 -35.273107)
					(end 131.0894 -35.783774)
				)
				(arc
					(start 131.9022 -35.783774)
					(mid 132.262307 -35.635137)
					(end 132.41274 -35.275774)
				)
				(arc
					(start 132.1689 -35.275774)
					(mid 131.9022 -35.539946)
					(end 131.6355 -35.275774)
				)
				(arc
					(start 131.3561 -35.275774)
					(mid 131.0894 -35.539946)
					(end 130.8227 -35.275774)
				)
				(arc
					(start 130.8227 -35.273234)
					(mid 131.0894 -35.006534)
					(end 131.3561 -35.273234)
				)
				(arc
					(start 131.6355 -35.273234)
					(mid 131.9022 -35.006534)
					(end 132.1689 -35.273234)
				)
				(arc
					(start 132.41274 -35.273234)
					(mid 132.263206 -34.912228)
					(end 131.9022 -34.762694)
				)
			)
		)
	)
	(zone
		(layers "B.Cu" "In2.Cu")
		(hatch none 0.5)
		(connect_pads
			(clearance 0)
		)
		(min_thickness 0.25)
		(keepout
			(tracks not_allowed)
			(vias allowed)
			(pads allowed)
			(copperpour not_allowed)
			(footprints allowed)
		)
		(placement
			(enabled no)
			(sheetname "")
		)
		(fill yes
			(thermal_gap 0.5)
			(thermal_bridge_width 0.5)
			(island_removal_mode 0)
		)
		(polygon
			(pts
				(arc
					(start 9.6647 -54.538372)
					(mid 9.15416 -55.048912)
					(end 9.6647 -55.559452)
				)
				(arc
					(start 10.477246 -55.559452)
					(mid 10.837517 -55.410905)
					(end 10.98804 -55.051452)
				)
				(arc
					(start 10.7442 -55.051452)
					(mid 10.4775 -55.315624)
					(end 10.2108 -55.051452)
				)
				(arc
					(start 9.9314 -55.051452)
					(mid 9.6647 -55.315624)
					(end 9.398 -55.051452)
				)
				(arc
					(start 9.398 -55.048912)
					(mid 9.6647 -54.782212)
					(end 9.9314 -55.048912)
				)
				(arc
					(start 10.2108 -55.048912)
					(mid 10.4775 -54.782212)
					(end 10.7442 -55.048912)
				)
				(arc
					(start 10.98804 -55.048912)
					(mid 10.838506 -54.687906)
					(end 10.4775 -54.538372)
				)
			)
		)
	)
	(zone
		(layers "B.Cu" "In2.Cu")
		(hatch none 0.5)
		(connect_pads
			(clearance 0)
		)
		(min_thickness 0.25)
		(keepout
			(tracks not_allowed)
			(vias allowed)
			(pads allowed)
			(copperpour not_allowed)
			(footprints allowed)
		)
		(placement
			(enabled no)
			(sheetname "")
		)
		(fill yes
			(thermal_gap 0.5)
			(thermal_bridge_width 0.5)
			(island_removal_mode 0)
		)
		(polygon
			(pts
				(arc
					(start 293.2938 -210.385914)
					(mid 292.783006 -210.896327)
					(end 293.293546 -211.406994)
				)
				(arc
					(start 294.106346 -211.406994)
					(mid 294.466453 -211.258357)
					(end 294.616886 -210.898994)
				)
				(arc
					(start 294.373046 -210.898994)
					(mid 294.106346 -211.163166)
					(end 293.839646 -210.898994)
				)
				(arc
					(start 293.560246 -210.898994)
					(mid 293.293546 -211.163166)
					(end 293.026846 -210.898994)
				)
				(arc
					(start 293.026846 -210.896454)
					(mid 293.293546 -210.629754)
					(end 293.560246 -210.896454)
				)
				(arc
					(start 293.839646 -210.896454)
					(mid 294.106346 -210.629754)
					(end 294.373046 -210.896454)
				)
				(arc
					(start 294.616886 -210.896454)
					(mid 294.467352 -210.535448)
					(end 294.106346 -210.385914)
				)
			)
		)
	)
	(zone
		(layers "B.Cu" "In2.Cu")
		(hatch none 0.5)
		(connect_pads
			(clearance 0)
		)
		(min_thickness 0.25)
		(keepout
			(tracks not_allowed)
			(vias allowed)
			(pads allowed)
			(copperpour not_allowed)
			(footprints allowed)
		)
		(placement
			(enabled no)
			(sheetname "")
		)
		(fill yes
			(thermal_gap 0.5)
			(thermal_bridge_width 0.5)
			(island_removal_mode 0)
		)
		(polygon
			(pts
				(arc
					(start 301.65929 -34.515806)
					(mid 301.14875 -35.026346)
					(end 301.65929 -35.536886)
				)
				(arc
					(start 302.471836 -35.536886)
					(mid 302.832107 -35.388339)
					(end 302.98263 -35.028886)
				)
				(arc
					(start 302.73879 -35.028886)
					(mid 302.47209 -35.293058)
					(end 302.20539 -35.028886)
				)
				(arc
					(start 301.92599 -35.028886)
					(mid 301.65929 -35.293058)
					(end 301.39259 -35.028886)
				)
				(arc
					(start 301.39259 -35.026346)
					(mid 301.65929 -34.759646)
					(end 301.92599 -35.026346)
				)
				(arc
					(start 302.20539 -35.026346)
					(mid 302.47209 -34.759646)
					(end 302.73879 -35.026346)
				)
				(arc
					(start 302.98263 -35.026346)
					(mid 302.833096 -34.66534)
					(end 302.47209 -34.515806)
				)
			)
		)
	)
	(zone
		(layers "B.Cu" "In2.Cu")
		(hatch none 0.5)
		(connect_pads
			(clearance 0)
		)
		(min_thickness 0.25)
		(keepout
			(tracks not_allowed)
			(vias allowed)
			(pads allowed)
			(copperpour not_allowed)
			(footprints allowed)
		)
		(placement
			(enabled no)
			(sheetname "")
		)
		(fill yes
			(thermal_gap 0.5)
			(thermal_bridge_width 0.5)
			(island_removal_mode 0)
		)
		(polygon
			(pts
				(arc
					(start 200.093834 -210.385914)
					(mid 199.58304 -210.896327)
					(end 200.09358 -211.406994)
				)
				(arc
					(start 200.90638 -211.406994)
					(mid 201.266487 -211.258357)
					(end 201.41692 -210.898994)
				)
				(arc
					(start 201.17308 -210.898994)
					(mid 200.90638 -211.163166)
					(end 200.63968 -210.898994)
				)
				(arc
					(start 200.36028 -210.898994)
					(mid 200.09358 -211.163166)
					(end 199.82688 -210.898994)
				)
				(arc
					(start 199.82688 -210.896454)
					(mid 200.09358 -210.629754)
					(end 200.36028 -210.896454)
				)
				(arc
					(start 200.63968 -210.896454)
					(mid 200.90638 -210.629754)
					(end 201.17308 -210.896454)
				)
				(arc
					(start 201.41692 -210.896454)
					(mid 201.267386 -210.535448)
					(end 200.90638 -210.385914)
				)
			)
		)
	)
	(zone
		(layers "B.Cu" "In2.Cu")
		(hatch none 0.5)
		(connect_pads
			(clearance 0)
		)
		(min_thickness 0.25)
		(keepout
			(tracks not_allowed)
			(vias allowed)
			(pads allowed)
			(copperpour not_allowed)
			(footprints allowed)
		)
		(placement
			(enabled no)
			(sheetname "")
		)
		(fill yes
			(thermal_gap 0.5)
			(thermal_bridge_width 0.5)
			(island_removal_mode 0)
		)
		(polygon
			(pts
				(arc
					(start 15.799054 -72.706484)
					(mid 15.28826 -73.216897)
					(end 15.7988 -73.727564)
				)
				(arc
					(start 16.6116 -73.727564)
					(mid 16.971707 -73.578927)
					(end 17.12214 -73.219564)
				)
				(arc
					(start 16.8783 -73.219564)
					(mid 16.6116 -73.483736)
					(end 16.3449 -73.219564)
				)
				(arc
					(start 16.0655 -73.219564)
					(mid 15.7988 -73.483736)
					(end 15.5321 -73.219564)
				)
				(arc
					(start 15.5321 -73.217024)
					(mid 15.7988 -72.950324)
					(end 16.0655 -73.217024)
				)
				(arc
					(start 16.3449 -73.217024)
					(mid 16.6116 -72.950324)
					(end 16.8783 -73.217024)
				)
				(arc
					(start 17.12214 -73.217024)
					(mid 16.972606 -72.856018)
					(end 16.6116 -72.706484)
				)
			)
		)
	)
	(zone
		(layers "B.Cu" "In2.Cu")
		(hatch none 0.5)
		(connect_pads
			(clearance 0)
		)
		(min_thickness 0.25)
		(keepout
			(tracks not_allowed)
			(vias allowed)
			(pads allowed)
			(copperpour not_allowed)
			(footprints allowed)
		)
		(placement
			(enabled no)
			(sheetname "")
		)
		(fill yes
			(thermal_gap 0.5)
			(thermal_bridge_width 0.5)
			(island_removal_mode 0)
		)
		(polygon
			(pts
				(arc
					(start 312.67654 -35.675062)
					(mid 312.165746 -36.185475)
					(end 312.676286 -36.696142)
				)
				(arc
					(start 313.489086 -36.696142)
					(mid 313.849193 -36.547505)
					(end 313.999626 -36.188142)
				)
				(arc
					(start 313.755786 -36.188142)
					(mid 313.489086 -36.452314)
					(end 313.222386 -36.188142)
				)
				(arc
					(start 312.942986 -36.188142)
					(mid 312.676286 -36.452314)
					(end 312.409586 -36.188142)
				)
				(arc
					(start 312.409586 -36.185602)
					(mid 312.676286 -35.918902)
					(end 312.942986 -36.185602)
				)
				(arc
					(start 313.222386 -36.185602)
					(mid 313.489086 -35.918902)
					(end 313.755786 -36.185602)
				)
				(arc
					(start 313.999626 -36.185602)
					(mid 313.850092 -35.824596)
					(end 313.489086 -35.675062)
				)
			)
		)
	)
	(zone
		(layers "B.Cu" "In2.Cu")
		(hatch none 0.5)
		(connect_pads
			(clearance 0)
		)
		(min_thickness 0.25)
		(keepout
			(tracks not_allowed)
			(vias allowed)
			(pads allowed)
			(copperpour not_allowed)
			(footprints allowed)
		)
		(placement
			(enabled no)
			(sheetname "")
		)
		(fill yes
			(thermal_gap 0.5)
			(thermal_bridge_width 0.5)
			(island_removal_mode 0)
		)
		(polygon
			(pts
				(arc
					(start 310.093868 -210.385914)
					(mid 309.583328 -210.896454)
					(end 310.093868 -211.406994)
				)
				(arc
					(start 310.906414 -211.406994)
					(mid 311.266685 -211.258447)
					(end 311.417208 -210.898994)
				)
				(arc
					(start 311.173368 -210.898994)
					(mid 310.906668 -211.163166)
					(end 310.639968 -210.898994)
				)
				(arc
					(start 310.360568 -210.898994)
					(mid 310.093868 -211.163166)
					(end 309.827168 -210.898994)
				)
				(arc
					(start 309.827168 -210.896454)
					(mid 310.093868 -210.629754)
					(end 310.360568 -210.896454)
				)
				(arc
					(start 310.639968 -210.896454)
					(mid 310.906668 -210.629754)
					(end 311.173368 -210.896454)
				)
				(arc
					(start 311.417208 -210.896454)
					(mid 311.267674 -210.535448)
					(end 310.906668 -210.385914)
				)
			)
		)
	)
	(zone
		(layers "B.Cu" "In2.Cu")
		(hatch none 0.5)
		(connect_pads
			(clearance 0)
		)
		(min_thickness 0.25)
		(keepout
			(tracks not_allowed)
			(vias allowed)
			(pads allowed)
			(copperpour not_allowed)
			(footprints allowed)
		)
		(placement
			(enabled no)
			(sheetname "")
		)
		(fill yes
			(thermal_gap 0.5)
			(thermal_bridge_width 0.5)
			(island_removal_mode 0)
		)
		(polygon
			(pts
				(arc
					(start 325.969122 -35.451034)
					(mid 325.458582 -35.961574)
					(end 325.969122 -36.472114)
				)
				(arc
					(start 326.781668 -36.472114)
					(mid 327.141939 -36.323567)
					(end 327.292462 -35.964114)
				)
				(arc
					(start 327.048622 -35.964114)
					(mid 326.781922 -36.228286)
					(end 326.515222 -35.964114)
				)
				(arc
					(start 326.235822 -35.964114)
					(mid 325.969122 -36.228286)
					(end 325.702422 -35.964114)
				)
				(arc
					(start 325.702422 -35.961574)
					(mid 325.969122 -35.694874)
					(end 326.235822 -35.961574)
				)
				(arc
					(start 326.515222 -35.961574)
					(mid 326.781922 -35.694874)
					(end 327.048622 -35.961574)
				)
				(arc
					(start 327.292462 -35.961574)
					(mid 327.142928 -35.600568)
					(end 326.781922 -35.451034)
				)
			)
		)
	)
	(zone
		(layers "B.Cu" "In2.Cu")
		(hatch none 0.5)
		(connect_pads
			(clearance 0)
		)
		(min_thickness 0.25)
		(keepout
			(tracks not_allowed)
			(vias allowed)
			(pads allowed)
			(copperpour not_allowed)
			(footprints allowed)
		)
		(placement
			(enabled no)
			(sheetname "")
		)
		(fill yes
			(thermal_gap 0.5)
			(thermal_bridge_width 0.5)
			(island_removal_mode 0)
		)
		(polygon
			(pts
				(arc
					(start 183.59374 -28.9941)
					(mid 183.0832 -28.48356)
					(end 182.57266 -28.9941)
				)
				(arc
					(start 182.57266 -29.8069)
					(mid 183.08193 -30.317438)
					(end 183.59374 -29.80944)
				)
				(arc
					(start 183.3499 -29.80944)
					(mid 183.0832 -30.073612)
					(end 182.8165 -29.80944)
				)
				(arc
					(start 182.8165 -29.8069)
					(mid 183.0832 -29.5402)
					(end 183.3499 -29.8069)
				)
				(xy 183.59374 -29.8069) (xy 183.59374 -28.99664)
				(arc
					(start 183.3499 -28.99664)
					(mid 183.0832 -29.260812)
					(end 182.8165 -28.99664)
				)
				(arc
					(start 182.8165 -28.9941)
					(mid 183.0832 -28.7274)
					(end 183.3499 -28.9941)
				)
			)
		)
	)
	(zone
		(layers "B.Cu" "In2.Cu")
		(hatch none 0.5)
		(connect_pads
			(clearance 0)
		)
		(min_thickness 0.25)
		(keepout
			(tracks not_allowed)
			(vias allowed)
			(pads allowed)
			(copperpour not_allowed)
			(footprints allowed)
		)
		(placement
			(enabled no)
			(sheetname "")
		)
		(fill yes
			(thermal_gap 0.5)
			(thermal_bridge_width 0.5)
			(island_removal_mode 0)
		)
		(polygon
			(pts
				(arc
					(start 152.7175 -34.48558)
					(mid 152.20696 -34.99612)
					(end 152.7175 -35.50666)
				)
				(arc
					(start 153.530046 -35.50666)
					(mid 153.890317 -35.358113)
					(end 154.04084 -34.99866)
				)
				(arc
					(start 153.797 -34.99866)
					(mid 153.5303 -35.262832)
					(end 153.2636 -34.99866)
				)
				(arc
					(start 152.9842 -34.99866)
					(mid 152.7175 -35.262832)
					(end 152.4508 -34.99866)
				)
				(arc
					(start 152.4508 -34.99612)
					(mid 152.7175 -34.72942)
					(end 152.9842 -34.99612)
				)
				(arc
					(start 153.2636 -34.99612)
					(mid 153.5303 -34.72942)
					(end 153.797 -34.99612)
				)
				(arc
					(start 154.04084 -34.99612)
					(mid 153.891306 -34.635114)
					(end 153.5303 -34.48558)
				)
			)
		)
	)
	(zone
		(layers "B.Cu" "In2.Cu")
		(hatch none 0.5)
		(connect_pads
			(clearance 0)
		)
		(min_thickness 0.25)
		(keepout
			(tracks not_allowed)
			(vias allowed)
			(pads allowed)
			(copperpour not_allowed)
			(footprints allowed)
		)
		(placement
			(enabled no)
			(sheetname "")
		)
		(fill yes
			(thermal_gap 0.5)
			(thermal_bridge_width 0.5)
			(island_removal_mode 0)
		)
		(polygon
			(pts
				(arc
					(start 20.396454 -86.91626)
					(mid 19.88566 -87.426673)
					(end 20.3962 -87.93734)
				)
				(arc
					(start 21.209 -87.93734)
					(mid 21.569107 -87.788703)
					(end 21.71954 -87.42934)
				)
				(arc
					(start 21.4757 -87.42934)
					(mid 21.209 -87.693512)
					(end 20.9423 -87.42934)
				)
				(arc
					(start 20.6629 -87.42934)
					(mid 20.3962 -87.693512)
					(end 20.1295 -87.42934)
				)
				(arc
					(start 20.1295 -87.4268)
					(mid 20.3962 -87.1601)
					(end 20.6629 -87.4268)
				)
				(arc
					(start 20.9423 -87.4268)
					(mid 21.209 -87.1601)
					(end 21.4757 -87.4268)
				)
				(arc
					(start 21.71954 -87.4268)
					(mid 21.570006 -87.065794)
					(end 21.209 -86.91626)
				)
			)
		)
	)
	(zone
		(layers "B.Cu" "In2.Cu")
		(hatch none 0.5)
		(connect_pads
			(clearance 0)
		)
		(min_thickness 0.25)
		(keepout
			(tracks not_allowed)
			(vias allowed)
			(pads allowed)
			(copperpour not_allowed)
			(footprints allowed)
		)
		(placement
			(enabled no)
			(sheetname "")
		)
		(fill yes
			(thermal_gap 0.5)
			(thermal_bridge_width 0.5)
			(island_removal_mode 0)
		)
		(polygon
			(pts
				(arc
					(start 168.212516 -88.646)
					(mid 167.701976 -88.13546)
					(end 167.191436 -88.646)
				)
				(arc
					(start 167.191436 -89.4588)
					(mid 167.700706 -89.969338)
					(end 168.212516 -89.46134)
				)
				(arc
					(start 167.968676 -89.46134)
					(mid 167.701976 -89.725512)
					(end 167.435276 -89.46134)
				)
				(arc
					(start 167.435276 -89.4588)
					(mid 167.701976 -89.1921)
					(end 167.968676 -89.4588)
				)
				(xy 168.212516 -89.4588) (xy 168.212516 -88.64854)
				(arc
					(start 167.968676 -88.64854)
					(mid 167.701976 -88.912712)
					(end 167.435276 -88.64854)
				)
				(arc
					(start 167.435276 -88.646)
					(mid 167.701976 -88.3793)
					(end 167.968676 -88.646)
				)
			)
		)
	)
	(zone
		(layers "B.Cu" "In2.Cu")
		(hatch none 0.5)
		(connect_pads
			(clearance 0)
		)
		(min_thickness 0.25)
		(keepout
			(tracks not_allowed)
			(vias allowed)
			(pads allowed)
			(copperpour not_allowed)
			(footprints allowed)
		)
		(placement
			(enabled no)
			(sheetname "")
		)
		(fill yes
			(thermal_gap 0.5)
			(thermal_bridge_width 0.5)
			(island_removal_mode 0)
		)
		(polygon
			(pts
				(arc
					(start 58.093864 -210.385914)
					(mid 57.58307 -210.896327)
					(end 58.09361 -211.406994)
				)
				(arc
					(start 58.90641 -211.406994)
					(mid 59.266517 -211.258357)
					(end 59.41695 -210.898994)
				)
				(arc
					(start 59.17311 -210.898994)
					(mid 58.90641 -211.163166)
					(end 58.63971 -210.898994)
				)
				(arc
					(start 58.36031 -210.898994)
					(mid 58.09361 -211.163166)
					(end 57.82691 -210.898994)
				)
				(arc
					(start 57.82691 -210.896454)
					(mid 58.09361 -210.629754)
					(end 58.36031 -210.896454)
				)
				(arc
					(start 58.63971 -210.896454)
					(mid 58.90641 -210.629754)
					(end 59.17311 -210.896454)
				)
				(arc
					(start 59.41695 -210.896454)
					(mid 59.267416 -210.535448)
					(end 58.90641 -210.385914)
				)
			)
		)
	)
	(zone
		(layers "B.Cu" "In2.Cu")
		(hatch none 0.5)
		(connect_pads
			(clearance 0)
		)
		(min_thickness 0.25)
		(keepout
			(tracks not_allowed)
			(vias allowed)
			(pads allowed)
			(copperpour not_allowed)
			(footprints allowed)
		)
		(placement
			(enabled no)
			(sheetname "")
		)
		(fill yes
			(thermal_gap 0.5)
			(thermal_bridge_width 0.5)
			(island_removal_mode 0)
		)
		(polygon
			(pts
				(arc
					(start 186.56554 -24.998934)
					(mid 186.055 -24.488394)
					(end 185.54446 -24.998934)
				)
				(arc
					(start 185.54446 -25.811734)
					(mid 186.05373 -26.322272)
					(end 186.56554 -25.814274)
				)
				(arc
					(start 186.3217 -25.814274)
					(mid 186.055 -26.078446)
					(end 185.7883 -25.814274)
				)
				(arc
					(start 185.7883 -25.811734)
					(mid 186.055 -25.545034)
					(end 186.3217 -25.811734)
				)
				(xy 186.56554 -25.811734) (xy 186.56554 -25.001474)
				(arc
					(start 186.3217 -25.001474)
					(mid 186.055 -25.265646)
					(end 185.7883 -25.001474)
				)
				(arc
					(start 185.7883 -24.998934)
					(mid 186.055 -24.732234)
					(end 186.3217 -24.998934)
				)
			)
		)
	)
	(zone
		(layers "B.Cu" "In2.Cu")
		(hatch none 0.5)
		(connect_pads
			(clearance 0)
		)
		(min_thickness 0.25)
		(keepout
			(tracks not_allowed)
			(vias allowed)
			(pads allowed)
			(copperpour not_allowed)
			(footprints allowed)
		)
		(placement
			(enabled no)
			(sheetname "")
		)
		(fill yes
			(thermal_gap 0.5)
			(thermal_bridge_width 0.5)
			(island_removal_mode 0)
		)
		(polygon
			(pts
				(arc
					(start 157.694122 -210.385914)
					(mid 157.183328 -210.896327)
					(end 157.693868 -211.406994)
				)
				(arc
					(start 158.506668 -211.406994)
					(mid 158.866775 -211.258357)
					(end 159.017208 -210.898994)
				)
				(arc
					(start 158.773368 -210.898994)
					(mid 158.506668 -211.163166)
					(end 158.239968 -210.898994)
				)
				(arc
					(start 157.960568 -210.898994)
					(mid 157.693868 -211.163166)
					(end 157.427168 -210.898994)
				)
				(arc
					(start 157.427168 -210.896454)
					(mid 157.693868 -210.629754)
					(end 157.960568 -210.896454)
				)
				(arc
					(start 158.239968 -210.896454)
					(mid 158.506668 -210.629754)
					(end 158.773368 -210.896454)
				)
				(arc
					(start 159.017208 -210.896454)
					(mid 158.867674 -210.535448)
					(end 158.506668 -210.385914)
				)
			)
		)
	)
	(zone
		(layers "B.Cu" "In2.Cu")
		(hatch none 0.5)
		(connect_pads
			(clearance 0)
		)
		(min_thickness 0.25)
		(keepout
			(tracks not_allowed)
			(vias allowed)
			(pads allowed)
			(copperpour not_allowed)
			(footprints allowed)
		)
		(placement
			(enabled no)
			(sheetname "")
		)
		(fill yes
			(thermal_gap 0.5)
			(thermal_bridge_width 0.5)
			(island_removal_mode 0)
		)
		(polygon
			(pts
				(arc
					(start 216.093802 -210.385914)
					(mid 215.583008 -210.896327)
					(end 216.093548 -211.406994)
				)
				(arc
					(start 216.906348 -211.406994)
					(mid 217.266455 -211.258357)
					(end 217.416888 -210.898994)
				)
				(arc
					(start 217.173048 -210.898994)
					(mid 216.906348 -211.163166)
					(end 216.639648 -210.898994)
				)
				(arc
					(start 216.360248 -210.898994)
					(mid 216.093548 -211.163166)
					(end 215.826848 -210.898994)
				)
				(arc
					(start 215.826848 -210.896454)
					(mid 216.093548 -210.629754)
					(end 216.360248 -210.896454)
				)
				(arc
					(start 216.639648 -210.896454)
					(mid 216.906348 -210.629754)
					(end 217.173048 -210.896454)
				)
				(arc
					(start 217.416888 -210.896454)
					(mid 217.267354 -210.535448)
					(end 216.906348 -210.385914)
				)
			)
		)
	)
	(zone
		(layers "B.Cu" "In2.Cu")
		(hatch none 0.5)
		(connect_pads
			(clearance 0)
		)
		(min_thickness 0.25)
		(keepout
			(tracks not_allowed)
			(vias allowed)
			(pads allowed)
			(copperpour not_allowed)
			(footprints allowed)
		)
		(placement
			(enabled no)
			(sheetname "")
		)
		(fill yes
			(thermal_gap 0.5)
			(thermal_bridge_width 0.5)
			(island_removal_mode 0)
		)
		(polygon
			(pts
				(arc
					(start 92.332048 -184.941718)
					(mid 91.61018 -184.941718)
					(end 91.61018 -185.663586)
				)
				(xy 91.608402 -185.665364) (xy 92.18295 -186.240166) (xy 92.183204 -186.240166)
				(arc
					(start 92.184982 -186.238388)
					(mid 92.740078 -186.349521)
					(end 93.056456 -185.879994)
				)
				(arc
					(start 92.812616 -185.879994)
					(mid 92.545916 -186.144166)
					(end 92.279216 -185.879994)
				)
				(arc
					(start 92.279216 -185.877454)
					(mid 92.545916 -185.610754)
					(end 92.812616 -185.877454)
				)
				(arc
					(start 93.056456 -185.877454)
					(mid 93.017578 -185.682093)
					(end 92.90685 -185.51652)
				)
				(xy 92.908628 -185.514742) (xy 92.699078 -185.305192)
				(arc
					(start 92.237814 -185.305192)
					(mid 91.971114 -185.569364)
					(end 91.704414 -185.305192)
				)
				(arc
					(start 91.704414 -185.302652)
					(mid 91.971114 -185.035952)
					(end 92.237814 -185.302652)
				)
				(xy 92.696538 -185.302652) (xy 92.333826 -184.93994)
			)
		)
	)
	(zone
		(layers "B.Cu" "In2.Cu")
		(hatch none 0.5)
		(connect_pads
			(clearance 0)
		)
		(min_thickness 0.25)
		(keepout
			(tracks not_allowed)
			(vias allowed)
			(pads allowed)
			(copperpour not_allowed)
			(footprints allowed)
		)
		(placement
			(enabled no)
			(sheetname "")
		)
		(fill yes
			(thermal_gap 0.5)
			(thermal_bridge_width 0.5)
			(island_removal_mode 0)
		)
		(polygon
			(pts
				(arc
					(start 18.574004 -72.700134)
					(mid 18.06321 -73.210547)
					(end 18.57375 -73.721214)
				)
				(arc
					(start 19.38655 -73.721214)
					(mid 19.746657 -73.572577)
					(end 19.89709 -73.213214)
				)
				(arc
					(start 19.65325 -73.213214)
					(mid 19.38655 -73.477386)
					(end 19.11985 -73.213214)
				)
				(arc
					(start 18.84045 -73.213214)
					(mid 18.57375 -73.477386)
					(end 18.30705 -73.213214)
				)
				(arc
					(start 18.30705 -73.210674)
					(mid 18.57375 -72.943974)
					(end 18.84045 -73.210674)
				)
				(arc
					(start 19.11985 -73.210674)
					(mid 19.38655 -72.943974)
					(end 19.65325 -73.210674)
				)
				(arc
					(start 19.89709 -73.210674)
					(mid 19.747556 -72.849668)
					(end 19.38655 -72.700134)
				)
			)
		)
	)
	(zone
		(layers "B.Cu" "In2.Cu")
		(hatch none 0.5)
		(connect_pads
			(clearance 0)
		)
		(min_thickness 0.25)
		(keepout
			(tracks not_allowed)
			(vias allowed)
			(pads allowed)
			(copperpour not_allowed)
			(footprints allowed)
		)
		(placement
			(enabled no)
			(sheetname "")
		)
		(fill yes
			(thermal_gap 0.5)
			(thermal_bridge_width 0.5)
			(island_removal_mode 0)
		)
		(polygon
			(pts
				(arc
					(start 150.9141 -37.57676)
					(mid 150.40356 -38.0873)
					(end 150.9141 -38.59784)
				)
				(arc
					(start 151.726646 -38.59784)
					(mid 152.086917 -38.449293)
					(end 152.23744 -38.08984)
				)
				(arc
					(start 151.9936 -38.08984)
					(mid 151.7269 -38.354012)
					(end 151.4602 -38.08984)
				)
				(arc
					(start 151.1808 -38.08984)
					(mid 150.9141 -38.354012)
					(end 150.6474 -38.08984)
				)
				(arc
					(start 150.6474 -38.0873)
					(mid 150.9141 -37.8206)
					(end 151.1808 -38.0873)
				)
				(arc
					(start 151.4602 -38.0873)
					(mid 151.7269 -37.8206)
					(end 151.9936 -38.0873)
				)
				(arc
					(start 152.23744 -38.0873)
					(mid 152.087906 -37.726294)
					(end 151.7269 -37.57676)
				)
			)
		)
	)
	(zone
		(layers "B.Cu" "In2.Cu")
		(hatch none 0.5)
		(connect_pads
			(clearance 0)
		)
		(min_thickness 0.25)
		(keepout
			(tracks not_allowed)
			(vias allowed)
			(pads allowed)
			(copperpour not_allowed)
			(footprints allowed)
		)
		(placement
			(enabled no)
			(sheetname "")
		)
		(fill yes
			(thermal_gap 0.5)
			(thermal_bridge_width 0.5)
			(island_removal_mode 0)
		)
		(polygon
			(pts
				(arc
					(start 264.49401 -210.385914)
					(mid 263.983216 -210.896327)
					(end 264.493756 -211.406994)
				)
				(arc
					(start 265.306556 -211.406994)
					(mid 265.666663 -211.258357)
					(end 265.817096 -210.898994)
				)
				(arc
					(start 265.573256 -210.898994)
					(mid 265.306556 -211.163166)
					(end 265.039856 -210.898994)
				)
				(arc
					(start 264.760456 -210.898994)
					(mid 264.493756 -211.163166)
					(end 264.227056 -210.898994)
				)
				(arc
					(start 264.227056 -210.896454)
					(mid 264.493756 -210.629754)
					(end 264.760456 -210.896454)
				)
				(arc
					(start 265.039856 -210.896454)
					(mid 265.306556 -210.629754)
					(end 265.573256 -210.896454)
				)
				(arc
					(start 265.817096 -210.896454)
					(mid 265.667562 -210.535448)
					(end 265.306556 -210.385914)
				)
			)
		)
	)
	(zone
		(layers "B.Cu" "In2.Cu")
		(hatch none 0.5)
		(connect_pads
			(clearance 0)
		)
		(min_thickness 0.25)
		(keepout
			(tracks not_allowed)
			(vias allowed)
			(pads allowed)
			(copperpour not_allowed)
			(footprints allowed)
		)
		(placement
			(enabled no)
			(sheetname "")
		)
		(fill yes
			(thermal_gap 0.5)
			(thermal_bridge_width 0.5)
			(island_removal_mode 0)
		)
		(polygon
			(pts
				(arc
					(start 319.694052 -210.385914)
					(mid 319.183258 -210.896327)
					(end 319.693798 -211.406994)
				)
				(arc
					(start 320.506598 -211.406994)
					(mid 320.866705 -211.258357)
					(end 321.017138 -210.898994)
				)
				(arc
					(start 320.773298 -210.898994)
					(mid 320.506598 -211.163166)
					(end 320.239898 -210.898994)
				)
				(arc
					(start 319.960498 -210.898994)
					(mid 319.693798 -211.163166)
					(end 319.427098 -210.898994)
				)
				(arc
					(start 319.427098 -210.896454)
					(mid 319.693798 -210.629754)
					(end 319.960498 -210.896454)
				)
				(arc
					(start 320.239898 -210.896454)
					(mid 320.506598 -210.629754)
					(end 320.773298 -210.896454)
				)
				(arc
					(start 321.017138 -210.896454)
					(mid 320.867604 -210.535448)
					(end 320.506598 -210.385914)
				)
			)
		)
	)
	(zone
		(layers "B.Cu" "In2.Cu")
		(hatch none 0.5)
		(connect_pads
			(clearance 0)
		)
		(min_thickness 0.25)
		(keepout
			(tracks not_allowed)
			(vias allowed)
			(pads allowed)
			(copperpour not_allowed)
			(footprints allowed)
		)
		(placement
			(enabled no)
			(sheetname "")
		)
		(fill yes
			(thermal_gap 0.5)
			(thermal_bridge_width 0.5)
			(island_removal_mode 0)
		)
		(polygon
			(pts
				(arc
					(start 338.893658 -210.385914)
					(mid 338.383118 -210.896454)
					(end 338.893658 -211.406994)
				)
				(arc
					(start 339.706204 -211.406994)
					(mid 340.066475 -211.258447)
					(end 340.216998 -210.898994)
				)
				(arc
					(start 339.973158 -210.898994)
					(mid 339.706458 -211.163166)
					(end 339.439758 -210.898994)
				)
				(arc
					(start 339.160358 -210.898994)
					(mid 338.893658 -211.163166)
					(end 338.626958 -210.898994)
				)
				(arc
					(start 338.626958 -210.896454)
					(mid 338.893658 -210.629754)
					(end 339.160358 -210.896454)
				)
				(arc
					(start 339.439758 -210.896454)
					(mid 339.706458 -210.629754)
					(end 339.973158 -210.896454)
				)
				(arc
					(start 340.216998 -210.896454)
					(mid 340.067464 -210.535448)
					(end 339.706458 -210.385914)
				)
			)
		)
	)
	(zone
		(layers "B.Cu" "In2.Cu")
		(hatch none 0.5)
		(connect_pads
			(clearance 0)
		)
		(min_thickness 0.25)
		(keepout
			(tracks not_allowed)
			(vias allowed)
			(pads allowed)
			(copperpour not_allowed)
			(footprints allowed)
		)
		(placement
			(enabled no)
			(sheetname "")
		)
		(fill yes
			(thermal_gap 0.5)
			(thermal_bridge_width 0.5)
			(island_removal_mode 0)
		)
		(polygon
			(pts
				(arc
					(start 145.910554 -34.48558)
					(mid 145.39976 -34.995993)
					(end 145.9103 -35.50666)
				)
				(arc
					(start 146.7231 -35.50666)
					(mid 147.083207 -35.358023)
					(end 147.23364 -34.99866)
				)
				(arc
					(start 146.9898 -34.99866)
					(mid 146.7231 -35.262832)
					(end 146.4564 -34.99866)
				)
				(arc
					(start 146.177 -34.99866)
					(mid 145.9103 -35.262832)
					(end 145.6436 -34.99866)
				)
				(arc
					(start 145.6436 -34.99612)
					(mid 145.9103 -34.72942)
					(end 146.177 -34.99612)
				)
				(arc
					(start 146.4564 -34.99612)
					(mid 146.7231 -34.72942)
					(end 146.9898 -34.99612)
				)
				(arc
					(start 147.23364 -34.99612)
					(mid 147.084106 -34.635114)
					(end 146.7231 -34.48558)
				)
			)
		)
	)
	(zone
		(layers "B.Cu" "In2.Cu")
		(hatch none 0.5)
		(connect_pads
			(clearance 0)
		)
		(min_thickness 0.25)
		(keepout
			(tracks not_allowed)
			(vias allowed)
			(pads allowed)
			(copperpour not_allowed)
			(footprints allowed)
		)
		(placement
			(enabled no)
			(sheetname "")
		)
		(fill yes
			(thermal_gap 0.5)
			(thermal_bridge_width 0.5)
			(island_removal_mode 0)
		)
		(polygon
			(pts
				(arc
					(start 313.294014 -210.385914)
					(mid 312.78322 -210.896327)
					(end 313.29376 -211.406994)
				)
				(arc
					(start 314.10656 -211.406994)
					(mid 314.466667 -211.258357)
					(end 314.6171 -210.898994)
				)
				(arc
					(start 314.37326 -210.898994)
					(mid 314.10656 -211.163166)
					(end 313.83986 -210.898994)
				)
				(arc
					(start 313.56046 -210.898994)
					(mid 313.29376 -211.163166)
					(end 313.02706 -210.898994)
				)
				(arc
					(start 313.02706 -210.896454)
					(mid 313.29376 -210.629754)
					(end 313.56046 -210.896454)
				)
				(arc
					(start 313.83986 -210.896454)
					(mid 314.10656 -210.629754)
					(end 314.37326 -210.896454)
				)
				(arc
					(start 314.6171 -210.896454)
					(mid 314.467566 -210.535448)
					(end 314.10656 -210.385914)
				)
			)
		)
	)
	(zone
		(layers "B.Cu" "In2.Cu")
		(hatch none 0.5)
		(connect_pads
			(clearance 0)
		)
		(min_thickness 0.25)
		(keepout
			(tracks not_allowed)
			(vias allowed)
			(pads allowed)
			(copperpour not_allowed)
			(footprints allowed)
		)
		(placement
			(enabled no)
			(sheetname "")
		)
		(fill yes
			(thermal_gap 0.5)
			(thermal_bridge_width 0.5)
			(island_removal_mode 0)
		)
		(polygon
			(pts
				(arc
					(start 138.494008 -210.385914)
					(mid 137.983214 -210.896327)
					(end 138.493754 -211.406994)
				)
				(arc
					(start 139.306554 -211.406994)
					(mid 139.666661 -211.258357)
					(end 139.817094 -210.898994)
				)
				(arc
					(start 139.573254 -210.898994)
					(mid 139.306554 -211.163166)
					(end 139.039854 -210.898994)
				)
				(arc
					(start 138.760454 -210.898994)
					(mid 138.493754 -211.163166)
					(end 138.227054 -210.898994)
				)
				(arc
					(start 138.227054 -210.896454)
					(mid 138.493754 -210.629754)
					(end 138.760454 -210.896454)
				)
				(arc
					(start 139.039854 -210.896454)
					(mid 139.306554 -210.629754)
					(end 139.573254 -210.896454)
				)
				(arc
					(start 139.817094 -210.896454)
					(mid 139.66756 -210.535448)
					(end 139.306554 -210.385914)
				)
			)
		)
	)
	(zone
		(layers "B.Cu" "In2.Cu")
		(hatch none 0.5)
		(connect_pads
			(clearance 0)
		)
		(min_thickness 0.25)
		(keepout
			(tracks not_allowed)
			(vias allowed)
			(pads allowed)
			(copperpour not_allowed)
			(footprints allowed)
		)
		(placement
			(enabled no)
			(sheetname "")
		)
		(fill yes
			(thermal_gap 0.5)
			(thermal_bridge_width 0.5)
			(island_removal_mode 0)
		)
		(polygon
			(pts
				(arc
					(start 148.5011 -34.49066)
					(mid 147.99056 -35.0012)
					(end 148.5011 -35.51174)
				)
				(arc
					(start 149.313646 -35.51174)
					(mid 149.673917 -35.363193)
					(end 149.82444 -35.00374)
				)
				(arc
					(start 149.5806 -35.00374)
					(mid 149.3139 -35.267912)
					(end 149.0472 -35.00374)
				)
				(arc
					(start 148.7678 -35.00374)
					(mid 148.5011 -35.267912)
					(end 148.2344 -35.00374)
				)
				(arc
					(start 148.2344 -35.0012)
					(mid 148.5011 -34.7345)
					(end 148.7678 -35.0012)
				)
				(arc
					(start 149.0472 -35.0012)
					(mid 149.3139 -34.7345)
					(end 149.5806 -35.0012)
				)
				(arc
					(start 149.82444 -35.0012)
					(mid 149.674906 -34.640194)
					(end 149.3139 -34.49066)
				)
			)
		)
	)
	(zone
		(layers "B.Cu" "In2.Cu")
		(hatch none 0.5)
		(connect_pads
			(clearance 0)
		)
		(min_thickness 0.25)
		(keepout
			(tracks not_allowed)
			(vias allowed)
			(pads allowed)
			(copperpour not_allowed)
			(footprints allowed)
		)
		(placement
			(enabled no)
			(sheetname "")
		)
		(fill yes
			(thermal_gap 0.5)
			(thermal_bridge_width 0.5)
			(island_removal_mode 0)
		)
		(polygon
			(pts
				(arc
					(start 13.563854 -53.319172)
					(mid 13.05306 -53.829585)
					(end 13.5636 -54.340252)
				)
				(arc
					(start 14.3764 -54.340252)
					(mid 14.736507 -54.191615)
					(end 14.88694 -53.832252)
				)
				(arc
					(start 14.6431 -53.832252)
					(mid 14.3764 -54.096424)
					(end 14.1097 -53.832252)
				)
				(arc
					(start 13.8303 -53.832252)
					(mid 13.5636 -54.096424)
					(end 13.2969 -53.832252)
				)
				(arc
					(start 13.2969 -53.829712)
					(mid 13.5636 -53.563012)
					(end 13.8303 -53.829712)
				)
				(arc
					(start 14.1097 -53.829712)
					(mid 14.3764 -53.563012)
					(end 14.6431 -53.829712)
				)
				(arc
					(start 14.88694 -53.829712)
					(mid 14.737406 -53.468706)
					(end 14.3764 -53.319172)
				)
			)
		)
	)
	(zone
		(layers "B.Cu" "In2.Cu")
		(hatch none 0.5)
		(connect_pads
			(clearance 0)
		)
		(min_thickness 0.25)
		(keepout
			(tracks not_allowed)
			(vias allowed)
			(pads allowed)
			(copperpour not_allowed)
			(footprints allowed)
		)
		(placement
			(enabled no)
			(sheetname "")
		)
		(fill yes
			(thermal_gap 0.5)
			(thermal_bridge_width 0.5)
			(island_removal_mode 0)
		)
		(polygon
			(pts
				(arc
					(start 98.094038 -210.385914)
					(mid 97.583244 -210.896327)
					(end 98.093784 -211.406994)
				)
				(arc
					(start 98.906584 -211.406994)
					(mid 99.266691 -211.258357)
					(end 99.417124 -210.898994)
				)
				(arc
					(start 99.173284 -210.898994)
					(mid 98.906584 -211.163166)
					(end 98.639884 -210.898994)
				)
				(arc
					(start 98.360484 -210.898994)
					(mid 98.093784 -211.163166)
					(end 97.827084 -210.898994)
				)
				(arc
					(start 97.827084 -210.896454)
					(mid 98.093784 -210.629754)
					(end 98.360484 -210.896454)
				)
				(arc
					(start 98.639884 -210.896454)
					(mid 98.906584 -210.629754)
					(end 99.173284 -210.896454)
				)
				(arc
					(start 99.417124 -210.896454)
					(mid 99.26759 -210.535448)
					(end 98.906584 -210.385914)
				)
			)
		)
	)
	(zone
		(layers "B.Cu" "In2.Cu")
		(hatch none 0.5)
		(connect_pads
			(clearance 0)
		)
		(min_thickness 0.25)
		(keepout
			(tracks not_allowed)
			(vias allowed)
			(pads allowed)
			(copperpour not_allowed)
			(footprints allowed)
		)
		(placement
			(enabled no)
			(sheetname "")
		)
		(fill yes
			(thermal_gap 0.5)
			(thermal_bridge_width 0.5)
			(island_removal_mode 0)
		)
		(polygon
			(pts
				(arc
					(start 305.762914 -39.29888)
					(mid 305.252374 -39.80942)
					(end 305.762914 -40.31996)
				)
				(arc
					(start 306.57546 -40.31996)
					(mid 306.935731 -40.171413)
					(end 307.086254 -39.81196)
				)
				(arc
					(start 306.842414 -39.81196)
					(mid 306.575714 -40.076132)
					(end 306.309014 -39.81196)
				)
				(arc
					(start 306.029614 -39.81196)
					(mid 305.762914 -40.076132)
					(end 305.496214 -39.81196)
				)
				(arc
					(start 305.496214 -39.80942)
					(mid 305.762914 -39.54272)
					(end 306.029614 -39.80942)
				)
				(arc
					(start 306.309014 -39.80942)
					(mid 306.575714 -39.54272)
					(end 306.842414 -39.80942)
				)
				(arc
					(start 307.086254 -39.80942)
					(mid 306.93672 -39.448414)
					(end 306.575714 -39.29888)
				)
			)
		)
	)
	(zone
		(layers "B.Cu" "In2.Cu")
		(hatch none 0.5)
		(connect_pads
			(clearance 0)
		)
		(min_thickness 0.25)
		(keepout
			(tracks not_allowed)
			(vias allowed)
			(pads allowed)
			(copperpour not_allowed)
			(footprints allowed)
		)
		(placement
			(enabled no)
			(sheetname "")
		)
		(fill yes
			(thermal_gap 0.5)
			(thermal_bridge_width 0.5)
			(island_removal_mode 0)
		)
		(polygon
			(pts
				(arc
					(start 82.893916 -210.385914)
					(mid 82.383122 -210.896327)
					(end 82.893662 -211.406994)
				)
				(arc
					(start 83.706462 -211.406994)
					(mid 84.066569 -211.258357)
					(end 84.217002 -210.898994)
				)
				(arc
					(start 83.973162 -210.898994)
					(mid 83.706462 -211.163166)
					(end 83.439762 -210.898994)
				)
				(arc
					(start 83.160362 -210.898994)
					(mid 82.893662 -211.163166)
					(end 82.626962 -210.898994)
				)
				(arc
					(start 82.626962 -210.896454)
					(mid 82.893662 -210.629754)
					(end 83.160362 -210.896454)
				)
				(arc
					(start 83.439762 -210.896454)
					(mid 83.706462 -210.629754)
					(end 83.973162 -210.896454)
				)
				(arc
					(start 84.217002 -210.896454)
					(mid 84.067468 -210.535448)
					(end 83.706462 -210.385914)
				)
			)
		)
	)
	(zone
		(layers "B.Cu" "In2.Cu")
		(hatch none 0.5)
		(connect_pads
			(clearance 0)
		)
		(min_thickness 0.25)
		(keepout
			(tracks not_allowed)
			(vias allowed)
			(pads allowed)
			(copperpour not_allowed)
			(footprints allowed)
		)
		(placement
			(enabled no)
			(sheetname "")
		)
		(fill yes
			(thermal_gap 0.5)
			(thermal_bridge_width 0.5)
			(island_removal_mode 0)
		)
		(polygon
			(pts
				(arc
					(start 280.493978 -210.385914)
					(mid 279.983184 -210.896327)
					(end 280.493724 -211.406994)
				)
				(arc
					(start 281.306524 -211.406994)
					(mid 281.666631 -211.258357)
					(end 281.817064 -210.898994)
				)
				(arc
					(start 281.573224 -210.898994)
					(mid 281.306524 -211.163166)
					(end 281.039824 -210.898994)
				)
				(arc
					(start 280.760424 -210.898994)
					(mid 280.493724 -211.163166)
					(end 280.227024 -210.898994)
				)
				(arc
					(start 280.227024 -210.896454)
					(mid 280.493724 -210.629754)
					(end 280.760424 -210.896454)
				)
				(arc
					(start 281.039824 -210.896454)
					(mid 281.306524 -210.629754)
					(end 281.573224 -210.896454)
				)
				(arc
					(start 281.817064 -210.896454)
					(mid 281.66753 -210.535448)
					(end 281.306524 -210.385914)
				)
			)
		)
	)
	(zone
		(layers "B.Cu" "In2.Cu")
		(hatch none 0.5)
		(connect_pads
			(clearance 0)
		)
		(min_thickness 0.25)
		(keepout
			(tracks not_allowed)
			(vias allowed)
			(pads allowed)
			(copperpour not_allowed)
			(footprints allowed)
		)
		(placement
			(enabled no)
			(sheetname "")
		)
		(fill yes
			(thermal_gap 0.5)
			(thermal_bridge_width 0.5)
			(island_removal_mode 0)
		)
		(polygon
			(pts
				(arc
					(start 323.612764 -34.458402)
					(mid 323.10197 -34.968815)
					(end 323.61251 -35.479482)
				)
				(arc
					(start 324.42531 -35.479482)
					(mid 324.785417 -35.330845)
					(end 324.93585 -34.971482)
				)
				(arc
					(start 324.69201 -34.971482)
					(mid 324.42531 -35.235654)
					(end 324.15861 -34.971482)
				)
				(arc
					(start 323.87921 -34.971482)
					(mid 323.61251 -35.235654)
					(end 323.34581 -34.971482)
				)
				(arc
					(start 323.34581 -34.968942)
					(mid 323.61251 -34.702242)
					(end 323.87921 -34.968942)
				)
				(arc
					(start 324.15861 -34.968942)
					(mid 324.42531 -34.702242)
					(end 324.69201 -34.968942)
				)
				(arc
					(start 324.93585 -34.968942)
					(mid 324.786316 -34.607936)
					(end 324.42531 -34.458402)
				)
			)
		)
	)
	(zone
		(layers "B.Cu" "In2.Cu")
		(hatch none 0.5)
		(connect_pads
			(clearance 0)
		)
		(min_thickness 0.25)
		(keepout
			(tracks not_allowed)
			(vias allowed)
			(pads allowed)
			(copperpour not_allowed)
			(footprints allowed)
		)
		(placement
			(enabled no)
			(sheetname "")
		)
		(fill yes
			(thermal_gap 0.5)
			(thermal_bridge_width 0.5)
			(island_removal_mode 0)
		)
		(polygon
			(pts
				(arc
					(start 212.89391 -210.385914)
					(mid 212.383116 -210.896327)
					(end 212.893656 -211.406994)
				)
				(arc
					(start 213.706456 -211.406994)
					(mid 214.066563 -211.258357)
					(end 214.216996 -210.898994)
				)
				(arc
					(start 213.973156 -210.898994)
					(mid 213.706456 -211.163166)
					(end 213.439756 -210.898994)
				)
				(arc
					(start 213.160356 -210.898994)
					(mid 212.893656 -211.163166)
					(end 212.626956 -210.898994)
				)
				(arc
					(start 212.626956 -210.896454)
					(mid 212.893656 -210.629754)
					(end 213.160356 -210.896454)
				)
				(arc
					(start 213.439756 -210.896454)
					(mid 213.706456 -210.629754)
					(end 213.973156 -210.896454)
				)
				(arc
					(start 214.216996 -210.896454)
					(mid 214.067462 -210.535448)
					(end 213.706456 -210.385914)
				)
			)
		)
	)
	(zone
		(layers "B.Cu" "In2.Cu")
		(hatch none 0.5)
		(connect_pads
			(clearance 0)
		)
		(min_thickness 0.25)
		(keepout
			(tracks not_allowed)
			(vias allowed)
			(pads allowed)
			(copperpour not_allowed)
			(footprints allowed)
		)
		(placement
			(enabled no)
			(sheetname "")
		)
		(fill yes
			(thermal_gap 0.5)
			(thermal_bridge_width 0.5)
			(island_removal_mode 0)
		)
		(polygon
			(pts
				(arc
					(start 285.498794 -33.051496)
					(mid 284.988254 -32.540956)
					(end 284.477714 -33.051496)
				)
				(arc
					(start 284.477714 -33.864042)
					(mid 284.986857 -34.374834)
					(end 285.498794 -33.866836)
				)
				(arc
					(start 285.254954 -33.866836)
					(mid 284.988254 -34.131008)
					(end 284.721554 -33.866836)
				)
				(arc
					(start 284.721554 -33.864296)
					(mid 284.988254 -33.597596)
					(end 285.254954 -33.864296)
				)
				(xy 285.498794 -33.864296) (xy 285.498794 -33.054036)
				(arc
					(start 285.254954 -33.054036)
					(mid 284.988254 -33.318208)
					(end 284.721554 -33.054036)
				)
				(arc
					(start 284.721554 -33.051496)
					(mid 284.988254 -32.784796)
					(end 285.254954 -33.051496)
				)
			)
		)
	)
	(zone
		(layers "B.Cu" "In2.Cu")
		(hatch none 0.5)
		(connect_pads
			(clearance 0)
		)
		(min_thickness 0.25)
		(keepout
			(tracks not_allowed)
			(vias allowed)
			(pads allowed)
			(copperpour not_allowed)
			(footprints allowed)
		)
		(placement
			(enabled no)
			(sheetname "")
		)
		(fill yes
			(thermal_gap 0.5)
			(thermal_bridge_width 0.5)
			(island_removal_mode 0)
		)
		(polygon
			(pts
				(arc
					(start 328.375518 -34.408872)
					(mid 327.864978 -34.919412)
					(end 328.375518 -35.429952)
				)
				(arc
					(start 329.188064 -35.429952)
					(mid 329.548335 -35.281405)
					(end 329.698858 -34.921952)
				)
				(arc
					(start 329.455018 -34.921952)
					(mid 329.188318 -35.186124)
					(end 328.921618 -34.921952)
				)
				(arc
					(start 328.642218 -34.921952)
					(mid 328.375518 -35.186124)
					(end 328.108818 -34.921952)
				)
				(arc
					(start 328.108818 -34.919412)
					(mid 328.375518 -34.652712)
					(end 328.642218 -34.919412)
				)
				(arc
					(start 328.921618 -34.919412)
					(mid 329.188318 -34.652712)
					(end 329.455018 -34.919412)
				)
				(arc
					(start 329.698858 -34.919412)
					(mid 329.549324 -34.558406)
					(end 329.188318 -34.408872)
				)
			)
		)
	)
	(zone
		(layers "B.Cu" "In2.Cu")
		(hatch none 0.5)
		(connect_pads
			(clearance 0)
		)
		(min_thickness 0.25)
		(keepout
			(tracks not_allowed)
			(vias allowed)
			(pads allowed)
			(copperpour not_allowed)
			(footprints allowed)
		)
		(placement
			(enabled no)
			(sheetname "")
		)
		(fill yes
			(thermal_gap 0.5)
			(thermal_bridge_width 0.5)
			(island_removal_mode 0)
		)
		(polygon
			(pts
				(arc
					(start 290.093908 -210.385914)
					(mid 289.583114 -210.896327)
					(end 290.093654 -211.406994)
				)
				(arc
					(start 290.906454 -211.406994)
					(mid 291.266561 -211.258357)
					(end 291.416994 -210.898994)
				)
				(arc
					(start 291.173154 -210.898994)
					(mid 290.906454 -211.163166)
					(end 290.639754 -210.898994)
				)
				(arc
					(start 290.360354 -210.898994)
					(mid 290.093654 -211.163166)
					(end 289.826954 -210.898994)
				)
				(arc
					(start 289.826954 -210.896454)
					(mid 290.093654 -210.629754)
					(end 290.360354 -210.896454)
				)
				(arc
					(start 290.639754 -210.896454)
					(mid 290.906454 -210.629754)
					(end 291.173154 -210.896454)
				)
				(arc
					(start 291.416994 -210.896454)
					(mid 291.26746 -210.535448)
					(end 290.906454 -210.385914)
				)
			)
		)
	)
	(zone
		(layers "B.Cu" "In2.Cu")
		(hatch none 0.5)
		(connect_pads
			(clearance 0)
		)
		(min_thickness 0.25)
		(keepout
			(tracks not_allowed)
			(vias allowed)
			(pads allowed)
			(copperpour not_allowed)
			(footprints allowed)
		)
		(placement
			(enabled no)
			(sheetname "")
		)
		(fill yes
			(thermal_gap 0.5)
			(thermal_bridge_width 0.5)
			(island_removal_mode 0)
		)
		(polygon
			(pts
				(arc
					(start 302.093884 -210.385914)
					(mid 301.58309 -210.896327)
					(end 302.09363 -211.406994)
				)
				(arc
					(start 302.90643 -211.406994)
					(mid 303.266537 -211.258357)
					(end 303.41697 -210.898994)
				)
				(arc
					(start 303.17313 -210.898994)
					(mid 302.90643 -211.163166)
					(end 302.63973 -210.898994)
				)
				(arc
					(start 302.36033 -210.898994)
					(mid 302.09363 -211.163166)
					(end 301.82693 -210.898994)
				)
				(arc
					(start 301.82693 -210.896454)
					(mid 302.09363 -210.629754)
					(end 302.36033 -210.896454)
				)
				(arc
					(start 302.63973 -210.896454)
					(mid 302.90643 -210.629754)
					(end 303.17313 -210.896454)
				)
				(arc
					(start 303.41697 -210.896454)
					(mid 303.267436 -210.535448)
					(end 302.90643 -210.385914)
				)
			)
		)
	)
	(zone
		(layers "B.Cu" "In2.Cu")
		(hatch none 0.5)
		(connect_pads
			(clearance 0)
		)
		(min_thickness 0.25)
		(keepout
			(tracks not_allowed)
			(vias allowed)
			(pads allowed)
			(copperpour not_allowed)
			(footprints allowed)
		)
		(placement
			(enabled no)
			(sheetname "")
		)
		(fill yes
			(thermal_gap 0.5)
			(thermal_bridge_width 0.5)
			(island_removal_mode 0)
		)
		(polygon
			(pts
				(arc
					(start 169.693844 -210.385914)
					(mid 169.18305 -210.896327)
					(end 169.69359 -211.406994)
				)
				(arc
					(start 170.50639 -211.406994)
					(mid 170.866497 -211.258357)
					(end 171.01693 -210.898994)
				)
				(arc
					(start 170.77309 -210.898994)
					(mid 170.50639 -211.163166)
					(end 170.23969 -210.898994)
				)
				(arc
					(start 169.96029 -210.898994)
					(mid 169.69359 -211.163166)
					(end 169.42689 -210.898994)
				)
				(arc
					(start 169.42689 -210.896454)
					(mid 169.69359 -210.629754)
					(end 169.96029 -210.896454)
				)
				(arc
					(start 170.23969 -210.896454)
					(mid 170.50639 -210.629754)
					(end 170.77309 -210.896454)
				)
				(arc
					(start 171.01693 -210.896454)
					(mid 170.867396 -210.535448)
					(end 170.50639 -210.385914)
				)
			)
		)
	)
	(zone
		(layers "B.Cu" "In2.Cu")
		(hatch none 0.5)
		(connect_pads
			(clearance 0)
		)
		(min_thickness 0.25)
		(keepout
			(tracks not_allowed)
			(vias allowed)
			(pads allowed)
			(copperpour not_allowed)
			(footprints allowed)
		)
		(placement
			(enabled no)
			(sheetname "")
		)
		(fill yes
			(thermal_gap 0.5)
			(thermal_bridge_width 0.5)
			(island_removal_mode 0)
		)
		(polygon
			(pts
				(arc
					(start 322.893944 -210.385914)
					(mid 322.38315 -210.896327)
					(end 322.89369 -211.406994)
				)
				(arc
					(start 323.70649 -211.406994)
					(mid 324.066597 -211.258357)
					(end 324.21703 -210.898994)
				)
				(arc
					(start 323.97319 -210.898994)
					(mid 323.70649 -211.163166)
					(end 323.43979 -210.898994)
				)
				(arc
					(start 323.16039 -210.898994)
					(mid 322.89369 -211.163166)
					(end 322.62699 -210.898994)
				)
				(arc
					(start 322.62699 -210.896454)
					(mid 322.89369 -210.629754)
					(end 323.16039 -210.896454)
				)
				(arc
					(start 323.43979 -210.896454)
					(mid 323.70649 -210.629754)
					(end 323.97319 -210.896454)
				)
				(arc
					(start 324.21703 -210.896454)
					(mid 324.067496 -210.535448)
					(end 323.70649 -210.385914)
				)
			)
		)
	)
	(zone
		(layers "B.Cu" "In2.Cu")
		(hatch none 0.5)
		(connect_pads
			(clearance 0)
		)
		(min_thickness 0.25)
		(keepout
			(tracks not_allowed)
			(vias allowed)
			(pads allowed)
			(copperpour not_allowed)
			(footprints allowed)
		)
		(placement
			(enabled no)
			(sheetname "")
		)
		(fill yes
			(thermal_gap 0.5)
			(thermal_bridge_width 0.5)
			(island_removal_mode 0)
		)
		(polygon
			(pts
				(arc
					(start 299.430948 -35.678872)
					(mid 298.920154 -36.189285)
					(end 299.430694 -36.699952)
				)
				(arc
					(start 300.243494 -36.699952)
					(mid 300.603601 -36.551315)
					(end 300.754034 -36.191952)
				)
				(arc
					(start 300.510194 -36.191952)
					(mid 300.243494 -36.456124)
					(end 299.976794 -36.191952)
				)
				(arc
					(start 299.697394 -36.191952)
					(mid 299.430694 -36.456124)
					(end 299.163994 -36.191952)
				)
				(arc
					(start 299.163994 -36.189412)
					(mid 299.430694 -35.922712)
					(end 299.697394 -36.189412)
				)
				(arc
					(start 299.976794 -36.189412)
					(mid 300.243494 -35.922712)
					(end 300.510194 -36.189412)
				)
				(arc
					(start 300.754034 -36.189412)
					(mid 300.6045 -35.828406)
					(end 300.243494 -35.678872)
				)
			)
		)
	)
	(zone
		(layers "B.Cu" "In2.Cu")
		(hatch none 0.5)
		(connect_pads
			(clearance 0)
		)
		(min_thickness 0.25)
		(keepout
			(tracks not_allowed)
			(vias allowed)
			(pads allowed)
			(copperpour not_allowed)
			(footprints allowed)
		)
		(placement
			(enabled no)
			(sheetname "")
		)
		(fill yes
			(thermal_gap 0.5)
			(thermal_bridge_width 0.5)
			(island_removal_mode 0)
		)
		(polygon
			(pts
				(arc
					(start 283.69387 -210.385914)
					(mid 283.183076 -210.896327)
					(end 283.693616 -211.406994)
				)
				(arc
					(start 284.506416 -211.406994)
					(mid 284.866523 -211.258357)
					(end 285.016956 -210.898994)
				)
				(arc
					(start 284.773116 -210.898994)
					(mid 284.506416 -211.163166)
					(end 284.239716 -210.898994)
				)
				(arc
					(start 283.960316 -210.898994)
					(mid 283.693616 -211.163166)
					(end 283.426916 -210.898994)
				)
				(arc
					(start 283.426916 -210.896454)
					(mid 283.693616 -210.629754)
					(end 283.960316 -210.896454)
				)
				(arc
					(start 284.239716 -210.896454)
					(mid 284.506416 -210.629754)
					(end 284.773116 -210.896454)
				)
				(arc
					(start 285.016956 -210.896454)
					(mid 284.867422 -210.535448)
					(end 284.506416 -210.385914)
				)
			)
		)
	)
	(zone
		(layers "B.Cu" "In2.Cu")
		(hatch none 0.5)
		(connect_pads
			(clearance 0)
		)
		(min_thickness 0.25)
		(keepout
			(tracks not_allowed)
			(vias allowed)
			(pads allowed)
			(copperpour not_allowed)
			(footprints allowed)
		)
		(placement
			(enabled no)
			(sheetname "")
		)
		(fill yes
			(thermal_gap 0.5)
			(thermal_bridge_width 0.5)
			(island_removal_mode 0)
		)
		(polygon
			(pts
				(arc
					(start 154.493976 -210.385914)
					(mid 153.983182 -210.896327)
					(end 154.493722 -211.406994)
				)
				(arc
					(start 155.306522 -211.406994)
					(mid 155.666629 -211.258357)
					(end 155.817062 -210.898994)
				)
				(arc
					(start 155.573222 -210.898994)
					(mid 155.306522 -211.163166)
					(end 155.039822 -210.898994)
				)
				(arc
					(start 154.760422 -210.898994)
					(mid 154.493722 -211.163166)
					(end 154.227022 -210.898994)
				)
				(arc
					(start 154.227022 -210.896454)
					(mid 154.493722 -210.629754)
					(end 154.760422 -210.896454)
				)
				(arc
					(start 155.039822 -210.896454)
					(mid 155.306522 -210.629754)
					(end 155.573222 -210.896454)
				)
				(arc
					(start 155.817062 -210.896454)
					(mid 155.667528 -210.535448)
					(end 155.306522 -210.385914)
				)
			)
		)
	)
	(zone
		(layers "B.Cu" "In2.Cu")
		(hatch none 0.5)
		(connect_pads
			(clearance 0)
		)
		(min_thickness 0.25)
		(keepout
			(tracks not_allowed)
			(vias allowed)
			(pads allowed)
			(copperpour not_allowed)
			(footprints allowed)
		)
		(placement
			(enabled no)
			(sheetname "")
		)
		(fill yes
			(thermal_gap 0.5)
			(thermal_bridge_width 0.5)
			(island_removal_mode 0)
		)
		(polygon
			(pts
				(arc
					(start 335.69402 -210.385914)
					(mid 335.183226 -210.896327)
					(end 335.693766 -211.406994)
				)
				(arc
					(start 336.506566 -211.406994)
					(mid 336.866673 -211.258357)
					(end 337.017106 -210.898994)
				)
				(arc
					(start 336.773266 -210.898994)
					(mid 336.506566 -211.163166)
					(end 336.239866 -210.898994)
				)
				(arc
					(start 335.960466 -210.898994)
					(mid 335.693766 -211.163166)
					(end 335.427066 -210.898994)
				)
				(arc
					(start 335.427066 -210.896454)
					(mid 335.693766 -210.629754)
					(end 335.960466 -210.896454)
				)
				(arc
					(start 336.239866 -210.896454)
					(mid 336.506566 -210.629754)
					(end 336.773266 -210.896454)
				)
				(arc
					(start 337.017106 -210.896454)
					(mid 336.867572 -210.535448)
					(end 336.506566 -210.385914)
				)
			)
		)
	)
	(zone
		(layers "B.Cu" "In2.Cu")
		(hatch none 0.5)
		(connect_pads
			(clearance 0)
		)
		(min_thickness 0.25)
		(keepout
			(tracks not_allowed)
			(vias allowed)
			(pads allowed)
			(copperpour not_allowed)
			(footprints allowed)
		)
		(placement
			(enabled no)
			(sheetname "")
		)
		(fill yes
			(thermal_gap 0.5)
			(thermal_bridge_width 0.5)
			(island_removal_mode 0)
		)
		(polygon
			(pts
				(arc
					(start 144.894046 -210.385914)
					(mid 144.383252 -210.896327)
					(end 144.893792 -211.406994)
				)
				(arc
					(start 145.706592 -211.406994)
					(mid 146.066699 -211.258357)
					(end 146.217132 -210.898994)
				)
				(arc
					(start 145.973292 -210.898994)
					(mid 145.706592 -211.163166)
					(end 145.439892 -210.898994)
				)
				(arc
					(start 145.160492 -210.898994)
					(mid 144.893792 -211.163166)
					(end 144.627092 -210.898994)
				)
				(arc
					(start 144.627092 -210.896454)
					(mid 144.893792 -210.629754)
					(end 145.160492 -210.896454)
				)
				(arc
					(start 145.439892 -210.896454)
					(mid 145.706592 -210.629754)
					(end 145.973292 -210.896454)
				)
				(arc
					(start 146.217132 -210.896454)
					(mid 146.067598 -210.535448)
					(end 145.706592 -210.385914)
				)
			)
		)
	)
	(zone
		(layers "B.Cu" "In2.Cu")
		(hatch none 0.5)
		(connect_pads
			(clearance 0)
		)
		(min_thickness 0.25)
		(keepout
			(tracks not_allowed)
			(vias allowed)
			(pads allowed)
			(copperpour not_allowed)
			(footprints allowed)
		)
		(placement
			(enabled no)
			(sheetname "")
		)
		(fill yes
			(thermal_gap 0.5)
			(thermal_bridge_width 0.5)
			(island_removal_mode 0)
		)
		(polygon
			(pts
				(arc
					(start 101.293676 -210.385914)
					(mid 100.783136 -210.896454)
					(end 101.293676 -211.406994)
				)
				(arc
					(start 102.106222 -211.406994)
					(mid 102.466493 -211.258447)
					(end 102.617016 -210.898994)
				)
				(arc
					(start 102.373176 -210.898994)
					(mid 102.106476 -211.163166)
					(end 101.839776 -210.898994)
				)
				(arc
					(start 101.560376 -210.898994)
					(mid 101.293676 -211.163166)
					(end 101.026976 -210.898994)
				)
				(arc
					(start 101.026976 -210.896454)
					(mid 101.293676 -210.629754)
					(end 101.560376 -210.896454)
				)
				(arc
					(start 101.839776 -210.896454)
					(mid 102.106476 -210.629754)
					(end 102.373176 -210.896454)
				)
				(arc
					(start 102.617016 -210.896454)
					(mid 102.467482 -210.535448)
					(end 102.106476 -210.385914)
				)
			)
		)
	)
	(zone
		(layers "B.Cu" "In2.Cu")
		(hatch none 0.5)
		(connect_pads
			(clearance 0)
		)
		(min_thickness 0.25)
		(keepout
			(tracks not_allowed)
			(vias allowed)
			(pads allowed)
			(copperpour not_allowed)
			(footprints allowed)
		)
		(placement
			(enabled no)
			(sheetname "")
		)
		(fill yes
			(thermal_gap 0.5)
			(thermal_bridge_width 0.5)
			(island_removal_mode 0)
		)
		(polygon
			(pts
				(arc
					(start 70.09384 -210.385914)
					(mid 69.583046 -210.896327)
					(end 70.093586 -211.406994)
				)
				(arc
					(start 70.906386 -211.406994)
					(mid 71.266493 -211.258357)
					(end 71.416926 -210.898994)
				)
				(arc
					(start 71.173086 -210.898994)
					(mid 70.906386 -211.163166)
					(end 70.639686 -210.898994)
				)
				(arc
					(start 70.360286 -210.898994)
					(mid 70.093586 -211.163166)
					(end 69.826886 -210.898994)
				)
				(arc
					(start 69.826886 -210.896454)
					(mid 70.093586 -210.629754)
					(end 70.360286 -210.896454)
				)
				(arc
					(start 70.639686 -210.896454)
					(mid 70.906386 -210.629754)
					(end 71.173086 -210.896454)
				)
				(arc
					(start 71.416926 -210.896454)
					(mid 71.267392 -210.535448)
					(end 70.906386 -210.385914)
				)
			)
		)
	)
	(zone
		(layers "B.Cu" "In2.Cu")
		(hatch none 0.5)
		(connect_pads
			(clearance 0)
		)
		(min_thickness 0.25)
		(keepout
			(tracks not_allowed)
			(vias allowed)
			(pads allowed)
			(copperpour not_allowed)
			(footprints allowed)
		)
		(placement
			(enabled no)
			(sheetname "")
		)
		(fill yes
			(thermal_gap 0.5)
			(thermal_bridge_width 0.5)
			(island_removal_mode 0)
		)
		(polygon
			(pts
				(arc
					(start 196.893942 -210.385914)
					(mid 196.383148 -210.896327)
					(end 196.893688 -211.406994)
				)
				(arc
					(start 197.706488 -211.406994)
					(mid 198.066595 -211.258357)
					(end 198.217028 -210.898994)
				)
				(arc
					(start 197.973188 -210.898994)
					(mid 197.706488 -211.163166)
					(end 197.439788 -210.898994)
				)
				(arc
					(start 197.160388 -210.898994)
					(mid 196.893688 -211.163166)
					(end 196.626988 -210.898994)
				)
				(arc
					(start 196.626988 -210.896454)
					(mid 196.893688 -210.629754)
					(end 197.160388 -210.896454)
				)
				(arc
					(start 197.439788 -210.896454)
					(mid 197.706488 -210.629754)
					(end 197.973188 -210.896454)
				)
				(arc
					(start 198.217028 -210.896454)
					(mid 198.067494 -210.535448)
					(end 197.706488 -210.385914)
				)
			)
		)
	)
	(zone
		(layers "B.Cu" "In2.Cu")
		(hatch none 0.5)
		(connect_pads
			(clearance 0)
		)
		(min_thickness 0.25)
		(keepout
			(tracks not_allowed)
			(vias allowed)
			(pads allowed)
			(copperpour not_allowed)
			(footprints allowed)
		)
		(placement
			(enabled no)
			(sheetname "")
		)
		(fill yes
			(thermal_gap 0.5)
			(thermal_bridge_width 0.5)
			(island_removal_mode 0)
		)
		(polygon
			(pts
				(arc
					(start 138.557254 -38.14826)
					(mid 138.04646 -38.658673)
					(end 138.557 -39.16934)
				)
				(arc
					(start 139.3698 -39.16934)
					(mid 139.729907 -39.020703)
					(end 139.88034 -38.66134)
				)
				(arc
					(start 139.6365 -38.66134)
					(mid 139.3698 -38.925512)
					(end 139.1031 -38.66134)
				)
				(arc
					(start 138.8237 -38.66134)
					(mid 138.557 -38.925512)
					(end 138.2903 -38.66134)
				)
				(arc
					(start 138.2903 -38.6588)
					(mid 138.557 -38.3921)
					(end 138.8237 -38.6588)
				)
				(arc
					(start 139.1031 -38.6588)
					(mid 139.3698 -38.3921)
					(end 139.6365 -38.6588)
				)
				(arc
					(start 139.88034 -38.6588)
					(mid 139.730806 -38.297794)
					(end 139.3698 -38.14826)
				)
			)
		)
	)
	(zone
		(layers "B.Cu" "In2.Cu")
		(hatch none 0.5)
		(connect_pads
			(clearance 0)
		)
		(min_thickness 0.25)
		(keepout
			(tracks not_allowed)
			(vias allowed)
			(pads allowed)
			(copperpour not_allowed)
			(footprints allowed)
		)
		(placement
			(enabled no)
			(sheetname "")
		)
		(fill yes
			(thermal_gap 0.5)
			(thermal_bridge_width 0.5)
			(island_removal_mode 0)
		)
		(polygon
			(pts
				(arc
					(start 172.89399 -210.385914)
					(mid 172.383196 -210.896327)
					(end 172.893736 -211.406994)
				)
				(arc
					(start 173.706536 -211.406994)
					(mid 174.066643 -211.258357)
					(end 174.217076 -210.898994)
				)
				(arc
					(start 173.973236 -210.898994)
					(mid 173.706536 -211.163166)
					(end 173.439836 -210.898994)
				)
				(arc
					(start 173.160436 -210.898994)
					(mid 172.893736 -211.163166)
					(end 172.627036 -210.898994)
				)
				(arc
					(start 172.627036 -210.896454)
					(mid 172.893736 -210.629754)
					(end 173.160436 -210.896454)
				)
				(arc
					(start 173.439836 -210.896454)
					(mid 173.706536 -210.629754)
					(end 173.973236 -210.896454)
				)
				(arc
					(start 174.217076 -210.896454)
					(mid 174.067542 -210.535448)
					(end 173.706536 -210.385914)
				)
			)
		)
	)
	(zone
		(layers "B.Cu" "In2.Cu")
		(hatch none 0.5)
		(connect_pads
			(clearance 0)
		)
		(min_thickness 0.25)
		(keepout
			(tracks not_allowed)
			(vias allowed)
			(pads allowed)
			(copperpour not_allowed)
			(footprints allowed)
		)
		(placement
			(enabled no)
			(sheetname "")
		)
		(fill yes
			(thermal_gap 0.5)
			(thermal_bridge_width 0.5)
			(island_removal_mode 0)
		)
		(polygon
			(pts
				(arc
					(start 298.893992 -210.385914)
					(mid 298.383198 -210.896327)
					(end 298.893738 -211.406994)
				)
				(arc
					(start 299.706538 -211.406994)
					(mid 300.066645 -211.258357)
					(end 300.217078 -210.898994)
				)
				(arc
					(start 299.973238 -210.898994)
					(mid 299.706538 -211.163166)
					(end 299.439838 -210.898994)
				)
				(arc
					(start 299.160438 -210.898994)
					(mid 298.893738 -211.163166)
					(end 298.627038 -210.898994)
				)
				(arc
					(start 298.627038 -210.896454)
					(mid 298.893738 -210.629754)
					(end 299.160438 -210.896454)
				)
				(arc
					(start 299.439838 -210.896454)
					(mid 299.706538 -210.629754)
					(end 299.973238 -210.896454)
				)
				(arc
					(start 300.217078 -210.896454)
					(mid 300.067544 -210.535448)
					(end 299.706538 -210.385914)
				)
			)
		)
	)
	(zone
		(layers "B.Cu" "In2.Cu")
		(hatch none 0.5)
		(connect_pads
			(clearance 0)
		)
		(min_thickness 0.25)
		(keepout
			(tracks not_allowed)
			(vias allowed)
			(pads allowed)
			(copperpour not_allowed)
			(footprints allowed)
		)
		(placement
			(enabled no)
			(sheetname "")
		)
		(fill yes
			(thermal_gap 0.5)
			(thermal_bridge_width 0.5)
			(island_removal_mode 0)
		)
		(polygon
			(pts
				(arc
					(start 79.69377 -210.385914)
					(mid 79.182976 -210.896327)
					(end 79.693516 -211.406994)
				)
				(arc
					(start 80.506316 -211.406994)
					(mid 80.866423 -211.258357)
					(end 81.016856 -210.898994)
				)
				(arc
					(start 80.773016 -210.898994)
					(mid 80.506316 -211.163166)
					(end 80.239616 -210.898994)
				)
				(arc
					(start 79.960216 -210.898994)
					(mid 79.693516 -211.163166)
					(end 79.426816 -210.898994)
				)
				(arc
					(start 79.426816 -210.896454)
					(mid 79.693516 -210.629754)
					(end 79.960216 -210.896454)
				)
				(arc
					(start 80.239616 -210.896454)
					(mid 80.506316 -210.629754)
					(end 80.773016 -210.896454)
				)
				(arc
					(start 81.016856 -210.896454)
					(mid 80.867322 -210.535448)
					(end 80.506316 -210.385914)
				)
			)
		)
	)
	(zone
		(layers "B.Cu" "In2.Cu")
		(hatch none 0.5)
		(connect_pads
			(clearance 0)
		)
		(min_thickness 0.25)
		(keepout
			(tracks not_allowed)
			(vias allowed)
			(pads allowed)
			(copperpour not_allowed)
			(footprints allowed)
		)
		(placement
			(enabled no)
			(sheetname "")
		)
		(fill yes
			(thermal_gap 0.5)
			(thermal_bridge_width 0.5)
			(island_removal_mode 0)
		)
		(polygon
			(pts
				(arc
					(start 162.6997 -81.15046)
					(mid 162.18916 -81.661)
					(end 162.6997 -82.17154)
				)
				(arc
					(start 163.512246 -82.17154)
					(mid 163.872517 -82.022993)
					(end 164.02304 -81.66354)
				)
				(arc
					(start 163.7792 -81.66354)
					(mid 163.5125 -81.927712)
					(end 163.2458 -81.66354)
				)
				(arc
					(start 162.9664 -81.66354)
					(mid 162.6997 -81.927712)
					(end 162.433 -81.66354)
				)
				(arc
					(start 162.433 -81.661)
					(mid 162.6997 -81.3943)
					(end 162.9664 -81.661)
				)
				(arc
					(start 163.2458 -81.661)
					(mid 163.5125 -81.3943)
					(end 163.7792 -81.661)
				)
				(arc
					(start 164.02304 -81.661)
					(mid 163.873506 -81.299994)
					(end 163.5125 -81.15046)
				)
			)
		)
	)
	(zone
		(layers "B.Cu" "In2.Cu")
		(hatch none 0.5)
		(connect_pads
			(clearance 0)
		)
		(min_thickness 0.25)
		(keepout
			(tracks not_allowed)
			(vias allowed)
			(pads allowed)
			(copperpour not_allowed)
			(footprints allowed)
		)
		(placement
			(enabled no)
			(sheetname "")
		)
		(fill yes
			(thermal_gap 0.5)
			(thermal_bridge_width 0.5)
			(island_removal_mode 0)
		)
		(polygon
			(pts
				(arc
					(start 326.093836 -210.385914)
					(mid 325.583042 -210.896327)
					(end 326.093582 -211.406994)
				)
				(arc
					(start 326.906382 -211.406994)
					(mid 327.266489 -211.258357)
					(end 327.416922 -210.898994)
				)
				(arc
					(start 327.173082 -210.898994)
					(mid 326.906382 -211.163166)
					(end 326.639682 -210.898994)
				)
				(arc
					(start 326.360282 -210.898994)
					(mid 326.093582 -211.163166)
					(end 325.826882 -210.898994)
				)
				(arc
					(start 325.826882 -210.896454)
					(mid 326.093582 -210.629754)
					(end 326.360282 -210.896454)
				)
				(arc
					(start 326.639682 -210.896454)
					(mid 326.906382 -210.629754)
					(end 327.173082 -210.896454)
				)
				(arc
					(start 327.416922 -210.896454)
					(mid 327.267388 -210.535448)
					(end 326.906382 -210.385914)
				)
			)
		)
	)
	(zone
		(layers "B.Cu" "In2.Cu")
		(hatch none 0.5)
		(connect_pads
			(clearance 0)
		)
		(min_thickness 0.25)
		(keepout
			(tracks not_allowed)
			(vias allowed)
			(pads allowed)
			(copperpour not_allowed)
			(footprints allowed)
		)
		(placement
			(enabled no)
			(sheetname "")
		)
		(fill yes
			(thermal_gap 0.5)
			(thermal_bridge_width 0.5)
			(island_removal_mode 0)
		)
		(polygon
			(pts
				(arc
					(start 342.09355 -210.385914)
					(mid 341.58301 -210.896454)
					(end 342.09355 -211.406994)
				)
				(arc
					(start 342.906096 -211.406994)
					(mid 343.266367 -211.258447)
					(end 343.41689 -210.898994)
				)
				(arc
					(start 343.17305 -210.898994)
					(mid 342.90635 -211.163166)
					(end 342.63965 -210.898994)
				)
				(arc
					(start 342.36025 -210.898994)
					(mid 342.09355 -211.163166)
					(end 341.82685 -210.898994)
				)
				(arc
					(start 341.82685 -210.896454)
					(mid 342.09355 -210.629754)
					(end 342.36025 -210.896454)
				)
				(arc
					(start 342.63965 -210.896454)
					(mid 342.90635 -210.629754)
					(end 343.17305 -210.896454)
				)
				(arc
					(start 343.41689 -210.896454)
					(mid 343.267356 -210.535448)
					(end 342.90635 -210.385914)
				)
			)
		)
	)
	(zone
		(layers "B.Cu" "In2.Cu")
		(hatch none 0.5)
		(connect_pads
			(clearance 0)
		)
		(min_thickness 0.25)
		(keepout
			(tracks not_allowed)
			(vias allowed)
			(pads allowed)
			(copperpour not_allowed)
			(footprints allowed)
		)
		(placement
			(enabled no)
			(sheetname "")
		)
		(fill yes
			(thermal_gap 0.5)
			(thermal_bridge_width 0.5)
			(island_removal_mode 0)
		)
		(polygon
			(pts
				(arc
					(start 314.8838 -34.503614)
					(mid 314.37326 -35.014154)
					(end 314.8838 -35.524694)
				)
				(arc
					(start 315.696346 -35.524694)
					(mid 316.056617 -35.376147)
					(end 316.20714 -35.016694)
				)
				(arc
					(start 315.9633 -35.016694)
					(mid 315.6966 -35.280866)
					(end 315.4299 -35.016694)
				)
				(arc
					(start 315.1505 -35.016694)
					(mid 314.8838 -35.280866)
					(end 314.6171 -35.016694)
				)
				(arc
					(start 314.6171 -35.014154)
					(mid 314.8838 -34.747454)
					(end 315.1505 -35.014154)
				)
				(arc
					(start 315.4299 -35.014154)
					(mid 315.6966 -34.747454)
					(end 315.9633 -35.014154)
				)
				(arc
					(start 316.20714 -35.014154)
					(mid 316.057606 -34.653148)
					(end 315.6966 -34.503614)
				)
			)
		)
	)
	(zone
		(layers "B.Cu" "In2.Cu")
		(hatch none 0.5)
		(connect_pads
			(clearance 0)
		)
		(min_thickness 0.25)
		(keepout
			(tracks not_allowed)
			(vias allowed)
			(pads allowed)
			(copperpour not_allowed)
			(footprints allowed)
		)
		(placement
			(enabled no)
			(sheetname "")
		)
		(fill yes
			(thermal_gap 0.5)
			(thermal_bridge_width 0.5)
			(island_removal_mode 0)
		)
		(polygon
			(pts
				(arc
					(start 286.893762 -210.385914)
					(mid 286.383222 -210.896454)
					(end 286.893762 -211.406994)
				)
				(arc
					(start 287.706308 -211.406994)
					(mid 288.066579 -211.258447)
					(end 288.217102 -210.898994)
				)
				(arc
					(start 287.973262 -210.898994)
					(mid 287.706562 -211.163166)
					(end 287.439862 -210.898994)
				)
				(arc
					(start 287.160462 -210.898994)
					(mid 286.893762 -211.163166)
					(end 286.627062 -210.898994)
				)
				(arc
					(start 286.627062 -210.896454)
					(mid 286.893762 -210.629754)
					(end 287.160462 -210.896454)
				)
				(arc
					(start 287.439862 -210.896454)
					(mid 287.706562 -210.629754)
					(end 287.973262 -210.896454)
				)
				(arc
					(start 288.217102 -210.896454)
					(mid 288.067568 -210.535448)
					(end 287.706562 -210.385914)
				)
			)
		)
	)
	(zone
		(layers "B.Cu" "In2.Cu")
		(hatch none 0.5)
		(connect_pads
			(clearance 0)
		)
		(min_thickness 0.25)
		(keepout
			(tracks not_allowed)
			(vias allowed)
			(pads allowed)
			(copperpour not_allowed)
			(footprints allowed)
		)
		(placement
			(enabled no)
			(sheetname "")
		)
		(fill yes
			(thermal_gap 0.5)
			(thermal_bridge_width 0.5)
			(island_removal_mode 0)
		)
		(polygon
			(pts
				(arc
					(start 141.694154 -210.385914)
					(mid 141.18336 -210.896327)
					(end 141.6939 -211.406994)
				)
				(arc
					(start 142.5067 -211.406994)
					(mid 142.866807 -211.258357)
					(end 143.01724 -210.898994)
				)
				(arc
					(start 142.7734 -210.898994)
					(mid 142.5067 -211.163166)
					(end 142.24 -210.898994)
				)
				(arc
					(start 141.9606 -210.898994)
					(mid 141.6939 -211.163166)
					(end 141.4272 -210.898994)
				)
				(arc
					(start 141.4272 -210.896454)
					(mid 141.6939 -210.629754)
					(end 141.9606 -210.896454)
				)
				(arc
					(start 142.24 -210.896454)
					(mid 142.5067 -210.629754)
					(end 142.7734 -210.896454)
				)
				(arc
					(start 143.01724 -210.896454)
					(mid 142.867706 -210.535448)
					(end 142.5067 -210.385914)
				)
			)
		)
	)
	(zone
		(layers "B.Cu" "In2.Cu")
		(hatch none 0.5)
		(connect_pads
			(clearance 0)
		)
		(min_thickness 0.25)
		(keepout
			(tracks not_allowed)
			(vias allowed)
			(pads allowed)
			(copperpour not_allowed)
			(footprints allowed)
		)
		(placement
			(enabled no)
			(sheetname "")
		)
		(fill yes
			(thermal_gap 0.5)
			(thermal_bridge_width 0.5)
			(island_removal_mode 0)
		)
		(polygon
			(pts
				(arc
					(start 18.852388 -81.39684)
					(mid 18.341594 -81.907253)
					(end 18.852134 -82.41792)
				)
				(arc
					(start 19.664934 -82.41792)
					(mid 20.025041 -82.269283)
					(end 20.175474 -81.90992)
				)
				(arc
					(start 19.931634 -81.90992)
					(mid 19.664934 -82.174092)
					(end 19.398234 -81.90992)
				)
				(arc
					(start 19.118834 -81.90992)
					(mid 18.852134 -82.174092)
					(end 18.585434 -81.90992)
				)
				(arc
					(start 18.585434 -81.90738)
					(mid 18.852134 -81.64068)
					(end 19.118834 -81.90738)
				)
				(arc
					(start 19.398234 -81.90738)
					(mid 19.664934 -81.64068)
					(end 19.931634 -81.90738)
				)
				(arc
					(start 20.175474 -81.90738)
					(mid 20.02594 -81.546374)
					(end 19.664934 -81.39684)
				)
			)
		)
	)
	(zone
		(layers "B.Cu" "In2.Cu")
		(hatch none 0.5)
		(connect_pads
			(clearance 0)
		)
		(min_thickness 0.25)
		(keepout
			(tracks not_allowed)
			(vias allowed)
			(pads allowed)
			(copperpour not_allowed)
			(footprints allowed)
		)
		(placement
			(enabled no)
			(sheetname "")
		)
		(fill yes
			(thermal_gap 0.5)
			(thermal_bridge_width 0.5)
			(island_removal_mode 0)
		)
		(polygon
			(pts
				(arc
					(start 270.894048 -210.385914)
					(mid 270.383254 -210.896327)
					(end 270.893794 -211.406994)
				)
				(arc
					(start 271.706594 -211.406994)
					(mid 272.066701 -211.258357)
					(end 272.217134 -210.898994)
				)
				(arc
					(start 271.973294 -210.898994)
					(mid 271.706594 -211.163166)
					(end 271.439894 -210.898994)
				)
				(arc
					(start 271.160494 -210.898994)
					(mid 270.893794 -211.163166)
					(end 270.627094 -210.898994)
				)
				(arc
					(start 270.627094 -210.896454)
					(mid 270.893794 -210.629754)
					(end 271.160494 -210.896454)
				)
				(arc
					(start 271.439894 -210.896454)
					(mid 271.706594 -210.629754)
					(end 271.973294 -210.896454)
				)
				(arc
					(start 272.217134 -210.896454)
					(mid 272.0676 -210.535448)
					(end 271.706594 -210.385914)
				)
			)
		)
	)
	(zone
		(layers "B.Cu" "In2.Cu")
		(hatch none 0.5)
		(connect_pads
			(clearance 0)
		)
		(min_thickness 0.25)
		(keepout
			(tracks not_allowed)
			(vias allowed)
			(pads allowed)
			(copperpour not_allowed)
			(footprints allowed)
		)
		(placement
			(enabled no)
			(sheetname "")
		)
		(fill yes
			(thermal_gap 0.5)
			(thermal_bridge_width 0.5)
			(island_removal_mode 0)
		)
		(polygon
			(pts
				(arc
					(start 63.693802 -210.385914)
					(mid 63.183008 -210.896327)
					(end 63.693548 -211.406994)
				)
				(arc
					(start 64.506348 -211.406994)
					(mid 64.866455 -211.258357)
					(end 65.016888 -210.898994)
				)
				(arc
					(start 64.773048 -210.898994)
					(mid 64.506348 -211.163166)
					(end 64.239648 -210.898994)
				)
				(arc
					(start 63.960248 -210.898994)
					(mid 63.693548 -211.163166)
					(end 63.426848 -210.898994)
				)
				(arc
					(start 63.426848 -210.896454)
					(mid 63.693548 -210.629754)
					(end 63.960248 -210.896454)
				)
				(arc
					(start 64.239648 -210.896454)
					(mid 64.506348 -210.629754)
					(end 64.773048 -210.896454)
				)
				(arc
					(start 65.016888 -210.896454)
					(mid 64.867354 -210.535448)
					(end 64.506348 -210.385914)
				)
			)
		)
	)
	(zone
		(layers "B.Cu" "In2.Cu")
		(hatch none 0.5)
		(connect_pads
			(clearance 0)
		)
		(min_thickness 0.25)
		(keepout
			(tracks not_allowed)
			(vias allowed)
			(pads allowed)
			(copperpour not_allowed)
			(footprints allowed)
		)
		(placement
			(enabled no)
			(sheetname "")
		)
		(fill yes
			(thermal_gap 0.5)
			(thermal_bridge_width 0.5)
			(island_removal_mode 0)
		)
		(polygon
			(pts
				(arc
					(start 332.494128 -210.385914)
					(mid 331.983334 -210.896327)
					(end 332.493874 -211.406994)
				)
				(arc
					(start 333.306674 -211.406994)
					(mid 333.666781 -211.258357)
					(end 333.817214 -210.898994)
				)
				(arc
					(start 333.573374 -210.898994)
					(mid 333.306674 -211.163166)
					(end 333.039974 -210.898994)
				)
				(arc
					(start 332.760574 -210.898994)
					(mid 332.493874 -211.163166)
					(end 332.227174 -210.898994)
				)
				(arc
					(start 332.227174 -210.896454)
					(mid 332.493874 -210.629754)
					(end 332.760574 -210.896454)
				)
				(arc
					(start 333.039974 -210.896454)
					(mid 333.306674 -210.629754)
					(end 333.573374 -210.896454)
				)
				(arc
					(start 333.817214 -210.896454)
					(mid 333.66768 -210.535448)
					(end 333.306674 -210.385914)
				)
			)
		)
	)
	(zone
		(layers "B.Cu" "In2.Cu")
		(hatch none 0.5)
		(connect_pads
			(clearance 0)
		)
		(min_thickness 0.25)
		(keepout
			(tracks not_allowed)
			(vias allowed)
			(pads allowed)
			(copperpour not_allowed)
			(footprints allowed)
		)
		(placement
			(enabled no)
			(sheetname "")
		)
		(fill yes
			(thermal_gap 0.5)
			(thermal_bridge_width 0.5)
			(island_removal_mode 0)
		)
		(polygon
			(pts
				(arc
					(start 161.277554 -34.51098)
					(mid 160.76676 -35.021393)
					(end 161.2773 -35.53206)
				)
				(arc
					(start 162.0901 -35.53206)
					(mid 162.450207 -35.383423)
					(end 162.60064 -35.02406)
				)
				(arc
					(start 162.3568 -35.02406)
					(mid 162.0901 -35.288232)
					(end 161.8234 -35.02406)
				)
				(arc
					(start 161.544 -35.02406)
					(mid 161.2773 -35.288232)
					(end 161.0106 -35.02406)
				)
				(arc
					(start 161.0106 -35.02152)
					(mid 161.2773 -34.75482)
					(end 161.544 -35.02152)
				)
				(arc
					(start 161.8234 -35.02152)
					(mid 162.0901 -34.75482)
					(end 162.3568 -35.02152)
				)
				(arc
					(start 162.60064 -35.02152)
					(mid 162.451106 -34.660514)
					(end 162.0901 -34.51098)
				)
			)
		)
	)
	(zone
		(layers "B.Cu" "In2.Cu")
		(hatch none 0.5)
		(connect_pads
			(clearance 0)
		)
		(min_thickness 0.25)
		(keepout
			(tracks not_allowed)
			(vias allowed)
			(pads allowed)
			(copperpour not_allowed)
			(footprints allowed)
		)
		(placement
			(enabled no)
			(sheetname "")
		)
		(fill yes
			(thermal_gap 0.5)
			(thermal_bridge_width 0.5)
			(island_removal_mode 0)
		)
		(polygon
			(pts
				(arc
					(start 187.294012 -210.385914)
					(mid 186.783218 -210.896327)
					(end 187.293758 -211.406994)
				)
				(arc
					(start 188.106558 -211.406994)
					(mid 188.466665 -211.258357)
					(end 188.617098 -210.898994)
				)
				(arc
					(start 188.373258 -210.898994)
					(mid 188.106558 -211.163166)
					(end 187.839858 -210.898994)
				)
				(arc
					(start 187.560458 -210.898994)
					(mid 187.293758 -211.163166)
					(end 187.027058 -210.898994)
				)
				(arc
					(start 187.027058 -210.896454)
					(mid 187.293758 -210.629754)
					(end 187.560458 -210.896454)
				)
				(arc
					(start 187.839858 -210.896454)
					(mid 188.106558 -210.629754)
					(end 188.373258 -210.896454)
				)
				(arc
					(start 188.617098 -210.896454)
					(mid 188.467564 -210.535448)
					(end 188.106558 -210.385914)
				)
			)
		)
	)
	(zone
		(layers "B.Cu" "In2.Cu")
		(hatch none 0.5)
		(connect_pads
			(clearance 0)
		)
		(min_thickness 0.25)
		(keepout
			(tracks not_allowed)
			(vias allowed)
			(pads allowed)
			(copperpour not_allowed)
			(footprints allowed)
		)
		(placement
			(enabled no)
			(sheetname "")
		)
		(fill yes
			(thermal_gap 0.5)
			(thermal_bridge_width 0.5)
			(island_removal_mode 0)
		)
		(polygon
			(pts
				(arc
					(start 158.655258 -34.51098)
					(mid 158.144464 -35.021393)
					(end 158.655004 -35.53206)
				)
				(arc
					(start 159.467804 -35.53206)
					(mid 159.827911 -35.383423)
					(end 159.978344 -35.02406)
				)
				(arc
					(start 159.734504 -35.02406)
					(mid 159.467804 -35.288232)
					(end 159.201104 -35.02406)
				)
				(arc
					(start 158.921704 -35.02406)
					(mid 158.655004 -35.288232)
					(end 158.388304 -35.02406)
				)
				(arc
					(start 158.388304 -35.02152)
					(mid 158.655004 -34.75482)
					(end 158.921704 -35.02152)
				)
				(arc
					(start 159.201104 -35.02152)
					(mid 159.467804 -34.75482)
					(end 159.734504 -35.02152)
				)
				(arc
					(start 159.978344 -35.02152)
					(mid 159.82881 -34.660514)
					(end 159.467804 -34.51098)
				)
			)
		)
	)
	(zone
		(layers "B.Cu" "In2.Cu")
		(hatch none 0.5)
		(connect_pads
			(clearance 0)
		)
		(min_thickness 0.25)
		(keepout
			(tracks not_allowed)
			(vias allowed)
			(pads allowed)
			(copperpour not_allowed)
			(footprints allowed)
		)
		(placement
			(enabled no)
			(sheetname "")
		)
		(fill yes
			(thermal_gap 0.5)
			(thermal_bridge_width 0.5)
			(island_removal_mode 0)
		)
		(polygon
			(pts
				(arc
					(start 86.093808 -210.385914)
					(mid 85.583014 -210.896327)
					(end 86.093554 -211.406994)
				)
				(arc
					(start 86.906354 -211.406994)
					(mid 87.266461 -211.258357)
					(end 87.416894 -210.898994)
				)
				(arc
					(start 87.173054 -210.898994)
					(mid 86.906354 -211.163166)
					(end 86.639654 -210.898994)
				)
				(arc
					(start 86.360254 -210.898994)
					(mid 86.093554 -211.163166)
					(end 85.826854 -210.898994)
				)
				(arc
					(start 85.826854 -210.896454)
					(mid 86.093554 -210.629754)
					(end 86.360254 -210.896454)
				)
				(arc
					(start 86.639654 -210.896454)
					(mid 86.906354 -210.629754)
					(end 87.173054 -210.896454)
				)
				(arc
					(start 87.416894 -210.896454)
					(mid 87.26736 -210.535448)
					(end 86.906354 -210.385914)
				)
			)
		)
	)
	(zone
		(layers "B.Cu" "In2.Cu")
		(hatch none 0.5)
		(connect_pads
			(clearance 0)
		)
		(min_thickness 0.25)
		(keepout
			(tracks not_allowed)
			(vias allowed)
			(pads allowed)
			(copperpour not_allowed)
			(footprints allowed)
		)
		(placement
			(enabled no)
			(sheetname "")
		)
		(fill yes
			(thermal_gap 0.5)
			(thermal_bridge_width 0.5)
			(island_removal_mode 0)
		)
		(polygon
			(pts
				(arc
					(start 133.852158 -35.229292)
					(mid 133.341618 -35.739832)
					(end 133.852158 -36.250372)
				)
				(arc
					(start 134.664704 -36.250372)
					(mid 135.024975 -36.101825)
					(end 135.175498 -35.742372)
				)
				(arc
					(start 134.931658 -35.742372)
					(mid 134.664958 -36.006544)
					(end 134.398258 -35.742372)
				)
				(arc
					(start 134.118858 -35.742372)
					(mid 133.852158 -36.006544)
					(end 133.585458 -35.742372)
				)
				(arc
					(start 133.585458 -35.739832)
					(mid 133.852158 -35.473132)
					(end 134.118858 -35.739832)
				)
				(arc
					(start 134.398258 -35.739832)
					(mid 134.664958 -35.473132)
					(end 134.931658 -35.739832)
				)
				(arc
					(start 135.175498 -35.739832)
					(mid 135.025964 -35.378826)
					(end 134.664958 -35.229292)
				)
			)
		)
	)
	(zone
		(layers "B.Cu" "In2.Cu")
		(hatch none 0.5)
		(connect_pads
			(clearance 0)
		)
		(min_thickness 0.25)
		(keepout
			(tracks not_allowed)
			(vias allowed)
			(pads allowed)
			(copperpour not_allowed)
			(footprints allowed)
		)
		(placement
			(enabled no)
			(sheetname "")
		)
		(fill yes
			(thermal_gap 0.5)
			(thermal_bridge_width 0.5)
			(island_removal_mode 0)
		)
		(polygon
			(pts
				(arc
					(start 190.493904 -210.385914)
					(mid 189.98311 -210.896327)
					(end 190.49365 -211.406994)
				)
				(arc
					(start 191.30645 -211.406994)
					(mid 191.666557 -211.258357)
					(end 191.81699 -210.898994)
				)
				(arc
					(start 191.57315 -210.898994)
					(mid 191.30645 -211.163166)
					(end 191.03975 -210.898994)
				)
				(arc
					(start 190.76035 -210.898994)
					(mid 190.49365 -211.163166)
					(end 190.22695 -210.898994)
				)
				(arc
					(start 190.22695 -210.896454)
					(mid 190.49365 -210.629754)
					(end 190.76035 -210.896454)
				)
				(arc
					(start 191.03975 -210.896454)
					(mid 191.30645 -210.629754)
					(end 191.57315 -210.896454)
				)
				(arc
					(start 191.81699 -210.896454)
					(mid 191.667456 -210.535448)
					(end 191.30645 -210.385914)
				)
			)
		)
	)
	(zone
		(layers "B.Cu" "In2.Cu")
		(hatch none 0.5)
		(connect_pads
			(clearance 0)
		)
		(min_thickness 0.25)
		(keepout
			(tracks not_allowed)
			(vias allowed)
			(pads allowed)
			(copperpour not_allowed)
			(footprints allowed)
		)
		(placement
			(enabled no)
			(sheetname "")
		)
		(fill yes
			(thermal_gap 0.5)
			(thermal_bridge_width 0.5)
			(island_removal_mode 0)
		)
		(polygon
			(pts
				(arc
					(start 22.555454 -53.045614)
					(mid 22.04466 -53.556027)
					(end 22.5552 -54.066694)
				)
				(arc
					(start 23.368 -54.066694)
					(mid 23.728107 -53.918057)
					(end 23.87854 -53.558694)
				)
				(arc
					(start 23.6347 -53.558694)
					(mid 23.368 -53.822866)
					(end 23.1013 -53.558694)
				)
				(arc
					(start 22.8219 -53.558694)
					(mid 22.5552 -53.822866)
					(end 22.2885 -53.558694)
				)
				(arc
					(start 22.2885 -53.556154)
					(mid 22.5552 -53.289454)
					(end 22.8219 -53.556154)
				)
				(arc
					(start 23.1013 -53.556154)
					(mid 23.368 -53.289454)
					(end 23.6347 -53.556154)
				)
				(arc
					(start 23.87854 -53.556154)
					(mid 23.729006 -53.195148)
					(end 23.368 -53.045614)
				)
			)
		)
	)
	(zone
		(layers "B.Cu" "In2.Cu")
		(hatch none 0.5)
		(connect_pads
			(clearance 0)
		)
		(min_thickness 0.25)
		(keepout
			(tracks not_allowed)
			(vias allowed)
			(pads allowed)
			(copperpour not_allowed)
			(footprints allowed)
		)
		(placement
			(enabled no)
			(sheetname "")
		)
		(fill yes
			(thermal_gap 0.5)
			(thermal_bridge_width 0.5)
			(island_removal_mode 0)
		)
		(polygon
			(pts
				(arc
					(start 183.59374 -25.9461)
					(mid 183.0832 -25.43556)
					(end 182.57266 -25.9461)
				)
				(arc
					(start 182.57266 -26.7589)
					(mid 183.08193 -27.269438)
					(end 183.59374 -26.76144)
				)
				(arc
					(start 183.3499 -26.76144)
					(mid 183.0832 -27.025612)
					(end 182.8165 -26.76144)
				)
				(arc
					(start 182.8165 -26.7589)
					(mid 183.0832 -26.4922)
					(end 183.3499 -26.7589)
				)
				(xy 183.59374 -26.7589) (xy 183.59374 -25.94864)
				(arc
					(start 183.3499 -25.94864)
					(mid 183.0832 -26.212812)
					(end 182.8165 -25.94864)
				)
				(arc
					(start 182.8165 -25.9461)
					(mid 183.0832 -25.6794)
					(end 183.3499 -25.9461)
				)
			)
		)
	)
	(zone
		(layers "B.Cu" "In2.Cu")
		(hatch none 0.5)
		(connect_pads
			(clearance 0)
		)
		(min_thickness 0.25)
		(keepout
			(tracks not_allowed)
			(vias allowed)
			(pads allowed)
			(copperpour not_allowed)
			(footprints allowed)
		)
		(placement
			(enabled no)
			(sheetname "")
		)
		(fill yes
			(thermal_gap 0.5)
			(thermal_bridge_width 0.5)
			(island_removal_mode 0)
		)
		(polygon
			(pts
				(arc
					(start 66.893948 -210.385914)
					(mid 66.383154 -210.896327)
					(end 66.893694 -211.406994)
				)
				(arc
					(start 67.706494 -211.406994)
					(mid 68.066601 -211.258357)
					(end 68.217034 -210.898994)
				)
				(arc
					(start 67.973194 -210.898994)
					(mid 67.706494 -211.163166)
					(end 67.439794 -210.898994)
				)
				(arc
					(start 67.160394 -210.898994)
					(mid 66.893694 -211.163166)
					(end 66.626994 -210.898994)
				)
				(arc
					(start 66.626994 -210.896454)
					(mid 66.893694 -210.629754)
					(end 67.160394 -210.896454)
				)
				(arc
					(start 67.439794 -210.896454)
					(mid 67.706494 -210.629754)
					(end 67.973194 -210.896454)
				)
				(arc
					(start 68.217034 -210.896454)
					(mid 68.0675 -210.535448)
					(end 67.706494 -210.385914)
				)
			)
		)
	)
	(zone
		(layers "B.Cu" "In2.Cu")
		(hatch none 0.5)
		(connect_pads
			(clearance 0)
		)
		(min_thickness 0.25)
		(keepout
			(tracks not_allowed)
			(vias allowed)
			(pads allowed)
			(copperpour not_allowed)
			(footprints allowed)
		)
		(placement
			(enabled no)
			(sheetname "")
		)
		(fill yes
			(thermal_gap 0.5)
			(thermal_bridge_width 0.5)
			(island_removal_mode 0)
		)
		(polygon
			(pts
				(arc
					(start 193.69405 -210.385914)
					(mid 193.183256 -210.896327)
					(end 193.693796 -211.406994)
				)
				(arc
					(start 194.506596 -211.406994)
					(mid 194.866703 -211.258357)
					(end 195.017136 -210.898994)
				)
				(arc
					(start 194.773296 -210.898994)
					(mid 194.506596 -211.163166)
					(end 194.239896 -210.898994)
				)
				(arc
					(start 193.960496 -210.898994)
					(mid 193.693796 -211.163166)
					(end 193.427096 -210.898994)
				)
				(arc
					(start 193.427096 -210.896454)
					(mid 193.693796 -210.629754)
					(end 193.960496 -210.896454)
				)
				(arc
					(start 194.239896 -210.896454)
					(mid 194.506596 -210.629754)
					(end 194.773296 -210.896454)
				)
				(arc
					(start 195.017136 -210.896454)
					(mid 194.867602 -210.535448)
					(end 194.506596 -210.385914)
				)
			)
		)
	)
	(zone
		(layers "B.Cu" "In2.Cu")
		(hatch none 0.5)
		(connect_pads
			(clearance 0)
		)
		(min_thickness 0.25)
		(keepout
			(tracks not_allowed)
			(vias allowed)
			(pads allowed)
			(copperpour not_allowed)
			(footprints allowed)
		)
		(placement
			(enabled no)
			(sheetname "")
		)
		(fill yes
			(thermal_gap 0.5)
			(thermal_bridge_width 0.5)
			(island_removal_mode 0)
		)
		(polygon
			(pts
				(arc
					(start 137.5664 -34.482786)
					(mid 137.05586 -34.993326)
					(end 137.5664 -35.503866)
				)
				(arc
					(start 138.378946 -35.503866)
					(mid 138.739217 -35.355319)
					(end 138.88974 -34.995866)
				)
				(arc
					(start 138.6459 -34.995866)
					(mid 138.3792 -35.260038)
					(end 138.1125 -34.995866)
				)
				(arc
					(start 137.8331 -34.995866)
					(mid 137.5664 -35.260038)
					(end 137.2997 -34.995866)
				)
				(arc
					(start 137.2997 -34.993326)
					(mid 137.5664 -34.726626)
					(end 137.8331 -34.993326)
				)
				(arc
					(start 138.1125 -34.993326)
					(mid 138.3792 -34.726626)
					(end 138.6459 -34.993326)
				)
				(arc
					(start 138.88974 -34.993326)
					(mid 138.740206 -34.63232)
					(end 138.3792 -34.482786)
				)
			)
		)
	)
	(zone
		(layers "B.Cu" "In2.Cu")
		(hatch none 0.5)
		(connect_pads
			(clearance 0)
		)
		(min_thickness 0.25)
		(keepout
			(tracks not_allowed)
			(vias allowed)
			(pads allowed)
			(copperpour not_allowed)
			(footprints allowed)
		)
		(placement
			(enabled no)
			(sheetname "")
		)
		(fill yes
			(thermal_gap 0.5)
			(thermal_bridge_width 0.5)
			(island_removal_mode 0)
		)
		(polygon
			(pts
				(arc
					(start 160.894014 -210.385914)
					(mid 160.38322 -210.896327)
					(end 160.89376 -211.406994)
				)
				(arc
					(start 161.70656 -211.406994)
					(mid 162.066667 -211.258357)
					(end 162.2171 -210.898994)
				)
				(arc
					(start 161.97326 -210.898994)
					(mid 161.70656 -211.163166)
					(end 161.43986 -210.898994)
				)
				(arc
					(start 161.16046 -210.898994)
					(mid 160.89376 -211.163166)
					(end 160.62706 -210.898994)
				)
				(arc
					(start 160.62706 -210.896454)
					(mid 160.89376 -210.629754)
					(end 161.16046 -210.896454)
				)
				(arc
					(start 161.43986 -210.896454)
					(mid 161.70656 -210.629754)
					(end 161.97326 -210.896454)
				)
				(arc
					(start 162.2171 -210.896454)
					(mid 162.067566 -210.535448)
					(end 161.70656 -210.385914)
				)
			)
		)
	)
	(zone
		(layers "B.Cu" "In2.Cu")
		(hatch none 0.5)
		(connect_pads
			(clearance 0)
		)
		(min_thickness 0.25)
		(keepout
			(tracks not_allowed)
			(vias allowed)
			(pads allowed)
			(copperpour not_allowed)
			(footprints allowed)
		)
		(placement
			(enabled no)
			(sheetname "")
		)
		(fill yes
			(thermal_gap 0.5)
			(thermal_bridge_width 0.5)
			(island_removal_mode 0)
		)
		(polygon
			(pts
				(arc
					(start 151.294084 -210.385914)
					(mid 150.78329 -210.896327)
					(end 151.29383 -211.406994)
				)
				(arc
					(start 152.10663 -211.406994)
					(mid 152.466737 -211.258357)
					(end 152.61717 -210.898994)
				)
				(arc
					(start 152.37333 -210.898994)
					(mid 152.10663 -211.163166)
					(end 151.83993 -210.898994)
				)
				(arc
					(start 151.56053 -210.898994)
					(mid 151.29383 -211.163166)
					(end 151.02713 -210.898994)
				)
				(arc
					(start 151.02713 -210.896454)
					(mid 151.29383 -210.629754)
					(end 151.56053 -210.896454)
				)
				(arc
					(start 151.83993 -210.896454)
					(mid 152.10663 -210.629754)
					(end 152.37333 -210.896454)
				)
				(arc
					(start 152.61717 -210.896454)
					(mid 152.467636 -210.535448)
					(end 152.10663 -210.385914)
				)
			)
		)
	)
	(zone
		(layers "B.Cu" "In2.Cu")
		(hatch none 0.5)
		(connect_pads
			(clearance 0)
		)
		(min_thickness 0.25)
		(keepout
			(tracks not_allowed)
			(vias allowed)
			(pads allowed)
			(copperpour not_allowed)
			(footprints allowed)
		)
		(placement
			(enabled no)
			(sheetname "")
		)
		(fill yes
			(thermal_gap 0.5)
			(thermal_bridge_width 0.5)
			(island_removal_mode 0)
		)
		(polygon
			(pts
				(arc
					(start 206.493872 -210.385914)
					(mid 205.983078 -210.896327)
					(end 206.493618 -211.406994)
				)
				(arc
					(start 207.306418 -211.406994)
					(mid 207.666525 -211.258357)
					(end 207.816958 -210.898994)
				)
				(arc
					(start 207.573118 -210.898994)
					(mid 207.306418 -211.163166)
					(end 207.039718 -210.898994)
				)
				(arc
					(start 206.760318 -210.898994)
					(mid 206.493618 -211.163166)
					(end 206.226918 -210.898994)
				)
				(arc
					(start 206.226918 -210.896454)
					(mid 206.493618 -210.629754)
					(end 206.760318 -210.896454)
				)
				(arc
					(start 207.039718 -210.896454)
					(mid 207.306418 -210.629754)
					(end 207.573118 -210.896454)
				)
				(arc
					(start 207.816958 -210.896454)
					(mid 207.667424 -210.535448)
					(end 207.306418 -210.385914)
				)
			)
		)
	)
	(zone
		(layers "B.Cu" "In2.Cu")
		(hatch none 0.5)
		(connect_pads
			(clearance 0)
		)
		(min_thickness 0.25)
		(keepout
			(tracks not_allowed)
			(vias allowed)
			(pads allowed)
			(copperpour not_allowed)
			(footprints allowed)
		)
		(placement
			(enabled no)
			(sheetname "")
		)
		(fill yes
			(thermal_gap 0.5)
			(thermal_bridge_width 0.5)
			(island_removal_mode 0)
		)
		(polygon
			(pts
				(arc
					(start 48.493934 -210.385914)
					(mid 47.98314 -210.896327)
					(end 48.49368 -211.406994)
				)
				(arc
					(start 49.30648 -211.406994)
					(mid 49.666587 -211.258357)
					(end 49.81702 -210.898994)
				)
				(arc
					(start 49.57318 -210.898994)
					(mid 49.30648 -211.163166)
					(end 49.03978 -210.898994)
				)
				(arc
					(start 48.76038 -210.898994)
					(mid 48.49368 -211.163166)
					(end 48.22698 -210.898994)
				)
				(arc
					(start 48.22698 -210.896454)
					(mid 48.49368 -210.629754)
					(end 48.76038 -210.896454)
				)
				(arc
					(start 49.03978 -210.896454)
					(mid 49.30648 -210.629754)
					(end 49.57318 -210.896454)
				)
				(arc
					(start 49.81702 -210.896454)
					(mid 49.667486 -210.535448)
					(end 49.30648 -210.385914)
				)
			)
		)
	)
	(zone
		(layers "B.Cu" "In2.Cu")
		(hatch none 0.5)
		(connect_pads
			(clearance 0)
		)
		(min_thickness 0.25)
		(keepout
			(tracks not_allowed)
			(vias allowed)
			(pads allowed)
			(copperpour not_allowed)
			(footprints allowed)
		)
		(placement
			(enabled no)
			(sheetname "")
		)
		(fill yes
			(thermal_gap 0.5)
			(thermal_bridge_width 0.5)
			(island_removal_mode 0)
		)
		(polygon
			(pts
				(arc
					(start 289.2298 -34.503614)
					(mid 288.71926 -35.014154)
					(end 289.2298 -35.524694)
				)
				(arc
					(start 290.042346 -35.524694)
					(mid 290.402617 -35.376147)
					(end 290.55314 -35.016694)
				)
				(arc
					(start 290.3093 -35.016694)
					(mid 290.0426 -35.280866)
					(end 289.7759 -35.016694)
				)
				(arc
					(start 289.4965 -35.016694)
					(mid 289.2298 -35.280866)
					(end 288.9631 -35.016694)
				)
				(arc
					(start 288.9631 -35.014154)
					(mid 289.2298 -34.747454)
					(end 289.4965 -35.014154)
				)
				(arc
					(start 289.7759 -35.014154)
					(mid 290.0426 -34.747454)
					(end 290.3093 -35.014154)
				)
				(arc
					(start 290.55314 -35.014154)
					(mid 290.403606 -34.653148)
					(end 290.0426 -34.503614)
				)
			)
		)
	)
	(zone
		(layers "B.Cu" "In2.Cu")
		(hatch none 0.5)
		(connect_pads
			(clearance 0)
		)
		(min_thickness 0.25)
		(keepout
			(tracks not_allowed)
			(vias allowed)
			(pads allowed)
			(copperpour not_allowed)
			(footprints allowed)
		)
		(placement
			(enabled no)
			(sheetname "")
		)
		(fill yes
			(thermal_gap 0.5)
			(thermal_bridge_width 0.5)
			(island_removal_mode 0)
		)
		(polygon
			(pts
				(arc
					(start 176.093882 -210.385914)
					(mid 175.583088 -210.896327)
					(end 176.093628 -211.406994)
				)
				(arc
					(start 176.906428 -211.406994)
					(mid 177.266535 -211.258357)
					(end 177.416968 -210.898994)
				)
				(arc
					(start 177.173128 -210.898994)
					(mid 176.906428 -211.163166)
					(end 176.639728 -210.898994)
				)
				(arc
					(start 176.360328 -210.898994)
					(mid 176.093628 -211.163166)
					(end 175.826928 -210.898994)
				)
				(arc
					(start 175.826928 -210.896454)
					(mid 176.093628 -210.629754)
					(end 176.360328 -210.896454)
				)
				(arc
					(start 176.639728 -210.896454)
					(mid 176.906428 -210.629754)
					(end 177.173128 -210.896454)
				)
				(arc
					(start 177.416968 -210.896454)
					(mid 177.267434 -210.535448)
					(end 176.906428 -210.385914)
				)
			)
		)
	)
	(zone
		(layers "B.Cu" "In2.Cu")
		(hatch none 0.5)
		(connect_pads
			(clearance 0)
		)
		(min_thickness 0.25)
		(keepout
			(tracks not_allowed)
			(vias allowed)
			(pads allowed)
			(copperpour not_allowed)
			(footprints allowed)
		)
		(placement
			(enabled no)
			(sheetname "")
		)
		(fill yes
			(thermal_gap 0.5)
			(thermal_bridge_width 0.5)
			(island_removal_mode 0)
		)
		(polygon
			(pts
				(arc
					(start 277.293832 -210.385914)
					(mid 276.783038 -210.896327)
					(end 277.293578 -211.406994)
				)
				(arc
					(start 278.106378 -211.406994)
					(mid 278.466485 -211.258357)
					(end 278.616918 -210.898994)
				)
				(arc
					(start 278.373078 -210.898994)
					(mid 278.106378 -211.163166)
					(end 277.839678 -210.898994)
				)
				(arc
					(start 277.560278 -210.898994)
					(mid 277.293578 -211.163166)
					(end 277.026878 -210.898994)
				)
				(arc
					(start 277.026878 -210.896454)
					(mid 277.293578 -210.629754)
					(end 277.560278 -210.896454)
				)
				(arc
					(start 277.839678 -210.896454)
					(mid 278.106378 -210.629754)
					(end 278.373078 -210.896454)
				)
				(arc
					(start 278.616918 -210.896454)
					(mid 278.467384 -210.535448)
					(end 278.106378 -210.385914)
				)
			)
		)
	)
	(zone
		(layers "B.Cu" "In2.Cu")
		(hatch none 0.5)
		(connect_pads
			(clearance 0)
		)
		(min_thickness 0.25)
		(keepout
			(tracks not_allowed)
			(vias allowed)
			(pads allowed)
			(copperpour not_allowed)
			(footprints allowed)
		)
		(placement
			(enabled no)
			(sheetname "")
		)
		(fill yes
			(thermal_gap 0.5)
			(thermal_bridge_width 0.5)
			(island_removal_mode 0)
		)
		(polygon
			(pts
				(arc
					(start 16.69034 -66.22415)
					(mid 16.1798 -65.71361)
					(end 15.66926 -66.22415)
				)
				(arc
					(start 15.66926 -67.03695)
					(mid 16.17853 -67.547488)
					(end 16.69034 -67.03949)
				)
				(arc
					(start 16.4465 -67.03949)
					(mid 16.1798 -67.303662)
					(end 15.9131 -67.03949)
				)
				(arc
					(start 15.9131 -67.03695)
					(mid 16.1798 -66.77025)
					(end 16.4465 -67.03695)
				)
				(xy 16.69034 -67.03695) (xy 16.69034 -66.22669)
				(arc
					(start 16.4465 -66.22669)
					(mid 16.1798 -66.490862)
					(end 15.9131 -66.22669)
				)
				(arc
					(start 15.9131 -66.22415)
					(mid 16.1798 -65.95745)
					(end 16.4465 -66.22415)
				)
			)
		)
	)
	(zone
		(layers "B.Cu" "In2.Cu")
		(hatch none 0.5)
		(connect_pads
			(clearance 0)
		)
		(min_thickness 0.25)
		(keepout
			(tracks not_allowed)
			(vias allowed)
			(pads allowed)
			(copperpour not_allowed)
			(footprints allowed)
		)
		(placement
			(enabled no)
			(sheetname "")
		)
		(fill yes
			(thermal_gap 0.5)
			(thermal_bridge_width 0.5)
			(island_removal_mode 0)
		)
		(polygon
			(pts
				(arc
					(start 107.693968 -210.385914)
					(mid 107.183174 -210.896327)
					(end 107.693714 -211.406994)
				)
				(arc
					(start 108.506514 -211.406994)
					(mid 108.866621 -211.258357)
					(end 109.017054 -210.898994)
				)
				(arc
					(start 108.773214 -210.898994)
					(mid 108.506514 -211.163166)
					(end 108.239814 -210.898994)
				)
				(arc
					(start 107.960414 -210.898994)
					(mid 107.693714 -211.163166)
					(end 107.427014 -210.898994)
				)
				(arc
					(start 107.427014 -210.896454)
					(mid 107.693714 -210.629754)
					(end 107.960414 -210.896454)
				)
				(arc
					(start 108.239814 -210.896454)
					(mid 108.506514 -210.629754)
					(end 108.773214 -210.896454)
				)
				(arc
					(start 109.017054 -210.896454)
					(mid 108.86752 -210.535448)
					(end 108.506514 -210.385914)
				)
			)
		)
	)
	(zone
		(layers "B.Cu" "In2.Cu")
		(hatch none 0.5)
		(connect_pads
			(clearance 0)
		)
		(min_thickness 0.25)
		(keepout
			(tracks not_allowed)
			(vias allowed)
			(pads allowed)
			(copperpour not_allowed)
			(footprints allowed)
		)
		(placement
			(enabled no)
			(sheetname "")
		)
		(fill yes
			(thermal_gap 0.5)
			(thermal_bridge_width 0.5)
			(island_removal_mode 0)
		)
		(polygon
			(pts
				(arc
					(start 58.051954 -195.75526)
					(mid 57.54116 -196.265673)
					(end 58.0517 -196.77634)
				)
				(arc
					(start 58.8645 -196.77634)
					(mid 59.224607 -196.627703)
					(end 59.37504 -196.26834)
				)
				(arc
					(start 59.1312 -196.26834)
					(mid 58.8645 -196.532512)
					(end 58.5978 -196.26834)
				)
				(arc
					(start 58.3184 -196.26834)
					(mid 58.0517 -196.532512)
					(end 57.785 -196.26834)
				)
				(arc
					(start 57.785 -196.2658)
					(mid 58.0517 -195.9991)
					(end 58.3184 -196.2658)
				)
				(arc
					(start 58.5978 -196.2658)
					(mid 58.8645 -195.9991)
					(end 59.1312 -196.2658)
				)
				(arc
					(start 59.37504 -196.2658)
					(mid 59.225506 -195.904794)
					(end 58.8645 -195.75526)
				)
			)
		)
	)
	(zone
		(layers "B.Cu" "In2.Cu")
		(hatch none 0.5)
		(connect_pads
			(clearance 0)
		)
		(min_thickness 0.25)
		(keepout
			(tracks not_allowed)
			(vias allowed)
			(pads allowed)
			(copperpour not_allowed)
			(footprints allowed)
		)
		(placement
			(enabled no)
			(sheetname "")
		)
		(fill yes
			(thermal_gap 0.5)
			(thermal_bridge_width 0.5)
			(island_removal_mode 0)
		)
		(polygon
			(pts
				(arc
					(start 54.893718 -210.385914)
					(mid 54.383178 -210.896454)
					(end 54.893718 -211.406994)
				)
				(arc
					(start 55.706264 -211.406994)
					(mid 56.066535 -211.258447)
					(end 56.217058 -210.898994)
				)
				(arc
					(start 55.973218 -210.898994)
					(mid 55.706518 -211.163166)
					(end 55.439818 -210.898994)
				)
				(arc
					(start 55.160418 -210.898994)
					(mid 54.893718 -211.163166)
					(end 54.627018 -210.898994)
				)
				(arc
					(start 54.627018 -210.896454)
					(mid 54.893718 -210.629754)
					(end 55.160418 -210.896454)
				)
				(arc
					(start 55.439818 -210.896454)
					(mid 55.706518 -210.629754)
					(end 55.973218 -210.896454)
				)
				(arc
					(start 56.217058 -210.896454)
					(mid 56.067524 -210.535448)
					(end 55.706518 -210.385914)
				)
			)
		)
	)
	(zone
		(layers "B.Cu" "In2.Cu")
		(hatch none 0.5)
		(connect_pads
			(clearance 0)
		)
		(min_thickness 0.25)
		(keepout
			(tracks not_allowed)
			(vias allowed)
			(pads allowed)
			(copperpour not_allowed)
			(footprints allowed)
		)
		(placement
			(enabled no)
			(sheetname "")
		)
		(fill yes
			(thermal_gap 0.5)
			(thermal_bridge_width 0.5)
			(island_removal_mode 0)
		)
		(polygon
			(pts
				(arc
					(start 148.093938 -210.385914)
					(mid 147.583144 -210.896327)
					(end 148.093684 -211.406994)
				)
				(arc
					(start 148.906484 -211.406994)
					(mid 149.266591 -211.258357)
					(end 149.417024 -210.898994)
				)
				(arc
					(start 149.173184 -210.898994)
					(mid 148.906484 -211.163166)
					(end 148.639784 -210.898994)
				)
				(arc
					(start 148.360384 -210.898994)
					(mid 148.093684 -211.163166)
					(end 147.826984 -210.898994)
				)
				(arc
					(start 147.826984 -210.896454)
					(mid 148.093684 -210.629754)
					(end 148.360384 -210.896454)
				)
				(arc
					(start 148.639784 -210.896454)
					(mid 148.906484 -210.629754)
					(end 149.173184 -210.896454)
				)
				(arc
					(start 149.417024 -210.896454)
					(mid 149.26749 -210.535448)
					(end 148.906484 -210.385914)
				)
			)
		)
	)
	(zone
		(layers "B.Cu" "In2.Cu")
		(hatch none 0.5)
		(connect_pads
			(clearance 0)
		)
		(min_thickness 0.25)
		(keepout
			(tracks not_allowed)
			(vias allowed)
			(pads allowed)
			(copperpour not_allowed)
			(footprints allowed)
		)
		(placement
			(enabled no)
			(sheetname "")
		)
		(fill yes
			(thermal_gap 0.5)
			(thermal_bridge_width 0.5)
			(island_removal_mode 0)
		)
		(polygon
			(pts
				(arc
					(start 267.693902 -210.385914)
					(mid 267.183108 -210.896327)
					(end 267.693648 -211.406994)
				)
				(arc
					(start 268.506448 -211.406994)
					(mid 268.866555 -211.258357)
					(end 269.016988 -210.898994)
				)
				(arc
					(start 268.773148 -210.898994)
					(mid 268.506448 -211.163166)
					(end 268.239748 -210.898994)
				)
				(arc
					(start 267.960348 -210.898994)
					(mid 267.693648 -211.163166)
					(end 267.426948 -210.898994)
				)
				(arc
					(start 267.426948 -210.896454)
					(mid 267.693648 -210.629754)
					(end 267.960348 -210.896454)
				)
				(arc
					(start 268.239748 -210.896454)
					(mid 268.506448 -210.629754)
					(end 268.773148 -210.896454)
				)
				(arc
					(start 269.016988 -210.896454)
					(mid 268.867454 -210.535448)
					(end 268.506448 -210.385914)
				)
			)
		)
	)
	(zone
		(layers "B.Cu" "In2.Cu")
		(hatch none 0.5)
		(connect_pads
			(clearance 0)
		)
		(min_thickness 0.25)
		(keepout
			(tracks not_allowed)
			(vias allowed)
			(pads allowed)
			(copperpour not_allowed)
			(footprints allowed)
		)
		(placement
			(enabled no)
			(sheetname "")
		)
		(fill yes
			(thermal_gap 0.5)
			(thermal_bridge_width 0.5)
			(island_removal_mode 0)
		)
		(polygon
			(pts
				(arc
					(start 310.425592 -34.5313)
					(mid 309.915052 -35.04184)
					(end 310.425592 -35.55238)
				)
				(arc
					(start 311.238138 -35.55238)
					(mid 311.598409 -35.403833)
					(end 311.748932 -35.04438)
				)
				(arc
					(start 311.505092 -35.04438)
					(mid 311.238392 -35.308552)
					(end 310.971692 -35.04438)
				)
				(arc
					(start 310.692292 -35.04438)
					(mid 310.425592 -35.308552)
					(end 310.158892 -35.04438)
				)
				(arc
					(start 310.158892 -35.04184)
					(mid 310.425592 -34.77514)
					(end 310.692292 -35.04184)
				)
				(arc
					(start 310.971692 -35.04184)
					(mid 311.238392 -34.77514)
					(end 311.505092 -35.04184)
				)
				(arc
					(start 311.748932 -35.04184)
					(mid 311.599398 -34.680834)
					(end 311.238392 -34.5313)
				)
			)
		)
	)
	(zone
		(layers "B.Cu" "In2.Cu")
		(hatch none 0.5)
		(connect_pads
			(clearance 0)
		)
		(min_thickness 0.25)
		(keepout
			(tracks not_allowed)
			(vias allowed)
			(pads allowed)
			(copperpour not_allowed)
			(footprints allowed)
		)
		(placement
			(enabled no)
			(sheetname "")
		)
		(fill yes
			(thermal_gap 0.5)
			(thermal_bridge_width 0.5)
			(island_removal_mode 0)
		)
		(polygon
			(pts
				(arc
					(start 316.49416 -210.385914)
					(mid 315.983366 -210.896327)
					(end 316.493906 -211.406994)
				)
				(arc
					(start 317.306706 -211.406994)
					(mid 317.666813 -211.258357)
					(end 317.817246 -210.898994)
				)
				(arc
					(start 317.573406 -210.898994)
					(mid 317.306706 -211.163166)
					(end 317.040006 -210.898994)
				)
				(arc
					(start 316.760606 -210.898994)
					(mid 316.493906 -211.163166)
					(end 316.227206 -210.898994)
				)
				(arc
					(start 316.227206 -210.896454)
					(mid 316.493906 -210.629754)
					(end 316.760606 -210.896454)
				)
				(arc
					(start 317.040006 -210.896454)
					(mid 317.306706 -210.629754)
					(end 317.573406 -210.896454)
				)
				(arc
					(start 317.817246 -210.896454)
					(mid 317.667712 -210.535448)
					(end 317.306706 -210.385914)
				)
			)
		)
	)
	(zone
		(layers "B.Cu" "In2.Cu")
		(hatch none 0.5)
		(connect_pads
			(clearance 0)
		)
		(min_thickness 0.25)
		(keepout
			(tracks not_allowed)
			(vias allowed)
			(pads allowed)
			(copperpour not_allowed)
			(footprints allowed)
		)
		(placement
			(enabled no)
			(sheetname "")
		)
		(fill yes
			(thermal_gap 0.5)
			(thermal_bridge_width 0.5)
			(island_removal_mode 0)
		)
		(polygon
			(pts
				(arc
					(start 294.159432 -34.66973)
					(mid 293.648638 -35.180143)
					(end 294.159178 -35.69081)
				)
				(arc
					(start 294.971978 -35.69081)
					(mid 295.332085 -35.542173)
					(end 295.482518 -35.18281)
				)
				(arc
					(start 295.238678 -35.18281)
					(mid 294.971978 -35.446982)
					(end 294.705278 -35.18281)
				)
				(arc
					(start 294.425878 -35.18281)
					(mid 294.159178 -35.446982)
					(end 293.892478 -35.18281)
				)
				(arc
					(start 293.892478 -35.18027)
					(mid 294.159178 -34.91357)
					(end 294.425878 -35.18027)
				)
				(arc
					(start 294.705278 -35.18027)
					(mid 294.971978 -34.91357)
					(end 295.238678 -35.18027)
				)
				(arc
					(start 295.482518 -35.18027)
					(mid 295.332984 -34.819264)
					(end 294.971978 -34.66973)
				)
			)
		)
	)
	(zone
		(layers "B.Cu" "In2.Cu")
		(hatch none 0.5)
		(connect_pads
			(clearance 0)
		)
		(min_thickness 0.25)
		(keepout
			(tracks not_allowed)
			(vias allowed)
			(pads allowed)
			(copperpour not_allowed)
			(footprints allowed)
		)
		(placement
			(enabled no)
			(sheetname "")
		)
		(fill yes
			(thermal_gap 0.5)
			(thermal_bridge_width 0.5)
			(island_removal_mode 0)
		)
		(polygon
			(pts
				(arc
					(start 14.68374 -67.638422)
					(mid 14.1732 -67.127882)
					(end 13.66266 -67.638422)
				)
				(arc
					(start 13.66266 -68.451222)
					(mid 14.17193 -68.96176)
					(end 14.68374 -68.453762)
				)
				(arc
					(start 14.4399 -68.453762)
					(mid 14.1732 -68.717934)
					(end 13.9065 -68.453762)
				)
				(arc
					(start 13.9065 -68.451222)
					(mid 14.1732 -68.184522)
					(end 14.4399 -68.451222)
				)
				(xy 14.68374 -68.451222) (xy 14.68374 -67.640962)
				(arc
					(start 14.4399 -67.640962)
					(mid 14.1732 -67.905134)
					(end 13.9065 -67.640962)
				)
				(arc
					(start 13.9065 -67.638422)
					(mid 14.1732 -67.371722)
					(end 14.4399 -67.638422)
				)
			)
		)
	)
	(zone
		(layers "B.Cu" "In2.Cu")
		(hatch none 0.5)
		(connect_pads
			(clearance 0)
		)
		(min_thickness 0.25)
		(keepout
			(tracks not_allowed)
			(vias allowed)
			(pads allowed)
			(copperpour not_allowed)
			(footprints allowed)
		)
		(placement
			(enabled no)
			(sheetname "")
		)
		(fill yes
			(thermal_gap 0.5)
			(thermal_bridge_width 0.5)
			(island_removal_mode 0)
		)
		(polygon
			(pts
				(arc
					(start 104.494076 -210.385914)
					(mid 103.983282 -210.896327)
					(end 104.493822 -211.406994)
				)
				(arc
					(start 105.306622 -211.406994)
					(mid 105.666729 -211.258357)
					(end 105.817162 -210.898994)
				)
				(arc
					(start 105.573322 -210.898994)
					(mid 105.306622 -211.163166)
					(end 105.039922 -210.898994)
				)
				(arc
					(start 104.760522 -210.898994)
					(mid 104.493822 -211.163166)
					(end 104.227122 -210.898994)
				)
				(arc
					(start 104.227122 -210.896454)
					(mid 104.493822 -210.629754)
					(end 104.760522 -210.896454)
				)
				(arc
					(start 105.039922 -210.896454)
					(mid 105.306622 -210.629754)
					(end 105.573322 -210.896454)
				)
				(arc
					(start 105.817162 -210.896454)
					(mid 105.667628 -210.535448)
					(end 105.306622 -210.385914)
				)
			)
		)
	)
	(zone
		(layers "B.Cu" "In2.Cu")
		(hatch none 0.5)
		(connect_pads
			(clearance 0)
		)
		(min_thickness 0.25)
		(keepout
			(tracks not_allowed)
			(vias allowed)
			(pads allowed)
			(copperpour not_allowed)
			(footprints allowed)
		)
		(placement
			(enabled no)
			(sheetname "")
		)
		(fill yes
			(thermal_gap 0.5)
			(thermal_bridge_width 0.5)
			(island_removal_mode 0)
		)
		(polygon
			(pts
				(arc
					(start 89.293954 -210.385914)
					(mid 88.78316 -210.896327)
					(end 89.2937 -211.406994)
				)
				(arc
					(start 90.1065 -211.406994)
					(mid 90.466607 -211.258357)
					(end 90.61704 -210.898994)
				)
				(arc
					(start 90.3732 -210.898994)
					(mid 90.1065 -211.163166)
					(end 89.8398 -210.898994)
				)
				(arc
					(start 89.5604 -210.898994)
					(mid 89.2937 -211.163166)
					(end 89.027 -210.898994)
				)
				(arc
					(start 89.027 -210.896454)
					(mid 89.2937 -210.629754)
					(end 89.5604 -210.896454)
				)
				(arc
					(start 89.8398 -210.896454)
					(mid 90.1065 -210.629754)
					(end 90.3732 -210.896454)
				)
				(arc
					(start 90.61704 -210.896454)
					(mid 90.467506 -210.535448)
					(end 90.1065 -210.385914)
				)
			)
		)
	)
	(zone
		(layers "B.Cu" "In2.Cu")
		(hatch none 0.5)
		(connect_pads
			(clearance 0)
		)
		(min_thickness 0.25)
		(keepout
			(tracks not_allowed)
			(vias allowed)
			(pads allowed)
			(copperpour not_allowed)
			(footprints allowed)
		)
		(placement
			(enabled no)
			(sheetname "")
		)
		(fill yes
			(thermal_gap 0.5)
			(thermal_bridge_width 0.5)
			(island_removal_mode 0)
		)
		(polygon
			(pts
				(arc
					(start 319.72123 -36.51504)
					(mid 319.210436 -37.025453)
					(end 319.720976 -37.53612)
				)
				(arc
					(start 320.533776 -37.53612)
					(mid 320.893883 -37.387483)
					(end 321.044316 -37.02812)
				)
				(arc
					(start 320.800476 -37.02812)
					(mid 320.533776 -37.292292)
					(end 320.267076 -37.02812)
				)
				(arc
					(start 319.987676 -37.02812)
					(mid 319.720976 -37.292292)
					(end 319.454276 -37.02812)
				)
				(arc
					(start 319.454276 -37.02558)
					(mid 319.720976 -36.75888)
					(end 319.987676 -37.02558)
				)
				(arc
					(start 320.267076 -37.02558)
					(mid 320.533776 -36.75888)
					(end 320.800476 -37.02558)
				)
				(arc
					(start 321.044316 -37.02558)
					(mid 320.894782 -36.664574)
					(end 320.533776 -36.51504)
				)
			)
		)
	)
	(zone
		(layers "B.Cu" "In2.Cu")
		(hatch none 0.5)
		(connect_pads
			(clearance 0)
		)
		(min_thickness 0.25)
		(keepout
			(tracks not_allowed)
			(vias allowed)
			(pads allowed)
			(copperpour not_allowed)
			(footprints allowed)
		)
		(placement
			(enabled no)
			(sheetname "")
		)
		(fill yes
			(thermal_gap 0.5)
			(thermal_bridge_width 0.5)
			(island_removal_mode 0)
		)
		(polygon
			(pts
				(arc
					(start 166.493952 -210.385914)
					(mid 165.983158 -210.896327)
					(end 166.493698 -211.406994)
				)
				(arc
					(start 167.306498 -211.406994)
					(mid 167.666605 -211.258357)
					(end 167.817038 -210.898994)
				)
				(arc
					(start 167.573198 -210.898994)
					(mid 167.306498 -211.163166)
					(end 167.039798 -210.898994)
				)
				(arc
					(start 166.760398 -210.898994)
					(mid 166.493698 -211.163166)
					(end 166.226998 -210.898994)
				)
				(arc
					(start 166.226998 -210.896454)
					(mid 166.493698 -210.629754)
					(end 166.760398 -210.896454)
				)
				(arc
					(start 167.039798 -210.896454)
					(mid 167.306498 -210.629754)
					(end 167.573198 -210.896454)
				)
				(arc
					(start 167.817038 -210.896454)
					(mid 167.667504 -210.535448)
					(end 167.306498 -210.385914)
				)
			)
		)
	)
	(zone
		(layers "B.Cu" "In2.Cu")
		(hatch none 0.5)
		(connect_pads
			(clearance 0)
		)
		(min_thickness 0.25)
		(keepout
			(tracks not_allowed)
			(vias allowed)
			(pads allowed)
			(copperpour not_allowed)
			(footprints allowed)
		)
		(placement
			(enabled no)
			(sheetname "")
		)
		(fill yes
			(thermal_gap 0.5)
			(thermal_bridge_width 0.5)
			(island_removal_mode 0)
		)
		(polygon
			(pts
				(arc
					(start 184.093866 -210.385914)
					(mid 183.583072 -210.896327)
					(end 184.093612 -211.406994)
				)
				(arc
					(start 184.906412 -211.406994)
					(mid 185.266519 -211.258357)
					(end 185.416952 -210.898994)
				)
				(arc
					(start 185.173112 -210.898994)
					(mid 184.906412 -211.163166)
					(end 184.639712 -210.898994)
				)
				(arc
					(start 184.360312 -210.898994)
					(mid 184.093612 -211.163166)
					(end 183.826912 -210.898994)
				)
				(arc
					(start 183.826912 -210.896454)
					(mid 184.093612 -210.629754)
					(end 184.360312 -210.896454)
				)
				(arc
					(start 184.639712 -210.896454)
					(mid 184.906412 -210.629754)
					(end 185.173112 -210.896454)
				)
				(arc
					(start 185.416952 -210.896454)
					(mid 185.267418 -210.535448)
					(end 184.906412 -210.385914)
				)
			)
		)
	)
	(zone
		(layers "B.Cu" "In2.Cu")
		(hatch none 0.5)
		(connect_pads
			(clearance 0)
		)
		(min_thickness 0.25)
		(keepout
			(tracks not_allowed)
			(vias allowed)
			(pads allowed)
			(copperpour not_allowed)
			(footprints allowed)
		)
		(placement
			(enabled no)
			(sheetname "")
		)
		(fill yes
			(thermal_gap 0.5)
			(thermal_bridge_width 0.5)
			(island_removal_mode 0)
		)
		(polygon
			(pts
				(arc
					(start 272.57883 -14.52245)
					(mid 272.06829 -14.01191)
					(end 271.55775 -14.52245)
				)
				(arc
					(start 271.55775 -15.334996)
					(mid 272.066893 -15.845788)
					(end 272.57883 -15.33779)
				)
				(arc
					(start 272.33499 -15.33779)
					(mid 272.06829 -15.601962)
					(end 271.80159 -15.33779)
				)
				(arc
					(start 271.80159 -15.33525)
					(mid 272.06829 -15.06855)
					(end 272.33499 -15.33525)
				)
				(xy 272.57883 -15.33525) (xy 272.57883 -14.52499)
				(arc
					(start 272.33499 -14.52499)
					(mid 272.06829 -14.789162)
					(end 271.80159 -14.52499)
				)
				(arc
					(start 271.80159 -14.52245)
					(mid 272.06829 -14.25575)
					(end 272.33499 -14.52245)
				)
			)
		)
	)
	(zone
		(layers "B.Cu" "In2.Cu")
		(hatch none 0.5)
		(connect_pads
			(clearance 0)
		)
		(min_thickness 0.25)
		(keepout
			(tracks not_allowed)
			(vias allowed)
			(pads allowed)
			(copperpour not_allowed)
			(footprints allowed)
		)
		(placement
			(enabled no)
			(sheetname "")
		)
		(fill yes
			(thermal_gap 0.5)
			(thermal_bridge_width 0.5)
			(island_removal_mode 0)
		)
		(polygon
			(pts
				(arc
					(start 268.98854 -13.843)
					(mid 268.478 -13.33246)
					(end 267.96746 -13.843)
				)
				(arc
					(start 267.96746 -14.6558)
					(mid 268.47673 -15.166338)
					(end 268.98854 -14.65834)
				)
				(arc
					(start 268.7447 -14.65834)
					(mid 268.478 -14.922512)
					(end 268.2113 -14.65834)
				)
				(arc
					(start 268.2113 -14.6558)
					(mid 268.478 -14.3891)
					(end 268.7447 -14.6558)
				)
				(xy 268.98854 -14.6558) (xy 268.98854 -13.84554)
				(arc
					(start 268.7447 -13.84554)
					(mid 268.478 -14.109712)
					(end 268.2113 -13.84554)
				)
				(arc
					(start 268.2113 -13.843)
					(mid 268.478 -13.5763)
					(end 268.7447 -13.843)
				)
			)
		)
	)
	(zone
		(layers "B.Cu" "In2.Cu")
		(hatch none 0.5)
		(connect_pads
			(clearance 0)
		)
		(min_thickness 0.25)
		(keepout
			(tracks not_allowed)
			(vias allowed)
			(pads allowed)
			(copperpour not_allowed)
			(footprints allowed)
		)
		(placement
			(enabled no)
			(sheetname "")
		)
		(fill yes
			(thermal_gap 0.5)
			(thermal_bridge_width 0.5)
			(island_removal_mode 0)
		)
		(polygon
			(pts
				(arc
					(start 51.693826 -210.385914)
					(mid 51.183032 -210.896327)
					(end 51.693572 -211.406994)
				)
				(arc
					(start 52.506372 -211.406994)
					(mid 52.866479 -211.258357)
					(end 53.016912 -210.898994)
				)
				(arc
					(start 52.773072 -210.898994)
					(mid 52.506372 -211.163166)
					(end 52.239672 -210.898994)
				)
				(arc
					(start 51.960272 -210.898994)
					(mid 51.693572 -211.163166)
					(end 51.426872 -210.898994)
				)
				(arc
					(start 51.426872 -210.896454)
					(mid 51.693572 -210.629754)
					(end 51.960272 -210.896454)
				)
				(arc
					(start 52.239672 -210.896454)
					(mid 52.506372 -210.629754)
					(end 52.773072 -210.896454)
				)
				(arc
					(start 53.016912 -210.896454)
					(mid 52.867378 -210.535448)
					(end 52.506372 -210.385914)
				)
			)
		)
	)
	(zone
		(layers "B.Cu" "In2.Cu")
		(hatch none 0.5)
		(connect_pads
			(clearance 0)
		)
		(min_thickness 0.25)
		(keepout
			(tracks not_allowed)
			(vias allowed)
			(pads allowed)
			(copperpour not_allowed)
			(footprints allowed)
		)
		(placement
			(enabled no)
			(sheetname "")
		)
		(fill yes
			(thermal_gap 0.5)
			(thermal_bridge_width 0.5)
			(island_removal_mode 0)
		)
		(polygon
			(pts
				(arc
					(start 203.29398 -210.385914)
					(mid 202.783186 -210.896327)
					(end 203.293726 -211.406994)
				)
				(arc
					(start 204.106526 -211.406994)
					(mid 204.466633 -211.258357)
					(end 204.617066 -210.898994)
				)
				(arc
					(start 204.373226 -210.898994)
					(mid 204.106526 -211.163166)
					(end 203.839826 -210.898994)
				)
				(arc
					(start 203.560426 -210.898994)
					(mid 203.293726 -211.163166)
					(end 203.027026 -210.898994)
				)
				(arc
					(start 203.027026 -210.896454)
					(mid 203.293726 -210.629754)
					(end 203.560426 -210.896454)
				)
				(arc
					(start 203.839826 -210.896454)
					(mid 204.106526 -210.629754)
					(end 204.373226 -210.896454)
				)
				(arc
					(start 204.617066 -210.896454)
					(mid 204.467532 -210.535448)
					(end 204.106526 -210.385914)
				)
			)
		)
	)
	(zone
		(layers "B.Cu" "In2.Cu")
		(hatch none 0.5)
		(connect_pads
			(clearance 0)
		)
		(min_thickness 0.25)
		(keepout
			(tracks not_allowed)
			(vias allowed)
			(pads allowed)
			(copperpour not_allowed)
			(footprints allowed)
		)
		(placement
			(enabled no)
			(sheetname "")
		)
		(fill yes
			(thermal_gap 0.5)
			(thermal_bridge_width 0.5)
			(island_removal_mode 0)
		)
		(polygon
			(pts
				(arc
					(start 18.8468 -54.487572)
					(mid 18.33626 -54.998112)
					(end 18.8468 -55.508652)
				)
				(arc
					(start 19.659346 -55.508652)
					(mid 20.019617 -55.360105)
					(end 20.17014 -55.000652)
				)
				(arc
					(start 19.9263 -55.000652)
					(mid 19.6596 -55.264824)
					(end 19.3929 -55.000652)
				)
				(arc
					(start 19.1135 -55.000652)
					(mid 18.8468 -55.264824)
					(end 18.5801 -55.000652)
				)
				(arc
					(start 18.5801 -54.998112)
					(mid 18.8468 -54.731412)
					(end 19.1135 -54.998112)
				)
				(arc
					(start 19.3929 -54.998112)
					(mid 19.6596 -54.731412)
					(end 19.9263 -54.998112)
				)
				(arc
					(start 20.17014 -54.998112)
					(mid 20.020606 -54.637106)
					(end 19.6596 -54.487572)
				)
			)
		)
	)
	(zone
		(layers "B.Cu" "In2.Cu" "In5.Cu")
		(hatch none 0.5)
		(connect_pads
			(clearance 0)
		)
		(min_thickness 0.25)
		(keepout
			(tracks not_allowed)
			(vias allowed)
			(pads allowed)
			(copperpour not_allowed)
			(footprints allowed)
		)
		(placement
			(enabled no)
			(sheetname "")
		)
		(fill yes
			(thermal_gap 0.5)
			(thermal_bridge_width 0.5)
			(island_removal_mode 0)
		)
		(polygon
			(pts
				(arc
					(start 134.509256 -23.930102)
					(mid 134.036418 -23.324032)
					(end 133.33349 -23.635208)
				)
				(xy 133.331458 -23.633938) (xy 132.581396 -25.033732) (xy 132.58165 -25.033986)
				(arc
					(start 132.583682 -25.035002)
					(mid 132.839358 -25.880903)
					(end 133.68528 -25.625044)
				)
				(xy 133.687312 -25.626314) (xy 133.844538 -25.33269)
				(arc
					(start 133.515354 -25.33269)
					(mid 133.134354 -25.711158)
					(end 132.753354 -25.33269)
				)
				(arc
					(start 132.753354 -25.33015)
					(mid 133.134354 -24.94915)
					(end 133.515354 -25.33015)
				)
				(xy 133.846062 -25.33015) (xy 134.437374 -24.226266)
				(arc
					(start 134.435342 -24.224996)
					(mid 134.490219 -24.083347)
					(end 134.509256 -23.932642)
				)
				(arc
					(start 134.265416 -23.932642)
					(mid 133.884416 -24.31111)
					(end 133.503416 -23.932642)
				)
				(arc
					(start 133.503416 -23.930102)
					(mid 133.884416 -23.549102)
					(end 134.265416 -23.930102)
				)
			)
		)
	)
	(zone
		(layers "B.Cu" "In2.Cu" "In5.Cu")
		(hatch none 0.5)
		(connect_pads
			(clearance 0)
		)
		(min_thickness 0.25)
		(keepout
			(tracks not_allowed)
			(vias allowed)
			(pads allowed)
			(copperpour not_allowed)
			(footprints allowed)
		)
		(placement
			(enabled no)
			(sheetname "")
		)
		(fill yes
			(thermal_gap 0.5)
			(thermal_bridge_width 0.5)
			(island_removal_mode 0)
		)
		(polygon
			(pts
				(arc
					(start 145.509234 -12.530074)
					(mid 145.036396 -11.924004)
					(end 144.333468 -12.23518)
				)
				(xy 144.331436 -12.23391) (xy 143.581374 -13.633704) (xy 143.581628 -13.633958)
				(arc
					(start 143.58366 -13.634974)
					(mid 143.839336 -14.480875)
					(end 144.685258 -14.225016)
				)
				(xy 144.68729 -14.226286) (xy 144.844516 -13.932662)
				(arc
					(start 144.515332 -13.932662)
					(mid 144.134332 -14.31113)
					(end 143.753332 -13.932662)
				)
				(arc
					(start 143.753332 -13.930122)
					(mid 144.134332 -13.549122)
					(end 144.515332 -13.930122)
				)
				(xy 144.84604 -13.930122) (xy 145.437352 -12.826238)
				(arc
					(start 145.43532 -12.824968)
					(mid 145.490197 -12.683319)
					(end 145.509234 -12.532614)
				)
				(arc
					(start 145.265394 -12.532614)
					(mid 144.884394 -12.911082)
					(end 144.503394 -12.532614)
				)
				(arc
					(start 144.503394 -12.530074)
					(mid 144.884394 -12.149074)
					(end 145.265394 -12.530074)
				)
			)
		)
	)
	(zone
		(layers "B.Cu" "In2.Cu" "In5.Cu")
		(hatch none 0.5)
		(connect_pads
			(clearance 0)
		)
		(min_thickness 0.25)
		(keepout
			(tracks not_allowed)
			(vias allowed)
			(pads allowed)
			(copperpour not_allowed)
			(footprints allowed)
		)
		(placement
			(enabled no)
			(sheetname "")
		)
		(fill yes
			(thermal_gap 0.5)
			(thermal_bridge_width 0.5)
			(island_removal_mode 0)
		)
		(polygon
			(pts
				(arc
					(start 139.009374 -23.930102)
					(mid 138.536536 -23.324032)
					(end 137.833608 -23.635208)
				)
				(xy 137.831576 -23.633938) (xy 137.081514 -25.033732) (xy 137.081768 -25.033986)
				(arc
					(start 137.0838 -25.035002)
					(mid 137.339476 -25.880903)
					(end 138.185398 -25.625044)
				)
				(xy 138.18743 -25.626314) (xy 138.344656 -25.33269)
				(arc
					(start 138.015472 -25.33269)
					(mid 137.634472 -25.711158)
					(end 137.253472 -25.33269)
				)
				(arc
					(start 137.253472 -25.33015)
					(mid 137.634472 -24.94915)
					(end 138.015472 -25.33015)
				)
				(xy 138.34618 -25.33015) (xy 138.937492 -24.226266)
				(arc
					(start 138.93546 -24.224996)
					(mid 138.990337 -24.083347)
					(end 139.009374 -23.932642)
				)
				(arc
					(start 138.765534 -23.932642)
					(mid 138.384534 -24.31111)
					(end 138.003534 -23.932642)
				)
				(arc
					(start 138.003534 -23.930102)
					(mid 138.384534 -23.549102)
					(end 138.765534 -23.930102)
				)
			)
		)
	)
	(zone
		(layers "B.Cu" "In2.Cu" "In5.Cu")
		(hatch none 0.5)
		(connect_pads
			(clearance 0)
		)
		(min_thickness 0.25)
		(keepout
			(tracks not_allowed)
			(vias allowed)
			(pads allowed)
			(copperpour not_allowed)
			(footprints allowed)
		)
		(placement
			(enabled no)
			(sheetname "")
		)
		(fill yes
			(thermal_gap 0.5)
			(thermal_bridge_width 0.5)
			(island_removal_mode 0)
		)
		(polygon
			(pts
				(arc
					(start 325.009256 -20.130008)
					(mid 324.536418 -19.523938)
					(end 323.83349 -19.835114)
				)
				(xy 323.831458 -19.833844) (xy 323.081396 -21.233892)
				(arc
					(start 323.083428 -21.235162)
					(mid 323.33946 -22.080982)
					(end 324.18528 -21.82495)
				)
				(xy 324.187312 -21.82622) (xy 324.344538 -21.532596)
				(arc
					(start 324.015354 -21.532596)
					(mid 323.634354 -21.911064)
					(end 323.253354 -21.532596)
				)
				(arc
					(start 323.253354 -21.530056)
					(mid 323.634354 -21.149056)
					(end 324.015354 -21.530056)
				)
				(xy 324.346062 -21.530056) (xy 324.937374 -20.426426) (xy 324.93712 -20.426172)
				(arc
					(start 324.935088 -20.425156)
					(mid 324.990134 -20.283401)
					(end 325.009256 -20.132548)
				)
				(arc
					(start 324.765416 -20.132548)
					(mid 324.384416 -20.511016)
					(end 324.003416 -20.132548)
				)
				(arc
					(start 324.003416 -20.130008)
					(mid 324.384416 -19.749008)
					(end 324.765416 -20.130008)
				)
			)
		)
	)
	(zone
		(layers "B.Cu" "In2.Cu" "In5.Cu")
		(hatch none 0.5)
		(connect_pads
			(clearance 0)
		)
		(min_thickness 0.25)
		(keepout
			(tracks not_allowed)
			(vias allowed)
			(pads allowed)
			(copperpour not_allowed)
			(footprints allowed)
		)
		(placement
			(enabled no)
			(sheetname "")
		)
		(fill yes
			(thermal_gap 0.5)
			(thermal_bridge_width 0.5)
			(island_removal_mode 0)
		)
		(polygon
			(pts
				(arc
					(start 322.759324 -20.130008)
					(mid 322.286486 -19.523938)
					(end 321.583558 -19.835114)
				)
				(xy 321.581526 -19.833844) (xy 320.831464 -21.233892)
				(arc
					(start 320.833496 -21.235162)
					(mid 321.089528 -22.080982)
					(end 321.935348 -21.82495)
				)
				(xy 321.93738 -21.82622) (xy 322.094606 -21.532596)
				(arc
					(start 321.765422 -21.532596)
					(mid 321.384422 -21.911064)
					(end 321.003422 -21.532596)
				)
				(arc
					(start 321.003422 -21.530056)
					(mid 321.384422 -21.149056)
					(end 321.765422 -21.530056)
				)
				(xy 322.09613 -21.530056) (xy 322.687442 -20.426426) (xy 322.687188 -20.426172)
				(arc
					(start 322.685156 -20.425156)
					(mid 322.740202 -20.283401)
					(end 322.759324 -20.132548)
				)
				(arc
					(start 322.515484 -20.132548)
					(mid 322.134484 -20.511016)
					(end 321.753484 -20.132548)
				)
				(arc
					(start 321.753484 -20.130008)
					(mid 322.134484 -19.749008)
					(end 322.515484 -20.130008)
				)
			)
		)
	)
	(zone
		(layers "B.Cu" "In2.Cu" "In5.Cu")
		(hatch none 0.5)
		(connect_pads
			(clearance 0)
		)
		(min_thickness 0.25)
		(keepout
			(tracks not_allowed)
			(vias allowed)
			(pads allowed)
			(copperpour not_allowed)
			(footprints allowed)
		)
		(placement
			(enabled no)
			(sheetname "")
		)
		(fill yes
			(thermal_gap 0.5)
			(thermal_bridge_width 0.5)
			(island_removal_mode 0)
		)
		(polygon
			(pts
				(arc
					(start 165.753542 -13.930122)
					(mid 166.134542 -13.549122)
					(end 166.515542 -13.930122)
				)
				(xy 166.843456 -13.930122)
				(arc
					(start 167.435276 -12.824968)
					(mid 167.490153 -12.683319)
					(end 167.50919 -12.532614)
				)
				(arc
					(start 167.26535 -12.532614)
					(mid 166.88435 -12.911082)
					(end 166.50335 -12.532614)
				)
				(arc
					(start 166.50335 -12.530074)
					(mid 166.88435 -12.149074)
					(end 167.26535 -12.530074)
				)
				(arc
					(start 167.50919 -12.530074)
					(mid 167.036352 -11.924004)
					(end 166.333424 -12.23518)
				)
				(arc
					(start 165.58768 -13.627608)
					(mid 165.835814 -14.479061)
					(end 166.685468 -14.225016)
				)
				(xy 166.841932 -13.932662)
				(arc
					(start 166.515542 -13.932662)
					(mid 166.134542 -14.31113)
					(end 165.753542 -13.932662)
				)
			)
		)
	)
	(zone
		(layers "B.Cu" "In2.Cu" "In5.Cu")
		(hatch none 0.5)
		(connect_pads
			(clearance 0)
		)
		(min_thickness 0.25)
		(keepout
			(tracks not_allowed)
			(vias allowed)
			(pads allowed)
			(copperpour not_allowed)
			(footprints allowed)
		)
		(placement
			(enabled no)
			(sheetname "")
		)
		(fill yes
			(thermal_gap 0.5)
			(thermal_bridge_width 0.5)
			(island_removal_mode 0)
		)
		(polygon
			(pts
				(arc
					(start 303.0093 -20.130008)
					(mid 302.536462 -19.523938)
					(end 301.833534 -19.835114)
				)
				(xy 301.831502 -19.833844) (xy 301.08144 -21.233892)
				(arc
					(start 301.083472 -21.235162)
					(mid 301.339504 -22.080982)
					(end 302.185324 -21.82495)
				)
				(xy 302.187356 -21.82622) (xy 302.344582 -21.532596)
				(arc
					(start 302.015398 -21.532596)
					(mid 301.634398 -21.911064)
					(end 301.253398 -21.532596)
				)
				(arc
					(start 301.253398 -21.530056)
					(mid 301.634398 -21.149056)
					(end 302.015398 -21.530056)
				)
				(xy 302.346106 -21.530056) (xy 302.937418 -20.426426) (xy 302.937164 -20.426172)
				(arc
					(start 302.935132 -20.425156)
					(mid 302.990178 -20.283401)
					(end 303.0093 -20.132548)
				)
				(arc
					(start 302.76546 -20.132548)
					(mid 302.38446 -20.511016)
					(end 302.00346 -20.132548)
				)
				(arc
					(start 302.00346 -20.130008)
					(mid 302.38446 -19.749008)
					(end 302.76546 -20.130008)
				)
			)
		)
	)
	(zone
		(layers "B.Cu" "In2.Cu" "In5.Cu")
		(hatch none 0.5)
		(connect_pads
			(clearance 0)
		)
		(min_thickness 0.25)
		(keepout
			(tracks not_allowed)
			(vias allowed)
			(pads allowed)
			(copperpour not_allowed)
			(footprints allowed)
		)
		(placement
			(enabled no)
			(sheetname "")
		)
		(fill yes
			(thermal_gap 0.5)
			(thermal_bridge_width 0.5)
			(island_removal_mode 0)
		)
		(polygon
			(pts
				(arc
					(start 314.009278 -23.930102)
					(mid 313.53644 -23.324032)
					(end 312.833512 -23.635208)
				)
				(xy 312.83148 -23.633938) (xy 312.081418 -25.033732) (xy 312.081672 -25.033986)
				(arc
					(start 312.083704 -25.035002)
					(mid 312.33938 -25.880903)
					(end 313.185302 -25.625044)
				)
				(xy 313.187334 -25.626314) (xy 313.34456 -25.33269)
				(arc
					(start 313.015376 -25.33269)
					(mid 312.634376 -25.711158)
					(end 312.253376 -25.33269)
				)
				(arc
					(start 312.253376 -25.33015)
					(mid 312.634376 -24.94915)
					(end 313.015376 -25.33015)
				)
				(xy 313.346084 -25.33015) (xy 313.937396 -24.226266)
				(arc
					(start 313.935364 -24.224996)
					(mid 313.990241 -24.083347)
					(end 314.009278 -23.932642)
				)
				(arc
					(start 313.765438 -23.932642)
					(mid 313.384438 -24.31111)
					(end 313.003438 -23.932642)
				)
				(arc
					(start 313.003438 -23.930102)
					(mid 313.384438 -23.549102)
					(end 313.765438 -23.930102)
				)
			)
		)
	)
	(zone
		(layers "B.Cu" "In2.Cu" "In5.Cu")
		(hatch none 0.5)
		(connect_pads
			(clearance 0)
		)
		(min_thickness 0.25)
		(keepout
			(tracks not_allowed)
			(vias allowed)
			(pads allowed)
			(copperpour not_allowed)
			(footprints allowed)
		)
		(placement
			(enabled no)
			(sheetname "")
		)
		(fill yes
			(thermal_gap 0.5)
			(thermal_bridge_width 0.5)
			(island_removal_mode 0)
		)
		(polygon
			(pts
				(arc
					(start 145.509234 -23.930102)
					(mid 145.036396 -23.324032)
					(end 144.333468 -23.635208)
				)
				(xy 144.331436 -23.633938) (xy 143.581374 -25.033986)
				(arc
					(start 143.583406 -25.035256)
					(mid 143.839438 -25.881076)
					(end 144.685258 -25.625044)
				)
				(xy 144.68729 -25.626314) (xy 144.844516 -25.33269)
				(arc
					(start 144.515332 -25.33269)
					(mid 144.134332 -25.711158)
					(end 143.753332 -25.33269)
				)
				(arc
					(start 143.753332 -25.33015)
					(mid 144.134332 -24.94915)
					(end 144.515332 -25.33015)
				)
				(xy 144.84604 -25.33015) (xy 145.437352 -24.22652) (xy 145.437098 -24.226266)
				(arc
					(start 145.435066 -24.22525)
					(mid 145.490112 -24.083495)
					(end 145.509234 -23.932642)
				)
				(arc
					(start 145.265394 -23.932642)
					(mid 144.884394 -24.31111)
					(end 144.503394 -23.932642)
				)
				(arc
					(start 144.503394 -23.930102)
					(mid 144.884394 -23.549102)
					(end 145.265394 -23.930102)
				)
			)
		)
	)
	(zone
		(layers "B.Cu" "In2.Cu" "In5.Cu")
		(hatch none 0.5)
		(connect_pads
			(clearance 0)
		)
		(min_thickness 0.25)
		(keepout
			(tracks not_allowed)
			(vias allowed)
			(pads allowed)
			(copperpour not_allowed)
			(footprints allowed)
		)
		(placement
			(enabled no)
			(sheetname "")
		)
		(fill yes
			(thermal_gap 0.5)
			(thermal_bridge_width 0.5)
			(island_removal_mode 0)
		)
		(polygon
			(pts
				(arc
					(start 172.009308 -23.930102)
					(mid 171.53647 -23.324032)
					(end 170.833542 -23.635208)
				)
				(xy 170.83151 -23.633938) (xy 170.081448 -25.033732) (xy 170.081702 -25.033986)
				(arc
					(start 170.083734 -25.035002)
					(mid 170.33941 -25.880903)
					(end 171.185332 -25.625044)
				)
				(xy 171.187364 -25.626314) (xy 171.34459 -25.33269)
				(arc
					(start 171.015406 -25.33269)
					(mid 170.634406 -25.711158)
					(end 170.253406 -25.33269)
				)
				(arc
					(start 170.253406 -25.33015)
					(mid 170.634406 -24.94915)
					(end 171.015406 -25.33015)
				)
				(xy 171.346114 -25.33015) (xy 171.937426 -24.226266)
				(arc
					(start 171.935394 -24.224996)
					(mid 171.990271 -24.083347)
					(end 172.009308 -23.932642)
				)
				(arc
					(start 171.765468 -23.932642)
					(mid 171.384468 -24.31111)
					(end 171.003468 -23.932642)
				)
				(arc
					(start 171.003468 -23.930102)
					(mid 171.384468 -23.549102)
					(end 171.765468 -23.930102)
				)
			)
		)
	)
	(zone
		(layers "B.Cu" "In2.Cu" "In5.Cu")
		(hatch none 0.5)
		(connect_pads
			(clearance 0)
		)
		(min_thickness 0.25)
		(keepout
			(tracks not_allowed)
			(vias allowed)
			(pads allowed)
			(copperpour not_allowed)
			(footprints allowed)
		)
		(placement
			(enabled no)
			(sheetname "")
		)
		(fill yes
			(thermal_gap 0.5)
			(thermal_bridge_width 0.5)
			(island_removal_mode 0)
		)
		(polygon
			(pts
				(arc
					(start 322.759324 -23.930102)
					(mid 322.286486 -23.324032)
					(end 321.583558 -23.635208)
				)
				(xy 321.581526 -23.633938) (xy 320.831464 -25.033732) (xy 320.831718 -25.033986)
				(arc
					(start 320.83375 -25.035002)
					(mid 321.089426 -25.880903)
					(end 321.935348 -25.625044)
				)
				(xy 321.93738 -25.626314) (xy 322.094606 -25.33269)
				(arc
					(start 321.765422 -25.33269)
					(mid 321.384422 -25.711158)
					(end 321.003422 -25.33269)
				)
				(arc
					(start 321.003422 -25.33015)
					(mid 321.384422 -24.94915)
					(end 321.765422 -25.33015)
				)
				(xy 322.09613 -25.33015) (xy 322.687442 -24.226266)
				(arc
					(start 322.68541 -24.224996)
					(mid 322.740287 -24.083347)
					(end 322.759324 -23.932642)
				)
				(arc
					(start 322.515484 -23.932642)
					(mid 322.134484 -24.31111)
					(end 321.753484 -23.932642)
				)
				(arc
					(start 321.753484 -23.930102)
					(mid 322.134484 -23.549102)
					(end 322.515484 -23.930102)
				)
			)
		)
	)
	(zone
		(layers "B.Cu" "In2.Cu" "In5.Cu")
		(hatch none 0.5)
		(connect_pads
			(clearance 0)
		)
		(min_thickness 0.25)
		(keepout
			(tracks not_allowed)
			(vias allowed)
			(pads allowed)
			(copperpour not_allowed)
			(footprints allowed)
		)
		(placement
			(enabled no)
			(sheetname "")
		)
		(fill yes
			(thermal_gap 0.5)
			(thermal_bridge_width 0.5)
			(island_removal_mode 0)
		)
		(polygon
			(pts
				(arc
					(start 156.509212 -23.930102)
					(mid 156.036374 -23.324032)
					(end 155.333446 -23.635208)
				)
				(arc
					(start 154.583638 -25.035256)
					(mid 154.83967 -25.881076)
					(end 155.68549 -25.625044)
				)
				(xy 155.841954 -25.33269)
				(arc
					(start 155.515564 -25.33269)
					(mid 155.134564 -25.711158)
					(end 154.753564 -25.33269)
				)
				(arc
					(start 154.753564 -25.33015)
					(mid 155.134564 -24.94915)
					(end 155.515564 -25.33015)
				)
				(xy 155.843478 -25.33015)
				(arc
					(start 156.431234 -24.232616)
					(mid 156.489114 -24.08754)
					(end 156.509212 -23.932642)
				)
				(arc
					(start 156.265372 -23.932642)
					(mid 155.884372 -24.31111)
					(end 155.503372 -23.932642)
				)
				(arc
					(start 155.503372 -23.930102)
					(mid 155.884372 -23.549102)
					(end 156.265372 -23.930102)
				)
			)
		)
	)
	(zone
		(layers "B.Cu" "In2.Cu" "In5.Cu")
		(hatch none 0.5)
		(connect_pads
			(clearance 0)
		)
		(min_thickness 0.25)
		(keepout
			(tracks not_allowed)
			(vias allowed)
			(pads allowed)
			(copperpour not_allowed)
			(footprints allowed)
		)
		(placement
			(enabled no)
			(sheetname "")
		)
		(fill yes
			(thermal_gap 0.5)
			(thermal_bridge_width 0.5)
			(island_removal_mode 0)
		)
		(polygon
			(pts
				(arc
					(start 320.509138 -23.930102)
					(mid 320.0363 -23.324032)
					(end 319.333372 -23.635208)
				)
				(arc
					(start 318.583564 -25.035256)
					(mid 318.839596 -25.881076)
					(end 319.685416 -25.625044)
				)
				(xy 319.84188 -25.33269)
				(arc
					(start 319.51549 -25.33269)
					(mid 319.13449 -25.711158)
					(end 318.75349 -25.33269)
				)
				(arc
					(start 318.75349 -25.33015)
					(mid 319.13449 -24.94915)
					(end 319.51549 -25.33015)
				)
				(xy 319.843404 -25.33015)
				(arc
					(start 320.43116 -24.232616)
					(mid 320.48904 -24.08754)
					(end 320.509138 -23.932642)
				)
				(arc
					(start 320.265298 -23.932642)
					(mid 319.884298 -24.31111)
					(end 319.503298 -23.932642)
				)
				(arc
					(start 319.503298 -23.930102)
					(mid 319.884298 -23.549102)
					(end 320.265298 -23.930102)
				)
			)
		)
	)
	(zone
		(layers "B.Cu" "In2.Cu" "In5.Cu")
		(hatch none 0.5)
		(connect_pads
			(clearance 0)
		)
		(min_thickness 0.25)
		(keepout
			(tracks not_allowed)
			(vias allowed)
			(pads allowed)
			(copperpour not_allowed)
			(footprints allowed)
		)
		(placement
			(enabled no)
			(sheetname "")
		)
		(fill yes
			(thermal_gap 0.5)
			(thermal_bridge_width 0.5)
			(island_removal_mode 0)
		)
		(polygon
			(pts
				(arc
					(start 158.759398 -23.930102)
					(mid 158.28656 -23.324032)
					(end 157.583632 -23.635208)
				)
				(xy 157.5816 -23.633938) (xy 156.831538 -25.033732) (xy 156.831792 -25.033986)
				(arc
					(start 156.833824 -25.035002)
					(mid 157.0895 -25.880903)
					(end 157.935422 -25.625044)
				)
				(xy 157.937454 -25.626314) (xy 158.09468 -25.33269)
				(arc
					(start 157.765496 -25.33269)
					(mid 157.384496 -25.711158)
					(end 157.003496 -25.33269)
				)
				(arc
					(start 157.003496 -25.33015)
					(mid 157.384496 -24.94915)
					(end 157.765496 -25.33015)
				)
				(xy 158.096204 -25.33015) (xy 158.687516 -24.226266)
				(arc
					(start 158.685484 -24.224996)
					(mid 158.740361 -24.083347)
					(end 158.759398 -23.932642)
				)
				(arc
					(start 158.515558 -23.932642)
					(mid 158.134558 -24.31111)
					(end 157.753558 -23.932642)
				)
				(arc
					(start 157.753558 -23.930102)
					(mid 158.134558 -23.549102)
					(end 158.515558 -23.930102)
				)
			)
		)
	)
	(zone
		(layers "B.Cu" "In2.Cu" "In5.Cu")
		(hatch none 0.5)
		(connect_pads
			(clearance 0)
		)
		(min_thickness 0.25)
		(keepout
			(tracks not_allowed)
			(vias allowed)
			(pads allowed)
			(copperpour not_allowed)
			(footprints allowed)
		)
		(placement
			(enabled no)
			(sheetname "")
		)
		(fill yes
			(thermal_gap 0.5)
			(thermal_bridge_width 0.5)
			(island_removal_mode 0)
		)
		(polygon
			(pts
				(arc
					(start 136.759188 -20.130008)
					(mid 136.28635 -19.523938)
					(end 135.583422 -19.835114)
				)
				(arc
					(start 134.837678 -21.227542)
					(mid 135.085812 -22.078995)
					(end 135.935466 -21.82495)
				)
				(xy 136.09193 -21.532596)
				(arc
					(start 135.76554 -21.532596)
					(mid 135.38454 -21.911064)
					(end 135.00354 -21.532596)
				)
				(arc
					(start 135.00354 -21.530056)
					(mid 135.38454 -21.149056)
					(end 135.76554 -21.530056)
				)
				(xy 136.093454 -21.530056)
				(arc
					(start 136.685274 -20.424902)
					(mid 136.740151 -20.283253)
					(end 136.759188 -20.132548)
				)
				(arc
					(start 136.515348 -20.132548)
					(mid 136.134348 -20.511016)
					(end 135.753348 -20.132548)
				)
				(arc
					(start 135.753348 -20.130008)
					(mid 136.134348 -19.749008)
					(end 136.515348 -20.130008)
				)
			)
		)
	)
	(zone
		(layers "B.Cu" "In2.Cu" "In5.Cu")
		(hatch none 0.5)
		(connect_pads
			(clearance 0)
		)
		(min_thickness 0.25)
		(keepout
			(tracks not_allowed)
			(vias allowed)
			(pads allowed)
			(copperpour not_allowed)
			(footprints allowed)
		)
		(placement
			(enabled no)
			(sheetname "")
		)
		(fill yes
			(thermal_gap 0.5)
			(thermal_bridge_width 0.5)
			(island_removal_mode 0)
		)
		(polygon
			(pts
				(arc
					(start 161.00933 -20.130008)
					(mid 160.536492 -19.523938)
					(end 159.833564 -19.835114)
				)
				(xy 159.831532 -19.833844) (xy 159.08147 -21.233892)
				(arc
					(start 159.083502 -21.235162)
					(mid 159.339534 -22.080982)
					(end 160.185354 -21.82495)
				)
				(xy 160.187386 -21.82622) (xy 160.344612 -21.532596)
				(arc
					(start 160.015428 -21.532596)
					(mid 159.634428 -21.911064)
					(end 159.253428 -21.532596)
				)
				(arc
					(start 159.253428 -21.530056)
					(mid 159.634428 -21.149056)
					(end 160.015428 -21.530056)
				)
				(xy 160.346136 -21.530056) (xy 160.937448 -20.426426) (xy 160.937194 -20.426172)
				(arc
					(start 160.935162 -20.425156)
					(mid 160.990208 -20.283401)
					(end 161.00933 -20.132548)
				)
				(arc
					(start 160.76549 -20.132548)
					(mid 160.38449 -20.511016)
					(end 160.00349 -20.132548)
				)
				(arc
					(start 160.00349 -20.130008)
					(mid 160.38449 -19.749008)
					(end 160.76549 -20.130008)
				)
			)
		)
	)
	(zone
		(layers "B.Cu" "In2.Cu" "In5.Cu")
		(hatch none 0.5)
		(connect_pads
			(clearance 0)
		)
		(min_thickness 0.25)
		(keepout
			(tracks not_allowed)
			(vias allowed)
			(pads allowed)
			(copperpour not_allowed)
			(footprints allowed)
		)
		(placement
			(enabled no)
			(sheetname "")
		)
		(fill yes
			(thermal_gap 0.5)
			(thermal_bridge_width 0.5)
			(island_removal_mode 0)
		)
		(polygon
			(pts
				(arc
					(start 150.009352 -23.930102)
					(mid 149.536514 -23.324032)
					(end 148.833586 -23.635208)
				)
				(xy 148.831554 -23.633938) (xy 148.081492 -25.033732) (xy 148.081746 -25.033986)
				(arc
					(start 148.083778 -25.035002)
					(mid 148.339454 -25.880903)
					(end 149.185376 -25.625044)
				)
				(xy 149.187408 -25.626314) (xy 149.344634 -25.33269)
				(arc
					(start 149.01545 -25.33269)
					(mid 148.63445 -25.711158)
					(end 148.25345 -25.33269)
				)
				(arc
					(start 148.25345 -25.33015)
					(mid 148.63445 -24.94915)
					(end 149.01545 -25.33015)
				)
				(xy 149.346158 -25.33015) (xy 149.93747 -24.226266)
				(arc
					(start 149.935438 -24.224996)
					(mid 149.990315 -24.083347)
					(end 150.009352 -23.932642)
				)
				(arc
					(start 149.765512 -23.932642)
					(mid 149.384512 -24.31111)
					(end 149.003512 -23.932642)
				)
				(arc
					(start 149.003512 -23.930102)
					(mid 149.384512 -23.549102)
					(end 149.765512 -23.930102)
				)
			)
		)
	)
	(zone
		(layers "B.Cu" "In2.Cu" "In5.Cu")
		(hatch none 0.5)
		(connect_pads
			(clearance 0)
		)
		(min_thickness 0.25)
		(keepout
			(tracks not_allowed)
			(vias allowed)
			(pads allowed)
			(copperpour not_allowed)
			(footprints allowed)
		)
		(placement
			(enabled no)
			(sheetname "")
		)
		(fill yes
			(thermal_gap 0.5)
			(thermal_bridge_width 0.5)
			(island_removal_mode 0)
		)
		(polygon
			(pts
				(arc
					(start 289.759136 -23.930102)
					(mid 289.286298 -23.324032)
					(end 288.58337 -23.635208)
				)
				(arc
					(start 287.837626 -25.027636)
					(mid 288.08576 -25.879089)
					(end 288.935414 -25.625044)
				)
				(xy 289.091878 -25.33269)
				(arc
					(start 288.765488 -25.33269)
					(mid 288.384488 -25.711158)
					(end 288.003488 -25.33269)
				)
				(arc
					(start 288.003488 -25.33015)
					(mid 288.384488 -24.94915)
					(end 288.765488 -25.33015)
				)
				(xy 289.093402 -25.33015)
				(arc
					(start 289.685222 -24.224996)
					(mid 289.740099 -24.083347)
					(end 289.759136 -23.932642)
				)
				(arc
					(start 289.515296 -23.932642)
					(mid 289.134296 -24.31111)
					(end 288.753296 -23.932642)
				)
				(arc
					(start 288.753296 -23.930102)
					(mid 289.134296 -23.549102)
					(end 289.515296 -23.930102)
				)
			)
		)
	)
	(zone
		(layers "B.Cu" "In2.Cu" "In5.Cu")
		(hatch none 0.5)
		(connect_pads
			(clearance 0)
		)
		(min_thickness 0.25)
		(keepout
			(tracks not_allowed)
			(vias allowed)
			(pads allowed)
			(copperpour not_allowed)
			(footprints allowed)
		)
		(placement
			(enabled no)
			(sheetname "")
		)
		(fill yes
			(thermal_gap 0.5)
			(thermal_bridge_width 0.5)
			(island_removal_mode 0)
		)
		(polygon
			(pts
				(arc
					(start 300.759114 -20.130008)
					(mid 300.286276 -19.523938)
					(end 299.583348 -19.835114)
				)
				(arc
					(start 298.83354 -21.235162)
					(mid 299.089572 -22.080982)
					(end 299.935392 -21.82495)
				)
				(xy 300.091856 -21.532596)
				(arc
					(start 299.765466 -21.532596)
					(mid 299.384466 -21.911064)
					(end 299.003466 -21.532596)
				)
				(arc
					(start 299.003466 -21.530056)
					(mid 299.384466 -21.149056)
					(end 299.765466 -21.530056)
				)
				(xy 300.09338 -21.530056)
				(arc
					(start 300.681136 -20.432522)
					(mid 300.739016 -20.287446)
					(end 300.759114 -20.132548)
				)
				(arc
					(start 300.515274 -20.132548)
					(mid 300.134274 -20.511016)
					(end 299.753274 -20.132548)
				)
				(arc
					(start 299.753274 -20.130008)
					(mid 300.134274 -19.749008)
					(end 300.515274 -20.130008)
				)
			)
		)
	)
	(zone
		(layers "B.Cu" "In2.Cu" "In5.Cu")
		(hatch none 0.5)
		(connect_pads
			(clearance 0)
		)
		(min_thickness 0.25)
		(keepout
			(tracks not_allowed)
			(vias allowed)
			(pads allowed)
			(copperpour not_allowed)
			(footprints allowed)
		)
		(placement
			(enabled no)
			(sheetname "")
		)
		(fill yes
			(thermal_gap 0.5)
			(thermal_bridge_width 0.5)
			(island_removal_mode 0)
		)
		(polygon
			(pts
				(arc
					(start 325.009256 -23.930102)
					(mid 324.536418 -23.324032)
					(end 323.83349 -23.635208)
				)
				(xy 323.831458 -23.633938) (xy 323.081396 -25.033732) (xy 323.08165 -25.033986)
				(arc
					(start 323.083682 -25.035002)
					(mid 323.339358 -25.880903)
					(end 324.18528 -25.625044)
				)
				(xy 324.187312 -25.626314) (xy 324.344538 -25.33269)
				(arc
					(start 324.015354 -25.33269)
					(mid 323.634354 -25.711158)
					(end 323.253354 -25.33269)
				)
				(arc
					(start 323.253354 -25.33015)
					(mid 323.634354 -24.94915)
					(end 324.015354 -25.33015)
				)
				(xy 324.346062 -25.33015) (xy 324.937374 -24.226266)
				(arc
					(start 324.935342 -24.224996)
					(mid 324.990219 -24.083347)
					(end 325.009256 -23.932642)
				)
				(arc
					(start 324.765416 -23.932642)
					(mid 324.384416 -24.31111)
					(end 324.003416 -23.932642)
				)
				(arc
					(start 324.003416 -23.930102)
					(mid 324.384416 -23.549102)
					(end 324.765416 -23.930102)
				)
			)
		)
	)
	(zone
		(layers "B.Cu" "In2.Cu" "In5.Cu")
		(hatch none 0.5)
		(connect_pads
			(clearance 0)
		)
		(min_thickness 0.25)
		(keepout
			(tracks not_allowed)
			(vias allowed)
			(pads allowed)
			(copperpour not_allowed)
			(footprints allowed)
		)
		(placement
			(enabled no)
			(sheetname "")
		)
		(fill yes
			(thermal_gap 0.5)
			(thermal_bridge_width 0.5)
			(island_removal_mode 0)
		)
		(polygon
			(pts
				(arc
					(start 314.009278 -20.130008)
					(mid 313.53644 -19.523938)
					(end 312.833512 -19.835114)
				)
				(xy 312.83148 -19.833844) (xy 312.081418 -21.233892)
				(arc
					(start 312.08345 -21.235162)
					(mid 312.339482 -22.080982)
					(end 313.185302 -21.82495)
				)
				(xy 313.187334 -21.82622) (xy 313.34456 -21.532596)
				(arc
					(start 313.015376 -21.532596)
					(mid 312.634376 -21.911064)
					(end 312.253376 -21.532596)
				)
				(arc
					(start 312.253376 -21.530056)
					(mid 312.634376 -21.149056)
					(end 313.015376 -21.530056)
				)
				(xy 313.346084 -21.530056) (xy 313.937396 -20.426426) (xy 313.937142 -20.426172)
				(arc
					(start 313.93511 -20.425156)
					(mid 313.990156 -20.283401)
					(end 314.009278 -20.132548)
				)
				(arc
					(start 313.765438 -20.132548)
					(mid 313.384438 -20.511016)
					(end 313.003438 -20.132548)
				)
				(arc
					(start 313.003438 -20.130008)
					(mid 313.384438 -19.749008)
					(end 313.765438 -20.130008)
				)
			)
		)
	)
	(zone
		(layers "B.Cu" "In2.Cu" "In5.Cu")
		(hatch none 0.5)
		(connect_pads
			(clearance 0)
		)
		(min_thickness 0.25)
		(keepout
			(tracks not_allowed)
			(vias allowed)
			(pads allowed)
			(copperpour not_allowed)
			(footprints allowed)
		)
		(placement
			(enabled no)
			(sheetname "")
		)
		(fill yes
			(thermal_gap 0.5)
			(thermal_bridge_width 0.5)
			(island_removal_mode 0)
		)
		(polygon
			(pts
				(arc
					(start 320.509138 -12.530074)
					(mid 320.0363 -11.924004)
					(end 319.333372 -12.23518)
				)
				(arc
					(start 318.587628 -13.627608)
					(mid 318.835762 -14.479061)
					(end 319.685416 -14.225016)
				)
				(xy 319.84188 -13.932662)
				(arc
					(start 319.51549 -13.932662)
					(mid 319.13449 -14.31113)
					(end 318.75349 -13.932662)
				)
				(arc
					(start 318.75349 -13.930122)
					(mid 319.13449 -13.549122)
					(end 319.51549 -13.930122)
				)
				(xy 319.843404 -13.930122)
				(arc
					(start 320.435224 -12.824968)
					(mid 320.490101 -12.683319)
					(end 320.509138 -12.532614)
				)
				(arc
					(start 320.265298 -12.532614)
					(mid 319.884298 -12.911082)
					(end 319.503298 -12.532614)
				)
				(arc
					(start 319.503298 -12.530074)
					(mid 319.884298 -12.149074)
					(end 320.265298 -12.530074)
				)
			)
		)
	)
	(zone
		(layers "B.Cu" "In2.Cu" "In5.Cu")
		(hatch none 0.5)
		(connect_pads
			(clearance 0)
		)
		(min_thickness 0.25)
		(keepout
			(tracks not_allowed)
			(vias allowed)
			(pads allowed)
			(copperpour not_allowed)
			(footprints allowed)
		)
		(placement
			(enabled no)
			(sheetname "")
		)
		(fill yes
			(thermal_gap 0.5)
			(thermal_bridge_width 0.5)
			(island_removal_mode 0)
		)
		(polygon
			(pts
				(arc
					(start 303.0093 -23.930102)
					(mid 302.536462 -23.324032)
					(end 301.833534 -23.635208)
				)
				(xy 301.831502 -23.633938) (xy 301.08144 -25.033732) (xy 301.081694 -25.033986)
				(arc
					(start 301.083726 -25.035002)
					(mid 301.339402 -25.880903)
					(end 302.185324 -25.625044)
				)
				(xy 302.187356 -25.626314) (xy 302.344582 -25.33269)
				(arc
					(start 302.015398 -25.33269)
					(mid 301.634398 -25.711158)
					(end 301.253398 -25.33269)
				)
				(arc
					(start 301.253398 -25.33015)
					(mid 301.634398 -24.94915)
					(end 302.015398 -25.33015)
				)
				(xy 302.346106 -25.33015) (xy 302.937418 -24.226266)
				(arc
					(start 302.935386 -24.224996)
					(mid 302.990263 -24.083347)
					(end 303.0093 -23.932642)
				)
				(arc
					(start 302.76546 -23.932642)
					(mid 302.38446 -24.31111)
					(end 302.00346 -23.932642)
				)
				(arc
					(start 302.00346 -23.930102)
					(mid 302.38446 -23.549102)
					(end 302.76546 -23.930102)
				)
			)
		)
	)
	(zone
		(layers "B.Cu" "In2.Cu" "In5.Cu")
		(hatch none 0.5)
		(connect_pads
			(clearance 0)
		)
		(min_thickness 0.25)
		(keepout
			(tracks not_allowed)
			(vias allowed)
			(pads allowed)
			(copperpour not_allowed)
			(footprints allowed)
		)
		(placement
			(enabled no)
			(sheetname "")
		)
		(fill yes
			(thermal_gap 0.5)
			(thermal_bridge_width 0.5)
			(island_removal_mode 0)
		)
		(polygon
			(pts
				(arc
					(start 298.509182 -12.530074)
					(mid 298.036344 -11.924004)
					(end 297.333416 -12.23518)
				)
				(xy 297.331384 -12.23391) (xy 296.581322 -13.633704) (xy 296.581576 -13.633958)
				(arc
					(start 296.583608 -13.634974)
					(mid 296.839284 -14.480875)
					(end 297.685206 -14.225016)
				)
				(xy 297.687238 -14.226286) (xy 297.844464 -13.932662)
				(arc
					(start 297.51528 -13.932662)
					(mid 297.13428 -14.31113)
					(end 296.75328 -13.932662)
				)
				(arc
					(start 296.75328 -13.930122)
					(mid 297.13428 -13.549122)
					(end 297.51528 -13.930122)
				)
				(xy 297.845988 -13.930122) (xy 298.4373 -12.826238)
				(arc
					(start 298.435268 -12.824968)
					(mid 298.490145 -12.683319)
					(end 298.509182 -12.532614)
				)
				(arc
					(start 298.265342 -12.532614)
					(mid 297.884342 -12.911082)
					(end 297.503342 -12.532614)
				)
				(arc
					(start 297.503342 -12.530074)
					(mid 297.884342 -12.149074)
					(end 298.265342 -12.530074)
				)
			)
		)
	)
	(zone
		(layers "B.Cu" "In2.Cu" "In5.Cu")
		(hatch none 0.5)
		(connect_pads
			(clearance 0)
		)
		(min_thickness 0.25)
		(keepout
			(tracks not_allowed)
			(vias allowed)
			(pads allowed)
			(copperpour not_allowed)
			(footprints allowed)
		)
		(placement
			(enabled no)
			(sheetname "")
		)
		(fill yes
			(thermal_gap 0.5)
			(thermal_bridge_width 0.5)
			(island_removal_mode 0)
		)
		(polygon
			(pts
				(arc
					(start 147.759166 -20.130008)
					(mid 147.286328 -19.523938)
					(end 146.5834 -19.835114)
				)
				(arc
					(start 145.833592 -21.235162)
					(mid 146.089624 -22.080982)
					(end 146.935444 -21.82495)
				)
				(xy 147.091908 -21.532596)
				(arc
					(start 146.765518 -21.532596)
					(mid 146.384518 -21.911064)
					(end 146.003518 -21.532596)
				)
				(arc
					(start 146.003518 -21.530056)
					(mid 146.384518 -21.149056)
					(end 146.765518 -21.530056)
				)
				(xy 147.093432 -21.530056)
				(arc
					(start 147.681188 -20.432522)
					(mid 147.739068 -20.287446)
					(end 147.759166 -20.132548)
				)
				(arc
					(start 147.515326 -20.132548)
					(mid 147.134326 -20.511016)
					(end 146.753326 -20.132548)
				)
				(arc
					(start 146.753326 -20.130008)
					(mid 147.134326 -19.749008)
					(end 147.515326 -20.130008)
				)
			)
		)
	)
	(zone
		(layers "B.Cu" "In2.Cu" "In5.Cu")
		(hatch none 0.5)
		(connect_pads
			(clearance 0)
		)
		(min_thickness 0.25)
		(keepout
			(tracks not_allowed)
			(vias allowed)
			(pads allowed)
			(copperpour not_allowed)
			(footprints allowed)
		)
		(placement
			(enabled no)
			(sheetname "")
		)
		(fill yes
			(thermal_gap 0.5)
			(thermal_bridge_width 0.5)
			(island_removal_mode 0)
		)
		(polygon
			(pts
				(arc
					(start 139.009374 -20.130008)
					(mid 138.536536 -19.523938)
					(end 137.833608 -19.835114)
				)
				(xy 137.831576 -19.833844) (xy 137.081514 -21.233638) (xy 137.081768 -21.233892)
				(arc
					(start 137.0838 -21.234908)
					(mid 137.339476 -22.080809)
					(end 138.185398 -21.82495)
				)
				(xy 138.18743 -21.82622) (xy 138.344656 -21.532596)
				(arc
					(start 138.015472 -21.532596)
					(mid 137.634472 -21.911064)
					(end 137.253472 -21.532596)
				)
				(arc
					(start 137.253472 -21.530056)
					(mid 137.634472 -21.149056)
					(end 138.015472 -21.530056)
				)
				(xy 138.34618 -21.530056) (xy 138.937492 -20.426172)
				(arc
					(start 138.93546 -20.424902)
					(mid 138.990337 -20.283253)
					(end 139.009374 -20.132548)
				)
				(arc
					(start 138.765534 -20.132548)
					(mid 138.384534 -20.511016)
					(end 138.003534 -20.132548)
				)
				(arc
					(start 138.003534 -20.130008)
					(mid 138.384534 -19.749008)
					(end 138.765534 -20.130008)
				)
			)
		)
	)
	(zone
		(layers "B.Cu" "In2.Cu" "In5.Cu")
		(hatch none 0.5)
		(connect_pads
			(clearance 0)
		)
		(min_thickness 0.25)
		(keepout
			(tracks not_allowed)
			(vias allowed)
			(pads allowed)
			(copperpour not_allowed)
			(footprints allowed)
		)
		(placement
			(enabled no)
			(sheetname "")
		)
		(fill yes
			(thermal_gap 0.5)
			(thermal_bridge_width 0.5)
			(island_removal_mode 0)
		)
		(polygon
			(pts
				(arc
					(start 309.50916 -23.930102)
					(mid 309.036322 -23.324032)
					(end 308.333394 -23.635208)
				)
				(arc
					(start 307.583586 -25.035256)
					(mid 307.839618 -25.881076)
					(end 308.685438 -25.625044)
				)
				(xy 308.841902 -25.33269)
				(arc
					(start 308.515512 -25.33269)
					(mid 308.134512 -25.711158)
					(end 307.753512 -25.33269)
				)
				(arc
					(start 307.753512 -25.33015)
					(mid 308.134512 -24.94915)
					(end 308.515512 -25.33015)
				)
				(xy 308.843426 -25.33015)
				(arc
					(start 309.431182 -24.232616)
					(mid 309.489062 -24.08754)
					(end 309.50916 -23.932642)
				)
				(arc
					(start 309.26532 -23.932642)
					(mid 308.88432 -24.31111)
					(end 308.50332 -23.932642)
				)
				(arc
					(start 308.50332 -23.930102)
					(mid 308.88432 -23.549102)
					(end 309.26532 -23.930102)
				)
			)
		)
	)
	(zone
		(layers "B.Cu" "In2.Cu" "In5.Cu")
		(hatch none 0.5)
		(connect_pads
			(clearance 0)
		)
		(min_thickness 0.25)
		(keepout
			(tracks not_allowed)
			(vias allowed)
			(pads allowed)
			(copperpour not_allowed)
			(footprints allowed)
		)
		(placement
			(enabled no)
			(sheetname "")
		)
		(fill yes
			(thermal_gap 0.5)
			(thermal_bridge_width 0.5)
			(island_removal_mode 0)
		)
		(polygon
			(pts
				(arc
					(start 136.759188 -23.930102)
					(mid 136.28635 -23.324032)
					(end 135.583422 -23.635208)
				)
				(arc
					(start 134.837678 -25.027636)
					(mid 135.085812 -25.879089)
					(end 135.935466 -25.625044)
				)
				(xy 136.09193 -25.33269)
				(arc
					(start 135.76554 -25.33269)
					(mid 135.38454 -25.711158)
					(end 135.00354 -25.33269)
				)
				(arc
					(start 135.00354 -25.33015)
					(mid 135.38454 -24.94915)
					(end 135.76554 -25.33015)
				)
				(xy 136.093454 -25.33015)
				(arc
					(start 136.685274 -24.224996)
					(mid 136.740151 -24.083347)
					(end 136.759188 -23.932642)
				)
				(arc
					(start 136.515348 -23.932642)
					(mid 136.134348 -24.31111)
					(end 135.753348 -23.932642)
				)
				(arc
					(start 135.753348 -23.930102)
					(mid 136.134348 -23.549102)
					(end 136.515348 -23.930102)
				)
			)
		)
	)
	(zone
		(layers "B.Cu" "In2.Cu" "In5.Cu")
		(hatch none 0.5)
		(connect_pads
			(clearance 0)
		)
		(min_thickness 0.25)
		(keepout
			(tracks not_allowed)
			(vias allowed)
			(pads allowed)
			(copperpour not_allowed)
			(footprints allowed)
		)
		(placement
			(enabled no)
			(sheetname "")
		)
		(fill yes
			(thermal_gap 0.5)
			(thermal_bridge_width 0.5)
			(island_removal_mode 0)
		)
		(polygon
			(pts
				(arc
					(start 172.009308 -20.130008)
					(mid 171.53647 -19.523938)
					(end 170.833542 -19.835114)
				)
				(xy 170.83151 -19.833844) (xy 170.081448 -21.233892)
				(arc
					(start 170.08348 -21.235162)
					(mid 170.339512 -22.080982)
					(end 171.185332 -21.82495)
				)
				(xy 171.187364 -21.82622) (xy 171.34459 -21.532596)
				(arc
					(start 171.015406 -21.532596)
					(mid 170.634406 -21.911064)
					(end 170.253406 -21.532596)
				)
				(arc
					(start 170.253406 -21.530056)
					(mid 170.634406 -21.149056)
					(end 171.015406 -21.530056)
				)
				(xy 171.346114 -21.530056) (xy 171.937426 -20.426426) (xy 171.937172 -20.426172)
				(arc
					(start 171.93514 -20.425156)
					(mid 171.990186 -20.283401)
					(end 172.009308 -20.132548)
				)
				(arc
					(start 171.765468 -20.132548)
					(mid 171.384468 -20.511016)
					(end 171.003468 -20.132548)
				)
				(arc
					(start 171.003468 -20.130008)
					(mid 171.384468 -19.749008)
					(end 171.765468 -20.130008)
				)
			)
		)
	)
	(zone
		(layers "B.Cu" "In2.Cu" "In5.Cu")
		(hatch none 0.5)
		(connect_pads
			(clearance 0)
		)
		(min_thickness 0.25)
		(keepout
			(tracks not_allowed)
			(vias allowed)
			(pads allowed)
			(copperpour not_allowed)
			(footprints allowed)
		)
		(placement
			(enabled no)
			(sheetname "")
		)
		(fill yes
			(thermal_gap 0.5)
			(thermal_bridge_width 0.5)
			(island_removal_mode 0)
		)
		(polygon
			(pts
				(arc
					(start 150.009352 -20.130008)
					(mid 149.536514 -19.523938)
					(end 148.833586 -19.835114)
				)
				(xy 148.831554 -19.833844) (xy 148.081492 -21.233892)
				(arc
					(start 148.083524 -21.235162)
					(mid 148.339556 -22.080982)
					(end 149.185376 -21.82495)
				)
				(xy 149.187408 -21.82622) (xy 149.344634 -21.532596)
				(arc
					(start 149.01545 -21.532596)
					(mid 148.63445 -21.911064)
					(end 148.25345 -21.532596)
				)
				(arc
					(start 148.25345 -21.530056)
					(mid 148.63445 -21.149056)
					(end 149.01545 -21.530056)
				)
				(xy 149.346158 -21.530056) (xy 149.93747 -20.426426) (xy 149.937216 -20.426172)
				(arc
					(start 149.935184 -20.425156)
					(mid 149.99023 -20.283401)
					(end 150.009352 -20.132548)
				)
				(arc
					(start 149.765512 -20.132548)
					(mid 149.384512 -20.511016)
					(end 149.003512 -20.132548)
				)
				(arc
					(start 149.003512 -20.130008)
					(mid 149.384512 -19.749008)
					(end 149.765512 -20.130008)
				)
			)
		)
	)
	(zone
		(layers "B.Cu" "In2.Cu" "In5.Cu")
		(hatch none 0.5)
		(connect_pads
			(clearance 0)
		)
		(min_thickness 0.25)
		(keepout
			(tracks not_allowed)
			(vias allowed)
			(pads allowed)
			(copperpour not_allowed)
			(footprints allowed)
		)
		(placement
			(enabled no)
			(sheetname "")
		)
		(fill yes
			(thermal_gap 0.5)
			(thermal_bridge_width 0.5)
			(island_removal_mode 0)
		)
		(polygon
			(pts
				(arc
					(start 147.759166 -23.930102)
					(mid 147.286328 -23.324032)
					(end 146.5834 -23.635208)
				)
				(arc
					(start 145.837656 -25.027636)
					(mid 146.08579 -25.879089)
					(end 146.935444 -25.625044)
				)
				(xy 147.091908 -25.33269)
				(arc
					(start 146.765518 -25.33269)
					(mid 146.384518 -25.711158)
					(end 146.003518 -25.33269)
				)
				(arc
					(start 146.003518 -25.33015)
					(mid 146.384518 -24.94915)
					(end 146.765518 -25.33015)
				)
				(xy 147.093432 -25.33015)
				(arc
					(start 147.685252 -24.224996)
					(mid 147.740129 -24.083347)
					(end 147.759166 -23.932642)
				)
				(arc
					(start 147.515326 -23.932642)
					(mid 147.134326 -24.31111)
					(end 146.753326 -23.932642)
				)
				(arc
					(start 146.753326 -23.930102)
					(mid 147.134326 -23.549102)
					(end 147.515326 -23.930102)
				)
			)
		)
	)
	(zone
		(layers "B.Cu" "In2.Cu" "In5.Cu")
		(hatch none 0.5)
		(connect_pads
			(clearance 0)
		)
		(min_thickness 0.25)
		(keepout
			(tracks not_allowed)
			(vias allowed)
			(pads allowed)
			(copperpour not_allowed)
			(footprints allowed)
		)
		(placement
			(enabled no)
			(sheetname "")
		)
		(fill yes
			(thermal_gap 0.5)
			(thermal_bridge_width 0.5)
			(island_removal_mode 0)
		)
		(polygon
			(pts
				(arc
					(start 167.50919 -23.930102)
					(mid 167.036352 -23.324032)
					(end 166.333424 -23.635208)
				)
				(arc
					(start 165.583616 -25.035256)
					(mid 165.839648 -25.881076)
					(end 166.685468 -25.625044)
				)
				(xy 166.841932 -25.33269)
				(arc
					(start 166.515542 -25.33269)
					(mid 166.134542 -25.711158)
					(end 165.753542 -25.33269)
				)
				(arc
					(start 165.753542 -25.33015)
					(mid 166.134542 -24.94915)
					(end 166.515542 -25.33015)
				)
				(xy 166.843456 -25.33015)
				(arc
					(start 167.431212 -24.232616)
					(mid 167.489092 -24.08754)
					(end 167.50919 -23.932642)
				)
				(arc
					(start 167.26535 -23.932642)
					(mid 166.88435 -24.31111)
					(end 166.50335 -23.932642)
				)
				(arc
					(start 166.50335 -23.930102)
					(mid 166.88435 -23.549102)
					(end 167.26535 -23.930102)
				)
			)
		)
	)
	(zone
		(layers "B.Cu" "In2.Cu" "In5.Cu")
		(hatch none 0.5)
		(connect_pads
			(clearance 0)
		)
		(min_thickness 0.25)
		(keepout
			(tracks not_allowed)
			(vias allowed)
			(pads allowed)
			(copperpour not_allowed)
			(footprints allowed)
		)
		(placement
			(enabled no)
			(sheetname "")
		)
		(fill yes
			(thermal_gap 0.5)
			(thermal_bridge_width 0.5)
			(island_removal_mode 0)
		)
		(polygon
			(pts
				(arc
					(start 292.009322 -20.130008)
					(mid 291.536484 -19.523938)
					(end 290.833556 -19.835114)
				)
				(xy 290.831524 -19.833844) (xy 290.081462 -21.233638) (xy 290.081716 -21.233892)
				(arc
					(start 290.083748 -21.234908)
					(mid 290.339424 -22.080809)
					(end 291.185346 -21.82495)
				)
				(xy 291.187378 -21.82622) (xy 291.344604 -21.532596)
				(arc
					(start 291.01542 -21.532596)
					(mid 290.63442 -21.911064)
					(end 290.25342 -21.532596)
				)
				(arc
					(start 290.25342 -21.530056)
					(mid 290.63442 -21.149056)
					(end 291.01542 -21.530056)
				)
				(xy 291.346128 -21.530056) (xy 291.93744 -20.426172)
				(arc
					(start 291.935408 -20.424902)
					(mid 291.990285 -20.283253)
					(end 292.009322 -20.132548)
				)
				(arc
					(start 291.765482 -20.132548)
					(mid 291.384482 -20.511016)
					(end 291.003482 -20.132548)
				)
				(arc
					(start 291.003482 -20.130008)
					(mid 291.384482 -19.749008)
					(end 291.765482 -20.130008)
				)
			)
		)
	)
	(zone
		(layers "B.Cu" "In2.Cu" "In5.Cu")
		(hatch none 0.5)
		(connect_pads
			(clearance 0)
		)
		(min_thickness 0.25)
		(keepout
			(tracks not_allowed)
			(vias allowed)
			(pads allowed)
			(copperpour not_allowed)
			(footprints allowed)
		)
		(placement
			(enabled no)
			(sheetname "")
		)
		(fill yes
			(thermal_gap 0.5)
			(thermal_bridge_width 0.5)
			(island_removal_mode 0)
		)
		(polygon
			(pts
				(arc
					(start 158.759398 -20.130008)
					(mid 158.28656 -19.523938)
					(end 157.583632 -19.835114)
				)
				(xy 157.5816 -19.833844) (xy 156.831538 -21.233892)
				(arc
					(start 156.83357 -21.235162)
					(mid 157.089602 -22.080982)
					(end 157.935422 -21.82495)
				)
				(xy 157.937454 -21.82622) (xy 158.09468 -21.532596)
				(arc
					(start 157.765496 -21.532596)
					(mid 157.384496 -21.911064)
					(end 157.003496 -21.532596)
				)
				(arc
					(start 157.003496 -21.530056)
					(mid 157.384496 -21.149056)
					(end 157.765496 -21.530056)
				)
				(xy 158.096204 -21.530056) (xy 158.687516 -20.426426) (xy 158.687262 -20.426172)
				(arc
					(start 158.68523 -20.425156)
					(mid 158.740276 -20.283401)
					(end 158.759398 -20.132548)
				)
				(arc
					(start 158.515558 -20.132548)
					(mid 158.134558 -20.511016)
					(end 157.753558 -20.132548)
				)
				(arc
					(start 157.753558 -20.130008)
					(mid 158.134558 -19.749008)
					(end 158.515558 -20.130008)
				)
			)
		)
	)
	(zone
		(layers "B.Cu" "In2.Cu" "In5.Cu")
		(hatch none 0.5)
		(connect_pads
			(clearance 0)
		)
		(min_thickness 0.25)
		(keepout
			(tracks not_allowed)
			(vias allowed)
			(pads allowed)
			(copperpour not_allowed)
			(footprints allowed)
		)
		(placement
			(enabled no)
			(sheetname "")
		)
		(fill yes
			(thermal_gap 0.5)
			(thermal_bridge_width 0.5)
			(island_removal_mode 0)
		)
		(polygon
			(pts
				(arc
					(start 292.009322 -23.930102)
					(mid 291.536484 -23.324032)
					(end 290.833556 -23.635208)
				)
				(xy 290.831524 -23.633938) (xy 290.081462 -25.033732) (xy 290.081716 -25.033986)
				(arc
					(start 290.083748 -25.035002)
					(mid 290.339424 -25.880903)
					(end 291.185346 -25.625044)
				)
				(xy 291.187378 -25.626314) (xy 291.344604 -25.33269)
				(arc
					(start 291.01542 -25.33269)
					(mid 290.63442 -25.711158)
					(end 290.25342 -25.33269)
				)
				(arc
					(start 290.25342 -25.33015)
					(mid 290.63442 -24.94915)
					(end 291.01542 -25.33015)
				)
				(xy 291.346128 -25.33015) (xy 291.93744 -24.226266)
				(arc
					(start 291.935408 -24.224996)
					(mid 291.990285 -24.083347)
					(end 292.009322 -23.932642)
				)
				(arc
					(start 291.765482 -23.932642)
					(mid 291.384482 -24.31111)
					(end 291.003482 -23.932642)
				)
				(arc
					(start 291.003482 -23.930102)
					(mid 291.384482 -23.549102)
					(end 291.765482 -23.930102)
				)
			)
		)
	)
	(zone
		(layers "B.Cu" "In2.Cu" "In5.Cu")
		(hatch none 0.5)
		(connect_pads
			(clearance 0)
		)
		(min_thickness 0.25)
		(keepout
			(tracks not_allowed)
			(vias allowed)
			(pads allowed)
			(copperpour not_allowed)
			(footprints allowed)
		)
		(placement
			(enabled no)
			(sheetname "")
		)
		(fill yes
			(thermal_gap 0.5)
			(thermal_bridge_width 0.5)
			(island_removal_mode 0)
		)
		(polygon
			(pts
				(arc
					(start 169.759376 -20.130008)
					(mid 169.286538 -19.523938)
					(end 168.58361 -19.835114)
				)
				(xy 168.581578 -19.833844) (xy 167.831516 -21.233892)
				(arc
					(start 167.833548 -21.235162)
					(mid 168.08958 -22.080982)
					(end 168.9354 -21.82495)
				)
				(xy 168.937432 -21.82622) (xy 169.094658 -21.532596)
				(arc
					(start 168.765474 -21.532596)
					(mid 168.384474 -21.911064)
					(end 168.003474 -21.532596)
				)
				(arc
					(start 168.003474 -21.530056)
					(mid 168.384474 -21.149056)
					(end 168.765474 -21.530056)
				)
				(xy 169.096182 -21.530056) (xy 169.687494 -20.426426) (xy 169.68724 -20.426172)
				(arc
					(start 169.685208 -20.425156)
					(mid 169.740254 -20.283401)
					(end 169.759376 -20.132548)
				)
				(arc
					(start 169.515536 -20.132548)
					(mid 169.134536 -20.511016)
					(end 168.753536 -20.132548)
				)
				(arc
					(start 168.753536 -20.130008)
					(mid 169.134536 -19.749008)
					(end 169.515536 -20.130008)
				)
			)
		)
	)
	(zone
		(layers "B.Cu" "In2.Cu" "In5.Cu")
		(hatch none 0.5)
		(connect_pads
			(clearance 0)
		)
		(min_thickness 0.25)
		(keepout
			(tracks not_allowed)
			(vias allowed)
			(pads allowed)
			(copperpour not_allowed)
			(footprints allowed)
		)
		(placement
			(enabled no)
			(sheetname "")
		)
		(fill yes
			(thermal_gap 0.5)
			(thermal_bridge_width 0.5)
			(island_removal_mode 0)
		)
		(polygon
			(pts
				(arc
					(start 161.00933 -23.930102)
					(mid 160.536492 -23.324032)
					(end 159.833564 -23.635208)
				)
				(xy 159.831532 -23.633938) (xy 159.08147 -25.033732) (xy 159.081724 -25.033986)
				(arc
					(start 159.083756 -25.035002)
					(mid 159.339432 -25.880903)
					(end 160.185354 -25.625044)
				)
				(xy 160.187386 -25.626314) (xy 160.344612 -25.33269)
				(arc
					(start 160.015428 -25.33269)
					(mid 159.634428 -25.711158)
					(end 159.253428 -25.33269)
				)
				(arc
					(start 159.253428 -25.33015)
					(mid 159.634428 -24.94915)
					(end 160.015428 -25.33015)
				)
				(xy 160.346136 -25.33015) (xy 160.937448 -24.226266)
				(arc
					(start 160.935416 -24.224996)
					(mid 160.990293 -24.083347)
					(end 161.00933 -23.932642)
				)
				(arc
					(start 160.76549 -23.932642)
					(mid 160.38449 -24.31111)
					(end 160.00349 -23.932642)
				)
				(arc
					(start 160.00349 -23.930102)
					(mid 160.38449 -23.549102)
					(end 160.76549 -23.930102)
				)
			)
		)
	)
	(zone
		(layers "B.Cu" "In2.Cu" "In5.Cu")
		(hatch none 0.5)
		(connect_pads
			(clearance 0)
		)
		(min_thickness 0.25)
		(keepout
			(tracks not_allowed)
			(vias allowed)
			(pads allowed)
			(copperpour not_allowed)
			(footprints allowed)
		)
		(placement
			(enabled no)
			(sheetname "")
		)
		(fill yes
			(thermal_gap 0.5)
			(thermal_bridge_width 0.5)
			(island_removal_mode 0)
		)
		(polygon
			(pts
				(arc
					(start 169.759376 -23.930102)
					(mid 169.286538 -23.324032)
					(end 168.58361 -23.635208)
				)
				(xy 168.581578 -23.633938) (xy 167.831516 -25.033732) (xy 167.83177 -25.033986)
				(arc
					(start 167.833802 -25.035002)
					(mid 168.089478 -25.880903)
					(end 168.9354 -25.625044)
				)
				(xy 168.937432 -25.626314) (xy 169.094658 -25.33269)
				(arc
					(start 168.765474 -25.33269)
					(mid 168.384474 -25.711158)
					(end 168.003474 -25.33269)
				)
				(arc
					(start 168.003474 -25.33015)
					(mid 168.384474 -24.94915)
					(end 168.765474 -25.33015)
				)
				(xy 169.096182 -25.33015) (xy 169.687494 -24.226266)
				(arc
					(start 169.685462 -24.224996)
					(mid 169.740339 -24.083347)
					(end 169.759376 -23.932642)
				)
				(arc
					(start 169.515536 -23.932642)
					(mid 169.134536 -24.31111)
					(end 168.753536 -23.932642)
				)
				(arc
					(start 168.753536 -23.930102)
					(mid 169.134536 -23.549102)
					(end 169.515536 -23.930102)
				)
			)
		)
	)
	(zone
		(layers "B.Cu" "In2.Cu" "In5.Cu")
		(hatch none 0.5)
		(connect_pads
			(clearance 0)
		)
		(min_thickness 0.25)
		(keepout
			(tracks not_allowed)
			(vias allowed)
			(pads allowed)
			(copperpour not_allowed)
			(footprints allowed)
		)
		(placement
			(enabled no)
			(sheetname "")
		)
		(fill yes
			(thermal_gap 0.5)
			(thermal_bridge_width 0.5)
			(island_removal_mode 0)
		)
		(polygon
			(pts
				(arc
					(start 311.759346 -23.930102)
					(mid 311.286508 -23.324032)
					(end 310.58358 -23.635208)
				)
				(xy 310.581548 -23.633938) (xy 309.831486 -25.033732) (xy 309.83174 -25.033986)
				(arc
					(start 309.833772 -25.035002)
					(mid 310.089448 -25.880903)
					(end 310.93537 -25.625044)
				)
				(xy 310.937402 -25.626314) (xy 311.094628 -25.33269)
				(arc
					(start 310.765444 -25.33269)
					(mid 310.384444 -25.711158)
					(end 310.003444 -25.33269)
				)
				(arc
					(start 310.003444 -25.33015)
					(mid 310.384444 -24.94915)
					(end 310.765444 -25.33015)
				)
				(xy 311.096152 -25.33015) (xy 311.687464 -24.226266)
				(arc
					(start 311.685432 -24.224996)
					(mid 311.740309 -24.083347)
					(end 311.759346 -23.932642)
				)
				(arc
					(start 311.515506 -23.932642)
					(mid 311.134506 -24.31111)
					(end 310.753506 -23.932642)
				)
				(arc
					(start 310.753506 -23.930102)
					(mid 311.134506 -23.549102)
					(end 311.515506 -23.930102)
				)
			)
		)
	)
	(zone
		(layers "B.Cu" "In2.Cu" "In5.Cu")
		(hatch none 0.5)
		(connect_pads
			(clearance 0)
		)
		(min_thickness 0.25)
		(keepout
			(tracks not_allowed)
			(vias allowed)
			(pads allowed)
			(copperpour not_allowed)
			(footprints allowed)
		)
		(placement
			(enabled no)
			(sheetname "")
		)
		(fill yes
			(thermal_gap 0.5)
			(thermal_bridge_width 0.5)
			(island_removal_mode 0)
		)
		(polygon
			(pts
				(arc
					(start 300.759114 -23.930102)
					(mid 300.286276 -23.324032)
					(end 299.583348 -23.635208)
				)
				(arc
					(start 298.837604 -25.027636)
					(mid 299.085738 -25.879089)
					(end 299.935392 -25.625044)
				)
				(xy 300.091856 -25.33269)
				(arc
					(start 299.765466 -25.33269)
					(mid 299.384466 -25.711158)
					(end 299.003466 -25.33269)
				)
				(arc
					(start 299.003466 -25.33015)
					(mid 299.384466 -24.94915)
					(end 299.765466 -25.33015)
				)
				(xy 300.09338 -25.33015)
				(arc
					(start 300.6852 -24.224996)
					(mid 300.740077 -24.083347)
					(end 300.759114 -23.932642)
				)
				(arc
					(start 300.515274 -23.932642)
					(mid 300.134274 -24.31111)
					(end 299.753274 -23.932642)
				)
				(arc
					(start 299.753274 -23.930102)
					(mid 300.134274 -23.549102)
					(end 300.515274 -23.930102)
				)
			)
		)
	)
	(zone
		(layers "B.Cu" "In2.Cu" "In5.Cu")
		(hatch none 0.5)
		(connect_pads
			(clearance 0)
		)
		(min_thickness 0.25)
		(keepout
			(tracks not_allowed)
			(vias allowed)
			(pads allowed)
			(copperpour not_allowed)
			(footprints allowed)
		)
		(placement
			(enabled no)
			(sheetname "")
		)
		(fill yes
			(thermal_gap 0.5)
			(thermal_bridge_width 0.5)
			(island_removal_mode 0)
		)
		(polygon
			(pts
				(arc
					(start 289.759136 -20.130008)
					(mid 289.286298 -19.523938)
					(end 288.58337 -19.835114)
				)
				(arc
					(start 287.837626 -21.227542)
					(mid 288.08576 -22.078995)
					(end 288.935414 -21.82495)
				)
				(xy 289.091878 -21.532596)
				(arc
					(start 288.765488 -21.532596)
					(mid 288.384488 -21.911064)
					(end 288.003488 -21.532596)
				)
				(arc
					(start 288.003488 -21.530056)
					(mid 288.384488 -21.149056)
					(end 288.765488 -21.530056)
				)
				(xy 289.093402 -21.530056)
				(arc
					(start 289.685222 -20.424902)
					(mid 289.740099 -20.283253)
					(end 289.759136 -20.132548)
				)
				(arc
					(start 289.515296 -20.132548)
					(mid 289.134296 -20.511016)
					(end 288.753296 -20.132548)
				)
				(arc
					(start 288.753296 -20.130008)
					(mid 289.134296 -19.749008)
					(end 289.515296 -20.130008)
				)
			)
		)
	)
	(zone
		(layers "B.Cu" "In2.Cu" "In5.Cu")
		(hatch none 0.5)
		(connect_pads
			(clearance 0)
		)
		(min_thickness 0.25)
		(keepout
			(tracks not_allowed)
			(vias allowed)
			(pads allowed)
			(copperpour not_allowed)
			(footprints allowed)
		)
		(placement
			(enabled no)
			(sheetname "")
		)
		(fill yes
			(thermal_gap 0.5)
			(thermal_bridge_width 0.5)
			(island_removal_mode 0)
		)
		(polygon
			(pts
				(arc
					(start 311.759346 -20.130008)
					(mid 311.286508 -19.523938)
					(end 310.58358 -19.835114)
				)
				(xy 310.581548 -19.833844) (xy 309.831486 -21.233892)
				(arc
					(start 309.833518 -21.235162)
					(mid 310.08955 -22.080982)
					(end 310.93537 -21.82495)
				)
				(xy 310.937402 -21.82622) (xy 311.094628 -21.532596)
				(arc
					(start 310.765444 -21.532596)
					(mid 310.384444 -21.911064)
					(end 310.003444 -21.532596)
				)
				(arc
					(start 310.003444 -21.530056)
					(mid 310.384444 -21.149056)
					(end 310.765444 -21.530056)
				)
				(xy 311.096152 -21.530056) (xy 311.687464 -20.426426) (xy 311.68721 -20.426172)
				(arc
					(start 311.685178 -20.425156)
					(mid 311.740224 -20.283401)
					(end 311.759346 -20.132548)
				)
				(arc
					(start 311.515506 -20.132548)
					(mid 311.134506 -20.511016)
					(end 310.753506 -20.132548)
				)
				(arc
					(start 310.753506 -20.130008)
					(mid 311.134506 -19.749008)
					(end 311.515506 -20.130008)
				)
			)
		)
	)
	(zone
		(layers "B.Cu" "In2.Cu" "In5.Cu")
		(hatch none 0.5)
		(connect_pads
			(clearance 0)
		)
		(min_thickness 0.25)
		(keepout
			(tracks not_allowed)
			(vias allowed)
			(pads allowed)
			(copperpour not_allowed)
			(footprints allowed)
		)
		(placement
			(enabled no)
			(sheetname "")
		)
		(fill yes
			(thermal_gap 0.5)
			(thermal_bridge_width 0.5)
			(island_removal_mode 0)
		)
		(polygon
			(pts
				(arc
					(start 298.509182 -23.930102)
					(mid 298.036344 -23.324032)
					(end 297.333416 -23.635208)
				)
				(xy 297.331384 -23.633938) (xy 296.581322 -25.033986)
				(arc
					(start 296.583354 -25.035256)
					(mid 296.839386 -25.881076)
					(end 297.685206 -25.625044)
				)
				(xy 297.687238 -25.626314) (xy 297.844464 -25.33269)
				(arc
					(start 297.51528 -25.33269)
					(mid 297.13428 -25.711158)
					(end 296.75328 -25.33269)
				)
				(arc
					(start 296.75328 -25.33015)
					(mid 297.13428 -24.94915)
					(end 297.51528 -25.33015)
				)
				(xy 297.845988 -25.33015) (xy 298.4373 -24.22652) (xy 298.437046 -24.226266)
				(arc
					(start 298.435014 -24.22525)
					(mid 298.49006 -24.083495)
					(end 298.509182 -23.932642)
				)
				(arc
					(start 298.265342 -23.932642)
					(mid 297.884342 -24.31111)
					(end 297.503342 -23.932642)
				)
				(arc
					(start 297.503342 -23.930102)
					(mid 297.884342 -23.549102)
					(end 298.265342 -23.930102)
				)
			)
		)
	)
	(zone
		(layers "B.Cu" "In5.Cu")
		(hatch none 0.5)
		(connect_pads
			(clearance 0)
		)
		(min_thickness 0.25)
		(keepout
			(tracks not_allowed)
			(vias allowed)
			(pads allowed)
			(copperpour not_allowed)
			(footprints allowed)
		)
		(placement
			(enabled no)
			(sheetname "")
		)
		(fill yes
			(thermal_gap 0.5)
			(thermal_bridge_width 0.5)
			(island_removal_mode 0)
		)
		(polygon
			(pts
				(arc
					(start 15.8496 -86.43366)
					(mid 15.23746 -87.0458)
					(end 15.8496 -87.65794)
				)
				(arc
					(start 16.9672 -87.65794)
					(mid 17.399149 -87.479545)
					(end 17.57934 -87.04834)
				)
				(arc
					(start 17.2339 -87.04834)
					(mid 16.9672 -87.312512)
					(end 16.7005 -87.04834)
				)
				(arc
					(start 16.1163 -87.04834)
					(mid 15.8496 -87.312512)
					(end 15.5829 -87.04834)
				)
				(arc
					(start 15.5829 -87.0458)
					(mid 15.8496 -86.7791)
					(end 16.1163 -87.0458)
				)
				(arc
					(start 16.7005 -87.0458)
					(mid 16.9672 -86.7791)
					(end 17.2339 -87.0458)
				)
				(arc
					(start 17.57934 -87.0458)
					(mid 17.400048 -86.612952)
					(end 16.9672 -86.43366)
				)
			)
		)
	)
	(zone
		(layers "B.Cu" "In5.Cu")
		(hatch none 0.5)
		(connect_pads
			(clearance 0)
		)
		(min_thickness 0.25)
		(keepout
			(tracks not_allowed)
			(vias allowed)
			(pads allowed)
			(copperpour not_allowed)
			(footprints allowed)
		)
		(placement
			(enabled no)
			(sheetname "")
		)
		(fill yes
			(thermal_gap 0.5)
			(thermal_bridge_width 0.5)
			(island_removal_mode 0)
		)
		(polygon
			(pts
				(arc
					(start 23.77694 -113.9952)
					(mid 23.1648 -113.38306)
					(end 22.55266 -113.9952)
				)
				(arc
					(start 22.55266 -115.1128)
					(mid 23.16353 -115.724939)
					(end 23.77694 -115.11534)
				)
				(arc
					(start 23.4315 -115.11534)
					(mid 23.1648 -115.379512)
					(end 22.8981 -115.11534)
				)
				(arc
					(start 22.8981 -115.1128)
					(mid 23.1648 -114.8461)
					(end 23.4315 -115.1128)
				)
				(xy 23.77694 -115.1128) (xy 23.77694 -113.99774)
				(arc
					(start 23.4315 -113.99774)
					(mid 23.1648 -114.261912)
					(end 22.8981 -113.99774)
				)
				(arc
					(start 22.8981 -113.9952)
					(mid 23.1648 -113.7285)
					(end 23.4315 -113.9952)
				)
			)
		)
	)
	(zone
		(layers "B.Cu" "In5.Cu")
		(hatch none 0.5)
		(connect_pads
			(clearance 0)
		)
		(min_thickness 0.25)
		(keepout
			(tracks not_allowed)
			(vias allowed)
			(pads allowed)
			(copperpour not_allowed)
			(footprints allowed)
		)
		(placement
			(enabled no)
			(sheetname "")
		)
		(fill yes
			(thermal_gap 0.5)
			(thermal_bridge_width 0.5)
			(island_removal_mode 0)
		)
		(polygon
			(pts
				(arc
					(start 26.74112 -142.58036)
					(mid 26.12898 -141.96822)
					(end 25.51684 -142.58036)
				)
				(arc
					(start 25.51684 -143.69796)
					(mid 26.12771 -144.310099)
					(end 26.74112 -143.7005)
				)
				(arc
					(start 26.39568 -143.7005)
					(mid 26.12898 -143.964672)
					(end 25.86228 -143.7005)
				)
				(arc
					(start 25.86228 -143.69796)
					(mid 26.12898 -143.43126)
					(end 26.39568 -143.69796)
				)
				(xy 26.74112 -143.69796) (xy 26.74112 -142.5829)
				(arc
					(start 26.39568 -142.5829)
					(mid 26.12898 -142.847072)
					(end 25.86228 -142.5829)
				)
				(arc
					(start 25.86228 -142.58036)
					(mid 26.12898 -142.31366)
					(end 26.39568 -142.58036)
				)
			)
		)
	)
	(zone
		(layers "B.Cu" "In5.Cu")
		(hatch none 0.5)
		(connect_pads
			(clearance 0)
		)
		(min_thickness 0.25)
		(keepout
			(tracks not_allowed)
			(vias allowed)
			(pads allowed)
			(copperpour not_allowed)
			(footprints allowed)
		)
		(placement
			(enabled no)
			(sheetname "")
		)
		(fill yes
			(thermal_gap 0.5)
			(thermal_bridge_width 0.5)
			(island_removal_mode 0)
		)
		(polygon
			(pts
				(arc
					(start 22.417786 -56.076596)
					(mid 21.805646 -56.688736)
					(end 22.417786 -57.300876)
				)
				(arc
					(start 23.535386 -57.300876)
					(mid 23.967335 -57.122481)
					(end 24.147526 -56.691276)
				)
				(arc
					(start 23.802086 -56.691276)
					(mid 23.535386 -56.955448)
					(end 23.268686 -56.691276)
				)
				(arc
					(start 22.684486 -56.691276)
					(mid 22.417786 -56.955448)
					(end 22.151086 -56.691276)
				)
				(arc
					(start 22.151086 -56.688736)
					(mid 22.417786 -56.422036)
					(end 22.684486 -56.688736)
				)
				(arc
					(start 23.268686 -56.688736)
					(mid 23.535386 -56.422036)
					(end 23.802086 -56.688736)
				)
				(arc
					(start 24.147526 -56.688736)
					(mid 23.968234 -56.255888)
					(end 23.535386 -56.076596)
				)
			)
		)
	)
	(zone
		(layers "B.Cu" "In5.Cu")
		(hatch none 0.5)
		(connect_pads
			(clearance 0)
		)
		(min_thickness 0.25)
		(keepout
			(tracks not_allowed)
			(vias allowed)
			(pads allowed)
			(copperpour not_allowed)
			(footprints allowed)
		)
		(placement
			(enabled no)
			(sheetname "")
		)
		(fill yes
			(thermal_gap 0.5)
			(thermal_bridge_width 0.5)
			(island_removal_mode 0)
		)
		(polygon
			(pts
				(arc
					(start 18.6944 -57.627266)
					(mid 18.08226 -58.239406)
					(end 18.6944 -58.851546)
				)
				(arc
					(start 19.812 -58.851546)
					(mid 20.243949 -58.673151)
					(end 20.42414 -58.241946)
				)
				(arc
					(start 20.0787 -58.241946)
					(mid 19.812 -58.506118)
					(end 19.5453 -58.241946)
				)
				(arc
					(start 18.9611 -58.241946)
					(mid 18.6944 -58.506118)
					(end 18.4277 -58.241946)
				)
				(arc
					(start 18.4277 -58.239406)
					(mid 18.6944 -57.972706)
					(end 18.9611 -58.239406)
				)
				(arc
					(start 19.5453 -58.239406)
					(mid 19.812 -57.972706)
					(end 20.0787 -58.239406)
				)
				(arc
					(start 20.42414 -58.239406)
					(mid 20.244848 -57.806558)
					(end 19.812 -57.627266)
				)
			)
		)
	)
	(zone
		(layers "B.Cu" "In5.Cu")
		(hatch none 0.5)
		(connect_pads
			(clearance 0)
		)
		(min_thickness 0.25)
		(keepout
			(tracks not_allowed)
			(vias allowed)
			(pads allowed)
			(copperpour not_allowed)
			(footprints allowed)
		)
		(placement
			(enabled no)
			(sheetname "")
		)
		(fill yes
			(thermal_gap 0.5)
			(thermal_bridge_width 0.5)
			(island_removal_mode 0)
		)
		(polygon
			(pts
				(arc
					(start 198.429118 -45.59046)
					(mid 197.816978 -44.97832)
					(end 197.204838 -45.59046)
				)
				(arc
					(start 197.204838 -46.70806)
					(mid 197.815708 -47.320199)
					(end 198.429118 -46.7106)
				)
				(arc
					(start 198.083678 -46.7106)
					(mid 197.816978 -46.974772)
					(end 197.550278 -46.7106)
				)
				(arc
					(start 197.550278 -46.70806)
					(mid 197.816978 -46.44136)
					(end 198.083678 -46.70806)
				)
				(xy 198.429118 -46.70806) (xy 198.429118 -45.593)
				(arc
					(start 198.083678 -45.593)
					(mid 197.816978 -45.857172)
					(end 197.550278 -45.593)
				)
				(arc
					(start 197.550278 -45.59046)
					(mid 197.816978 -45.32376)
					(end 198.083678 -45.59046)
				)
			)
		)
	)
	(zone
		(layers "B.Cu" "In5.Cu")
		(hatch none 0.5)
		(connect_pads
			(clearance 0)
		)
		(min_thickness 0.25)
		(keepout
			(tracks not_allowed)
			(vias allowed)
			(pads allowed)
			(copperpour not_allowed)
			(footprints allowed)
		)
		(placement
			(enabled no)
			(sheetname "")
		)
		(fill yes
			(thermal_gap 0.5)
			(thermal_bridge_width 0.5)
			(island_removal_mode 0)
		)
		(polygon
			(pts
				(arc
					(start 25.085294 -111.4044)
					(mid 24.473154 -110.79226)
					(end 23.861014 -111.4044)
				)
				(arc
					(start 23.861014 -112.521746)
					(mid 24.471757 -113.134138)
					(end 25.085294 -112.52454)
				)
				(arc
					(start 24.739854 -112.52454)
					(mid 24.473154 -112.788712)
					(end 24.206454 -112.52454)
				)
				(arc
					(start 24.206454 -112.522)
					(mid 24.473154 -112.2553)
					(end 24.739854 -112.522)
				)
				(xy 25.085294 -112.522) (xy 25.085294 -111.40694)
				(arc
					(start 24.739854 -111.40694)
					(mid 24.473154 -111.671112)
					(end 24.206454 -111.40694)
				)
				(arc
					(start 24.206454 -111.4044)
					(mid 24.473154 -111.1377)
					(end 24.739854 -111.4044)
				)
			)
		)
	)
	(zone
		(layers "B.Cu" "In5.Cu")
		(hatch none 0.5)
		(connect_pads
			(clearance 0)
		)
		(min_thickness 0.25)
		(keepout
			(tracks not_allowed)
			(vias allowed)
			(pads allowed)
			(copperpour not_allowed)
			(footprints allowed)
		)
		(placement
			(enabled no)
			(sheetname "")
		)
		(fill yes
			(thermal_gap 0.5)
			(thermal_bridge_width 0.5)
			(island_removal_mode 0)
		)
		(polygon
			(pts
				(arc
					(start 56.86298 -85.21065)
					(mid 56.25084 -84.59851)
					(end 55.6387 -85.21065)
				)
				(arc
					(start 55.6387 -86.32825)
					(mid 56.24957 -86.940389)
					(end 56.86298 -86.33079)
				)
				(arc
					(start 56.51754 -86.33079)
					(mid 56.25084 -86.594962)
					(end 55.98414 -86.33079)
				)
				(arc
					(start 55.98414 -86.32825)
					(mid 56.25084 -86.06155)
					(end 56.51754 -86.32825)
				)
				(xy 56.86298 -86.32825) (xy 56.86298 -85.21319)
				(arc
					(start 56.51754 -85.21319)
					(mid 56.25084 -85.477362)
					(end 55.98414 -85.21319)
				)
				(arc
					(start 55.98414 -85.21065)
					(mid 56.25084 -84.94395)
					(end 56.51754 -85.21065)
				)
			)
		)
	)
	(zone
		(layers "B.Cu" "In5.Cu")
		(hatch none 0.5)
		(connect_pads
			(clearance 0)
		)
		(min_thickness 0.25)
		(keepout
			(tracks not_allowed)
			(vias allowed)
			(pads allowed)
			(copperpour not_allowed)
			(footprints allowed)
		)
		(placement
			(enabled no)
			(sheetname "")
		)
		(fill yes
			(thermal_gap 0.5)
			(thermal_bridge_width 0.5)
			(island_removal_mode 0)
		)
		(polygon
			(pts
				(arc
					(start 132.358384 -41.6052)
					(mid 131.746244 -40.99306)
					(end 131.134104 -41.6052)
				)
				(arc
					(start 131.134104 -42.7228)
					(mid 131.744974 -43.334939)
					(end 132.358384 -42.72534)
				)
				(arc
					(start 132.012944 -42.72534)
					(mid 131.746244 -42.989512)
					(end 131.479544 -42.72534)
				)
				(arc
					(start 131.479544 -42.7228)
					(mid 131.746244 -42.4561)
					(end 132.012944 -42.7228)
				)
				(xy 132.358384 -42.7228) (xy 132.358384 -41.60774)
				(arc
					(start 132.012944 -41.60774)
					(mid 131.746244 -41.871912)
					(end 131.479544 -41.60774)
				)
				(arc
					(start 131.479544 -41.6052)
					(mid 131.746244 -41.3385)
					(end 132.012944 -41.6052)
				)
			)
		)
	)
	(zone
		(layers "B.Cu" "In5.Cu")
		(hatch none 0.5)
		(connect_pads
			(clearance 0)
		)
		(min_thickness 0.25)
		(keepout
			(tracks not_allowed)
			(vias allowed)
			(pads allowed)
			(copperpour not_allowed)
			(footprints allowed)
		)
		(placement
			(enabled no)
			(sheetname "")
		)
		(fill yes
			(thermal_gap 0.5)
			(thermal_bridge_width 0.5)
			(island_removal_mode 0)
		)
		(polygon
			(pts
				(arc
					(start 103.2383 -81.0006)
					(mid 102.62616 -80.38846)
					(end 102.01402 -81.0006)
				)
				(arc
					(start 102.01402 -82.1182)
					(mid 102.62489 -82.730339)
					(end 103.2383 -82.12074)
				)
				(arc
					(start 102.89286 -82.12074)
					(mid 102.62616 -82.384912)
					(end 102.35946 -82.12074)
				)
				(arc
					(start 102.35946 -82.1182)
					(mid 102.62616 -81.8515)
					(end 102.89286 -82.1182)
				)
				(xy 103.2383 -82.1182) (xy 103.2383 -81.00314)
				(arc
					(start 102.89286 -81.00314)
					(mid 102.62616 -81.267312)
					(end 102.35946 -81.00314)
				)
				(arc
					(start 102.35946 -81.0006)
					(mid 102.62616 -80.7339)
					(end 102.89286 -81.0006)
				)
			)
		)
	)
	(zone
		(layers "B.Cu" "In5.Cu")
		(hatch none 0.5)
		(connect_pads
			(clearance 0)
		)
		(min_thickness 0.25)
		(keepout
			(tracks not_allowed)
			(vias allowed)
			(pads allowed)
			(copperpour not_allowed)
			(footprints allowed)
		)
		(placement
			(enabled no)
			(sheetname "")
		)
		(fill yes
			(thermal_gap 0.5)
			(thermal_bridge_width 0.5)
			(island_removal_mode 0)
		)
		(polygon
			(pts
				(arc
					(start 201.78014 -49.727612)
					(mid 201.599589 -49.293508)
					(end 201.164444 -49.115472)
				)
				(arc
					(start 200.046844 -49.122076)
					(mid 199.43826 -49.737772)
					(end 200.053956 -50.346356)
				)
				(arc
					(start 201.171302 -50.339752)
					(mid 201.601124 -50.160197)
					(end 201.78014 -49.730152)
				)
				(arc
					(start 201.4347 -49.730152)
					(mid 201.171305 -49.994304)
					(end 200.901554 -49.736756)
				)
				(arc
					(start 200.3171 -49.736756)
					(mid 200.0504 -50.000928)
					(end 199.7837 -49.736756)
				)
				(arc
					(start 199.7837 -49.734216)
					(mid 200.0504 -49.467516)
					(end 200.3171 -49.734216)
				)
				(xy 200.9013 -49.734216) (xy 200.9013 -49.730152)
				(arc
					(start 200.9013 -49.727612)
					(mid 201.168 -49.460912)
					(end 201.4347 -49.727612)
				)
			)
		)
	)
	(zone
		(layers "B.Cu" "In5.Cu")
		(hatch none 0.5)
		(connect_pads
			(clearance 0)
		)
		(min_thickness 0.25)
		(keepout
			(tracks not_allowed)
			(vias allowed)
			(pads allowed)
			(copperpour not_allowed)
			(footprints allowed)
		)
		(placement
			(enabled no)
			(sheetname "")
		)
		(fill yes
			(thermal_gap 0.5)
			(thermal_bridge_width 0.5)
			(island_removal_mode 0)
		)
		(polygon
			(pts
				(arc
					(start 201.97318 -44.714922)
					(mid 201.36104 -44.102782)
					(end 200.7489 -44.714922)
				)
				(arc
					(start 200.7489 -45.832268)
					(mid 201.359643 -46.44466)
					(end 201.97318 -45.835062)
				)
				(arc
					(start 201.62774 -45.835062)
					(mid 201.36104 -46.099234)
					(end 201.09434 -45.835062)
				)
				(arc
					(start 201.09434 -45.832522)
					(mid 201.36104 -45.565822)
					(end 201.62774 -45.832522)
				)
				(xy 201.97318 -45.832522) (xy 201.97318 -44.717462)
				(arc
					(start 201.62774 -44.717462)
					(mid 201.36104 -44.981634)
					(end 201.09434 -44.717462)
				)
				(arc
					(start 201.09434 -44.714922)
					(mid 201.36104 -44.448222)
					(end 201.62774 -44.714922)
				)
			)
		)
	)
	(zone
		(layers "B.Cu" "In5.Cu")
		(hatch none 0.5)
		(connect_pads
			(clearance 0)
		)
		(min_thickness 0.25)
		(keepout
			(tracks not_allowed)
			(vias allowed)
			(pads allowed)
			(copperpour not_allowed)
			(footprints allowed)
		)
		(placement
			(enabled no)
			(sheetname "")
		)
		(fill yes
			(thermal_gap 0.5)
			(thermal_bridge_width 0.5)
			(island_removal_mode 0)
		)
		(polygon
			(pts
				(arc
					(start 28.47594 -105.502202)
					(mid 27.610308 -105.502202)
					(end 27.610308 -106.367834)
				)
				(xy 27.60853 -106.369612) (xy 28.398978 -107.16006)
				(arc
					(start 28.400756 -107.158282)
					(mid 29.066637 -107.291452)
					(end 29.445712 -106.728006)
				)
				(arc
					(start 29.100272 -106.728006)
					(mid 28.833572 -106.992178)
					(end 28.566872 -106.728006)
				)
				(arc
					(start 28.566872 -106.725466)
					(mid 28.833572 -106.458766)
					(end 29.100272 -106.725466)
				)
				(arc
					(start 29.445712 -106.725466)
					(mid 29.399101 -106.491224)
					(end 29.266388 -106.29265)
				)
				(xy 29.268166 -106.290872) (xy 28.914852 -105.937558)
				(arc
					(start 28.309824 -105.937558)
					(mid 28.043124 -106.20173)
					(end 27.776424 -105.937558)
				)
				(arc
					(start 27.776424 -105.935018)
					(mid 28.043124 -105.668318)
					(end 28.309824 -105.935018)
				)
				(xy 28.912312 -105.935018) (xy 28.477972 -105.500678) (xy 28.477464 -105.500678)
			)
		)
	)
	(zone
		(layer "In1.Cu")
		(hatch none 0.5)
		(connect_pads
			(clearance 0)
		)
		(min_thickness 0.25)
		(keepout
			(tracks not_allowed)
			(vias allowed)
			(pads allowed)
			(copperpour not_allowed)
			(footprints allowed)
		)
		(placement
			(enabled no)
			(sheetname "")
		)
		(fill
			(thermal_gap 0.5)
			(thermal_bridge_width 0.5)
			(island_removal_mode 0)
		)
		(polygon
			(pts
				(arc
					(start 212.588856 -211.633054)
					(mid 212.499053 -211.670251)
					(end 212.461856 -211.760054)
				)
				(arc
					(start 212.461856 -213.080854)
					(mid 212.499053 -213.170657)
					(end 212.588856 -213.207854)
				)
				(arc
					(start 214.011256 -213.207854)
					(mid 214.101059 -213.170657)
					(end 214.138256 -213.080854)
				)
				(arc
					(start 214.138256 -211.760054)
					(mid 214.101059 -211.670251)
					(end 214.011256 -211.633054)
				)
			)
		)
	)
	(zone
		(net "GND")
		(layer "In1.Cu")
		(hatch none 0.5)
		(connect_pads
			(clearance 0.5)
		)
		(min_thickness 0.25)
		(fill yes
			(thermal_gap 0.5)
			(thermal_bridge_width 0.5)
			(island_removal_mode 0)
		)
		(polygon
			(pts
				(xy 6.301994 -82.6389) (xy 6.0071 -82.933794) (xy 6.0071 -91.208606) (xy 6.276594 -91.4781) (xy 7.210806 -91.4781)
				(xy 7.744206 -90.9447) (xy 11.147806 -90.9447) (xy 11.9507 -90.141806) (xy 11.9507 -83.111594) (xy 11.478006 -82.6389)
			)
		)
	)
	(zone
		(layer "In1.Cu")
		(hatch none 0.5)
		(connect_pads
			(clearance 0)
		)
		(min_thickness 0.25)
		(keepout
			(tracks not_allowed)
			(vias allowed)
			(pads allowed)
			(copperpour not_allowed)
			(footprints allowed)
		)
		(placement
			(enabled no)
			(sheetname "")
		)
		(fill
			(thermal_gap 0.5)
			(thermal_bridge_width 0.5)
			(island_removal_mode 0)
		)
		(polygon
			(pts
				(arc
					(start 325.788782 -211.633054)
					(mid 325.698979 -211.670251)
					(end 325.661782 -211.760054)
				)
				(arc
					(start 325.661782 -213.080854)
					(mid 325.698979 -213.170657)
					(end 325.788782 -213.207854)
				)
				(arc
					(start 327.211182 -213.207854)
					(mid 327.300985 -213.170657)
					(end 327.338182 -213.080854)
				)
				(arc
					(start 327.338182 -211.760054)
					(mid 327.300985 -211.670251)
					(end 327.211182 -211.633054)
				)
			)
		)
	)
	(zone
		(layer "In1.Cu")
		(hatch none 0.5)
		(connect_pads
			(clearance 0)
		)
		(min_thickness 0.25)
		(keepout
			(tracks not_allowed)
			(vias allowed)
			(pads allowed)
			(copperpour not_allowed)
			(footprints allowed)
		)
		(placement
			(enabled no)
			(sheetname "")
		)
		(fill
			(thermal_gap 0.5)
			(thermal_bridge_width 0.5)
			(island_removal_mode 0)
		)
		(polygon
			(pts
				(arc
					(start 97.788984 -211.633054)
					(mid 97.699181 -211.670251)
					(end 97.661984 -211.760054)
				)
				(arc
					(start 97.661984 -213.080854)
					(mid 97.699181 -213.170657)
					(end 97.788984 -213.207854)
				)
				(arc
					(start 99.211384 -213.207854)
					(mid 99.301187 -213.170657)
					(end 99.338384 -213.080854)
				)
				(arc
					(start 99.338384 -211.760054)
					(mid 99.301187 -211.670251)
					(end 99.211384 -211.633054)
				)
			)
		)
	)
	(zone
		(layer "In1.Cu")
		(hatch none 0.5)
		(connect_pads
			(clearance 0)
		)
		(min_thickness 0.25)
		(keepout
			(tracks not_allowed)
			(vias allowed)
			(pads allowed)
			(copperpour not_allowed)
			(footprints allowed)
		)
		(placement
			(enabled no)
			(sheetname "")
		)
		(fill
			(thermal_gap 0.5)
			(thermal_bridge_width 0.5)
			(island_removal_mode 0)
		)
		(polygon
			(pts
				(arc
					(start 63.388748 -211.633054)
					(mid 63.298945 -211.670251)
					(end 63.261748 -211.760054)
				)
				(arc
					(start 63.261748 -213.080854)
					(mid 63.298945 -213.170657)
					(end 63.388748 -213.207854)
				)
				(arc
					(start 64.811148 -213.207854)
					(mid 64.900951 -213.170657)
					(end 64.938148 -213.080854)
				)
				(arc
					(start 64.938148 -211.760054)
					(mid 64.900951 -211.670251)
					(end 64.811148 -211.633054)
				)
			)
		)
	)
	(zone
		(layer "In1.Cu")
		(hatch none 0.5)
		(connect_pads
			(clearance 0)
		)
		(min_thickness 0.25)
		(keepout
			(tracks not_allowed)
			(vias allowed)
			(pads allowed)
			(copperpour not_allowed)
			(footprints allowed)
		)
		(placement
			(enabled no)
			(sheetname "")
		)
		(fill
			(thermal_gap 0.5)
			(thermal_bridge_width 0.5)
			(island_removal_mode 0)
		)
		(polygon
			(pts
				(xy 160.879536 -87.568278) (xy 161.684462 -87.568278) (xy 161.684462 -88.609678) (xy 160.879536 -88.609678)
			)
		)
	)
	(zone
		(layer "In1.Cu")
		(hatch none 0.5)
		(connect_pads
			(clearance 0)
		)
		(min_thickness 0.25)
		(keepout
			(tracks not_allowed)
			(vias allowed)
			(pads allowed)
			(copperpour not_allowed)
			(footprints allowed)
		)
		(placement
			(enabled no)
			(sheetname "")
		)
		(fill
			(thermal_gap 0.5)
			(thermal_bridge_width 0.5)
			(island_removal_mode 0)
		)
		(polygon
			(pts
				(arc
					(start 292.988746 -211.633054)
					(mid 292.898943 -211.670251)
					(end 292.861746 -211.760054)
				)
				(arc
					(start 292.861746 -213.080854)
					(mid 292.898943 -213.170657)
					(end 292.988746 -213.207854)
				)
				(arc
					(start 294.411146 -213.207854)
					(mid 294.500949 -213.170657)
					(end 294.538146 -213.080854)
				)
				(arc
					(start 294.538146 -211.760054)
					(mid 294.500949 -211.670251)
					(end 294.411146 -211.633054)
				)
			)
		)
	)
	(zone
		(layer "In1.Cu")
		(hatch none 0.5)
		(connect_pads
			(clearance 0)
		)
		(min_thickness 0.25)
		(keepout
			(tracks not_allowed)
			(vias allowed)
			(pads allowed)
			(copperpour not_allowed)
			(footprints allowed)
		)
		(placement
			(enabled no)
			(sheetname "")
		)
		(fill
			(thermal_gap 0.5)
			(thermal_bridge_width 0.5)
			(island_removal_mode 0)
		)
		(polygon
			(pts
				(arc
					(start 338.588858 -211.633054)
					(mid 338.499055 -211.670251)
					(end 338.461858 -211.760054)
				)
				(arc
					(start 338.461858 -213.080854)
					(mid 338.499055 -213.170657)
					(end 338.588858 -213.207854)
				)
				(arc
					(start 340.011258 -213.207854)
					(mid 340.101061 -213.170657)
					(end 340.138258 -213.080854)
				)
				(arc
					(start 340.138258 -211.760054)
					(mid 340.101061 -211.670251)
					(end 340.011258 -211.633054)
				)
			)
		)
	)
	(zone
		(layer "In1.Cu")
		(hatch none 0.5)
		(connect_pads
			(clearance 0)
		)
		(min_thickness 0.25)
		(keepout
			(tracks not_allowed)
			(vias allowed)
			(pads allowed)
			(copperpour not_allowed)
			(footprints allowed)
		)
		(placement
			(enabled no)
			(sheetname "")
		)
		(fill
			(thermal_gap 0.5)
			(thermal_bridge_width 0.5)
			(island_removal_mode 0)
		)
		(polygon
			(pts
				(arc
					(start 54.588918 -211.633054)
					(mid 54.499115 -211.670251)
					(end 54.461918 -211.760054)
				)
				(arc
					(start 54.461918 -213.080854)
					(mid 54.499115 -213.170657)
					(end 54.588918 -213.207854)
				)
				(arc
					(start 56.011318 -213.207854)
					(mid 56.101121 -213.170657)
					(end 56.138318 -213.080854)
				)
				(arc
					(start 56.138318 -211.760054)
					(mid 56.101121 -211.670251)
					(end 56.011318 -211.633054)
				)
			)
		)
	)
	(zone
		(layer "In1.Cu")
		(hatch none 0.5)
		(connect_pads
			(clearance 0)
		)
		(min_thickness 0.25)
		(keepout
			(tracks not_allowed)
			(vias allowed)
			(pads allowed)
			(copperpour not_allowed)
			(footprints allowed)
		)
		(placement
			(enabled no)
			(sheetname "")
		)
		(fill
			(thermal_gap 0.5)
			(thermal_bridge_width 0.5)
			(island_removal_mode 0)
		)
		(polygon
			(pts
				(arc
					(start 328.107802 -32.639)
					(mid 328.017999 -32.676197)
					(end 327.980802 -32.766)
				)
				(arc
					(start 327.980802 -34.0868)
					(mid 328.017999 -34.176603)
					(end 328.107802 -34.2138)
				)
				(arc
					(start 329.403202 -34.2138)
					(mid 329.493005 -34.176603)
					(end 329.530202 -34.0868)
				)
				(arc
					(start 329.530202 -32.766)
					(mid 329.493005 -32.676197)
					(end 329.403202 -32.639)
				)
			)
		)
	)
	(zone
		(layer "In1.Cu")
		(hatch none 0.5)
		(connect_pads
			(clearance 0)
		)
		(min_thickness 0.25)
		(keepout
			(tracks not_allowed)
			(vias allowed)
			(pads allowed)
			(copperpour not_allowed)
			(footprints allowed)
		)
		(placement
			(enabled no)
			(sheetname "")
		)
		(fill
			(thermal_gap 0.5)
			(thermal_bridge_width 0.5)
			(island_removal_mode 0)
		)
		(polygon
			(pts
				(arc
					(start 202.988926 -211.633054)
					(mid 202.899123 -211.670251)
					(end 202.861926 -211.760054)
				)
				(arc
					(start 202.861926 -213.080854)
					(mid 202.899123 -213.170657)
					(end 202.988926 -213.207854)
				)
				(arc
					(start 204.411326 -213.207854)
					(mid 204.501129 -213.170657)
					(end 204.538326 -213.080854)
				)
				(arc
					(start 204.538326 -211.760054)
					(mid 204.501129 -211.670251)
					(end 204.411326 -211.633054)
				)
			)
		)
	)
	(zone
		(layer "In1.Cu")
		(hatch none 0.5)
		(connect_pads
			(clearance 0)
		)
		(min_thickness 0.25)
		(keepout
			(tracks not_allowed)
			(vias allowed)
			(pads allowed)
			(copperpour not_allowed)
			(footprints allowed)
		)
		(placement
			(enabled no)
			(sheetname "")
		)
		(fill
			(thermal_gap 0.5)
			(thermal_bridge_width 0.5)
			(island_removal_mode 0)
		)
		(polygon
			(pts
				(arc
					(start 193.388996 -211.633054)
					(mid 193.299193 -211.670251)
					(end 193.261996 -211.760054)
				)
				(arc
					(start 193.261996 -213.080854)
					(mid 193.299193 -213.170657)
					(end 193.388996 -213.207854)
				)
				(arc
					(start 194.811396 -213.207854)
					(mid 194.901199 -213.170657)
					(end 194.938396 -213.080854)
				)
				(arc
					(start 194.938396 -211.760054)
					(mid 194.901199 -211.670251)
					(end 194.811396 -211.633054)
				)
			)
		)
	)
	(zone
		(layer "In1.Cu")
		(hatch none 0.5)
		(connect_pads
			(clearance 0)
		)
		(min_thickness 0.25)
		(keepout
			(tracks not_allowed)
			(vias allowed)
			(pads allowed)
			(copperpour not_allowed)
			(footprints allowed)
		)
		(placement
			(enabled no)
			(sheetname "")
		)
		(fill
			(thermal_gap 0.5)
			(thermal_bridge_width 0.5)
			(island_removal_mode 0)
		)
		(polygon
			(pts
				(arc
					(start 85.788754 -211.633054)
					(mid 85.698951 -211.670251)
					(end 85.661754 -211.760054)
				)
				(arc
					(start 85.661754 -213.080854)
					(mid 85.698951 -213.170657)
					(end 85.788754 -213.207854)
				)
				(arc
					(start 87.211154 -213.207854)
					(mid 87.300957 -213.170657)
					(end 87.338154 -213.080854)
				)
				(arc
					(start 87.338154 -211.760054)
					(mid 87.300957 -211.670251)
					(end 87.211154 -211.633054)
				)
			)
		)
	)
	(zone
		(layer "In1.Cu")
		(hatch none 0.5)
		(connect_pads
			(clearance 0)
		)
		(min_thickness 0.25)
		(keepout
			(tracks not_allowed)
			(vias allowed)
			(pads allowed)
			(copperpour not_allowed)
			(footprints allowed)
		)
		(placement
			(enabled no)
			(sheetname "")
		)
		(fill
			(thermal_gap 0.5)
			(thermal_bridge_width 0.5)
			(island_removal_mode 0)
		)
		(polygon
			(pts
				(arc
					(start 137.31494 -32.74314)
					(mid 137.225137 -32.780337)
					(end 137.18794 -32.87014)
				)
				(arc
					(start 137.18794 -34.19094)
					(mid 137.225137 -34.280743)
					(end 137.31494 -34.31794)
				)
				(arc
					(start 138.61034 -34.31794)
					(mid 138.700143 -34.280743)
					(end 138.73734 -34.19094)
				)
				(arc
					(start 138.73734 -32.87014)
					(mid 138.700143 -32.780337)
					(end 138.61034 -32.74314)
				)
			)
		)
	)
	(zone
		(layer "In1.Cu")
		(hatch none 0.5)
		(connect_pads
			(clearance 0)
		)
		(min_thickness 0.25)
		(keepout
			(tracks not_allowed)
			(vias allowed)
			(pads allowed)
			(copperpour not_allowed)
			(footprints allowed)
		)
		(placement
			(enabled no)
			(sheetname "")
		)
		(fill
			(thermal_gap 0.5)
			(thermal_bridge_width 0.5)
			(island_removal_mode 0)
		)
		(polygon
			(pts
				(arc
					(start 175.788828 -211.633054)
					(mid 175.699025 -211.670251)
					(end 175.661828 -211.760054)
				)
				(arc
					(start 175.661828 -213.080854)
					(mid 175.699025 -213.170657)
					(end 175.788828 -213.207854)
				)
				(arc
					(start 177.211228 -213.207854)
					(mid 177.301031 -213.170657)
					(end 177.338228 -213.080854)
				)
				(arc
					(start 177.338228 -211.760054)
					(mid 177.301031 -211.670251)
					(end 177.211228 -211.633054)
				)
			)
		)
	)
	(zone
		(layer "In1.Cu")
		(hatch none 0.5)
		(connect_pads
			(clearance 0)
		)
		(min_thickness 0.25)
		(keepout
			(tracks not_allowed)
			(vias allowed)
			(pads allowed)
			(copperpour not_allowed)
			(footprints allowed)
		)
		(placement
			(enabled no)
			(sheetname "")
		)
		(fill
			(thermal_gap 0.5)
			(thermal_bridge_width 0.5)
			(island_removal_mode 0)
		)
		(polygon
			(pts
				(arc
					(start 273.2786 -14.1478)
					(mid 273.188797 -14.184997)
					(end 273.1516 -14.2748)
				)
				(arc
					(start 273.1516 -15.5702)
					(mid 273.188797 -15.660003)
					(end 273.2786 -15.6972)
				)
				(arc
					(start 274.5994 -15.6972)
					(mid 274.689203 -15.660003)
					(end 274.7264 -15.5702)
				)
				(arc
					(start 274.7264 -14.2748)
					(mid 274.689203 -14.184997)
					(end 274.5994 -14.1478)
				)
			)
		)
	)
	(zone
		(layer "In1.Cu")
		(hatch none 0.5)
		(connect_pads
			(clearance 0)
		)
		(min_thickness 0.25)
		(keepout
			(tracks not_allowed)
			(vias allowed)
			(pads allowed)
			(copperpour not_allowed)
			(footprints allowed)
		)
		(placement
			(enabled no)
			(sheetname "")
		)
		(fill
			(thermal_gap 0.5)
			(thermal_bridge_width 0.5)
			(island_removal_mode 0)
		)
		(polygon
			(pts
				(arc
					(start 144.588992 -211.633054)
					(mid 144.499189 -211.670251)
					(end 144.461992 -211.760054)
				)
				(arc
					(start 144.461992 -213.080854)
					(mid 144.499189 -213.170657)
					(end 144.588992 -213.207854)
				)
				(arc
					(start 146.011392 -213.207854)
					(mid 146.101195 -213.170657)
					(end 146.138392 -213.080854)
				)
				(arc
					(start 146.138392 -211.760054)
					(mid 146.101195 -211.670251)
					(end 146.011392 -211.633054)
				)
			)
		)
	)
	(zone
		(net "GND")
		(layer "In1.Cu")
		(hatch none 0.5)
		(connect_pads
			(clearance 0.5)
		)
		(min_thickness 0.25)
		(fill yes
			(thermal_gap 0.5)
			(thermal_bridge_width 0.5)
			(island_removal_mode 0)
		)
		(polygon
			(pts
				(xy 132.565394 -80.6831) (xy 132.4229 -80.825594) (xy 132.4229 -84.757006) (xy 132.666994 -85.0011)
				(xy 136.192006 -85.0011) (xy 136.2583 -84.934806) (xy 136.2583 -80.977994) (xy 135.963406 -80.6831)
			)
		)
	)
	(zone
		(layer "In1.Cu")
		(hatch none 0.5)
		(connect_pads
			(clearance 0)
		)
		(min_thickness 0.25)
		(keepout
			(tracks not_allowed)
			(vias allowed)
			(pads allowed)
			(copperpour not_allowed)
			(footprints allowed)
		)
		(placement
			(enabled no)
			(sheetname "")
		)
		(fill
			(thermal_gap 0.5)
			(thermal_bridge_width 0.5)
			(island_removal_mode 0)
		)
		(polygon
			(pts
				(arc
					(start 157.389068 -211.633054)
					(mid 157.299265 -211.670251)
					(end 157.262068 -211.760054)
				)
				(arc
					(start 157.262068 -213.080854)
					(mid 157.299265 -213.170657)
					(end 157.389068 -213.207854)
				)
				(arc
					(start 158.811468 -213.207854)
					(mid 158.901271 -213.170657)
					(end 158.938468 -213.080854)
				)
				(arc
					(start 158.938468 -211.760054)
					(mid 158.901271 -211.670251)
					(end 158.811468 -211.633054)
				)
			)
		)
	)
	(zone
		(layer "In1.Cu")
		(hatch none 0.5)
		(connect_pads
			(clearance 0)
		)
		(min_thickness 0.25)
		(keepout
			(tracks not_allowed)
			(vias allowed)
			(pads allowed)
			(copperpour not_allowed)
			(footprints allowed)
		)
		(placement
			(enabled no)
			(sheetname "")
		)
		(fill
			(thermal_gap 0.5)
			(thermal_bridge_width 0.5)
			(island_removal_mode 0)
		)
		(polygon
			(pts
				(arc
					(start 107.388914 -211.633054)
					(mid 107.299111 -211.670251)
					(end 107.261914 -211.760054)
				)
				(arc
					(start 107.261914 -213.080854)
					(mid 107.299111 -213.170657)
					(end 107.388914 -213.207854)
				)
				(arc
					(start 108.811314 -213.207854)
					(mid 108.901117 -213.170657)
					(end 108.938314 -213.080854)
				)
				(arc
					(start 108.938314 -211.760054)
					(mid 108.901117 -211.670251)
					(end 108.811314 -211.633054)
				)
			)
		)
	)
	(zone
		(layer "In1.Cu")
		(hatch none 0.5)
		(connect_pads
			(clearance 0)
		)
		(min_thickness 0.25)
		(keepout
			(tracks not_allowed)
			(vias allowed)
			(pads allowed)
			(copperpour not_allowed)
			(footprints allowed)
		)
		(placement
			(enabled no)
			(sheetname "")
		)
		(fill
			(thermal_gap 0.5)
			(thermal_bridge_width 0.5)
			(island_removal_mode 0)
		)
		(polygon
			(pts
				(arc
					(start 154.188922 -211.633054)
					(mid 154.099119 -211.670251)
					(end 154.061922 -211.760054)
				)
				(arc
					(start 154.061922 -213.080854)
					(mid 154.099119 -213.170657)
					(end 154.188922 -213.207854)
				)
				(arc
					(start 155.611322 -213.207854)
					(mid 155.701125 -213.170657)
					(end 155.738322 -213.080854)
				)
				(arc
					(start 155.738322 -211.760054)
					(mid 155.701125 -211.670251)
					(end 155.611322 -211.633054)
				)
			)
		)
	)
	(zone
		(layer "In1.Cu")
		(hatch none 0.5)
		(connect_pads
			(clearance 0)
		)
		(min_thickness 0.25)
		(keepout
			(tracks not_allowed)
			(vias allowed)
			(pads allowed)
			(copperpour not_allowed)
			(footprints allowed)
		)
		(placement
			(enabled no)
			(sheetname "")
		)
		(fill
			(thermal_gap 0.5)
			(thermal_bridge_width 0.5)
			(island_removal_mode 0)
		)
		(polygon
			(pts
				(arc
					(start 166.188898 -211.633054)
					(mid 166.099095 -211.670251)
					(end 166.061898 -211.760054)
				)
				(arc
					(start 166.061898 -213.080854)
					(mid 166.099095 -213.170657)
					(end 166.188898 -213.207854)
				)
				(arc
					(start 167.611298 -213.207854)
					(mid 167.701101 -213.170657)
					(end 167.738298 -213.080854)
				)
				(arc
					(start 167.738298 -211.760054)
					(mid 167.701101 -211.670251)
					(end 167.611298 -211.633054)
				)
			)
		)
	)
	(zone
		(layer "In1.Cu")
		(hatch none 0.5)
		(connect_pads
			(clearance 0)
		)
		(min_thickness 0.25)
		(keepout
			(tracks not_allowed)
			(vias allowed)
			(pads allowed)
			(copperpour not_allowed)
			(footprints allowed)
		)
		(placement
			(enabled no)
			(sheetname "")
		)
		(fill
			(thermal_gap 0.5)
			(thermal_bridge_width 0.5)
			(island_removal_mode 0)
		)
		(polygon
			(pts
				(arc
					(start 283.388816 -211.633054)
					(mid 283.299013 -211.670251)
					(end 283.261816 -211.760054)
				)
				(arc
					(start 283.261816 -213.080854)
					(mid 283.299013 -213.170657)
					(end 283.388816 -213.207854)
				)
				(arc
					(start 284.811216 -213.207854)
					(mid 284.901019 -213.170657)
					(end 284.938216 -213.080854)
				)
				(arc
					(start 284.938216 -211.760054)
					(mid 284.901019 -211.670251)
					(end 284.811216 -211.633054)
				)
			)
		)
	)
	(zone
		(layer "In1.Cu")
		(hatch none 0.5)
		(connect_pads
			(clearance 0)
		)
		(min_thickness 0.25)
		(keepout
			(tracks not_allowed)
			(vias allowed)
			(pads allowed)
			(copperpour not_allowed)
			(footprints allowed)
		)
		(placement
			(enabled no)
			(sheetname "")
		)
		(fill
			(thermal_gap 0.5)
			(thermal_bridge_width 0.5)
			(island_removal_mode 0)
		)
		(polygon
			(pts
				(arc
					(start 160.58896 -211.633054)
					(mid 160.499157 -211.670251)
					(end 160.46196 -211.760054)
				)
				(arc
					(start 160.46196 -213.080854)
					(mid 160.499157 -213.170657)
					(end 160.58896 -213.207854)
				)
				(arc
					(start 162.01136 -213.207854)
					(mid 162.101163 -213.170657)
					(end 162.13836 -213.080854)
				)
				(arc
					(start 162.13836 -211.760054)
					(mid 162.101163 -211.670251)
					(end 162.01136 -211.633054)
				)
			)
		)
	)
	(zone
		(layer "In1.Cu")
		(hatch none 0.5)
		(connect_pads
			(clearance 0)
		)
		(min_thickness 0.25)
		(keepout
			(tracks not_allowed)
			(vias allowed)
			(pads allowed)
			(copperpour not_allowed)
			(footprints allowed)
		)
		(placement
			(enabled no)
			(sheetname "")
		)
		(fill
			(thermal_gap 0.5)
			(thermal_bridge_width 0.5)
			(island_removal_mode 0)
		)
		(polygon
			(pts
				(arc
					(start 341.78875 -211.633054)
					(mid 341.698947 -211.670251)
					(end 341.66175 -211.760054)
				)
				(arc
					(start 341.66175 -213.080854)
					(mid 341.698947 -213.170657)
					(end 341.78875 -213.207854)
				)
				(arc
					(start 343.21115 -213.207854)
					(mid 343.300953 -213.170657)
					(end 343.33815 -213.080854)
				)
				(arc
					(start 343.33815 -211.760054)
					(mid 343.300953 -211.670251)
					(end 343.21115 -211.633054)
				)
			)
		)
	)
	(zone
		(layer "In1.Cu")
		(hatch none 0.5)
		(connect_pads
			(clearance 0)
		)
		(min_thickness 0.25)
		(keepout
			(tracks not_allowed)
			(vias allowed)
			(pads allowed)
			(copperpour not_allowed)
			(footprints allowed)
		)
		(placement
			(enabled no)
			(sheetname "")
		)
		(fill
			(thermal_gap 0.5)
			(thermal_bridge_width 0.5)
			(island_removal_mode 0)
		)
		(polygon
			(pts
				(arc
					(start 69.788786 -211.633054)
					(mid 69.698983 -211.670251)
					(end 69.661786 -211.760054)
				)
				(arc
					(start 69.661786 -213.080854)
					(mid 69.698983 -213.170657)
					(end 69.788786 -213.207854)
				)
				(arc
					(start 71.211186 -213.207854)
					(mid 71.300989 -213.170657)
					(end 71.338186 -213.080854)
				)
				(arc
					(start 71.338186 -211.760054)
					(mid 71.300989 -211.670251)
					(end 71.211186 -211.633054)
				)
			)
		)
	)
	(zone
		(layer "In1.Cu")
		(hatch none 0.5)
		(connect_pads
			(clearance 0)
		)
		(min_thickness 0.25)
		(keepout
			(tracks not_allowed)
			(vias allowed)
			(pads allowed)
			(copperpour not_allowed)
			(footprints allowed)
		)
		(placement
			(enabled no)
			(sheetname "")
		)
		(fill
			(thermal_gap 0.5)
			(thermal_bridge_width 0.5)
			(island_removal_mode 0)
		)
		(polygon
			(pts
				(arc
					(start 92.188792 -211.633054)
					(mid 92.098989 -211.670251)
					(end 92.061792 -211.760054)
				)
				(arc
					(start 92.061792 -213.080854)
					(mid 92.098989 -213.170657)
					(end 92.188792 -213.207854)
				)
				(arc
					(start 93.611192 -213.207854)
					(mid 93.700995 -213.170657)
					(end 93.738192 -213.080854)
				)
				(arc
					(start 93.738192 -211.760054)
					(mid 93.700995 -211.670251)
					(end 93.611192 -211.633054)
				)
			)
		)
	)
	(zone
		(layer "In1.Cu")
		(hatch none 0.5)
		(connect_pads
			(clearance 0)
		)
		(min_thickness 0.25)
		(keepout
			(tracks not_allowed)
			(vias allowed)
			(pads allowed)
			(copperpour not_allowed)
			(footprints allowed)
		)
		(placement
			(enabled no)
			(sheetname "")
		)
		(fill
			(thermal_gap 0.5)
			(thermal_bridge_width 0.5)
			(island_removal_mode 0)
		)
		(polygon
			(pts
				(arc
					(start 183.789066 -211.633054)
					(mid 183.699263 -211.670251)
					(end 183.662066 -211.760054)
				)
				(arc
					(start 183.662066 -213.080854)
					(mid 183.699263 -213.170657)
					(end 183.789066 -213.207854)
				)
				(arc
					(start 185.211466 -213.207854)
					(mid 185.301269 -213.170657)
					(end 185.338466 -213.080854)
				)
				(arc
					(start 185.338466 -211.760054)
					(mid 185.301269 -211.670251)
					(end 185.211466 -211.633054)
				)
			)
		)
	)
	(zone
		(layer "In1.Cu")
		(hatch none 0.5)
		(connect_pads
			(clearance 0)
		)
		(min_thickness 0.25)
		(keepout
			(tracks not_allowed)
			(vias allowed)
			(pads allowed)
			(copperpour not_allowed)
			(footprints allowed)
		)
		(placement
			(enabled no)
			(sheetname "")
		)
		(fill
			(thermal_gap 0.5)
			(thermal_bridge_width 0.5)
			(island_removal_mode 0)
		)
		(polygon
			(pts
				(arc
					(start 186.988958 -211.633054)
					(mid 186.899155 -211.670251)
					(end 186.861958 -211.760054)
				)
				(arc
					(start 186.861958 -213.080854)
					(mid 186.899155 -213.170657)
					(end 186.988958 -213.207854)
				)
				(arc
					(start 188.411358 -213.207854)
					(mid 188.501161 -213.170657)
					(end 188.538358 -213.080854)
				)
				(arc
					(start 188.538358 -211.760054)
					(mid 188.501161 -211.670251)
					(end 188.411358 -211.633054)
				)
			)
		)
	)
	(zone
		(layer "In1.Cu")
		(hatch none 0.5)
		(connect_pads
			(clearance 0)
		)
		(min_thickness 0.25)
		(keepout
			(tracks not_allowed)
			(vias allowed)
			(pads allowed)
			(copperpour not_allowed)
			(footprints allowed)
		)
		(placement
			(enabled no)
			(sheetname "")
		)
		(fill
			(thermal_gap 0.5)
			(thermal_bridge_width 0.5)
			(island_removal_mode 0)
		)
		(polygon
			(pts
				(arc
					(start 165.484048 -89.841578)
					(mid 165.427842 -89.807976)
					(end 165.405816 -89.746328)
				)
				(arc
					(start 165.405816 -88.348566)
					(mid 165.439078 -88.289304)
					(end 165.502844 -88.265762)
				)
				(arc
					(start 166.734744 -88.265762)
					(mid 166.800096 -88.295592)
					(end 166.826692 -88.362282)
				)
				(arc
					(start 166.826692 -89.746328)
					(mid 166.793473 -89.814217)
					(end 166.72306 -89.841578)
				)
			)
		)
	)
	(zone
		(layer "In1.Cu")
		(hatch none 0.5)
		(connect_pads
			(clearance 0)
		)
		(min_thickness 0.25)
		(keepout
			(tracks not_allowed)
			(vias allowed)
			(pads allowed)
			(copperpour not_allowed)
			(footprints allowed)
		)
		(placement
			(enabled no)
			(sheetname "")
		)
		(fill
			(thermal_gap 0.5)
			(thermal_bridge_width 0.5)
			(island_removal_mode 0)
		)
		(polygon
			(pts
				(arc
					(start 27.074368 -142.321026)
					(mid 26.984565 -142.358223)
					(end 26.947368 -142.448026)
				)
				(xy 26.947368 -142.803626) (xy 26.947368 -143.464026) (xy 28.420568 -143.464026) (xy 28.420568 -142.803626)
				(arc
					(start 28.420568 -142.448026)
					(mid 28.383371 -142.358223)
					(end 28.293568 -142.321026)
				)
			)
		)
	)
	(zone
		(net "GND")
		(layer "In1.Cu")
		(hatch none 0.5)
		(connect_pads
			(clearance 0.5)
		)
		(min_thickness 0.25)
		(fill yes
			(thermal_gap 0.5)
			(thermal_bridge_width 0.5)
			(island_removal_mode 0)
		)
		(polygon
			(pts
				(arc
					(start 123.637548 4.236974)
					(mid 122.762871 3.874671)
					(end 122.400568 2.999994)
				)
				(arc
					(start 122.400568 1.999996)
					(mid 121.591301 0.046251)
					(end 119.637556 -0.763016)
				)
				(arc
					(start 53.950108 -0.763016)
					(mid 53.075431 -1.125319)
					(end 52.713128 -1.999996)
				)
				(arc
					(start 52.713128 -24.010112)
					(mid 51.903861 -25.963857)
					(end 49.950116 -26.773124)
				)
				(arc
					(start 1.999996 -26.773124)
					(mid 1.125319 -27.135427)
					(end 0.763016 -28.010104)
				)
				(arc
					(start 0.763016 -212.499956)
					(mid 0.832426 -212.667528)
					(end 0.999998 -212.736938)
				)
				(arc
					(start 25.4 -212.736938)
					(mid 26.858753 -213.341173)
					(end 27.462988 -214.799926)
				)
				(xy 27.462988 -221.136972)
				(arc
					(start 28.000198 -221.136972)
					(mid 28.89312 -221.506938)
					(end 29.263086 -222.39986)
				)
				(xy 29.263086 -225.460052) (xy 73.337928 -225.460052)
				(arc
					(start 73.337928 -222.600012)
					(mid 73.343892 -222.44689)
					(end 73.361804 -222.294704)
				)
				(arc
					(start 73.361804 -222.294704)
					(mid 73.927667 -221.197654)
					(end 75.03668 -220.655642)
				)
				(arc
					(start 75.03668 -220.655642)
					(mid 75.299952 -220.636928)
					(end 75.563222 -220.655642)
				)
				(arc
					(start 75.563222 -220.655642)
					(mid 76.777453 -221.309057)
					(end 77.261974 -222.600012)
				)
				(xy 77.261974 -225.460052) (xy 111.736886 -225.460052)
				(arc
					(start 111.736886 -222.39986)
					(mid 112.106852 -221.506938)
					(end 112.999774 -221.136972)
				)
				(xy 113.536984 -221.136972)
				(arc
					(start 113.536984 -214.799926)
					(mid 114.141219 -213.341173)
					(end 115.599972 -212.736938)
				)
				(arc
					(start 131.400042 -212.736938)
					(mid 132.858795 -213.341173)
					(end 133.46303 -214.799926)
				)
				(xy 133.46303 -221.136972)
				(arc
					(start 134.00024 -221.136972)
					(mid 134.893162 -221.506938)
					(end 135.263128 -222.39986)
				)
				(xy 135.263128 -225.460052) (xy 179.33797 -225.460052)
				(arc
					(start 179.33797 -222.600012)
					(mid 179.343934 -222.44689)
					(end 179.361846 -222.294704)
				)
				(arc
					(start 179.361846 -222.294704)
					(mid 179.927709 -221.197654)
					(end 181.036722 -220.655642)
				)
				(arc
					(start 181.036722 -220.655642)
					(mid 181.299994 -220.636928)
					(end 181.563264 -220.655642)
				)
				(arc
					(start 181.563264 -220.655642)
					(mid 182.777495 -221.309057)
					(end 183.262016 -222.600012)
				)
				(xy 183.262016 -225.460052) (xy 217.736928 -225.460052)
				(arc
					(start 217.736928 -222.39986)
					(mid 218.106894 -221.506938)
					(end 218.999816 -221.136972)
				)
				(xy 219.537026 -221.136972)
				(arc
					(start 219.537026 -214.799926)
					(mid 220.141261 -213.341173)
					(end 221.600014 -212.736938)
				)
				(arc
					(start 229.142036 -212.736938)
					(mid 232.138029 -211.495957)
					(end 233.37901 -208.499964)
				)
				(arc
					(start 233.37901 -165.269926)
					(mid 233.974467 -163.832367)
					(end 235.412026 -163.23691)
				)
				(arc
					(start 249.871992 -163.23691)
					(mid 251.309551 -163.832367)
					(end 251.905008 -165.269926)
				)
				(arc
					(start 251.905008 -208.499964)
					(mid 253.145989 -211.495957)
					(end 256.141982 -212.736938)
				)
				(arc
					(start 257.400044 -212.736938)
					(mid 258.858797 -213.341173)
					(end 259.463032 -214.799926)
				)
				(xy 259.463032 -221.136972)
				(arc
					(start 260.000242 -221.136972)
					(mid 260.893164 -221.506938)
					(end 261.26313 -222.39986)
				)
				(xy 261.26313 -225.460052) (xy 305.337972 -225.460052)
				(arc
					(start 305.337972 -222.600012)
					(mid 305.343936 -222.44689)
					(end 305.361848 -222.294704)
				)
				(arc
					(start 305.361848 -222.294704)
					(mid 305.927711 -221.197654)
					(end 307.036724 -220.655642)
				)
				(arc
					(start 307.036724 -220.655642)
					(mid 307.299996 -220.636928)
					(end 307.563266 -220.655642)
				)
				(arc
					(start 307.563266 -220.655642)
					(mid 308.777497 -221.309057)
					(end 309.262018 -222.600012)
				)
				(xy 309.262018 -225.460052) (xy 343.73693 -225.460052)
				(arc
					(start 343.73693 -222.39986)
					(mid 344.106896 -221.506938)
					(end 344.999818 -221.136972)
				)
				(xy 345.537028 -221.136972)
				(arc
					(start 345.537028 -214.799926)
					(mid 346.141263 -213.341173)
					(end 347.600016 -212.736938)
				)
				(arc
					(start 354.600002 -212.736938)
					(mid 354.767574 -212.667528)
					(end 354.836984 -212.499956)
				)
				(xy 354.836984 -19.463004)
				(arc
					(start 354.749862 -19.463004)
					(mid 353.856865 -19.093113)
					(end 353.486974 -18.200116)
				)
				(arc
					(start 353.486974 -10.199878)
					(mid 353.856865 -9.306881)
					(end 354.749862 -8.93699)
				)
				(xy 354.836984 -8.93699)
				(arc
					(start 354.836984 -0.999998)
					(mid 354.767574 -0.832426)
					(end 354.600002 -0.763016)
				)
				(arc
					(start 332.749906 -0.763016)
					(mid 331.503267 -0.246641)
					(end 330.986892 0.999998)
				)
				(arc
					(start 330.986892 3.999992)
					(mid 330.917482 4.167564)
					(end 330.74991 4.236974)
				)
			)
		)
		(polygon
			(pts
				(arc
					(start 341.306404 -222.805244)
					(mid 341.816944 -222.294704)
					(end 341.306404 -221.784164)
				)
				(arc
					(start 340.49335 -221.784164)
					(mid 339.983064 -222.294831)
					(end 340.493604 -222.805244)
				)
			)
		)
		(polygon
			(pts
				(arc
					(start 338.106766 -222.805244)
					(mid 338.617052 -222.294577)
					(end 338.106512 -221.784164)
				)
				(arc
					(start 337.293712 -221.784164)
					(mid 336.783172 -222.294704)
					(end 337.293712 -222.805244)
				)
			)
		)
		(polygon
			(pts
				(arc
					(start 334.90662 -222.805244)
					(mid 335.416906 -222.294577)
					(end 334.906366 -221.784164)
				)
				(arc
					(start 334.093566 -221.784164)
					(mid 333.583026 -222.294704)
					(end 334.093566 -222.805244)
				)
			)
		)
		(polygon
			(pts
				(arc
					(start 331.706728 -222.805244)
					(mid 332.217014 -222.294577)
					(end 331.706474 -221.784164)
				)
				(arc
					(start 330.893674 -221.784164)
					(mid 330.383134 -222.294704)
					(end 330.893674 -222.805244)
				)
			)
		)
		(polygon
			(pts
				(arc
					(start 328.506836 -222.805244)
					(mid 329.017122 -222.294577)
					(end 328.506582 -221.784164)
				)
				(arc
					(start 327.693782 -221.784164)
					(mid 327.183242 -222.294704)
					(end 327.693782 -222.805244)
				)
			)
		)
		(polygon
			(pts
				(arc
					(start 325.30669 -222.805244)
					(mid 325.816976 -222.294577)
					(end 325.306436 -221.784164)
				)
				(arc
					(start 324.493636 -221.784164)
					(mid 323.983096 -222.294704)
					(end 324.493636 -222.805244)
				)
			)
		)
		(polygon
			(pts
				(arc
					(start 322.106798 -222.805244)
					(mid 322.617084 -222.294577)
					(end 322.106544 -221.784164)
				)
				(arc
					(start 321.293744 -221.784164)
					(mid 320.783204 -222.294704)
					(end 321.293744 -222.805244)
				)
			)
		)
		(polygon
			(pts
				(arc
					(start 318.906652 -222.805244)
					(mid 319.416938 -222.294577)
					(end 318.906398 -221.784164)
				)
				(arc
					(start 318.093598 -221.784164)
					(mid 317.583058 -222.294704)
					(end 318.093598 -222.805244)
				)
			)
		)
		(polygon
			(pts
				(arc
					(start 315.70676 -222.805244)
					(mid 316.217046 -222.294577)
					(end 315.706506 -221.784164)
				)
				(arc
					(start 314.893706 -221.784164)
					(mid 314.383166 -222.294704)
					(end 314.893706 -222.805244)
				)
			)
		)
		(polygon
			(pts
				(arc
					(start 312.506614 -222.805244)
					(mid 313.0169 -222.294577)
					(end 312.50636 -221.784164)
				)
				(arc
					(start 311.69356 -221.784164)
					(mid 311.18302 -222.294704)
					(end 311.69356 -222.805244)
				)
			)
		)
		(polygon
			(pts
				(arc
					(start 301.306738 -222.805244)
					(mid 301.817024 -222.294577)
					(end 301.306484 -221.784164)
				)
				(arc
					(start 300.493684 -221.784164)
					(mid 299.983144 -222.294704)
					(end 300.493684 -222.805244)
				)
			)
		)
		(polygon
			(pts
				(arc
					(start 295.7068 -222.805244)
					(mid 296.217086 -222.294577)
					(end 295.706546 -221.784164)
				)
				(arc
					(start 294.893746 -221.784164)
					(mid 294.383206 -222.294704)
					(end 294.893746 -222.805244)
				)
			)
		)
		(polygon
			(pts
				(arc
					(start 292.506654 -222.805244)
					(mid 293.01694 -222.294577)
					(end 292.5064 -221.784164)
				)
				(arc
					(start 291.6936 -221.784164)
					(mid 291.18306 -222.294704)
					(end 291.6936 -222.805244)
				)
			)
		)
		(polygon
			(pts
				(arc
					(start 289.306762 -222.805244)
					(mid 289.817048 -222.294577)
					(end 289.306508 -221.784164)
				)
				(arc
					(start 288.493708 -221.784164)
					(mid 287.983168 -222.294704)
					(end 288.493708 -222.805244)
				)
			)
		)
		(polygon
			(pts
				(arc
					(start 286.106616 -222.805244)
					(mid 286.616902 -222.294577)
					(end 286.106362 -221.784164)
				)
				(arc
					(start 285.293562 -221.784164)
					(mid 284.783022 -222.294704)
					(end 285.293562 -222.805244)
				)
			)
		)
		(polygon
			(pts
				(arc
					(start 282.906724 -222.805244)
					(mid 283.41701 -222.294577)
					(end 282.90647 -221.784164)
				)
				(arc
					(start 282.09367 -221.784164)
					(mid 281.58313 -222.294704)
					(end 282.09367 -222.805244)
				)
			)
		)
		(polygon
			(pts
				(arc
					(start 279.706832 -222.805244)
					(mid 280.217118 -222.294577)
					(end 279.706578 -221.784164)
				)
				(arc
					(start 278.893778 -221.784164)
					(mid 278.383238 -222.294704)
					(end 278.893778 -222.805244)
				)
			)
		)
		(polygon
			(pts
				(arc
					(start 276.506686 -222.805244)
					(mid 277.016972 -222.294577)
					(end 276.506432 -221.784164)
				)
				(arc
					(start 275.693632 -221.784164)
					(mid 275.183092 -222.294704)
					(end 275.693632 -222.805244)
				)
			)
		)
		(polygon
			(pts
				(arc
					(start 273.306794 -222.805244)
					(mid 273.81708 -222.294577)
					(end 273.30654 -221.784164)
				)
				(arc
					(start 272.49374 -221.784164)
					(mid 271.9832 -222.294704)
					(end 272.49374 -222.805244)
				)
			)
		)
		(polygon
			(pts
				(arc
					(start 266.906756 -222.805244)
					(mid 267.417042 -222.294577)
					(end 266.906502 -221.784164)
				)
				(arc
					(start 266.093702 -221.784164)
					(mid 265.583162 -222.294704)
					(end 266.093702 -222.805244)
				)
			)
		)
		(polygon
			(pts
				(arc
					(start 263.70661 -222.805244)
					(mid 264.216896 -222.294577)
					(end 263.706356 -221.784164)
				)
				(arc
					(start 262.893556 -221.784164)
					(mid 262.383016 -222.294704)
					(end 262.893556 -222.805244)
				)
			)
		)
		(polygon
			(pts
				(arc
					(start 215.306656 -222.805244)
					(mid 215.816942 -222.294577)
					(end 215.306402 -221.784164)
				)
				(arc
					(start 214.493602 -221.784164)
					(mid 213.983062 -222.294704)
					(end 214.493602 -222.805244)
				)
			)
		)
		(polygon
			(pts
				(arc
					(start 212.106764 -222.805244)
					(mid 212.61705 -222.294577)
					(end 212.10651 -221.784164)
				)
				(arc
					(start 211.29371 -221.784164)
					(mid 210.78317 -222.294704)
					(end 211.29371 -222.805244)
				)
			)
		)
		(polygon
			(pts
				(arc
					(start 205.706726 -222.805244)
					(mid 206.217012 -222.294577)
					(end 205.706472 -221.784164)
				)
				(arc
					(start 204.893672 -221.784164)
					(mid 204.383132 -222.294704)
					(end 204.893672 -222.805244)
				)
			)
		)
		(polygon
			(pts
				(arc
					(start 202.506834 -222.805244)
					(mid 203.01712 -222.294577)
					(end 202.50658 -221.784164)
				)
				(arc
					(start 201.69378 -221.784164)
					(mid 201.18324 -222.294704)
					(end 201.69378 -222.805244)
				)
			)
		)
		(polygon
			(pts
				(arc
					(start 199.306688 -222.805244)
					(mid 199.816974 -222.294577)
					(end 199.306434 -221.784164)
				)
				(arc
					(start 198.493634 -221.784164)
					(mid 197.983094 -222.294704)
					(end 198.493634 -222.805244)
				)
			)
		)
		(polygon
			(pts
				(arc
					(start 196.106796 -222.805244)
					(mid 196.617082 -222.294577)
					(end 196.106542 -221.784164)
				)
				(arc
					(start 195.293742 -221.784164)
					(mid 194.783202 -222.294704)
					(end 195.293742 -222.805244)
				)
			)
		)
		(polygon
			(pts
				(arc
					(start 192.90665 -222.805244)
					(mid 193.416936 -222.294577)
					(end 192.906396 -221.784164)
				)
				(arc
					(start 192.093596 -221.784164)
					(mid 191.583056 -222.294704)
					(end 192.093596 -222.805244)
				)
			)
		)
		(polygon
			(pts
				(arc
					(start 189.706758 -222.805244)
					(mid 190.217044 -222.294577)
					(end 189.706504 -221.784164)
				)
				(arc
					(start 188.893704 -221.784164)
					(mid 188.383164 -222.294704)
					(end 188.893704 -222.805244)
				)
			)
		)
		(polygon
			(pts
				(arc
					(start 186.506358 -222.805244)
					(mid 187.016898 -222.294704)
					(end 186.506358 -221.784164)
				)
				(arc
					(start 185.693304 -221.784164)
					(mid 185.183018 -222.294831)
					(end 185.693558 -222.805244)
				)
			)
		)
		(polygon
			(pts
				(arc
					(start 175.306736 -222.805244)
					(mid 175.817022 -222.294577)
					(end 175.306482 -221.784164)
				)
				(arc
					(start 174.493682 -221.784164)
					(mid 173.983142 -222.294704)
					(end 174.493682 -222.805244)
				)
			)
		)
		(polygon
			(pts
				(arc
					(start 172.106844 -222.805244)
					(mid 172.61713 -222.294577)
					(end 172.10659 -221.784164)
				)
				(arc
					(start 171.29379 -221.784164)
					(mid 170.78325 -222.294704)
					(end 171.29379 -222.805244)
				)
			)
		)
		(polygon
			(pts
				(arc
					(start 168.906698 -222.805244)
					(mid 169.416984 -222.294577)
					(end 168.906444 -221.784164)
				)
				(arc
					(start 168.093644 -221.784164)
					(mid 167.583104 -222.294704)
					(end 168.093644 -222.805244)
				)
			)
		)
		(polygon
			(pts
				(arc
					(start 165.706806 -222.805244)
					(mid 166.217092 -222.294577)
					(end 165.706552 -221.784164)
				)
				(arc
					(start 164.893752 -221.784164)
					(mid 164.383212 -222.294704)
					(end 164.893752 -222.805244)
				)
			)
		)
		(polygon
			(pts
				(arc
					(start 160.106614 -222.805244)
					(mid 160.6169 -222.294577)
					(end 160.10636 -221.784164)
				)
				(arc
					(start 159.29356 -221.784164)
					(mid 158.78302 -222.294704)
					(end 159.29356 -222.805244)
				)
			)
		)
		(polygon
			(pts
				(arc
					(start 156.906722 -222.805244)
					(mid 157.417008 -222.294577)
					(end 156.906468 -221.784164)
				)
				(arc
					(start 156.093668 -221.784164)
					(mid 155.583128 -222.294704)
					(end 156.093668 -222.805244)
				)
			)
		)
		(polygon
			(pts
				(arc
					(start 153.70683 -222.805244)
					(mid 154.217116 -222.294577)
					(end 153.706576 -221.784164)
				)
				(arc
					(start 152.893776 -221.784164)
					(mid 152.383236 -222.294704)
					(end 152.893776 -222.805244)
				)
			)
		)
		(polygon
			(pts
				(arc
					(start 150.506684 -222.805244)
					(mid 151.01697 -222.294577)
					(end 150.50643 -221.784164)
				)
				(arc
					(start 149.69363 -221.784164)
					(mid 149.18309 -222.294704)
					(end 149.69363 -222.805244)
				)
			)
		)
		(polygon
			(pts
				(arc
					(start 147.306792 -222.805244)
					(mid 147.817078 -222.294577)
					(end 147.306538 -221.784164)
				)
				(arc
					(start 146.493738 -221.784164)
					(mid 145.983198 -222.294704)
					(end 146.493738 -222.805244)
				)
			)
		)
		(polygon
			(pts
				(arc
					(start 144.106646 -222.805244)
					(mid 144.616932 -222.294577)
					(end 144.106392 -221.784164)
				)
				(arc
					(start 143.293592 -221.784164)
					(mid 142.783052 -222.294704)
					(end 143.293592 -222.805244)
				)
			)
		)
		(polygon
			(pts
				(arc
					(start 140.906754 -222.805244)
					(mid 141.41704 -222.294577)
					(end 140.9065 -221.784164)
				)
				(arc
					(start 140.0937 -221.784164)
					(mid 139.58316 -222.294704)
					(end 140.0937 -222.805244)
				)
			)
		)
		(polygon
			(pts
				(arc
					(start 137.706608 -222.805244)
					(mid 138.216894 -222.294577)
					(end 137.706354 -221.784164)
				)
				(arc
					(start 136.893554 -221.784164)
					(mid 136.383014 -222.294704)
					(end 136.893554 -222.805244)
				)
			)
		)
		(polygon
			(pts
				(arc
					(start 106.906568 -222.805244)
					(mid 107.416854 -222.294577)
					(end 106.906314 -221.784164)
				)
				(arc
					(start 106.093514 -221.784164)
					(mid 105.582974 -222.294704)
					(end 106.093514 -222.805244)
				)
			)
		)
		(polygon
			(pts
				(arc
					(start 103.706422 -222.805244)
					(mid 104.216708 -222.294577)
					(end 103.706168 -221.784164)
				)
				(arc
					(start 102.893368 -221.784164)
					(mid 102.382828 -222.294704)
					(end 102.893368 -222.805244)
				)
			)
		)
		(polygon
			(pts
				(arc
					(start 100.50653 -222.805244)
					(mid 101.016816 -222.294577)
					(end 100.506276 -221.784164)
				)
				(arc
					(start 99.693476 -221.784164)
					(mid 99.182936 -222.294704)
					(end 99.693476 -222.805244)
				)
			)
		)
		(polygon
			(pts
				(arc
					(start 97.306638 -222.805244)
					(mid 97.816924 -222.294577)
					(end 97.306384 -221.784164)
				)
				(arc
					(start 96.493584 -221.784164)
					(mid 95.983044 -222.294704)
					(end 96.493584 -222.805244)
				)
			)
		)
		(polygon
			(pts
				(arc
					(start 91.706446 -222.805244)
					(mid 92.216732 -222.294577)
					(end 91.706192 -221.784164)
				)
				(arc
					(start 90.893392 -221.784164)
					(mid 90.382852 -222.294704)
					(end 90.893392 -222.805244)
				)
			)
		)
		(polygon
			(pts
				(arc
					(start 88.506554 -222.805244)
					(mid 89.01684 -222.294577)
					(end 88.5063 -221.784164)
				)
				(arc
					(start 87.6935 -221.784164)
					(mid 87.18296 -222.294704)
					(end 87.6935 -222.805244)
				)
			)
		)
		(polygon
			(pts
				(arc
					(start 85.306408 -222.805244)
					(mid 85.816694 -222.294577)
					(end 85.306154 -221.784164)
				)
				(arc
					(start 84.493354 -221.784164)
					(mid 83.982814 -222.294704)
					(end 84.493354 -222.805244)
				)
			)
		)
		(polygon
			(pts
				(arc
					(start 82.106516 -222.805244)
					(mid 82.616802 -222.294577)
					(end 82.106262 -221.784164)
				)
				(arc
					(start 81.293462 -221.784164)
					(mid 80.782922 -222.294704)
					(end 81.293462 -222.805244)
				)
			)
		)
		(polygon
			(pts
				(arc
					(start 69.30644 -222.805244)
					(mid 69.816726 -222.294577)
					(end 69.306186 -221.784164)
				)
				(arc
					(start 68.493386 -221.784164)
					(mid 67.982846 -222.294704)
					(end 68.493386 -222.805244)
				)
			)
		)
		(polygon
			(pts
				(arc
					(start 66.106548 -222.805244)
					(mid 66.616834 -222.294577)
					(end 66.106294 -221.784164)
				)
				(arc
					(start 65.293494 -221.784164)
					(mid 64.782954 -222.294704)
					(end 65.293494 -222.805244)
				)
			)
		)
		(polygon
			(pts
				(arc
					(start 60.506356 -222.805244)
					(mid 61.016642 -222.294577)
					(end 60.506102 -221.784164)
				)
				(arc
					(start 59.693302 -221.784164)
					(mid 59.182762 -222.294704)
					(end 59.693302 -222.805244)
				)
			)
		)
		(polygon
			(pts
				(arc
					(start 57.306464 -222.805244)
					(mid 57.81675 -222.294577)
					(end 57.30621 -221.784164)
				)
				(arc
					(start 56.49341 -221.784164)
					(mid 55.98287 -222.294704)
					(end 56.49341 -222.805244)
				)
			)
		)
		(polygon
			(pts
				(arc
					(start 54.106572 -222.805244)
					(mid 54.616858 -222.294577)
					(end 54.106318 -221.784164)
				)
				(arc
					(start 53.293518 -221.784164)
					(mid 52.782978 -222.294704)
					(end 53.293518 -222.805244)
				)
			)
		)
		(polygon
			(pts
				(arc
					(start 50.906426 -221.916244)
					(mid 51.416712 -221.405577)
					(end 50.906172 -220.895164)
				)
				(arc
					(start 50.093372 -220.895164)
					(mid 49.582832 -221.405704)
					(end 50.093372 -221.916244)
				)
			)
		)
		(polygon
			(pts
				(arc
					(start 178.409854 -221.18574)
					(mid 178.92014 -220.675073)
					(end 178.4096 -220.16466)
				)
				(arc
					(start 177.5968 -220.16466)
					(mid 177.08626 -220.6752)
					(end 177.5968 -221.18574)
				)
			)
		)
		(polygon
			(pts
				(arc
					(start 304.562002 -220.779086)
					(mid 305.056286 -220.252798)
					(end 304.529998 -219.758514)
				)
				(xy 304.529998 -219.755974) (xy 303.717198 -219.781374)
				(arc
					(start 303.717198 -219.783914)
					(mid 303.222914 -220.310202)
					(end 303.749202 -220.804486)
				)
				(xy 303.749202 -220.807026) (xy 304.561748 -220.781626) (xy 304.562002 -220.781372)
			)
		)
		(polygon
			(pts
				(arc
					(start 72.517254 -220.52534)
					(mid 73.02754 -220.014673)
					(end 72.517 -219.50426)
				)
				(arc
					(start 71.7042 -219.50426)
					(mid 71.19366 -220.0148)
					(end 71.7042 -220.52534)
				)
			)
		)
		(polygon
			(pts
				(arc
					(start 78.982824 -220.392244)
					(mid 79.49311 -219.881577)
					(end 78.98257 -219.371164)
				)
				(arc
					(start 78.16977 -219.371164)
					(mid 77.65923 -219.881704)
					(end 78.16977 -220.392244)
				)
			)
		)
		(polygon
			(pts
				(arc
					(start 340.138258 -211.760054)
					(mid 340.101061 -211.670251)
					(end 340.011258 -211.633054)
				)
				(arc
					(start 338.588858 -211.633054)
					(mid 338.499055 -211.670251)
					(end 338.461858 -211.760054)
				)
				(arc
					(start 338.461858 -213.080854)
					(mid 338.499055 -213.170657)
					(end 338.588858 -213.207854)
				)
				(xy 338.995258 -213.207854) (xy 338.995512 -213.2076) (xy 339.59673 -213.2076) (xy 339.604858 -213.207854)
				(arc
					(start 340.011258 -213.207854)
					(mid 340.101061 -213.170657)
					(end 340.138258 -213.080854)
				)
			)
		)
		(polygon
			(pts
				(arc
					(start 336.938366 -211.760054)
					(mid 336.901169 -211.670251)
					(end 336.811366 -211.633054)
				)
				(arc
					(start 335.388966 -211.633054)
					(mid 335.299163 -211.670251)
					(end 335.261966 -211.760054)
				)
				(arc
					(start 335.261966 -213.080854)
					(mid 335.299163 -213.170657)
					(end 335.388966 -213.207854)
				)
				(xy 335.795366 -213.207854) (xy 335.79562 -213.2076) (xy 336.396838 -213.2076) (xy 336.404966 -213.207854)
				(arc
					(start 336.811366 -213.207854)
					(mid 336.901169 -213.170657)
					(end 336.938366 -213.080854)
				)
			)
		)
		(polygon
			(pts
				(arc
					(start 333.73822 -211.760054)
					(mid 333.701023 -211.670251)
					(end 333.61122 -211.633054)
				)
				(arc
					(start 332.18882 -211.633054)
					(mid 332.099017 -211.670251)
					(end 332.06182 -211.760054)
				)
				(arc
					(start 332.06182 -213.080854)
					(mid 332.099017 -213.170657)
					(end 332.18882 -213.207854)
				)
				(xy 332.59522 -213.207854) (xy 332.595474 -213.2076) (xy 333.196692 -213.2076) (xy 333.20482 -213.207854)
				(arc
					(start 333.61122 -213.207854)
					(mid 333.701023 -213.170657)
					(end 333.73822 -213.080854)
				)
			)
		)
		(polygon
			(pts
				(arc
					(start 327.338182 -211.760054)
					(mid 327.300985 -211.670251)
					(end 327.211182 -211.633054)
				)
				(arc
					(start 325.788782 -211.633054)
					(mid 325.698979 -211.670251)
					(end 325.661782 -211.760054)
				)
				(arc
					(start 325.661782 -213.080854)
					(mid 325.698979 -213.170657)
					(end 325.788782 -213.207854)
				)
				(xy 326.195182 -213.207854) (xy 326.195436 -213.2076) (xy 326.796654 -213.2076) (xy 326.804782 -213.207854)
				(arc
					(start 327.211182 -213.207854)
					(mid 327.300985 -213.170657)
					(end 327.338182 -213.080854)
				)
			)
		)
		(polygon
			(pts
				(arc
					(start 324.13829 -211.760054)
					(mid 324.101093 -211.670251)
					(end 324.01129 -211.633054)
				)
				(arc
					(start 322.58889 -211.633054)
					(mid 322.499087 -211.670251)
					(end 322.46189 -211.760054)
				)
				(arc
					(start 322.46189 -213.080854)
					(mid 322.499087 -213.170657)
					(end 322.58889 -213.207854)
				)
				(xy 322.99529 -213.207854) (xy 322.995544 -213.2076) (xy 323.596762 -213.2076) (xy 323.60489 -213.207854)
				(arc
					(start 324.01129 -213.207854)
					(mid 324.101093 -213.170657)
					(end 324.13829 -213.080854)
				)
			)
		)
		(polygon
			(pts
				(arc
					(start 320.938398 -211.760054)
					(mid 320.901201 -211.670251)
					(end 320.811398 -211.633054)
				)
				(arc
					(start 319.388998 -211.633054)
					(mid 319.299195 -211.670251)
					(end 319.261998 -211.760054)
				)
				(arc
					(start 319.261998 -213.080854)
					(mid 319.299195 -213.170657)
					(end 319.388998 -213.207854)
				)
				(xy 319.795398 -213.207854) (xy 319.795652 -213.2076) (xy 320.39687 -213.2076) (xy 320.404998 -213.207854)
				(arc
					(start 320.811398 -213.207854)
					(mid 320.901201 -213.170657)
					(end 320.938398 -213.080854)
				)
			)
		)
		(polygon
			(pts
				(arc
					(start 317.738252 -211.760054)
					(mid 317.701055 -211.670251)
					(end 317.611252 -211.633054)
				)
				(arc
					(start 316.188852 -211.633054)
					(mid 316.099049 -211.670251)
					(end 316.061852 -211.760054)
				)
				(arc
					(start 316.061852 -213.080854)
					(mid 316.099049 -213.170657)
					(end 316.188852 -213.207854)
				)
				(xy 316.595252 -213.207854) (xy 316.595506 -213.2076) (xy 317.196724 -213.2076) (xy 317.204852 -213.207854)
				(arc
					(start 317.611252 -213.207854)
					(mid 317.701055 -213.170657)
					(end 317.738252 -213.080854)
				)
			)
		)
		(polygon
			(pts
				(arc
					(start 314.53836 -211.760054)
					(mid 314.501163 -211.670251)
					(end 314.41136 -211.633054)
				)
				(arc
					(start 312.98896 -211.633054)
					(mid 312.899157 -211.670251)
					(end 312.86196 -211.760054)
				)
				(arc
					(start 312.86196 -213.080854)
					(mid 312.899157 -213.170657)
					(end 312.98896 -213.207854)
				)
				(xy 313.39536 -213.207854) (xy 313.395614 -213.2076) (xy 313.996832 -213.2076) (xy 314.00496 -213.207854)
				(arc
					(start 314.41136 -213.207854)
					(mid 314.501163 -213.170657)
					(end 314.53836 -213.080854)
				)
			)
		)
		(polygon
			(pts
				(arc
					(start 311.338214 -211.760054)
					(mid 311.301017 -211.670251)
					(end 311.211214 -211.633054)
				)
				(arc
					(start 309.788814 -211.633054)
					(mid 309.699011 -211.670251)
					(end 309.661814 -211.760054)
				)
				(arc
					(start 309.661814 -213.080854)
					(mid 309.699011 -213.170657)
					(end 309.788814 -213.207854)
				)
				(xy 310.195214 -213.207854) (xy 310.195468 -213.2076) (xy 310.796686 -213.2076) (xy 310.804814 -213.207854)
				(arc
					(start 311.211214 -213.207854)
					(mid 311.301017 -213.170657)
					(end 311.338214 -213.080854)
				)
			)
		)
		(polygon
			(pts
				(arc
					(start 303.33823 -211.760054)
					(mid 303.301033 -211.670251)
					(end 303.21123 -211.633054)
				)
				(arc
					(start 301.78883 -211.633054)
					(mid 301.699027 -211.670251)
					(end 301.66183 -211.760054)
				)
				(arc
					(start 301.66183 -213.080854)
					(mid 301.699027 -213.170657)
					(end 301.78883 -213.207854)
				)
				(xy 302.19523 -213.207854) (xy 302.195484 -213.2076) (xy 302.796702 -213.2076) (xy 302.80483 -213.207854)
				(arc
					(start 303.21123 -213.207854)
					(mid 303.301033 -213.170657)
					(end 303.33823 -213.080854)
				)
			)
		)
		(polygon
			(pts
				(arc
					(start 300.138338 -211.760054)
					(mid 300.101141 -211.670251)
					(end 300.011338 -211.633054)
				)
				(arc
					(start 298.588938 -211.633054)
					(mid 298.499135 -211.670251)
					(end 298.461938 -211.760054)
				)
				(arc
					(start 298.461938 -213.080854)
					(mid 298.499135 -213.170657)
					(end 298.588938 -213.207854)
				)
				(xy 298.995338 -213.207854) (xy 298.995592 -213.2076) (xy 299.59681 -213.2076) (xy 299.604938 -213.207854)
				(arc
					(start 300.011338 -213.207854)
					(mid 300.101141 -213.170657)
					(end 300.138338 -213.080854)
				)
			)
		)
		(polygon
			(pts
				(arc
					(start 294.538146 -211.760054)
					(mid 294.500949 -211.670251)
					(end 294.411146 -211.633054)
				)
				(arc
					(start 292.988746 -211.633054)
					(mid 292.898943 -211.670251)
					(end 292.861746 -211.760054)
				)
				(arc
					(start 292.861746 -213.080854)
					(mid 292.898943 -213.170657)
					(end 292.988746 -213.207854)
				)
				(xy 293.395146 -213.207854) (xy 293.3954 -213.2076) (xy 293.996618 -213.2076) (xy 294.004746 -213.207854)
				(arc
					(start 294.411146 -213.207854)
					(mid 294.500949 -213.170657)
					(end 294.538146 -213.080854)
				)
			)
		)
		(polygon
			(pts
				(arc
					(start 291.338254 -211.760054)
					(mid 291.301057 -211.670251)
					(end 291.211254 -211.633054)
				)
				(arc
					(start 289.788854 -211.633054)
					(mid 289.699051 -211.670251)
					(end 289.661854 -211.760054)
				)
				(arc
					(start 289.661854 -213.080854)
					(mid 289.699051 -213.170657)
					(end 289.788854 -213.207854)
				)
				(xy 290.195254 -213.207854) (xy 290.195508 -213.2076) (xy 290.796726 -213.2076) (xy 290.804854 -213.207854)
				(arc
					(start 291.211254 -213.207854)
					(mid 291.301057 -213.170657)
					(end 291.338254 -213.080854)
				)
			)
		)
		(polygon
			(pts
				(arc
					(start 288.138362 -211.760054)
					(mid 288.101165 -211.670251)
					(end 288.011362 -211.633054)
				)
				(arc
					(start 286.588962 -211.633054)
					(mid 286.499159 -211.670251)
					(end 286.461962 -211.760054)
				)
				(arc
					(start 286.461962 -213.080854)
					(mid 286.499159 -213.170657)
					(end 286.588962 -213.207854)
				)
				(xy 286.995362 -213.207854) (xy 286.995616 -213.2076) (xy 287.596834 -213.2076) (xy 287.604962 -213.207854)
				(arc
					(start 288.011362 -213.207854)
					(mid 288.101165 -213.170657)
					(end 288.138362 -213.080854)
				)
			)
		)
		(polygon
			(pts
				(arc
					(start 284.938216 -211.760054)
					(mid 284.901019 -211.670251)
					(end 284.811216 -211.633054)
				)
				(arc
					(start 283.388816 -211.633054)
					(mid 283.299013 -211.670251)
					(end 283.261816 -211.760054)
				)
				(arc
					(start 283.261816 -213.080854)
					(mid 283.299013 -213.170657)
					(end 283.388816 -213.207854)
				)
				(xy 283.795216 -213.207854) (xy 283.79547 -213.2076) (xy 284.396688 -213.2076) (xy 284.404816 -213.207854)
				(arc
					(start 284.811216 -213.207854)
					(mid 284.901019 -213.170657)
					(end 284.938216 -213.080854)
				)
			)
		)
		(polygon
			(pts
				(arc
					(start 281.738324 -211.760054)
					(mid 281.701127 -211.670251)
					(end 281.611324 -211.633054)
				)
				(arc
					(start 280.188924 -211.633054)
					(mid 280.099121 -211.670251)
					(end 280.061924 -211.760054)
				)
				(arc
					(start 280.061924 -213.080854)
					(mid 280.099121 -213.170657)
					(end 280.188924 -213.207854)
				)
				(xy 280.595324 -213.207854) (xy 280.595578 -213.2076) (xy 281.196796 -213.2076) (xy 281.204924 -213.207854)
				(arc
					(start 281.611324 -213.207854)
					(mid 281.701127 -213.170657)
					(end 281.738324 -213.080854)
				)
			)
		)
		(polygon
			(pts
				(arc
					(start 278.538178 -211.760054)
					(mid 278.500981 -211.670251)
					(end 278.411178 -211.633054)
				)
				(arc
					(start 276.988778 -211.633054)
					(mid 276.898975 -211.670251)
					(end 276.861778 -211.760054)
				)
				(arc
					(start 276.861778 -213.080854)
					(mid 276.898975 -213.170657)
					(end 276.988778 -213.207854)
				)
				(xy 277.395178 -213.207854) (xy 277.395432 -213.2076) (xy 277.99665 -213.2076) (xy 278.004778 -213.207854)
				(arc
					(start 278.411178 -213.207854)
					(mid 278.500981 -213.170657)
					(end 278.538178 -213.080854)
				)
			)
		)
		(polygon
			(pts
				(arc
					(start 275.338286 -211.760054)
					(mid 275.301089 -211.670251)
					(end 275.211286 -211.633054)
				)
				(arc
					(start 273.788886 -211.633054)
					(mid 273.699083 -211.670251)
					(end 273.661886 -211.760054)
				)
				(arc
					(start 273.661886 -213.080854)
					(mid 273.699083 -213.170657)
					(end 273.788886 -213.207854)
				)
				(xy 274.195286 -213.207854) (xy 274.19554 -213.2076) (xy 274.796758 -213.2076) (xy 274.804886 -213.207854)
				(arc
					(start 275.211286 -213.207854)
					(mid 275.301089 -213.170657)
					(end 275.338286 -213.080854)
				)
			)
		)
		(polygon
			(pts
				(arc
					(start 272.138394 -211.760054)
					(mid 272.101197 -211.670251)
					(end 272.011394 -211.633054)
				)
				(arc
					(start 270.588994 -211.633054)
					(mid 270.499191 -211.670251)
					(end 270.461994 -211.760054)
				)
				(arc
					(start 270.461994 -213.080854)
					(mid 270.499191 -213.170657)
					(end 270.588994 -213.207854)
				)
				(xy 270.995394 -213.207854) (xy 270.995648 -213.2076) (xy 271.596866 -213.2076) (xy 271.604994 -213.207854)
				(arc
					(start 272.011394 -213.207854)
					(mid 272.101197 -213.170657)
					(end 272.138394 -213.080854)
				)
			)
		)
		(polygon
			(pts
				(arc
					(start 268.938248 -211.760054)
					(mid 268.901051 -211.670251)
					(end 268.811248 -211.633054)
				)
				(arc
					(start 267.388848 -211.633054)
					(mid 267.299045 -211.670251)
					(end 267.261848 -211.760054)
				)
				(arc
					(start 267.261848 -213.080854)
					(mid 267.299045 -213.170657)
					(end 267.388848 -213.207854)
				)
				(xy 267.795248 -213.207854) (xy 267.795502 -213.2076) (xy 268.39672 -213.2076) (xy 268.404848 -213.207854)
				(arc
					(start 268.811248 -213.207854)
					(mid 268.901051 -213.170657)
					(end 268.938248 -213.080854)
				)
			)
		)
		(polygon
			(pts
				(arc
					(start 265.738356 -211.760054)
					(mid 265.701159 -211.670251)
					(end 265.611356 -211.633054)
				)
				(arc
					(start 264.188956 -211.633054)
					(mid 264.099153 -211.670251)
					(end 264.061956 -211.760054)
				)
				(arc
					(start 264.061956 -213.080854)
					(mid 264.099153 -213.170657)
					(end 264.188956 -213.207854)
				)
				(xy 264.595356 -213.207854) (xy 264.59561 -213.2076) (xy 265.196828 -213.2076) (xy 265.204956 -213.207854)
				(arc
					(start 265.611356 -213.207854)
					(mid 265.701159 -213.170657)
					(end 265.738356 -213.080854)
				)
			)
		)
		(polygon
			(pts
				(arc
					(start 217.338148 -211.760054)
					(mid 217.300951 -211.670251)
					(end 217.211148 -211.633054)
				)
				(arc
					(start 215.788748 -211.633054)
					(mid 215.698945 -211.670251)
					(end 215.661748 -211.760054)
				)
				(arc
					(start 215.661748 -213.080854)
					(mid 215.698945 -213.170657)
					(end 215.788748 -213.207854)
				)
				(xy 216.195148 -213.207854) (xy 216.195402 -213.2076) (xy 216.79662 -213.2076) (xy 216.804748 -213.207854)
				(arc
					(start 217.211148 -213.207854)
					(mid 217.300951 -213.170657)
					(end 217.338148 -213.080854)
				)
			)
		)
		(polygon
			(pts
				(arc
					(start 214.138256 -211.760054)
					(mid 214.101059 -211.670251)
					(end 214.011256 -211.633054)
				)
				(arc
					(start 212.588856 -211.633054)
					(mid 212.499053 -211.670251)
					(end 212.461856 -211.760054)
				)
				(arc
					(start 212.461856 -213.080854)
					(mid 212.499053 -213.170657)
					(end 212.588856 -213.207854)
				)
				(xy 212.995256 -213.207854) (xy 212.99551 -213.2076) (xy 213.596728 -213.2076) (xy 213.604856 -213.207854)
				(arc
					(start 214.011256 -213.207854)
					(mid 214.101059 -213.170657)
					(end 214.138256 -213.080854)
				)
			)
		)
		(polygon
			(pts
				(arc
					(start 207.738218 -211.760054)
					(mid 207.701021 -211.670251)
					(end 207.611218 -211.633054)
				)
				(arc
					(start 206.188818 -211.633054)
					(mid 206.099015 -211.670251)
					(end 206.061818 -211.760054)
				)
				(arc
					(start 206.061818 -213.080854)
					(mid 206.099015 -213.170657)
					(end 206.188818 -213.207854)
				)
				(xy 206.595218 -213.207854) (xy 206.595472 -213.2076) (xy 207.19669 -213.2076) (xy 207.204818 -213.207854)
				(arc
					(start 207.611218 -213.207854)
					(mid 207.701021 -213.170657)
					(end 207.738218 -213.080854)
				)
			)
		)
		(polygon
			(pts
				(arc
					(start 204.538326 -211.760054)
					(mid 204.501129 -211.670251)
					(end 204.411326 -211.633054)
				)
				(arc
					(start 202.988926 -211.633054)
					(mid 202.899123 -211.670251)
					(end 202.861926 -211.760054)
				)
				(arc
					(start 202.861926 -213.080854)
					(mid 202.899123 -213.170657)
					(end 202.988926 -213.207854)
				)
				(xy 203.395326 -213.207854) (xy 203.39558 -213.2076) (xy 203.996798 -213.2076) (xy 204.004926 -213.207854)
				(arc
					(start 204.411326 -213.207854)
					(mid 204.501129 -213.170657)
					(end 204.538326 -213.080854)
				)
			)
		)
		(polygon
			(pts
				(arc
					(start 201.33818 -211.760054)
					(mid 201.300983 -211.670251)
					(end 201.21118 -211.633054)
				)
				(arc
					(start 199.78878 -211.633054)
					(mid 199.698977 -211.670251)
					(end 199.66178 -211.760054)
				)
				(arc
					(start 199.66178 -213.080854)
					(mid 199.698977 -213.170657)
					(end 199.78878 -213.207854)
				)
				(xy 200.19518 -213.207854) (xy 200.195434 -213.2076) (xy 200.796652 -213.2076) (xy 200.80478 -213.207854)
				(arc
					(start 201.21118 -213.207854)
					(mid 201.300983 -213.170657)
					(end 201.33818 -213.080854)
				)
			)
		)
		(polygon
			(pts
				(arc
					(start 198.138288 -211.760054)
					(mid 198.101091 -211.670251)
					(end 198.011288 -211.633054)
				)
				(arc
					(start 196.588888 -211.633054)
					(mid 196.499085 -211.670251)
					(end 196.461888 -211.760054)
				)
				(arc
					(start 196.461888 -213.080854)
					(mid 196.499085 -213.170657)
					(end 196.588888 -213.207854)
				)
				(xy 196.995288 -213.207854) (xy 196.995542 -213.2076) (xy 197.59676 -213.2076) (xy 197.604888 -213.207854)
				(arc
					(start 198.011288 -213.207854)
					(mid 198.101091 -213.170657)
					(end 198.138288 -213.080854)
				)
			)
		)
		(polygon
			(pts
				(arc
					(start 194.938396 -211.760054)
					(mid 194.901199 -211.670251)
					(end 194.811396 -211.633054)
				)
				(arc
					(start 193.388996 -211.633054)
					(mid 193.299193 -211.670251)
					(end 193.261996 -211.760054)
				)
				(arc
					(start 193.261996 -213.080854)
					(mid 193.299193 -213.170657)
					(end 193.388996 -213.207854)
				)
				(xy 193.795396 -213.207854) (xy 193.79565 -213.2076) (xy 194.396868 -213.2076) (xy 194.404996 -213.207854)
				(arc
					(start 194.811396 -213.207854)
					(mid 194.901199 -213.170657)
					(end 194.938396 -213.080854)
				)
			)
		)
		(polygon
			(pts
				(arc
					(start 191.738504 -211.760054)
					(mid 191.701307 -211.670251)
					(end 191.611504 -211.633054)
				)
				(arc
					(start 190.189104 -211.633054)
					(mid 190.099301 -211.670251)
					(end 190.062104 -211.760054)
				)
				(arc
					(start 190.062104 -213.080854)
					(mid 190.099301 -213.170657)
					(end 190.189104 -213.207854)
				)
				(xy 190.595504 -213.207854) (xy 190.595758 -213.2076) (xy 191.196976 -213.2076) (xy 191.205104 -213.207854)
				(arc
					(start 191.611504 -213.207854)
					(mid 191.701307 -213.170657)
					(end 191.738504 -213.080854)
				)
			)
		)
		(polygon
			(pts
				(arc
					(start 188.538358 -211.760054)
					(mid 188.501161 -211.670251)
					(end 188.411358 -211.633054)
				)
				(arc
					(start 186.988958 -211.633054)
					(mid 186.899155 -211.670251)
					(end 186.861958 -211.760054)
				)
				(arc
					(start 186.861958 -213.080854)
					(mid 186.899155 -213.170657)
					(end 186.988958 -213.207854)
				)
				(xy 187.395358 -213.207854) (xy 187.395612 -213.2076) (xy 187.99683 -213.2076) (xy 188.004958 -213.207854)
				(arc
					(start 188.411358 -213.207854)
					(mid 188.501161 -213.170657)
					(end 188.538358 -213.080854)
				)
			)
		)
		(polygon
			(pts
				(arc
					(start 185.338466 -211.760054)
					(mid 185.301269 -211.670251)
					(end 185.211466 -211.633054)
				)
				(arc
					(start 183.789066 -211.633054)
					(mid 183.699263 -211.670251)
					(end 183.662066 -211.760054)
				)
				(arc
					(start 183.662066 -213.080854)
					(mid 183.699263 -213.170657)
					(end 183.789066 -213.207854)
				)
				(xy 184.195466 -213.207854) (xy 184.19572 -213.2076) (xy 184.796938 -213.2076) (xy 184.805066 -213.207854)
				(arc
					(start 185.211466 -213.207854)
					(mid 185.301269 -213.170657)
					(end 185.338466 -213.080854)
				)
			)
		)
		(polygon
			(pts
				(arc
					(start 177.338228 -211.760054)
					(mid 177.301031 -211.670251)
					(end 177.211228 -211.633054)
				)
				(arc
					(start 175.788828 -211.633054)
					(mid 175.699025 -211.670251)
					(end 175.661828 -211.760054)
				)
				(arc
					(start 175.661828 -213.080854)
					(mid 175.699025 -213.170657)
					(end 175.788828 -213.207854)
				)
				(xy 176.195228 -213.207854) (xy 176.195482 -213.2076) (xy 176.7967 -213.2076) (xy 176.804828 -213.207854)
				(arc
					(start 177.211228 -213.207854)
					(mid 177.301031 -213.170657)
					(end 177.338228 -213.080854)
				)
			)
		)
		(polygon
			(pts
				(arc
					(start 174.138336 -211.760054)
					(mid 174.101139 -211.670251)
					(end 174.011336 -211.633054)
				)
				(arc
					(start 172.588936 -211.633054)
					(mid 172.499133 -211.670251)
					(end 172.461936 -211.760054)
				)
				(arc
					(start 172.461936 -213.080854)
					(mid 172.499133 -213.170657)
					(end 172.588936 -213.207854)
				)
				(xy 172.995336 -213.207854) (xy 172.99559 -213.2076) (xy 173.596808 -213.2076) (xy 173.604936 -213.207854)
				(arc
					(start 174.011336 -213.207854)
					(mid 174.101139 -213.170657)
					(end 174.138336 -213.080854)
				)
			)
		)
		(polygon
			(pts
				(arc
					(start 170.93819 -211.760054)
					(mid 170.900993 -211.670251)
					(end 170.81119 -211.633054)
				)
				(arc
					(start 169.38879 -211.633054)
					(mid 169.298987 -211.670251)
					(end 169.26179 -211.760054)
				)
				(arc
					(start 169.26179 -213.080854)
					(mid 169.298987 -213.170657)
					(end 169.38879 -213.207854)
				)
				(xy 169.79519 -213.207854) (xy 169.795444 -213.2076) (xy 170.396662 -213.2076) (xy 170.40479 -213.207854)
				(arc
					(start 170.81119 -213.207854)
					(mid 170.900993 -213.170657)
					(end 170.93819 -213.080854)
				)
			)
		)
		(polygon
			(pts
				(arc
					(start 167.738298 -211.760054)
					(mid 167.701101 -211.670251)
					(end 167.611298 -211.633054)
				)
				(arc
					(start 166.188898 -211.633054)
					(mid 166.099095 -211.670251)
					(end 166.061898 -211.760054)
				)
				(arc
					(start 166.061898 -213.080854)
					(mid 166.099095 -213.170657)
					(end 166.188898 -213.207854)
				)
				(xy 166.595298 -213.207854) (xy 166.595552 -213.2076) (xy 167.19677 -213.2076) (xy 167.204898 -213.207854)
				(arc
					(start 167.611298 -213.207854)
					(mid 167.701101 -213.170657)
					(end 167.738298 -213.080854)
				)
			)
		)
		(polygon
			(pts
				(arc
					(start 162.13836 -211.760054)
					(mid 162.101163 -211.670251)
					(end 162.01136 -211.633054)
				)
				(arc
					(start 160.58896 -211.633054)
					(mid 160.499157 -211.670251)
					(end 160.46196 -211.760054)
				)
				(arc
					(start 160.46196 -213.080854)
					(mid 160.499157 -213.170657)
					(end 160.58896 -213.207854)
				)
				(xy 160.99536 -213.207854) (xy 160.995614 -213.2076) (xy 161.596832 -213.2076) (xy 161.60496 -213.207854)
				(arc
					(start 162.01136 -213.207854)
					(mid 162.101163 -213.170657)
					(end 162.13836 -213.080854)
				)
			)
		)
		(polygon
			(pts
				(arc
					(start 158.938468 -211.760054)
					(mid 158.901271 -211.670251)
					(end 158.811468 -211.633054)
				)
				(arc
					(start 157.389068 -211.633054)
					(mid 157.299265 -211.670251)
					(end 157.262068 -211.760054)
				)
				(arc
					(start 157.262068 -213.080854)
					(mid 157.299265 -213.170657)
					(end 157.389068 -213.207854)
				)
				(xy 157.795468 -213.207854) (xy 157.795722 -213.2076) (xy 158.39694 -213.2076) (xy 158.405068 -213.207854)
				(arc
					(start 158.811468 -213.207854)
					(mid 158.901271 -213.170657)
					(end 158.938468 -213.080854)
				)
			)
		)
		(polygon
			(pts
				(arc
					(start 155.738322 -211.760054)
					(mid 155.701125 -211.670251)
					(end 155.611322 -211.633054)
				)
				(arc
					(start 154.188922 -211.633054)
					(mid 154.099119 -211.670251)
					(end 154.061922 -211.760054)
				)
				(arc
					(start 154.061922 -213.080854)
					(mid 154.099119 -213.170657)
					(end 154.188922 -213.207854)
				)
				(xy 154.595322 -213.207854) (xy 154.595576 -213.2076) (xy 155.196794 -213.2076) (xy 155.204922 -213.207854)
				(arc
					(start 155.611322 -213.207854)
					(mid 155.701125 -213.170657)
					(end 155.738322 -213.080854)
				)
			)
		)
		(polygon
			(pts
				(arc
					(start 152.53843 -211.760054)
					(mid 152.501233 -211.670251)
					(end 152.41143 -211.633054)
				)
				(arc
					(start 150.98903 -211.633054)
					(mid 150.899227 -211.670251)
					(end 150.86203 -211.760054)
				)
				(arc
					(start 150.86203 -213.080854)
					(mid 150.899227 -213.170657)
					(end 150.98903 -213.207854)
				)
				(xy 151.39543 -213.207854) (xy 151.395684 -213.2076) (xy 151.996902 -213.2076) (xy 152.00503 -213.207854)
				(arc
					(start 152.41143 -213.207854)
					(mid 152.501233 -213.170657)
					(end 152.53843 -213.080854)
				)
			)
		)
		(polygon
			(pts
				(arc
					(start 149.338284 -211.760054)
					(mid 149.301087 -211.670251)
					(end 149.211284 -211.633054)
				)
				(arc
					(start 147.788884 -211.633054)
					(mid 147.699081 -211.670251)
					(end 147.661884 -211.760054)
				)
				(arc
					(start 147.661884 -213.080854)
					(mid 147.699081 -213.170657)
					(end 147.788884 -213.207854)
				)
				(xy 148.195284 -213.207854) (xy 148.195538 -213.2076) (xy 148.796756 -213.2076) (xy 148.804884 -213.207854)
				(arc
					(start 149.211284 -213.207854)
					(mid 149.301087 -213.170657)
					(end 149.338284 -213.080854)
				)
			)
		)
		(polygon
			(pts
				(arc
					(start 146.138392 -211.760054)
					(mid 146.101195 -211.670251)
					(end 146.011392 -211.633054)
				)
				(arc
					(start 144.588992 -211.633054)
					(mid 144.499189 -211.670251)
					(end 144.461992 -211.760054)
				)
				(arc
					(start 144.461992 -213.080854)
					(mid 144.499189 -213.170657)
					(end 144.588992 -213.207854)
				)
				(xy 144.995392 -213.207854) (xy 144.995646 -213.2076) (xy 145.596864 -213.2076) (xy 145.604992 -213.207854)
				(arc
					(start 146.011392 -213.207854)
					(mid 146.101195 -213.170657)
					(end 146.138392 -213.080854)
				)
			)
		)
		(polygon
			(pts
				(arc
					(start 142.938246 -211.760054)
					(mid 142.901049 -211.670251)
					(end 142.811246 -211.633054)
				)
				(arc
					(start 141.388846 -211.633054)
					(mid 141.299043 -211.670251)
					(end 141.261846 -211.760054)
				)
				(arc
					(start 141.261846 -213.080854)
					(mid 141.299043 -213.170657)
					(end 141.388846 -213.207854)
				)
				(xy 141.795246 -213.207854) (xy 141.7955 -213.2076) (xy 142.396718 -213.2076) (xy 142.404846 -213.207854)
				(arc
					(start 142.811246 -213.207854)
					(mid 142.901049 -213.170657)
					(end 142.938246 -213.080854)
				)
			)
		)
		(polygon
			(pts
				(arc
					(start 139.738354 -211.760054)
					(mid 139.701157 -211.670251)
					(end 139.611354 -211.633054)
				)
				(arc
					(start 138.188954 -211.633054)
					(mid 138.099151 -211.670251)
					(end 138.061954 -211.760054)
				)
				(arc
					(start 138.061954 -213.080854)
					(mid 138.099151 -213.170657)
					(end 138.188954 -213.207854)
				)
				(xy 138.595354 -213.207854) (xy 138.595608 -213.2076) (xy 139.196826 -213.2076) (xy 139.204954 -213.207854)
				(arc
					(start 139.611354 -213.207854)
					(mid 139.701157 -213.170657)
					(end 139.738354 -213.080854)
				)
			)
		)
		(polygon
			(pts
				(arc
					(start 108.938314 -211.760054)
					(mid 108.901117 -211.670251)
					(end 108.811314 -211.633054)
				)
				(arc
					(start 107.388914 -211.633054)
					(mid 107.299111 -211.670251)
					(end 107.261914 -211.760054)
				)
				(arc
					(start 107.261914 -213.080854)
					(mid 107.299111 -213.170657)
					(end 107.388914 -213.207854)
				)
				(xy 107.795314 -213.207854) (xy 107.795568 -213.2076) (xy 108.396786 -213.2076) (xy 108.404914 -213.207854)
				(arc
					(start 108.811314 -213.207854)
					(mid 108.901117 -213.170657)
					(end 108.938314 -213.080854)
				)
			)
		)
		(polygon
			(pts
				(arc
					(start 105.738422 -211.760054)
					(mid 105.701225 -211.670251)
					(end 105.611422 -211.633054)
				)
				(arc
					(start 104.189022 -211.633054)
					(mid 104.099219 -211.670251)
					(end 104.062022 -211.760054)
				)
				(arc
					(start 104.062022 -213.080854)
					(mid 104.099219 -213.170657)
					(end 104.189022 -213.207854)
				)
				(xy 104.595422 -213.207854) (xy 104.595676 -213.2076) (xy 105.196894 -213.2076) (xy 105.205022 -213.207854)
				(arc
					(start 105.611422 -213.207854)
					(mid 105.701225 -213.170657)
					(end 105.738422 -213.080854)
				)
			)
		)
		(polygon
			(pts
				(arc
					(start 102.538276 -211.760054)
					(mid 102.501079 -211.670251)
					(end 102.411276 -211.633054)
				)
				(arc
					(start 100.988876 -211.633054)
					(mid 100.899073 -211.670251)
					(end 100.861876 -211.760054)
				)
				(arc
					(start 100.861876 -213.080854)
					(mid 100.899073 -213.170657)
					(end 100.988876 -213.207854)
				)
				(xy 101.395276 -213.207854) (xy 101.39553 -213.2076) (xy 101.996748 -213.2076) (xy 102.004876 -213.207854)
				(arc
					(start 102.411276 -213.207854)
					(mid 102.501079 -213.170657)
					(end 102.538276 -213.080854)
				)
			)
		)
		(polygon
			(pts
				(arc
					(start 99.338384 -211.760054)
					(mid 99.301187 -211.670251)
					(end 99.211384 -211.633054)
				)
				(arc
					(start 97.788984 -211.633054)
					(mid 97.699181 -211.670251)
					(end 97.661984 -211.760054)
				)
				(arc
					(start 97.661984 -213.080854)
					(mid 97.699181 -213.170657)
					(end 97.788984 -213.207854)
				)
				(xy 98.195384 -213.207854) (xy 98.195638 -213.2076) (xy 98.796856 -213.2076) (xy 98.804984 -213.207854)
				(arc
					(start 99.211384 -213.207854)
					(mid 99.301187 -213.170657)
					(end 99.338384 -213.080854)
				)
			)
		)
		(polygon
			(pts
				(arc
					(start 93.738192 -211.760054)
					(mid 93.700995 -211.670251)
					(end 93.611192 -211.633054)
				)
				(arc
					(start 92.188792 -211.633054)
					(mid 92.098989 -211.670251)
					(end 92.061792 -211.760054)
				)
				(arc
					(start 92.061792 -213.080854)
					(mid 92.098989 -213.170657)
					(end 92.188792 -213.207854)
				)
				(xy 92.595192 -213.207854) (xy 92.595446 -213.2076) (xy 93.196664 -213.2076) (xy 93.204792 -213.207854)
				(arc
					(start 93.611192 -213.207854)
					(mid 93.700995 -213.170657)
					(end 93.738192 -213.080854)
				)
			)
		)
		(polygon
			(pts
				(arc
					(start 90.5383 -211.760054)
					(mid 90.501103 -211.670251)
					(end 90.4113 -211.633054)
				)
				(arc
					(start 88.9889 -211.633054)
					(mid 88.899097 -211.670251)
					(end 88.8619 -211.760054)
				)
				(arc
					(start 88.8619 -213.080854)
					(mid 88.899097 -213.170657)
					(end 88.9889 -213.207854)
				)
				(xy 89.3953 -213.207854) (xy 89.395554 -213.2076) (xy 89.996772 -213.2076) (xy 90.0049 -213.207854)
				(arc
					(start 90.4113 -213.207854)
					(mid 90.501103 -213.170657)
					(end 90.5383 -213.080854)
				)
			)
		)
		(polygon
			(pts
				(arc
					(start 87.338154 -211.760054)
					(mid 87.300957 -211.670251)
					(end 87.211154 -211.633054)
				)
				(arc
					(start 85.788754 -211.633054)
					(mid 85.698951 -211.670251)
					(end 85.661754 -211.760054)
				)
				(arc
					(start 85.661754 -213.080854)
					(mid 85.698951 -213.170657)
					(end 85.788754 -213.207854)
				)
				(xy 86.195154 -213.207854) (xy 86.195408 -213.2076) (xy 86.796626 -213.2076) (xy 86.804754 -213.207854)
				(arc
					(start 87.211154 -213.207854)
					(mid 87.300957 -213.170657)
					(end 87.338154 -213.080854)
				)
			)
		)
		(polygon
			(pts
				(arc
					(start 84.138262 -211.760054)
					(mid 84.101065 -211.670251)
					(end 84.011262 -211.633054)
				)
				(arc
					(start 82.588862 -211.633054)
					(mid 82.499059 -211.670251)
					(end 82.461862 -211.760054)
				)
				(arc
					(start 82.461862 -213.080854)
					(mid 82.499059 -213.170657)
					(end 82.588862 -213.207854)
				)
				(xy 82.995262 -213.207854) (xy 82.995516 -213.2076) (xy 83.596734 -213.2076) (xy 83.604862 -213.207854)
				(arc
					(start 84.011262 -213.207854)
					(mid 84.101065 -213.170657)
					(end 84.138262 -213.080854)
				)
			)
		)
		(polygon
			(pts
				(arc
					(start 80.938116 -211.760054)
					(mid 80.900919 -211.670251)
					(end 80.811116 -211.633054)
				)
				(arc
					(start 79.388716 -211.633054)
					(mid 79.298913 -211.670251)
					(end 79.261716 -211.760054)
				)
				(arc
					(start 79.261716 -213.080854)
					(mid 79.298913 -213.170657)
					(end 79.388716 -213.207854)
				)
				(xy 79.795116 -213.207854) (xy 79.79537 -213.2076) (xy 80.396588 -213.2076) (xy 80.404716 -213.207854)
				(arc
					(start 80.811116 -213.207854)
					(mid 80.900919 -213.170657)
					(end 80.938116 -213.080854)
				)
			)
		)
		(polygon
			(pts
				(arc
					(start 71.338186 -211.760054)
					(mid 71.300989 -211.670251)
					(end 71.211186 -211.633054)
				)
				(arc
					(start 69.788786 -211.633054)
					(mid 69.698983 -211.670251)
					(end 69.661786 -211.760054)
				)
				(arc
					(start 69.661786 -213.080854)
					(mid 69.698983 -213.170657)
					(end 69.788786 -213.207854)
				)
				(xy 70.195186 -213.207854) (xy 70.19544 -213.2076) (xy 70.796658 -213.2076) (xy 70.804786 -213.207854)
				(arc
					(start 71.211186 -213.207854)
					(mid 71.300989 -213.170657)
					(end 71.338186 -213.080854)
				)
			)
		)
		(polygon
			(pts
				(arc
					(start 68.138294 -211.760054)
					(mid 68.101097 -211.670251)
					(end 68.011294 -211.633054)
				)
				(arc
					(start 66.588894 -211.633054)
					(mid 66.499091 -211.670251)
					(end 66.461894 -211.760054)
				)
				(arc
					(start 66.461894 -213.080854)
					(mid 66.499091 -213.170657)
					(end 66.588894 -213.207854)
				)
				(xy 66.995294 -213.207854) (xy 66.995548 -213.2076) (xy 67.596766 -213.2076) (xy 67.604894 -213.207854)
				(arc
					(start 68.011294 -213.207854)
					(mid 68.101097 -213.170657)
					(end 68.138294 -213.080854)
				)
			)
		)
		(polygon
			(pts
				(arc
					(start 64.938148 -211.760054)
					(mid 64.900951 -211.670251)
					(end 64.811148 -211.633054)
				)
				(arc
					(start 63.388748 -211.633054)
					(mid 63.298945 -211.670251)
					(end 63.261748 -211.760054)
				)
				(arc
					(start 63.261748 -213.080854)
					(mid 63.298945 -213.170657)
					(end 63.388748 -213.207854)
				)
				(xy 63.795148 -213.207854) (xy 63.795402 -213.2076) (xy 64.39662 -213.2076) (xy 64.404748 -213.207854)
				(arc
					(start 64.811148 -213.207854)
					(mid 64.900951 -213.170657)
					(end 64.938148 -213.080854)
				)
			)
		)
		(polygon
			(pts
				(arc
					(start 59.33821 -211.760054)
					(mid 59.301013 -211.670251)
					(end 59.21121 -211.633054)
				)
				(arc
					(start 57.78881 -211.633054)
					(mid 57.699007 -211.670251)
					(end 57.66181 -211.760054)
				)
				(arc
					(start 57.66181 -213.080854)
					(mid 57.699007 -213.170657)
					(end 57.78881 -213.207854)
				)
				(xy 58.19521 -213.207854) (xy 58.195464 -213.2076) (xy 58.796682 -213.2076) (xy 58.80481 -213.207854)
				(arc
					(start 59.21121 -213.207854)
					(mid 59.301013 -213.170657)
					(end 59.33821 -213.080854)
				)
			)
		)
		(polygon
			(pts
				(arc
					(start 56.138318 -211.760054)
					(mid 56.101121 -211.670251)
					(end 56.011318 -211.633054)
				)
				(arc
					(start 54.588918 -211.633054)
					(mid 54.499115 -211.670251)
					(end 54.461918 -211.760054)
				)
				(arc
					(start 54.461918 -213.080854)
					(mid 54.499115 -213.170657)
					(end 54.588918 -213.207854)
				)
				(xy 54.995318 -213.207854) (xy 54.995572 -213.2076) (xy 55.59679 -213.2076) (xy 55.604918 -213.207854)
				(arc
					(start 56.011318 -213.207854)
					(mid 56.101121 -213.170657)
					(end 56.138318 -213.080854)
				)
			)
		)
		(polygon
			(pts
				(arc
					(start 52.938172 -211.760054)
					(mid 52.900975 -211.670251)
					(end 52.811172 -211.633054)
				)
				(arc
					(start 51.388772 -211.633054)
					(mid 51.298969 -211.670251)
					(end 51.261772 -211.760054)
				)
				(arc
					(start 51.261772 -213.080854)
					(mid 51.298969 -213.170657)
					(end 51.388772 -213.207854)
				)
				(xy 51.795172 -213.207854) (xy 51.795426 -213.2076) (xy 52.396644 -213.2076) (xy 52.404772 -213.207854)
				(arc
					(start 52.811172 -213.207854)
					(mid 52.900975 -213.170657)
					(end 52.938172 -213.080854)
				)
			)
		)
		(polygon
			(pts
				(arc
					(start 49.73828 -211.760054)
					(mid 49.701083 -211.670251)
					(end 49.61128 -211.633054)
				)
				(arc
					(start 48.18888 -211.633054)
					(mid 48.099077 -211.670251)
					(end 48.06188 -211.760054)
				)
				(arc
					(start 48.06188 -213.080854)
					(mid 48.099077 -213.170657)
					(end 48.18888 -213.207854)
				)
				(xy 48.59528 -213.207854) (xy 48.595534 -213.2076) (xy 49.196752 -213.2076) (xy 49.20488 -213.207854)
				(arc
					(start 49.61128 -213.207854)
					(mid 49.701083 -213.170657)
					(end 49.73828 -213.080854)
				)
			)
		)
		(polygon
			(pts
				(arc
					(start 342.906604 -211.406994)
					(mid 343.41689 -210.896327)
					(end 342.90635 -210.385914)
				)
				(arc
					(start 342.09355 -210.385914)
					(mid 341.58301 -210.896454)
					(end 342.09355 -211.406994)
				)
			)
		)
		(polygon
			(pts
				(arc
					(start 339.706712 -211.406994)
					(mid 340.216998 -210.896327)
					(end 339.706458 -210.385914)
				)
				(arc
					(start 338.893658 -210.385914)
					(mid 338.383118 -210.896454)
					(end 338.893658 -211.406994)
				)
			)
		)
		(polygon
			(pts
				(arc
					(start 336.506566 -211.406994)
					(mid 337.017106 -210.896454)
					(end 336.506566 -210.385914)
				)
				(arc
					(start 335.693512 -210.385914)
					(mid 335.183226 -210.896581)
					(end 335.693766 -211.406994)
				)
			)
		)
		(polygon
			(pts
				(arc
					(start 333.306674 -211.406994)
					(mid 333.817214 -210.896454)
					(end 333.306674 -210.385914)
				)
				(arc
					(start 332.49362 -210.385914)
					(mid 331.983334 -210.896581)
					(end 332.493874 -211.406994)
				)
			)
		)
		(polygon
			(pts
				(arc
					(start 326.906382 -211.406994)
					(mid 327.416922 -210.896454)
					(end 326.906382 -210.385914)
				)
				(arc
					(start 326.093328 -210.385914)
					(mid 325.583042 -210.896581)
					(end 326.093582 -211.406994)
				)
			)
		)
		(polygon
			(pts
				(arc
					(start 323.70649 -211.406994)
					(mid 324.21703 -210.896454)
					(end 323.70649 -210.385914)
				)
				(arc
					(start 322.893436 -210.385914)
					(mid 322.38315 -210.896581)
					(end 322.89369 -211.406994)
				)
			)
		)
		(polygon
			(pts
				(arc
					(start 320.506598 -211.406994)
					(mid 321.017138 -210.896454)
					(end 320.506598 -210.385914)
				)
				(arc
					(start 319.693544 -210.385914)
					(mid 319.183258 -210.896581)
					(end 319.693798 -211.406994)
				)
			)
		)
		(polygon
			(pts
				(arc
					(start 317.306706 -211.406994)
					(mid 317.817246 -210.896454)
					(end 317.306706 -210.385914)
				)
				(arc
					(start 316.493652 -210.385914)
					(mid 315.983366 -210.896581)
					(end 316.493906 -211.406994)
				)
			)
		)
		(polygon
			(pts
				(arc
					(start 314.10656 -211.406994)
					(mid 314.6171 -210.896454)
					(end 314.10656 -210.385914)
				)
				(arc
					(start 313.293506 -210.385914)
					(mid 312.78322 -210.896581)
					(end 313.29376 -211.406994)
				)
			)
		)
		(polygon
			(pts
				(arc
					(start 310.906922 -211.406994)
					(mid 311.417208 -210.896327)
					(end 310.906668 -210.385914)
				)
				(arc
					(start 310.093868 -210.385914)
					(mid 309.583328 -210.896454)
					(end 310.093868 -211.406994)
				)
			)
		)
		(polygon
			(pts
				(arc
					(start 302.90643 -211.406994)
					(mid 303.41697 -210.896454)
					(end 302.90643 -210.385914)
				)
				(arc
					(start 302.093376 -210.385914)
					(mid 301.58309 -210.896581)
					(end 302.09363 -211.406994)
				)
			)
		)
		(polygon
			(pts
				(arc
					(start 299.706538 -211.406994)
					(mid 300.217078 -210.896454)
					(end 299.706538 -210.385914)
				)
				(arc
					(start 298.893484 -210.385914)
					(mid 298.383198 -210.896581)
					(end 298.893738 -211.406994)
				)
			)
		)
		(polygon
			(pts
				(arc
					(start 294.106346 -211.406994)
					(mid 294.616886 -210.896454)
					(end 294.106346 -210.385914)
				)
				(arc
					(start 293.293292 -210.385914)
					(mid 292.783006 -210.896581)
					(end 293.293546 -211.406994)
				)
			)
		)
		(polygon
			(pts
				(arc
					(start 290.906454 -211.406994)
					(mid 291.416994 -210.896454)
					(end 290.906454 -210.385914)
				)
				(arc
					(start 290.0934 -210.385914)
					(mid 289.583114 -210.896581)
					(end 290.093654 -211.406994)
				)
			)
		)
		(polygon
			(pts
				(arc
					(start 287.706816 -211.406994)
					(mid 288.217102 -210.896327)
					(end 287.706562 -210.385914)
				)
				(arc
					(start 286.893762 -210.385914)
					(mid 286.383222 -210.896454)
					(end 286.893762 -211.406994)
				)
			)
		)
		(polygon
			(pts
				(arc
					(start 284.506416 -211.406994)
					(mid 285.016956 -210.896454)
					(end 284.506416 -210.385914)
				)
				(arc
					(start 283.693362 -210.385914)
					(mid 283.183076 -210.896581)
					(end 283.693616 -211.406994)
				)
			)
		)
		(polygon
			(pts
				(arc
					(start 281.306524 -211.406994)
					(mid 281.817064 -210.896454)
					(end 281.306524 -210.385914)
				)
				(arc
					(start 280.49347 -210.385914)
					(mid 279.983184 -210.896581)
					(end 280.493724 -211.406994)
				)
			)
		)
		(polygon
			(pts
				(arc
					(start 278.106378 -211.406994)
					(mid 278.616918 -210.896454)
					(end 278.106378 -210.385914)
				)
				(arc
					(start 277.293324 -210.385914)
					(mid 276.783038 -210.896581)
					(end 277.293578 -211.406994)
				)
			)
		)
		(polygon
			(pts
				(arc
					(start 274.906486 -211.406994)
					(mid 275.417026 -210.896454)
					(end 274.906486 -210.385914)
				)
				(arc
					(start 274.093432 -210.385914)
					(mid 273.583146 -210.896581)
					(end 274.093686 -211.406994)
				)
			)
		)
		(polygon
			(pts
				(arc
					(start 271.706594 -211.406994)
					(mid 272.217134 -210.896454)
					(end 271.706594 -210.385914)
				)
				(arc
					(start 270.89354 -210.385914)
					(mid 270.383254 -210.896581)
					(end 270.893794 -211.406994)
				)
			)
		)
		(polygon
			(pts
				(arc
					(start 268.506448 -211.406994)
					(mid 269.016988 -210.896454)
					(end 268.506448 -210.385914)
				)
				(arc
					(start 267.693394 -210.385914)
					(mid 267.183108 -210.896581)
					(end 267.693648 -211.406994)
				)
			)
		)
		(polygon
			(pts
				(arc
					(start 265.306556 -211.406994)
					(mid 265.817096 -210.896454)
					(end 265.306556 -210.385914)
				)
				(arc
					(start 264.493502 -210.385914)
					(mid 263.983216 -210.896581)
					(end 264.493756 -211.406994)
				)
			)
		)
		(polygon
			(pts
				(arc
					(start 216.906348 -211.406994)
					(mid 217.416888 -210.896454)
					(end 216.906348 -210.385914)
				)
				(arc
					(start 216.093294 -210.385914)
					(mid 215.583008 -210.896581)
					(end 216.093548 -211.406994)
				)
			)
		)
		(polygon
			(pts
				(arc
					(start 213.706456 -211.406994)
					(mid 214.216996 -210.896454)
					(end 213.706456 -210.385914)
				)
				(arc
					(start 212.893402 -210.385914)
					(mid 212.383116 -210.896581)
					(end 212.893656 -211.406994)
				)
			)
		)
		(polygon
			(pts
				(arc
					(start 207.306418 -211.406994)
					(mid 207.816958 -210.896454)
					(end 207.306418 -210.385914)
				)
				(arc
					(start 206.493364 -210.385914)
					(mid 205.983078 -210.896581)
					(end 206.493618 -211.406994)
				)
			)
		)
		(polygon
			(pts
				(arc
					(start 204.106526 -211.406994)
					(mid 204.617066 -210.896454)
					(end 204.106526 -210.385914)
				)
				(arc
					(start 203.293472 -210.385914)
					(mid 202.783186 -210.896581)
					(end 203.293726 -211.406994)
				)
			)
		)
		(polygon
			(pts
				(arc
					(start 200.90638 -211.406994)
					(mid 201.41692 -210.896454)
					(end 200.90638 -210.385914)
				)
				(arc
					(start 200.093326 -210.385914)
					(mid 199.58304 -210.896581)
					(end 200.09358 -211.406994)
				)
			)
		)
		(polygon
			(pts
				(arc
					(start 197.706488 -211.406994)
					(mid 198.217028 -210.896454)
					(end 197.706488 -210.385914)
				)
				(arc
					(start 196.893434 -210.385914)
					(mid 196.383148 -210.896581)
					(end 196.893688 -211.406994)
				)
			)
		)
		(polygon
			(pts
				(arc
					(start 194.506596 -211.406994)
					(mid 195.017136 -210.896454)
					(end 194.506596 -210.385914)
				)
				(arc
					(start 193.693542 -210.385914)
					(mid 193.183256 -210.896581)
					(end 193.693796 -211.406994)
				)
			)
		)
		(polygon
			(pts
				(arc
					(start 191.30645 -211.406994)
					(mid 191.81699 -210.896454)
					(end 191.30645 -210.385914)
				)
				(arc
					(start 190.493396 -210.385914)
					(mid 189.98311 -210.896581)
					(end 190.49365 -211.406994)
				)
			)
		)
		(polygon
			(pts
				(arc
					(start 188.106558 -211.406994)
					(mid 188.617098 -210.896454)
					(end 188.106558 -210.385914)
				)
				(arc
					(start 187.293504 -210.385914)
					(mid 186.783218 -210.896581)
					(end 187.293758 -211.406994)
				)
			)
		)
		(polygon
			(pts
				(arc
					(start 184.906412 -211.406994)
					(mid 185.416952 -210.896454)
					(end 184.906412 -210.385914)
				)
				(arc
					(start 184.093358 -210.385914)
					(mid 183.583072 -210.896581)
					(end 184.093612 -211.406994)
				)
			)
		)
		(polygon
			(pts
				(arc
					(start 176.906428 -211.406994)
					(mid 177.416968 -210.896454)
					(end 176.906428 -210.385914)
				)
				(arc
					(start 176.093374 -210.385914)
					(mid 175.583088 -210.896581)
					(end 176.093628 -211.406994)
				)
			)
		)
		(polygon
			(pts
				(arc
					(start 173.706536 -211.406994)
					(mid 174.217076 -210.896454)
					(end 173.706536 -210.385914)
				)
				(arc
					(start 172.893482 -210.385914)
					(mid 172.383196 -210.896581)
					(end 172.893736 -211.406994)
				)
			)
		)
		(polygon
			(pts
				(arc
					(start 170.50639 -211.406994)
					(mid 171.01693 -210.896454)
					(end 170.50639 -210.385914)
				)
				(arc
					(start 169.693336 -210.385914)
					(mid 169.18305 -210.896581)
					(end 169.69359 -211.406994)
				)
			)
		)
		(polygon
			(pts
				(arc
					(start 167.306498 -211.406994)
					(mid 167.817038 -210.896454)
					(end 167.306498 -210.385914)
				)
				(arc
					(start 166.493444 -210.385914)
					(mid 165.983158 -210.896581)
					(end 166.493698 -211.406994)
				)
			)
		)
		(polygon
			(pts
				(arc
					(start 161.70656 -211.406994)
					(mid 162.2171 -210.896454)
					(end 161.70656 -210.385914)
				)
				(arc
					(start 160.893506 -210.385914)
					(mid 160.38322 -210.896581)
					(end 160.89376 -211.406994)
				)
			)
		)
		(polygon
			(pts
				(arc
					(start 158.506668 -211.406994)
					(mid 159.017208 -210.896454)
					(end 158.506668 -210.385914)
				)
				(arc
					(start 157.693614 -210.385914)
					(mid 157.183328 -210.896581)
					(end 157.693868 -211.406994)
				)
			)
		)
		(polygon
			(pts
				(arc
					(start 155.306522 -211.406994)
					(mid 155.817062 -210.896454)
					(end 155.306522 -210.385914)
				)
				(arc
					(start 154.493468 -210.385914)
					(mid 153.983182 -210.896581)
					(end 154.493722 -211.406994)
				)
			)
		)
		(polygon
			(pts
				(arc
					(start 152.10663 -211.406994)
					(mid 152.61717 -210.896454)
					(end 152.10663 -210.385914)
				)
				(arc
					(start 151.293576 -210.385914)
					(mid 150.78329 -210.896581)
					(end 151.29383 -211.406994)
				)
			)
		)
		(polygon
			(pts
				(arc
					(start 148.906484 -211.406994)
					(mid 149.417024 -210.896454)
					(end 148.906484 -210.385914)
				)
				(arc
					(start 148.09343 -210.385914)
					(mid 147.583144 -210.896581)
					(end 148.093684 -211.406994)
				)
			)
		)
		(polygon
			(pts
				(arc
					(start 145.706592 -211.406994)
					(mid 146.217132 -210.896454)
					(end 145.706592 -210.385914)
				)
				(arc
					(start 144.893538 -210.385914)
					(mid 144.383252 -210.896581)
					(end 144.893792 -211.406994)
				)
			)
		)
		(polygon
			(pts
				(arc
					(start 142.5067 -211.406994)
					(mid 143.01724 -210.896454)
					(end 142.5067 -210.385914)
				)
				(arc
					(start 141.693646 -210.385914)
					(mid 141.18336 -210.896581)
					(end 141.6939 -211.406994)
				)
			)
		)
		(polygon
			(pts
				(arc
					(start 139.306554 -211.406994)
					(mid 139.817094 -210.896454)
					(end 139.306554 -210.385914)
				)
				(arc
					(start 138.4935 -210.385914)
					(mid 137.983214 -210.896581)
					(end 138.493754 -211.406994)
				)
			)
		)
		(polygon
			(pts
				(arc
					(start 108.506514 -211.406994)
					(mid 109.017054 -210.896454)
					(end 108.506514 -210.385914)
				)
				(arc
					(start 107.69346 -210.385914)
					(mid 107.183174 -210.896581)
					(end 107.693714 -211.406994)
				)
			)
		)
		(polygon
			(pts
				(arc
					(start 105.306622 -211.406994)
					(mid 105.817162 -210.896454)
					(end 105.306622 -210.385914)
				)
				(arc
					(start 104.493568 -210.385914)
					(mid 103.983282 -210.896581)
					(end 104.493822 -211.406994)
				)
			)
		)
		(polygon
			(pts
				(arc
					(start 102.10673 -211.406994)
					(mid 102.617016 -210.896327)
					(end 102.106476 -210.385914)
				)
				(arc
					(start 101.293676 -210.385914)
					(mid 100.783136 -210.896454)
					(end 101.293676 -211.406994)
				)
			)
		)
		(polygon
			(pts
				(arc
					(start 98.906584 -211.406994)
					(mid 99.417124 -210.896454)
					(end 98.906584 -210.385914)
				)
				(arc
					(start 98.09353 -210.385914)
					(mid 97.583244 -210.896581)
					(end 98.093784 -211.406994)
				)
			)
		)
		(polygon
			(pts
				(arc
					(start 93.306392 -211.406994)
					(mid 93.816932 -210.896454)
					(end 93.306392 -210.385914)
				)
				(arc
					(start 92.493338 -210.385914)
					(mid 91.983052 -210.896581)
					(end 92.493592 -211.406994)
				)
			)
		)
		(polygon
			(pts
				(arc
					(start 90.1065 -211.406994)
					(mid 90.61704 -210.896454)
					(end 90.1065 -210.385914)
				)
				(arc
					(start 89.293446 -210.385914)
					(mid 88.78316 -210.896581)
					(end 89.2937 -211.406994)
				)
			)
		)
		(polygon
			(pts
				(arc
					(start 86.906354 -211.406994)
					(mid 87.416894 -210.896454)
					(end 86.906354 -210.385914)
				)
				(arc
					(start 86.0933 -210.385914)
					(mid 85.583014 -210.896581)
					(end 86.093554 -211.406994)
				)
			)
		)
		(polygon
			(pts
				(arc
					(start 83.706462 -211.406994)
					(mid 84.217002 -210.896454)
					(end 83.706462 -210.385914)
				)
				(arc
					(start 82.893408 -210.385914)
					(mid 82.383122 -210.896581)
					(end 82.893662 -211.406994)
				)
			)
		)
		(polygon
			(pts
				(arc
					(start 80.506316 -211.406994)
					(mid 81.016856 -210.896454)
					(end 80.506316 -210.385914)
				)
				(arc
					(start 79.693262 -210.385914)
					(mid 79.182976 -210.896581)
					(end 79.693516 -211.406994)
				)
			)
		)
		(polygon
			(pts
				(arc
					(start 70.906386 -211.406994)
					(mid 71.416926 -210.896454)
					(end 70.906386 -210.385914)
				)
				(arc
					(start 70.093332 -210.385914)
					(mid 69.583046 -210.896581)
					(end 70.093586 -211.406994)
				)
			)
		)
		(polygon
			(pts
				(arc
					(start 67.706494 -211.406994)
					(mid 68.217034 -210.896454)
					(end 67.706494 -210.385914)
				)
				(arc
					(start 66.89344 -210.385914)
					(mid 66.383154 -210.896581)
					(end 66.893694 -211.406994)
				)
			)
		)
		(polygon
			(pts
				(arc
					(start 64.506348 -211.406994)
					(mid 65.016888 -210.896454)
					(end 64.506348 -210.385914)
				)
				(arc
					(start 63.693294 -210.385914)
					(mid 63.183008 -210.896581)
					(end 63.693548 -211.406994)
				)
			)
		)
		(polygon
			(pts
				(arc
					(start 58.90641 -211.406994)
					(mid 59.41695 -210.896454)
					(end 58.90641 -210.385914)
				)
				(arc
					(start 58.093356 -210.385914)
					(mid 57.58307 -210.896581)
					(end 58.09361 -211.406994)
				)
			)
		)
		(polygon
			(pts
				(arc
					(start 55.706772 -211.406994)
					(mid 56.217058 -210.896327)
					(end 55.706518 -210.385914)
				)
				(arc
					(start 54.893718 -210.385914)
					(mid 54.383178 -210.896454)
					(end 54.893718 -211.406994)
				)
			)
		)
		(polygon
			(pts
				(arc
					(start 52.506372 -211.406994)
					(mid 53.016912 -210.896454)
					(end 52.506372 -210.385914)
				)
				(arc
					(start 51.693318 -210.385914)
					(mid 51.183032 -210.896581)
					(end 51.693572 -211.406994)
				)
			)
		)
		(polygon
			(pts
				(arc
					(start 49.30648 -211.406994)
					(mid 49.81702 -210.896454)
					(end 49.30648 -210.385914)
				)
				(arc
					(start 48.493426 -210.385914)
					(mid 47.98314 -210.896581)
					(end 48.49368 -211.406994)
				)
			)
		)
		(polygon
			(pts
				(arc
					(start 50.95748 -209.222594)
					(mid 51.46802 -208.712054)
					(end 50.95748 -208.201514)
				)
				(arc
					(start 50.144426 -208.201514)
					(mid 49.63414 -208.712181)
					(end 50.14468 -209.222594)
				)
			)
		)
		(polygon
			(pts
				(arc
					(start 58.8645 -196.77634)
					(mid 59.37504 -196.2658)
					(end 58.8645 -195.75526)
				)
				(arc
					(start 58.051446 -195.75526)
					(mid 57.54116 -196.265927)
					(end 58.0517 -196.77634)
				)
			)
		)
		(polygon
			(pts
				(arc
					(start 92.332048 -184.941718)
					(mid 91.61018 -184.941718)
					(end 91.61018 -185.663586)
				)
				(xy 91.608402 -185.665364) (xy 92.18295 -186.240166) (xy 92.183204 -186.240166)
				(arc
					(start 92.184982 -186.238388)
					(mid 92.90685 -186.238388)
					(end 92.90685 -185.51652)
				)
				(xy 92.908628 -185.514742) (xy 92.333826 -184.93994)
			)
		)
		(polygon
			(pts
				(arc
					(start 94.202504 -184.15254)
					(mid 94.71279 -183.641873)
					(end 94.20225 -183.13146)
				)
				(arc
					(start 93.38945 -183.13146)
					(mid 92.87891 -183.642)
					(end 93.38945 -184.15254)
				)
			)
		)
		(polygon
			(pts
				(xy 15.318994 -177.9905) (xy 8.049006 -177.9905) (xy 6.9215 -179.118006) (xy 6.9215 -181.561994)
				(xy 7.668006 -182.3085) (xy 9.065006 -182.3085) (xy 10.208006 -183.4515) (xy 12.113006 -183.4515)
				(xy 12.2555 -183.593994) (xy 12.2555 -184.452006) (xy 11.6205 -185.087006) (xy 11.6205 -186.865006)
				(xy 10.970006 -187.5155) (xy 9.954006 -187.5155) (xy 8.557006 -188.9125) (xy 6.017006 -188.9125)
				(xy 5.2705 -189.659006) (xy 5.2705 -195.658994) (xy 8.938006 -199.3265) (xy 22.811994 -199.3265)
				(xy 24.8285 -197.309994) (xy 24.8285 -187.627006) (xy 23.573994 -186.3725) (xy 19.225006 -186.3725)
				(xy 18.336006 -187.2615) (xy 15.826994 -187.2615) (xy 15.6845 -187.119006) (xy 15.6845 -185.214006)
				(xy 15.318994 -184.8485) (xy 14.937994 -184.8485) (xy 14.7955 -184.706006) (xy 14.7955 -183.466994)
				(xy 16.4465 -181.815994) (xy 16.4465 -179.118006)
			)
		)
		(polygon
			(pts
				(xy 25.809194 -144.6657) (xy 23.974806 -144.6657) (xy 23.3045 -145.336006) (xy 23.3045 -149.583394)
				(xy 23.568406 -149.8473) (xy 26.418794 -149.8473) (xy 26.7081 -149.557994) (xy 26.7081 -145.564606)
			)
		)
		(polygon
			(pts
				(arc
					(start 28.4226 -142.4432)
					(mid 28.385403 -142.353397)
					(end 28.2956 -142.3162)
				)
				(arc
					(start 27.0764 -142.3162)
					(mid 26.986597 -142.353397)
					(end 26.9494 -142.4432)
				)
				(arc
					(start 26.9494 -143.8148)
					(mid 26.986597 -143.904603)
					(end 27.0764 -143.9418)
				)
				(arc
					(start 28.2956 -143.9418)
					(mid 28.385403 -143.904603)
					(end 28.4226 -143.8148)
				)
				(xy 28.4226 -142.804134) (xy 28.4226 -142.7988)
			)
		)
		(polygon
			(pts
				(arc
					(start 26.74112 -142.580106)
					(mid 26.128853 -141.96822)
					(end 25.51684 -142.58036)
				)
				(arc
					(start 25.51684 -143.69796)
					(mid 26.12898 -144.3101)
					(end 26.74112 -143.69796)
				)
			)
		)
		(polygon
			(pts
				(arc
					(start 54.4322 -127.3302)
					(mid 54.402442 -127.258358)
					(end 54.3306 -127.2286)
				)
				(arc
					(start 53.1114 -127.2286)
					(mid 53.039558 -127.258358)
					(end 53.0098 -127.3302)
				)
				(arc
					(start 53.0098 -128.70434)
					(mid 53.039558 -128.776182)
					(end 53.1114 -128.80594)
				)
				(arc
					(start 54.3306 -128.80594)
					(mid 54.402442 -128.776182)
					(end 54.4322 -128.70434)
				)
			)
		)
		(polygon
			(pts
				(arc
					(start 66.143378 -128.189736)
					(mid 66.653918 -127.679196)
					(end 66.143378 -127.168656)
				)
				(arc
					(start 65.330324 -127.168656)
					(mid 64.820038 -127.679323)
					(end 65.330578 -128.189736)
				)
			)
		)
		(polygon
			(pts
				(arc
					(start 24.75738 -125.934978)
					(mid 24.741757 -125.897261)
					(end 24.70404 -125.881638)
				)
				(arc
					(start 24.50084 -125.881638)
					(mid 24.463123 -125.897261)
					(end 24.4475 -125.934978)
				)
				(arc
					(start 24.4475 -126.188978)
					(mid 24.463123 -126.226695)
					(end 24.50084 -126.242318)
				)
				(arc
					(start 24.70404 -126.242318)
					(mid 24.741757 -126.226695)
					(end 24.75738 -126.188978)
				)
			)
		)
		(polygon
			(pts
				(arc
					(start 24.75738 -125.376178)
					(mid 24.741757 -125.338461)
					(end 24.70404 -125.322838)
				)
				(arc
					(start 24.50084 -125.322838)
					(mid 24.463123 -125.338461)
					(end 24.4475 -125.376178)
				)
				(arc
					(start 24.4475 -125.630178)
					(mid 24.463123 -125.667895)
					(end 24.50084 -125.683518)
				)
				(arc
					(start 24.70404 -125.683518)
					(mid 24.741757 -125.667895)
					(end 24.75738 -125.630178)
				)
			)
		)
		(polygon
			(pts
				(arc
					(start 23.507954 -123.2281)
					(mid 23.470757 -123.138297)
					(end 23.380954 -123.1011)
				)
				(arc
					(start 22.060154 -123.1011)
					(mid 21.970351 -123.138297)
					(end 21.933154 -123.2281)
				)
				(arc
					(start 21.933154 -124.5235)
					(mid 21.970351 -124.613303)
					(end 22.060154 -124.6505)
				)
				(arc
					(start 23.380954 -124.6505)
					(mid 23.470757 -124.613303)
					(end 23.507954 -124.5235)
				)
			)
		)
		(polygon
			(pts
				(arc
					(start 23.77694 -113.994946)
					(mid 23.164673 -113.38306)
					(end 22.55266 -113.9952)
				)
				(arc
					(start 22.55266 -115.1128)
					(mid 23.1648 -115.72494)
					(end 23.77694 -115.1128)
				)
			)
		)
		(polygon
			(pts
				(arc
					(start 25.085294 -111.4044)
					(mid 24.473154 -110.79226)
					(end 23.861014 -111.4044)
				)
				(arc
					(start 23.861014 -112.522254)
					(mid 24.473281 -113.13414)
					(end 25.085294 -112.522)
				)
			)
		)
		(polygon
			(pts
				(arc
					(start 24.676862 -109.230922)
					(mid 24.64636 -109.157284)
					(end 24.572722 -109.126782)
				)
				(arc
					(start 24.217122 -109.126782)
					(mid 24.143484 -109.157284)
					(end 24.112982 -109.230922)
				)
				(arc
					(start 24.112982 -109.586522)
					(mid 24.143484 -109.66016)
					(end 24.217122 -109.690662)
				)
				(arc
					(start 24.572722 -109.690662)
					(mid 24.64636 -109.66016)
					(end 24.676862 -109.586522)
				)
			)
		)
		(polygon
			(pts
				(arc
					(start 25.701244 -109.22762)
					(mid 25.670742 -109.153982)
					(end 25.597104 -109.12348)
				)
				(arc
					(start 25.241504 -109.12348)
					(mid 25.167866 -109.153982)
					(end 25.137364 -109.22762)
				)
				(arc
					(start 25.137364 -109.58322)
					(mid 25.167866 -109.656858)
					(end 25.241504 -109.68736)
				)
				(arc
					(start 25.597104 -109.68736)
					(mid 25.670742 -109.656858)
					(end 25.701244 -109.58322)
				)
			)
		)
		(polygon
			(pts
				(arc
					(start 27.652472 -108.255816)
					(mid 27.62197 -108.182178)
					(end 27.548332 -108.151676)
				)
				(arc
					(start 26.227532 -108.151676)
					(mid 26.153894 -108.182178)
					(end 26.123392 -108.255816)
				)
				(xy 26.123392 -109.521244) (xy 26.124408 -109.52226)
				(arc
					(start 26.124408 -109.52988)
					(mid 26.15491 -109.603518)
					(end 26.228548 -109.63402)
				)
				(arc
					(start 27.549348 -109.63402)
					(mid 27.622986 -109.603518)
					(end 27.653488 -109.52988)
				)
				(xy 27.653488 -109.12348) (xy 27.652472 -109.109002)
			)
		)
		(polygon
			(pts
				(arc
					(start 24.677624 -108.21162)
					(mid 24.647122 -108.137982)
					(end 24.573484 -108.10748)
				)
				(arc
					(start 24.217884 -108.10748)
					(mid 24.144246 -108.137982)
					(end 24.113744 -108.21162)
				)
				(arc
					(start 24.113744 -108.56722)
					(mid 24.144246 -108.640858)
					(end 24.217884 -108.67136)
				)
				(arc
					(start 24.573484 -108.67136)
					(mid 24.647122 -108.640858)
					(end 24.677624 -108.56722)
				)
			)
		)
		(polygon
			(pts
				(arc
					(start 25.702006 -108.208318)
					(mid 25.671504 -108.13468)
					(end 25.597866 -108.104178)
				)
				(arc
					(start 25.242266 -108.104178)
					(mid 25.168628 -108.13468)
					(end 25.138126 -108.208318)
				)
				(arc
					(start 25.138126 -108.563918)
					(mid 25.168628 -108.637556)
					(end 25.242266 -108.668058)
				)
				(arc
					(start 25.597866 -108.668058)
					(mid 25.671504 -108.637556)
					(end 25.702006 -108.563918)
				)
			)
		)
		(polygon
			(pts
				(arc
					(start 28.47594 -105.502202)
					(mid 27.610308 -105.502202)
					(end 27.610308 -106.367834)
				)
				(xy 27.60853 -106.369612) (xy 28.398978 -107.16006)
				(arc
					(start 28.400756 -107.158282)
					(mid 29.266388 -107.158282)
					(end 29.266388 -106.29265)
				)
				(xy 29.268166 -106.290872) (xy 28.477972 -105.500678) (xy 28.477464 -105.500678)
			)
		)
		(polygon
			(pts
				(arc
					(start 173.6344 -96.704912)
					(mid 174.14494 -96.194372)
					(end 173.6344 -95.683832)
				)
				(arc
					(start 172.745146 -95.683832)
					(mid 172.23486 -96.194499)
					(end 172.7454 -96.704912)
				)
			)
		)
		(polygon
			(pts
				(xy 155.095194 -89.5985) (xy 151.228806 -89.5985) (xy 150.8125 -90.014806) (xy 150.8125 -93.855794)
				(xy 151.051006 -94.0943) (xy 155.171394 -94.0943) (xy 155.4861 -93.779594) (xy 155.4861 -89.989406)
			)
		)
		(polygon
			(pts
				(xy 163.790122 -88.980518) (xy 162.748722 -88.980518) (xy 162.748722 -90.168222) (xy 163.790122 -90.168222)
			)
		)
		(polygon
			(pts
				(arc
					(start 166.8272 -88.3666)
					(mid 166.797442 -88.294758)
					(end 166.7256 -88.265)
				)
				(arc
					(start 165.5064 -88.265)
					(mid 165.434558 -88.294758)
					(end 165.4048 -88.3666)
				)
				(arc
					(start 165.4048 -89.7382)
					(mid 165.434558 -89.810042)
					(end 165.5064 -89.8398)
				)
				(arc
					(start 166.7256 -89.8398)
					(mid 166.797442 -89.810042)
					(end 166.8272 -89.7382)
				)
			)
		)
		(polygon
			(pts
				(arc
					(start 168.212516 -88.645746)
					(mid 167.701849 -88.13546)
					(end 167.191436 -88.646)
				)
				(arc
					(start 167.191436 -89.4588)
					(mid 167.701976 -89.96934)
					(end 168.212516 -89.4588)
				)
			)
		)
		(polygon
			(pts
				(xy 160.879536 -87.568024) (xy 160.685226 -87.568024) (xy 160.685226 -88.608662) (xy 160.879536 -88.608662)
				(xy 160.879536 -88.609678) (xy 161.878264 -88.609678) (xy 161.878264 -87.568278) (xy 160.879536 -87.568278)
			)
		)
		(polygon
			(pts
				(arc
					(start 21.209 -87.93734)
					(mid 21.71954 -87.4268)
					(end 21.209 -86.91626)
				)
				(arc
					(start 20.395946 -86.91626)
					(mid 19.88566 -87.426927)
					(end 20.3962 -87.93734)
				)
			)
		)
		(polygon
			(pts
				(arc
					(start 16.9672 -87.65794)
					(mid 17.57934 -87.0458)
					(end 16.9672 -86.43366)
				)
				(arc
					(start 15.8496 -86.43366)
					(mid 15.23746 -87.0458)
					(end 15.8496 -87.65794)
				)
			)
		)
		(polygon
			(pts
				(arc
					(start 56.86298 -85.210396)
					(mid 56.250713 -84.59851)
					(end 55.6387 -85.21065)
				)
				(arc
					(start 55.6387 -86.32825)
					(mid 56.25084 -86.94039)
					(end 56.86298 -86.32825)
				)
			)
		)
		(polygon
			(pts
				(arc
					(start 162.3822 -84.5312)
					(mid 162.370698 -84.531824)
					(end 162.35934 -84.53374)
				)
				(xy 162.3568 -84.5312)
				(arc
					(start 161.3662 -84.5312)
					(mid 161.294358 -84.560958)
					(end 161.2646 -84.6328)
				)
				(arc
					(start 161.2646 -85.852)
					(mid 161.294358 -85.923842)
					(end 161.3662 -85.9536)
				)
				(arc
					(start 162.7378 -85.9536)
					(mid 162.809642 -85.923842)
					(end 162.8394 -85.852)
				)
				(arc
					(start 162.8394 -84.6328)
					(mid 162.809642 -84.560958)
					(end 162.7378 -84.5312)
				)
			)
		)
		(polygon
			(pts
				(arc
					(start 21.8186 -83.1596)
					(mid 21.788842 -83.087758)
					(end 21.717 -83.058)
				)
				(arc
					(start 20.447 -83.058)
					(mid 20.375158 -83.087758)
					(end 20.3454 -83.1596)
				)
				(arc
					(start 20.3454 -84.4804)
					(mid 20.375158 -84.552242)
					(end 20.447 -84.582)
				)
				(arc
					(start 21.717 -84.582)
					(mid 21.788842 -84.552242)
					(end 21.8186 -84.4804)
				)
			)
		)
		(polygon
			(pts
				(xy 11.635994 -82.2579) (xy 6.144006 -82.2579) (xy 5.6261 -82.775806) (xy 5.6261 -91.366594) (xy 6.118606 -91.8591)
				(xy 7.368794 -91.8591) (xy 7.902194 -91.3257) (xy 11.305794 -91.3257) (xy 12.3317 -90.299794) (xy 12.3317 -82.953606)
			)
		)
		(polygon
			(pts
				(arc
					(start 19.664934 -82.41792)
					(mid 20.175474 -81.90738)
					(end 19.664934 -81.39684)
				)
				(arc
					(start 18.85188 -81.39684)
					(mid 18.341594 -81.907507)
					(end 18.852134 -82.41792)
				)
			)
		)
		(polygon
			(pts
				(arc
					(start 163.512754 -82.17154)
					(mid 164.02304 -81.660873)
					(end 163.5125 -81.15046)
				)
				(arc
					(start 162.6997 -81.15046)
					(mid 162.18916 -81.661)
					(end 162.6997 -82.17154)
				)
			)
		)
		(polygon
			(pts
				(arc
					(start 103.2383 -81.000346)
					(mid 102.626033 -80.38846)
					(end 102.01402 -81.0006)
				)
				(arc
					(start 102.01402 -82.1182)
					(mid 102.62616 -82.73034)
					(end 103.2383 -82.1182)
				)
			)
		)
		(polygon
			(pts
				(xy 136.121394 -80.3021) (xy 132.407406 -80.3021) (xy 132.0419 -80.667606) (xy 132.0419 -84.914994)
				(xy 132.509006 -85.3821) (xy 136.349994 -85.3821) (xy 136.6393 -85.092794) (xy 136.6393 -80.820006)
			)
		)
		(polygon
			(pts
				(arc
					(start 87.290148 -76.589636)
					(mid 86.779608 -76.079096)
					(end 86.269068 -76.589636)
				)
				(arc
					(start 86.269068 -77.47889)
					(mid 86.779735 -77.989176)
					(end 87.290148 -77.478636)
				)
			)
		)
		(polygon
			(pts
				(arc
					(start 16.6116 -73.727564)
					(mid 17.12214 -73.217024)
					(end 16.6116 -72.706484)
				)
				(arc
					(start 15.798546 -72.706484)
					(mid 15.28826 -73.217151)
					(end 15.7988 -73.727564)
				)
			)
		)
		(polygon
			(pts
				(arc
					(start 19.38655 -73.721214)
					(mid 19.89709 -73.210674)
					(end 19.38655 -72.700134)
				)
				(arc
					(start 18.573496 -72.700134)
					(mid 18.06321 -73.210801)
					(end 18.57375 -73.721214)
				)
			)
		)
		(polygon
			(pts
				(xy 8.968994 -67.1957) (xy 5.890006 -67.1957) (xy 5.5245 -67.561206) (xy 5.5245 -74.424794) (xy 5.915406 -74.8157)
				(xy 9.121394 -74.8157) (xy 10.4267 -73.510394) (xy 10.4267 -68.653406)
			)
		)
		(polygon
			(pts
				(arc
					(start 14.68374 -67.638168)
					(mid 14.173073 -67.127882)
					(end 13.66266 -67.638422)
				)
				(arc
					(start 13.66266 -68.451222)
					(mid 14.1732 -68.961762)
					(end 14.68374 -68.451222)
				)
			)
		)
		(polygon
			(pts
				(arc
					(start 16.69034 -66.223896)
					(mid 16.179673 -65.71361)
					(end 15.66926 -66.22415)
				)
				(arc
					(start 15.66926 -67.03695)
					(mid 16.1798 -67.54749)
					(end 16.69034 -67.03695)
				)
			)
		)
		(polygon
			(pts
				(arc
					(start 19.812 -58.851546)
					(mid 20.42414 -58.239406)
					(end 19.812 -57.627266)
				)
				(arc
					(start 18.6944 -57.627266)
					(mid 18.08226 -58.239406)
					(end 18.6944 -58.851546)
				)
			)
		)
		(polygon
			(pts
				(arc
					(start 23.535386 -57.300876)
					(mid 24.147526 -56.688736)
					(end 23.535386 -56.076596)
				)
				(arc
					(start 22.417786 -56.076596)
					(mid 21.805646 -56.688736)
					(end 22.417786 -57.300876)
				)
			)
		)
		(polygon
			(pts
				(arc
					(start 10.477754 -55.559452)
					(mid 10.98804 -55.048785)
					(end 10.4775 -54.538372)
				)
				(arc
					(start 9.6647 -54.538372)
					(mid 9.15416 -55.048912)
					(end 9.6647 -55.559452)
				)
			)
		)
		(polygon
			(pts
				(arc
					(start 19.659854 -55.508652)
					(mid 20.17014 -54.997985)
					(end 19.6596 -54.487572)
				)
				(arc
					(start 18.8468 -54.487572)
					(mid 18.33626 -54.998112)
					(end 18.8468 -55.508652)
				)
			)
		)
		(polygon
			(pts
				(arc
					(start 14.3764 -54.340252)
					(mid 14.88694 -53.829712)
					(end 14.3764 -53.319172)
				)
				(arc
					(start 13.563346 -53.319172)
					(mid 13.05306 -53.829839)
					(end 13.5636 -54.340252)
				)
			)
		)
		(polygon
			(pts
				(arc
					(start 23.368 -54.066694)
					(mid 23.87854 -53.556154)
					(end 23.368 -53.045614)
				)
				(arc
					(start 22.554946 -53.045614)
					(mid 22.04466 -53.556281)
					(end 22.5552 -54.066694)
				)
			)
		)
		(polygon
			(pts
				(arc
					(start 203.7588 -50.29454)
					(mid 204.26934 -49.784)
					(end 203.7588 -49.27346)
				)
				(arc
					(start 202.945746 -49.27346)
					(mid 202.43546 -49.784127)
					(end 202.946 -50.29454)
				)
			)
		)
		(polygon
			(pts
				(arc
					(start 201.171302 -50.339752)
					(mid 201.780139 -49.724183)
					(end 201.164444 -49.115472)
				)
				(arc
					(start 200.046844 -49.122076)
					(mid 199.43826 -49.737772)
					(end 200.053956 -50.346356)
				)
			)
		)
		(polygon
			(pts
				(arc
					(start 53.305964 -48.387508)
					(mid 53.816504 -47.876968)
					(end 53.305964 -47.366428)
				)
				(arc
					(start 52.399184 -47.366428)
					(mid 51.888898 -47.877095)
					(end 52.399438 -48.387508)
				)
			)
		)
		(polygon
			(pts
				(arc
					(start 198.429118 -45.590206)
					(mid 197.816851 -44.97832)
					(end 197.204838 -45.59046)
				)
				(arc
					(start 197.204838 -46.70806)
					(mid 197.816978 -47.3202)
					(end 198.429118 -46.70806)
				)
			)
		)
		(polygon
			(pts
				(arc
					(start 201.97318 -44.714922)
					(mid 201.36104 -44.102782)
					(end 200.7489 -44.714922)
				)
				(arc
					(start 200.7489 -45.832776)
					(mid 201.361167 -46.444662)
					(end 201.97318 -45.832522)
				)
			)
		)
		(polygon
			(pts
				(arc
					(start 132.358384 -41.604946)
					(mid 131.746117 -40.99306)
					(end 131.134104 -41.6052)
				)
				(arc
					(start 131.134104 -42.7228)
					(mid 131.746244 -43.33494)
					(end 132.358384 -42.7228)
				)
			)
		)
		(polygon
			(pts
				(arc
					(start 213.381844 -39.98976)
					(mid 213.344647 -39.899957)
					(end 213.254844 -39.86276)
				)
				(arc
					(start 211.934044 -39.86276)
					(mid 211.844241 -39.899957)
					(end 211.807044 -39.98976)
				)
				(arc
					(start 211.807044 -41.28516)
					(mid 211.844241 -41.374963)
					(end 211.934044 -41.41216)
				)
				(arc
					(start 213.254844 -41.41216)
					(mid 213.344647 -41.374963)
					(end 213.381844 -41.28516)
				)
			)
		)
		(polygon
			(pts
				(arc
					(start 306.575968 -40.31996)
					(mid 307.086254 -39.809293)
					(end 306.575714 -39.29888)
				)
				(arc
					(start 305.762914 -39.29888)
					(mid 305.252374 -39.80942)
					(end 305.762914 -40.31996)
				)
			)
		)
		(polygon
			(pts
				(arc
					(start 102.44074 -38.916356)
					(mid 101.930073 -38.40607)
					(end 101.41966 -38.91661)
				)
				(arc
					(start 101.41966 -39.80561)
					(mid 101.9302 -40.31615)
					(end 102.44074 -39.80561)
				)
			)
		)
		(polygon
			(pts
				(arc
					(start 139.3698 -39.16934)
					(mid 139.88034 -38.6588)
					(end 139.3698 -38.14826)
				)
				(arc
					(start 138.556746 -38.14826)
					(mid 138.04646 -38.658927)
					(end 138.557 -39.16934)
				)
			)
		)
		(polygon
			(pts
				(arc
					(start 151.727154 -38.59784)
					(mid 152.23744 -38.087173)
					(end 151.7269 -37.57676)
				)
				(arc
					(start 150.9141 -37.57676)
					(mid 150.40356 -38.0873)
					(end 150.9141 -38.59784)
				)
			)
		)
		(polygon
			(pts
				(arc
					(start 162.598354 -38.52164)
					(mid 163.10864 -38.010973)
					(end 162.5981 -37.50056)
				)
				(arc
					(start 161.7853 -37.50056)
					(mid 161.27476 -38.0111)
					(end 161.7853 -38.52164)
				)
			)
		)
		(polygon
			(pts
				(arc
					(start 320.53403 -37.53612)
					(mid 321.044316 -37.025453)
					(end 320.533776 -36.51504)
				)
				(arc
					(start 319.720722 -36.51504)
					(mid 319.210436 -37.025707)
					(end 319.720976 -37.53612)
				)
			)
		)
		(polygon
			(pts
				(arc
					(start 304.647854 -36.794694)
					(mid 305.15814 -36.284027)
					(end 304.6476 -35.773614)
				)
				(arc
					(start 303.8348 -35.773614)
					(mid 303.32426 -36.284154)
					(end 303.8348 -36.794694)
				)
			)
		)
		(polygon
			(pts
				(arc
					(start 103.02494 -36.205668)
					(mid 102.5144 -35.695128)
					(end 102.00386 -36.205668)
				)
				(arc
					(start 102.00386 -37.094922)
					(mid 102.514527 -37.605208)
					(end 103.02494 -37.094668)
				)
			)
		)
		(polygon
			(pts
				(arc
					(start 300.243494 -36.699952)
					(mid 300.754034 -36.189412)
					(end 300.243494 -35.678872)
				)
				(arc
					(start 299.43044 -35.678872)
					(mid 298.920154 -36.189539)
					(end 299.430694 -36.699952)
				)
			)
		)
		(polygon
			(pts
				(arc
					(start 313.489086 -36.696142)
					(mid 313.999626 -36.185602)
					(end 313.489086 -35.675062)
				)
				(arc
					(start 312.676032 -35.675062)
					(mid 312.165746 -36.185729)
					(end 312.676286 -36.696142)
				)
			)
		)
		(polygon
			(pts
				(arc
					(start 326.782176 -36.472114)
					(mid 327.292462 -35.961447)
					(end 326.781922 -35.451034)
				)
				(arc
					(start 325.969122 -35.451034)
					(mid 325.458582 -35.961574)
					(end 325.969122 -36.472114)
				)
			)
		)
		(polygon
			(pts
				(arc
					(start 134.665212 -36.250372)
					(mid 135.175498 -35.739705)
					(end 134.664958 -35.229292)
				)
				(arc
					(start 133.852158 -35.229292)
					(mid 133.341618 -35.739832)
					(end 133.852158 -36.250372)
				)
			)
		)
		(polygon
			(pts
				(arc
					(start 131.9022 -35.783774)
					(mid 132.41274 -35.273234)
					(end 131.9022 -34.762694)
				)
				(arc
					(start 131.089146 -34.762694)
					(mid 130.57886 -35.273361)
					(end 131.0894 -35.783774)
				)
			)
		)
		(polygon
			(pts
				(arc
					(start 294.971978 -35.69081)
					(mid 295.482518 -35.18027)
					(end 294.971978 -34.66973)
				)
				(arc
					(start 294.158924 -34.66973)
					(mid 293.648638 -35.180397)
					(end 294.159178 -35.69081)
				)
			)
		)
		(polygon
			(pts
				(arc
					(start 311.238646 -35.55238)
					(mid 311.748932 -35.041713)
					(end 311.238392 -34.5313)
				)
				(arc
					(start 310.425592 -34.5313)
					(mid 309.915052 -35.04184)
					(end 310.425592 -35.55238)
				)
			)
		)
		(polygon
			(pts
				(arc
					(start 302.472344 -35.536886)
					(mid 302.98263 -35.026219)
					(end 302.47209 -34.515806)
				)
				(arc
					(start 301.65929 -34.515806)
					(mid 301.14875 -35.026346)
					(end 301.65929 -35.536886)
				)
			)
		)
		(polygon
			(pts
				(arc
					(start 162.0901 -35.53206)
					(mid 162.60064 -35.02152)
					(end 162.0901 -34.51098)
				)
				(arc
					(start 161.277046 -34.51098)
					(mid 160.76676 -35.021647)
					(end 161.2773 -35.53206)
				)
			)
		)
		(polygon
			(pts
				(arc
					(start 159.467804 -35.53206)
					(mid 159.978344 -35.02152)
					(end 159.467804 -34.51098)
				)
				(arc
					(start 158.65475 -34.51098)
					(mid 158.144464 -35.021647)
					(end 158.655004 -35.53206)
				)
			)
		)
		(polygon
			(pts
				(arc
					(start 315.696854 -35.524694)
					(mid 316.20714 -35.014027)
					(end 315.6966 -34.503614)
				)
				(arc
					(start 314.8838 -34.503614)
					(mid 314.37326 -35.014154)
					(end 314.8838 -35.524694)
				)
			)
		)
		(polygon
			(pts
				(arc
					(start 290.042854 -35.524694)
					(mid 290.55314 -35.014027)
					(end 290.0426 -34.503614)
				)
				(arc
					(start 289.2298 -34.503614)
					(mid 288.71926 -35.014154)
					(end 289.2298 -35.524694)
				)
			)
		)
		(polygon
			(pts
				(arc
					(start 149.314154 -35.51174)
					(mid 149.82444 -35.001073)
					(end 149.3139 -34.49066)
				)
				(arc
					(start 148.5011 -34.49066)
					(mid 147.99056 -35.0012)
					(end 148.5011 -35.51174)
				)
			)
		)
		(polygon
			(pts
				(arc
					(start 153.530554 -35.50666)
					(mid 154.04084 -34.995993)
					(end 153.5303 -34.48558)
				)
				(arc
					(start 152.7175 -34.48558)
					(mid 152.20696 -34.99612)
					(end 152.7175 -35.50666)
				)
			)
		)
		(polygon
			(pts
				(arc
					(start 146.7231 -35.50666)
					(mid 147.23364 -34.99612)
					(end 146.7231 -34.48558)
				)
				(arc
					(start 145.910046 -34.48558)
					(mid 145.39976 -34.996247)
					(end 145.9103 -35.50666)
				)
			)
		)
		(polygon
			(pts
				(arc
					(start 138.379454 -35.503866)
					(mid 138.88974 -34.993199)
					(end 138.3792 -34.482786)
				)
				(arc
					(start 137.5664 -34.482786)
					(mid 137.05586 -34.993326)
					(end 137.5664 -35.503866)
				)
			)
		)
		(polygon
			(pts
				(arc
					(start 324.425564 -35.479482)
					(mid 324.93585 -34.968815)
					(end 324.42531 -34.458402)
				)
				(arc
					(start 323.612256 -34.458402)
					(mid 323.10197 -34.969069)
					(end 323.61251 -35.479482)
				)
			)
		)
		(polygon
			(pts
				(arc
					(start 329.188572 -35.429952)
					(mid 329.698858 -34.919285)
					(end 329.188318 -34.408872)
				)
				(arc
					(start 328.375518 -34.408872)
					(mid 327.864978 -34.919412)
					(end 328.375518 -35.429952)
				)
			)
		)
		(polygon
			(pts
				(arc
					(start 295.329864 -33.02)
					(mid 295.292667 -32.930197)
					(end 295.202864 -32.893)
				)
				(arc
					(start 293.907464 -32.893)
					(mid 293.817661 -32.930197)
					(end 293.780464 -33.02)
				)
				(arc
					(start 293.780464 -34.3408)
					(mid 293.817661 -34.430603)
					(end 293.907464 -34.4678)
				)
				(arc
					(start 295.202864 -34.4678)
					(mid 295.292667 -34.430603)
					(end 295.329864 -34.3408)
				)
			)
		)
		(polygon
			(pts
				(arc
					(start 128.358392 -32.9819)
					(mid 128.328634 -32.910058)
					(end 128.256792 -32.8803)
				)
				(arc
					(start 126.882652 -32.8803)
					(mid 126.81081 -32.910058)
					(end 126.781052 -32.9819)
				)
				(arc
					(start 126.781052 -34.2011)
					(mid 126.81081 -34.272942)
					(end 126.882652 -34.3027)
				)
				(arc
					(start 128.256792 -34.3027)
					(mid 128.328634 -34.272942)
					(end 128.358392 -34.2011)
				)
			)
		)
		(polygon
			(pts
				(arc
					(start 300.599094 -32.899858)
					(mid 300.561897 -32.810055)
					(end 300.472094 -32.772858)
				)
				(arc
					(start 299.176694 -32.772858)
					(mid 299.086891 -32.810055)
					(end 299.049694 -32.899858)
				)
				(arc
					(start 299.049694 -34.220658)
					(mid 299.086891 -34.310461)
					(end 299.176694 -34.347658)
				)
				(arc
					(start 300.472094 -34.347658)
					(mid 300.561897 -34.310461)
					(end 300.599094 -34.220658)
				)
			)
		)
		(polygon
			(pts
				(arc
					(start 313.844686 -32.896048)
					(mid 313.807489 -32.806245)
					(end 313.717686 -32.769048)
				)
				(arc
					(start 312.422286 -32.769048)
					(mid 312.332483 -32.806245)
					(end 312.295286 -32.896048)
				)
				(arc
					(start 312.295286 -34.216848)
					(mid 312.332483 -34.306651)
					(end 312.422286 -34.343848)
				)
				(arc
					(start 313.717686 -34.343848)
					(mid 313.807489 -34.306651)
					(end 313.844686 -34.216848)
				)
			)
		)
		(polygon
			(pts
				(arc
					(start 311.593992 -32.895286)
					(mid 311.556795 -32.805483)
					(end 311.466992 -32.768286)
				)
				(arc
					(start 310.171592 -32.768286)
					(mid 310.081789 -32.805483)
					(end 310.044592 -32.895286)
				)
				(arc
					(start 310.044592 -34.216086)
					(mid 310.081789 -34.305889)
					(end 310.171592 -34.343086)
				)
				(arc
					(start 311.466992 -34.343086)
					(mid 311.556795 -34.305889)
					(end 311.593992 -34.216086)
				)
			)
		)
		(polygon
			(pts
				(arc
					(start 132.2705 -32.89046)
					(mid 132.233303 -32.800657)
					(end 132.1435 -32.76346)
				)
				(arc
					(start 130.8481 -32.76346)
					(mid 130.758297 -32.800657)
					(end 130.7211 -32.89046)
				)
				(arc
					(start 130.7211 -34.21126)
					(mid 130.758297 -34.301063)
					(end 130.8481 -34.33826)
				)
				(arc
					(start 132.1435 -34.33826)
					(mid 132.233303 -34.301063)
					(end 132.2705 -34.21126)
				)
			)
		)
		(polygon
			(pts
				(arc
					(start 136.58342 -32.88792)
					(mid 136.546223 -32.798117)
					(end 136.45642 -32.76092)
				)
				(arc
					(start 135.16102 -32.76092)
					(mid 135.071217 -32.798117)
					(end 135.03402 -32.88792)
				)
				(arc
					(start 135.03402 -34.20872)
					(mid 135.071217 -34.298523)
					(end 135.16102 -34.33572)
				)
				(arc
					(start 136.45642 -34.33572)
					(mid 136.546223 -34.298523)
					(end 136.58342 -34.20872)
				)
			)
		)
		(polygon
			(pts
				(arc
					(start 302.82769 -32.879792)
					(mid 302.790493 -32.789989)
					(end 302.70069 -32.752792)
				)
				(arc
					(start 301.40529 -32.752792)
					(mid 301.315487 -32.789989)
					(end 301.27829 -32.879792)
				)
				(arc
					(start 301.27829 -34.200592)
					(mid 301.315487 -34.290395)
					(end 301.40529 -34.327592)
				)
				(arc
					(start 302.70069 -34.327592)
					(mid 302.790493 -34.290395)
					(end 302.82769 -34.200592)
				)
			)
		)
		(polygon
			(pts
				(arc
					(start 134.43204 -32.87776)
					(mid 134.394843 -32.787957)
					(end 134.30504 -32.75076)
				)
				(arc
					(start 133.00964 -32.75076)
					(mid 132.919837 -32.787957)
					(end 132.88264 -32.87776)
				)
				(arc
					(start 132.88264 -34.19856)
					(mid 132.919837 -34.288363)
					(end 133.00964 -34.32556)
				)
				(arc
					(start 134.30504 -34.32556)
					(mid 134.394843 -34.288363)
					(end 134.43204 -34.19856)
				)
			)
		)
		(polygon
			(pts
				(arc
					(start 138.73734 -32.87014)
					(mid 138.700143 -32.780337)
					(end 138.61034 -32.74314)
				)
				(arc
					(start 137.31494 -32.74314)
					(mid 137.225137 -32.780337)
					(end 137.18794 -32.87014)
				)
				(arc
					(start 137.18794 -34.19094)
					(mid 137.225137 -34.280743)
					(end 137.31494 -34.31794)
				)
				(arc
					(start 138.61034 -34.31794)
					(mid 138.700143 -34.280743)
					(end 138.73734 -34.19094)
				)
			)
		)
		(polygon
			(pts
				(arc
					(start 316.0522 -32.8676)
					(mid 316.015003 -32.777797)
					(end 315.9252 -32.7406)
				)
				(arc
					(start 314.6298 -32.7406)
					(mid 314.539997 -32.777797)
					(end 314.5028 -32.8676)
				)
				(arc
					(start 314.5028 -34.1884)
					(mid 314.539997 -34.278203)
					(end 314.6298 -34.3154)
				)
				(arc
					(start 315.9252 -34.3154)
					(mid 316.015003 -34.278203)
					(end 316.0522 -34.1884)
				)
			)
		)
		(polygon
			(pts
				(arc
					(start 305.0032 -32.8676)
					(mid 304.966003 -32.777797)
					(end 304.8762 -32.7406)
				)
				(arc
					(start 303.5808 -32.7406)
					(mid 303.490997 -32.777797)
					(end 303.4538 -32.8676)
				)
				(arc
					(start 303.4538 -34.1884)
					(mid 303.490997 -34.278203)
					(end 303.5808 -34.3154)
				)
				(arc
					(start 304.8762 -34.3154)
					(mid 304.966003 -34.278203)
					(end 305.0032 -34.1884)
				)
			)
		)
		(polygon
			(pts
				(arc
					(start 290.3982 -32.8676)
					(mid 290.361003 -32.777797)
					(end 290.2712 -32.7406)
				)
				(arc
					(start 288.9758 -32.7406)
					(mid 288.885997 -32.777797)
					(end 288.8488 -32.8676)
				)
				(arc
					(start 288.8488 -34.1884)
					(mid 288.885997 -34.278203)
					(end 288.9758 -34.3154)
				)
				(arc
					(start 290.2712 -34.3154)
					(mid 290.361003 -34.278203)
					(end 290.3982 -34.1884)
				)
			)
		)
		(polygon
			(pts
				(arc
					(start 164.4142 -32.8676)
					(mid 164.377003 -32.777797)
					(end 164.2872 -32.7406)
				)
				(arc
					(start 162.9918 -32.7406)
					(mid 162.901997 -32.777797)
					(end 162.8648 -32.8676)
				)
				(arc
					(start 162.8648 -34.1884)
					(mid 162.901997 -34.278203)
					(end 162.9918 -34.3154)
				)
				(arc
					(start 164.2872 -34.3154)
					(mid 164.377003 -34.278203)
					(end 164.4142 -34.1884)
				)
			)
		)
		(polygon
			(pts
				(arc
					(start 162.3822 -32.8676)
					(mid 162.345003 -32.777797)
					(end 162.2552 -32.7406)
				)
				(arc
					(start 160.9598 -32.7406)
					(mid 160.869997 -32.777797)
					(end 160.8328 -32.8676)
				)
				(arc
					(start 160.8328 -34.1884)
					(mid 160.869997 -34.278203)
					(end 160.9598 -34.3154)
				)
				(arc
					(start 162.2552 -34.3154)
					(mid 162.345003 -34.278203)
					(end 162.3822 -34.1884)
				)
			)
		)
		(polygon
			(pts
				(arc
					(start 159.759904 -32.8676)
					(mid 159.722707 -32.777797)
					(end 159.632904 -32.7406)
				)
				(arc
					(start 158.337504 -32.7406)
					(mid 158.247701 -32.777797)
					(end 158.210504 -32.8676)
				)
				(arc
					(start 158.210504 -34.1884)
					(mid 158.247701 -34.278203)
					(end 158.337504 -34.3154)
				)
				(arc
					(start 159.632904 -34.3154)
					(mid 159.722707 -34.278203)
					(end 159.759904 -34.1884)
				)
			)
		)
		(polygon
			(pts
				(arc
					(start 151.8412 -32.8676)
					(mid 151.804003 -32.777797)
					(end 151.7142 -32.7406)
				)
				(arc
					(start 150.4188 -32.7406)
					(mid 150.328997 -32.777797)
					(end 150.2918 -32.8676)
				)
				(arc
					(start 150.2918 -34.1884)
					(mid 150.328997 -34.278203)
					(end 150.4188 -34.3154)
				)
				(arc
					(start 151.7142 -34.3154)
					(mid 151.804003 -34.278203)
					(end 151.8412 -34.1884)
				)
			)
		)
		(polygon
			(pts
				(arc
					(start 149.6822 -32.8676)
					(mid 149.645003 -32.777797)
					(end 149.5552 -32.7406)
				)
				(arc
					(start 148.2598 -32.7406)
					(mid 148.169997 -32.777797)
					(end 148.1328 -32.8676)
				)
				(arc
					(start 148.1328 -34.1884)
					(mid 148.169997 -34.278203)
					(end 148.2598 -34.3154)
				)
				(arc
					(start 149.5552 -34.3154)
					(mid 149.645003 -34.278203)
					(end 149.6822 -34.1884)
				)
			)
		)
		(polygon
			(pts
				(arc
					(start 147.0914 -32.86252)
					(mid 147.054203 -32.772717)
					(end 146.9644 -32.73552)
				)
				(arc
					(start 145.669 -32.73552)
					(mid 145.579197 -32.772717)
					(end 145.542 -32.86252)
				)
				(arc
					(start 145.542 -34.18332)
					(mid 145.579197 -34.273123)
					(end 145.669 -34.31032)
				)
				(arc
					(start 146.9644 -34.31032)
					(mid 147.054203 -34.273123)
					(end 147.0914 -34.18332)
				)
			)
		)
		(polygon
			(pts
				(arc
					(start 307.154834 -32.854138)
					(mid 307.117637 -32.764335)
					(end 307.027834 -32.727138)
				)
				(arc
					(start 305.732434 -32.727138)
					(mid 305.642631 -32.764335)
					(end 305.605434 -32.854138)
				)
				(arc
					(start 305.605434 -34.174938)
					(mid 305.642631 -34.264741)
					(end 305.732434 -34.301938)
				)
				(arc
					(start 307.027834 -34.301938)
					(mid 307.117637 -34.264741)
					(end 307.154834 -34.174938)
				)
			)
		)
		(polygon
			(pts
				(arc
					(start 320.889376 -32.847026)
					(mid 320.852179 -32.757223)
					(end 320.762376 -32.720026)
				)
				(arc
					(start 319.466976 -32.720026)
					(mid 319.377173 -32.757223)
					(end 319.339976 -32.847026)
				)
				(arc
					(start 319.339976 -34.167826)
					(mid 319.377173 -34.257629)
					(end 319.466976 -34.294826)
				)
				(arc
					(start 320.762376 -34.294826)
					(mid 320.852179 -34.257629)
					(end 320.889376 -34.167826)
				)
			)
		)
		(polygon
			(pts
				(arc
					(start 153.8224 -32.8422)
					(mid 153.785203 -32.752397)
					(end 153.6954 -32.7152)
				)
				(arc
					(start 152.4 -32.7152)
					(mid 152.310197 -32.752397)
					(end 152.273 -32.8422)
				)
				(arc
					(start 152.273 -34.163)
					(mid 152.310197 -34.252803)
					(end 152.4 -34.29)
				)
				(arc
					(start 153.6954 -34.29)
					(mid 153.785203 -34.252803)
					(end 153.8224 -34.163)
				)
			)
		)
		(polygon
			(pts
				(arc
					(start 324.78091 -32.822388)
					(mid 324.743713 -32.732585)
					(end 324.65391 -32.695388)
				)
				(arc
					(start 323.35851 -32.695388)
					(mid 323.268707 -32.732585)
					(end 323.23151 -32.822388)
				)
				(arc
					(start 323.23151 -34.143188)
					(mid 323.268707 -34.232991)
					(end 323.35851 -34.270188)
				)
				(arc
					(start 324.65391 -34.270188)
					(mid 324.743713 -34.232991)
					(end 324.78091 -34.143188)
				)
			)
		)
		(polygon
			(pts
				(arc
					(start 327.137522 -32.79902)
					(mid 327.100325 -32.709217)
					(end 327.010522 -32.67202)
				)
				(arc
					(start 325.715122 -32.67202)
					(mid 325.625319 -32.709217)
					(end 325.588122 -32.79902)
				)
				(arc
					(start 325.588122 -34.11982)
					(mid 325.625319 -34.209623)
					(end 325.715122 -34.24682)
				)
				(arc
					(start 327.010522 -34.24682)
					(mid 327.100325 -34.209623)
					(end 327.137522 -34.11982)
				)
			)
		)
		(polygon
			(pts
				(arc
					(start 287.274 -32.766)
					(mid 287.236803 -32.676197)
					(end 287.147 -32.639)
				)
				(arc
					(start 285.8262 -32.639)
					(mid 285.736397 -32.676197)
					(end 285.6992 -32.766)
				)
				(arc
					(start 285.6992 -34.0614)
					(mid 285.736397 -34.151203)
					(end 285.8262 -34.1884)
				)
				(arc
					(start 287.147 -34.1884)
					(mid 287.236803 -34.151203)
					(end 287.274 -34.0614)
				)
			)
		)
		(polygon
			(pts
				(arc
					(start 285.498794 -33.051496)
					(mid 284.988254 -32.540956)
					(end 284.477714 -33.051496)
				)
				(arc
					(start 284.477714 -33.86455)
					(mid 284.988381 -34.374836)
					(end 285.498794 -33.864296)
				)
			)
		)
		(polygon
			(pts
				(arc
					(start 182.3974 -28.7528)
					(mid 182.360203 -28.662997)
					(end 182.2704 -28.6258)
				)
				(arc
					(start 180.9496 -28.6258)
					(mid 180.859797 -28.662997)
					(end 180.8226 -28.7528)
				)
				(arc
					(start 180.8226 -30.0482)
					(mid 180.859797 -30.138003)
					(end 180.9496 -30.1752)
				)
				(arc
					(start 182.2704 -30.1752)
					(mid 182.360203 -30.138003)
					(end 182.3974 -30.0482)
				)
			)
		)
		(polygon
			(pts
				(arc
					(start 183.59374 -28.993846)
					(mid 183.083073 -28.48356)
					(end 182.57266 -28.9941)
				)
				(arc
					(start 182.57266 -29.8069)
					(mid 183.0832 -30.31744)
					(end 183.59374 -29.8069)
				)
			)
		)
		(polygon
			(pts
				(arc
					(start 182.3974 -25.7048)
					(mid 182.360203 -25.614997)
					(end 182.2704 -25.5778)
				)
				(arc
					(start 180.9496 -25.5778)
					(mid 180.859797 -25.614997)
					(end 180.8226 -25.7048)
				)
				(arc
					(start 180.8226 -27.0002)
					(mid 180.859797 -27.090003)
					(end 180.9496 -27.1272)
				)
				(arc
					(start 182.2704 -27.1272)
					(mid 182.360203 -27.090003)
					(end 182.3974 -27.0002)
				)
			)
		)
		(polygon
			(pts
				(arc
					(start 183.59374 -25.945846)
					(mid 183.083073 -25.43556)
					(end 182.57266 -25.9461)
				)
				(arc
					(start 182.57266 -26.7589)
					(mid 183.0832 -27.26944)
					(end 183.59374 -26.7589)
				)
			)
		)
		(polygon
			(pts
				(arc
					(start 186.56554 -24.99868)
					(mid 186.054873 -24.488394)
					(end 185.54446 -24.998934)
				)
				(arc
					(start 185.54446 -25.811734)
					(mid 186.055 -26.322274)
					(end 186.56554 -25.811734)
				)
			)
		)
		(polygon
			(pts
				(arc
					(start 145.435066 -24.22525)
					(mid 145.17939 -23.379349)
					(end 144.333468 -23.635208)
				)
				(xy 144.331436 -23.633938) (xy 143.581374 -25.033986)
				(arc
					(start 143.583406 -25.035256)
					(mid 143.839438 -25.881076)
					(end 144.685258 -25.625044)
				)
				(xy 144.68729 -25.626314) (xy 145.437352 -24.22652) (xy 145.437098 -24.226266)
			)
		)
		(polygon
			(pts
				(arc
					(start 298.435014 -24.22525)
					(mid 298.179338 -23.379349)
					(end 297.333416 -23.635208)
				)
				(xy 297.331384 -23.633938) (xy 296.581322 -25.033986)
				(arc
					(start 296.583354 -25.035256)
					(mid 296.839386 -25.881076)
					(end 297.685206 -25.625044)
				)
				(xy 297.687238 -25.626314) (xy 298.4373 -24.22652) (xy 298.437046 -24.226266)
			)
		)
		(polygon
			(pts
				(arc
					(start 324.935342 -24.224996)
					(mid 324.67931 -23.379176)
					(end 323.83349 -23.635208)
				)
				(xy 323.831458 -23.633938) (xy 323.081396 -25.033732) (xy 323.08165 -25.033986)
				(arc
					(start 323.083682 -25.035002)
					(mid 323.339358 -25.880903)
					(end 324.18528 -25.625044)
				)
				(xy 324.187312 -25.626314) (xy 324.937374 -24.226266)
			)
		)
		(polygon
			(pts
				(arc
					(start 322.68541 -24.224996)
					(mid 322.429378 -23.379176)
					(end 321.583558 -23.635208)
				)
				(xy 321.581526 -23.633938) (xy 320.831464 -25.033732) (xy 320.831718 -25.033986)
				(arc
					(start 320.83375 -25.035002)
					(mid 321.089426 -25.880903)
					(end 321.935348 -25.625044)
				)
				(xy 321.93738 -25.626314) (xy 322.687442 -24.226266)
			)
		)
		(polygon
			(pts
				(arc
					(start 313.935364 -24.224996)
					(mid 313.679332 -23.379176)
					(end 312.833512 -23.635208)
				)
				(xy 312.83148 -23.633938) (xy 312.081418 -25.033732) (xy 312.081672 -25.033986)
				(arc
					(start 312.083704 -25.035002)
					(mid 312.33938 -25.880903)
					(end 313.185302 -25.625044)
				)
				(xy 313.187334 -25.626314) (xy 313.937396 -24.226266)
			)
		)
		(polygon
			(pts
				(arc
					(start 311.685432 -24.224996)
					(mid 311.4294 -23.379176)
					(end 310.58358 -23.635208)
				)
				(xy 310.581548 -23.633938) (xy 309.831486 -25.033732) (xy 309.83174 -25.033986)
				(arc
					(start 309.833772 -25.035002)
					(mid 310.089448 -25.880903)
					(end 310.93537 -25.625044)
				)
				(xy 310.937402 -25.626314) (xy 311.687464 -24.226266)
			)
		)
		(polygon
			(pts
				(arc
					(start 302.935386 -24.224996)
					(mid 302.679354 -23.379176)
					(end 301.833534 -23.635208)
				)
				(xy 301.831502 -23.633938) (xy 301.08144 -25.033732) (xy 301.081694 -25.033986)
				(arc
					(start 301.083726 -25.035002)
					(mid 301.339402 -25.880903)
					(end 302.185324 -25.625044)
				)
				(xy 302.187356 -25.626314) (xy 302.937418 -24.226266)
			)
		)
		(polygon
			(pts
				(arc
					(start 300.6852 -24.224996)
					(mid 300.429168 -23.379176)
					(end 299.583348 -23.635208)
				)
				(arc
					(start 298.837604 -25.027636)
					(mid 299.085738 -25.879089)
					(end 299.935392 -25.625044)
				)
			)
		)
		(polygon
			(pts
				(arc
					(start 291.935408 -24.224996)
					(mid 291.679376 -23.379176)
					(end 290.833556 -23.635208)
				)
				(xy 290.831524 -23.633938) (xy 290.081462 -25.033732) (xy 290.081716 -25.033986)
				(arc
					(start 290.083748 -25.035002)
					(mid 290.339424 -25.880903)
					(end 291.185346 -25.625044)
				)
				(xy 291.187378 -25.626314) (xy 291.93744 -24.226266)
			)
		)
		(polygon
			(pts
				(arc
					(start 289.685222 -24.224996)
					(mid 289.42919 -23.379176)
					(end 288.58337 -23.635208)
				)
				(arc
					(start 287.837626 -25.027636)
					(mid 288.08576 -25.879089)
					(end 288.935414 -25.625044)
				)
			)
		)
		(polygon
			(pts
				(arc
					(start 287.43529 -24.224996)
					(mid 287.179258 -23.379176)
					(end 286.333438 -23.635208)
				)
				(xy 286.331406 -23.633938) (xy 285.581344 -25.033732) (xy 285.581598 -25.033986)
				(arc
					(start 285.58363 -25.035002)
					(mid 285.839306 -25.880903)
					(end 286.685228 -25.625044)
				)
				(xy 286.68726 -25.626314) (xy 287.437322 -24.226266)
			)
		)
		(polygon
			(pts
				(arc
					(start 171.935394 -24.224996)
					(mid 171.679362 -23.379176)
					(end 170.833542 -23.635208)
				)
				(xy 170.83151 -23.633938) (xy 170.081448 -25.033732) (xy 170.081702 -25.033986)
				(arc
					(start 170.083734 -25.035002)
					(mid 170.33941 -25.880903)
					(end 171.185332 -25.625044)
				)
				(xy 171.187364 -25.626314) (xy 171.937426 -24.226266)
			)
		)
		(polygon
			(pts
				(arc
					(start 169.685462 -24.224996)
					(mid 169.42943 -23.379176)
					(end 168.58361 -23.635208)
				)
				(xy 168.581578 -23.633938) (xy 167.831516 -25.033732) (xy 167.83177 -25.033986)
				(arc
					(start 167.833802 -25.035002)
					(mid 168.089478 -25.880903)
					(end 168.9354 -25.625044)
				)
				(xy 168.937432 -25.626314) (xy 169.687494 -24.226266)
			)
		)
		(polygon
			(pts
				(arc
					(start 160.935416 -24.224996)
					(mid 160.679384 -23.379176)
					(end 159.833564 -23.635208)
				)
				(xy 159.831532 -23.633938) (xy 159.08147 -25.033732) (xy 159.081724 -25.033986)
				(arc
					(start 159.083756 -25.035002)
					(mid 159.339432 -25.880903)
					(end 160.185354 -25.625044)
				)
				(xy 160.187386 -25.626314) (xy 160.937448 -24.226266)
			)
		)
		(polygon
			(pts
				(arc
					(start 158.685484 -24.224996)
					(mid 158.429452 -23.379176)
					(end 157.583632 -23.635208)
				)
				(xy 157.5816 -23.633938) (xy 156.831538 -25.033732) (xy 156.831792 -25.033986)
				(arc
					(start 156.833824 -25.035002)
					(mid 157.0895 -25.880903)
					(end 157.935422 -25.625044)
				)
				(xy 157.937454 -25.626314) (xy 158.687516 -24.226266)
			)
		)
		(polygon
			(pts
				(arc
					(start 149.935438 -24.224996)
					(mid 149.679406 -23.379176)
					(end 148.833586 -23.635208)
				)
				(xy 148.831554 -23.633938) (xy 148.081492 -25.033732) (xy 148.081746 -25.033986)
				(arc
					(start 148.083778 -25.035002)
					(mid 148.339454 -25.880903)
					(end 149.185376 -25.625044)
				)
				(xy 149.187408 -25.626314) (xy 149.93747 -24.226266)
			)
		)
		(polygon
			(pts
				(arc
					(start 147.685252 -24.224996)
					(mid 147.42922 -23.379176)
					(end 146.5834 -23.635208)
				)
				(arc
					(start 145.837656 -25.027636)
					(mid 146.08579 -25.879089)
					(end 146.935444 -25.625044)
				)
			)
		)
		(polygon
			(pts
				(arc
					(start 138.93546 -24.224996)
					(mid 138.679428 -23.379176)
					(end 137.833608 -23.635208)
				)
				(xy 137.831576 -23.633938) (xy 137.081514 -25.033732) (xy 137.081768 -25.033986)
				(arc
					(start 137.0838 -25.035002)
					(mid 137.339476 -25.880903)
					(end 138.185398 -25.625044)
				)
				(xy 138.18743 -25.626314) (xy 138.937492 -24.226266)
			)
		)
		(polygon
			(pts
				(arc
					(start 136.685274 -24.224996)
					(mid 136.429242 -23.379176)
					(end 135.583422 -23.635208)
				)
				(arc
					(start 134.837678 -25.027636)
					(mid 135.085812 -25.879089)
					(end 135.935466 -25.625044)
				)
			)
		)
		(polygon
			(pts
				(arc
					(start 134.435342 -24.224996)
					(mid 134.17931 -23.379176)
					(end 133.33349 -23.635208)
				)
				(xy 133.331458 -23.633938) (xy 132.581396 -25.033732) (xy 132.58165 -25.033986)
				(arc
					(start 132.583682 -25.035002)
					(mid 132.839358 -25.880903)
					(end 133.68528 -25.625044)
				)
				(xy 133.687312 -25.626314) (xy 134.437374 -24.226266)
			)
		)
		(polygon
			(pts
				(arc
					(start 320.43116 -24.232616)
					(mid 320.183026 -23.381163)
					(end 319.333372 -23.635208)
				)
				(arc
					(start 318.583564 -25.035256)
					(mid 318.596918 -25.648738)
					(end 319.128648 -25.95499)
				)
				(arc
					(start 319.128648 -25.95499)
					(mid 319.453069 -25.867706)
					(end 319.685416 -25.625044)
				)
			)
		)
		(polygon
			(pts
				(arc
					(start 309.431182 -24.232616)
					(mid 309.183048 -23.381163)
					(end 308.333394 -23.635208)
				)
				(arc
					(start 307.583586 -25.035256)
					(mid 307.839618 -25.881076)
					(end 308.685438 -25.625044)
				)
			)
		)
		(polygon
			(pts
				(arc
					(start 167.431212 -24.232616)
					(mid 167.183078 -23.381163)
					(end 166.333424 -23.635208)
				)
				(arc
					(start 165.583616 -25.035256)
					(mid 165.839648 -25.881076)
					(end 166.685468 -25.625044)
				)
			)
		)
		(polygon
			(pts
				(arc
					(start 156.431234 -24.232616)
					(mid 156.1831 -23.381163)
					(end 155.333446 -23.635208)
				)
				(arc
					(start 154.583638 -25.035256)
					(mid 154.83967 -25.881076)
					(end 155.68549 -25.625044)
				)
			)
		)
		(polygon
			(pts
				(arc
					(start 182.3974 -23.4188)
					(mid 182.360203 -23.328997)
					(end 182.2704 -23.2918)
				)
				(arc
					(start 180.9496 -23.2918)
					(mid 180.859797 -23.328997)
					(end 180.8226 -23.4188)
				)
				(arc
					(start 180.8226 -24.7142)
					(mid 180.859797 -24.804003)
					(end 180.9496 -24.8412)
				)
				(arc
					(start 182.2704 -24.8412)
					(mid 182.360203 -24.804003)
					(end 182.3974 -24.7142)
				)
			)
		)
		(polygon
			(pts
				(arc
					(start 183.59374 -23.6601)
					(mid 183.0832 -23.14956)
					(end 182.57266 -23.6601)
				)
				(arc
					(start 182.57266 -24.473154)
					(mid 183.083327 -24.98344)
					(end 183.59374 -24.4729)
				)
			)
		)
		(polygon
			(pts
				(arc
					(start 182.3974 -21.3868)
					(mid 182.360203 -21.296997)
					(end 182.2704 -21.2598)
				)
				(arc
					(start 180.9496 -21.2598)
					(mid 180.859797 -21.296997)
					(end 180.8226 -21.3868)
				)
				(arc
					(start 180.8226 -22.6822)
					(mid 180.859797 -22.772003)
					(end 180.9496 -22.8092)
				)
				(arc
					(start 182.2704 -22.8092)
					(mid 182.360203 -22.772003)
					(end 182.3974 -22.6822)
				)
			)
		)
		(polygon
			(pts
				(arc
					(start 283.005276 -20.15617)
					(mid 282.284107 -20.118381)
					(end 282.246578 -20.83943)
				)
				(xy 282.244546 -20.841208) (xy 282.788614 -21.44522)
				(arc
					(start 282.790646 -21.443442)
					(mid 283.511498 -21.481034)
					(end 283.54909 -20.760182)
				)
				(xy 283.551122 -20.758404) (xy 283.007308 -20.154646) (xy 283.0068 -20.154646)
			)
		)
		(polygon
			(pts
				(arc
					(start 160.935162 -20.425156)
					(mid 160.679486 -19.579255)
					(end 159.833564 -19.835114)
				)
				(xy 159.831532 -19.833844) (xy 159.08147 -21.233892)
				(arc
					(start 159.083502 -21.235162)
					(mid 159.339534 -22.080982)
					(end 160.185354 -21.82495)
				)
				(xy 160.187386 -21.82622) (xy 160.937448 -20.426426) (xy 160.937194 -20.426172)
			)
		)
		(polygon
			(pts
				(arc
					(start 158.68523 -20.425156)
					(mid 158.429554 -19.579255)
					(end 157.583632 -19.835114)
				)
				(xy 157.5816 -19.833844) (xy 156.831538 -21.233892)
				(arc
					(start 156.83357 -21.235162)
					(mid 157.089602 -22.080982)
					(end 157.935422 -21.82495)
				)
				(xy 157.937454 -21.82622) (xy 158.687516 -20.426426) (xy 158.687262 -20.426172)
			)
		)
		(polygon
			(pts
				(arc
					(start 324.935088 -20.425156)
					(mid 324.679412 -19.579255)
					(end 323.83349 -19.835114)
				)
				(xy 323.831458 -19.833844) (xy 323.081396 -21.233892)
				(arc
					(start 323.083428 -21.235162)
					(mid 323.33946 -22.080982)
					(end 324.18528 -21.82495)
				)
				(xy 324.187312 -21.82622) (xy 324.937374 -20.426426) (xy 324.93712 -20.426172)
			)
		)
		(polygon
			(pts
				(arc
					(start 322.685156 -20.425156)
					(mid 322.42948 -19.579255)
					(end 321.583558 -19.835114)
				)
				(xy 321.581526 -19.833844) (xy 320.831464 -21.233892)
				(arc
					(start 320.833496 -21.235162)
					(mid 321.089528 -22.080982)
					(end 321.935348 -21.82495)
				)
				(xy 321.93738 -21.82622) (xy 322.687442 -20.426426) (xy 322.687188 -20.426172)
			)
		)
		(polygon
			(pts
				(arc
					(start 313.93511 -20.425156)
					(mid 313.679434 -19.579255)
					(end 312.833512 -19.835114)
				)
				(xy 312.83148 -19.833844) (xy 312.081418 -21.233892)
				(arc
					(start 312.08345 -21.235162)
					(mid 312.339482 -22.080982)
					(end 313.185302 -21.82495)
				)
				(xy 313.187334 -21.82622) (xy 313.937396 -20.426426) (xy 313.937142 -20.426172)
			)
		)
		(polygon
			(pts
				(arc
					(start 311.685178 -20.425156)
					(mid 311.429502 -19.579255)
					(end 310.58358 -19.835114)
				)
				(xy 310.581548 -19.833844) (xy 309.831486 -21.233892)
				(arc
					(start 309.833518 -21.235162)
					(mid 310.08955 -22.080982)
					(end 310.93537 -21.82495)
				)
				(xy 310.937402 -21.82622) (xy 311.687464 -20.426426) (xy 311.68721 -20.426172)
			)
		)
		(polygon
			(pts
				(arc
					(start 171.93514 -20.425156)
					(mid 171.679464 -19.579255)
					(end 170.833542 -19.835114)
				)
				(xy 170.83151 -19.833844) (xy 170.081448 -21.233892)
				(arc
					(start 170.08348 -21.235162)
					(mid 170.339512 -22.080982)
					(end 171.185332 -21.82495)
				)
				(xy 171.187364 -21.82622) (xy 171.937426 -20.426426) (xy 171.937172 -20.426172)
			)
		)
		(polygon
			(pts
				(arc
					(start 169.685208 -20.425156)
					(mid 169.429532 -19.579255)
					(end 168.58361 -19.835114)
				)
				(xy 168.581578 -19.833844) (xy 167.831516 -21.233892)
				(arc
					(start 167.833548 -21.235162)
					(mid 168.08958 -22.080982)
					(end 168.9354 -21.82495)
				)
				(xy 168.937432 -21.82622) (xy 169.687494 -20.426426) (xy 169.68724 -20.426172)
			)
		)
		(polygon
			(pts
				(arc
					(start 149.935184 -20.425156)
					(mid 149.679508 -19.579255)
					(end 148.833586 -19.835114)
				)
				(xy 148.831554 -19.833844) (xy 148.081492 -21.233892)
				(arc
					(start 148.083524 -21.235162)
					(mid 148.339556 -22.080982)
					(end 149.185376 -21.82495)
				)
				(xy 149.187408 -21.82622) (xy 149.93747 -20.426426) (xy 149.937216 -20.426172)
			)
		)
		(polygon
			(pts
				(arc
					(start 302.935132 -20.425156)
					(mid 302.679456 -19.579255)
					(end 301.833534 -19.835114)
				)
				(xy 301.831502 -19.833844) (xy 301.08144 -21.233892)
				(arc
					(start 301.083472 -21.235162)
					(mid 301.339504 -22.080982)
					(end 302.185324 -21.82495)
				)
				(xy 302.187356 -21.82622) (xy 302.937418 -20.426426) (xy 302.937164 -20.426172)
			)
		)
		(polygon
			(pts
				(arc
					(start 291.935408 -20.424902)
					(mid 291.679376 -19.579082)
					(end 290.833556 -19.835114)
				)
				(xy 290.831524 -19.833844) (xy 290.081462 -21.233638) (xy 290.081716 -21.233892)
				(arc
					(start 290.083748 -21.234908)
					(mid 290.339424 -22.080809)
					(end 291.185346 -21.82495)
				)
				(xy 291.187378 -21.82622) (xy 291.93744 -20.426172)
			)
		)
		(polygon
			(pts
				(arc
					(start 289.685222 -20.424902)
					(mid 289.42919 -19.579082)
					(end 288.58337 -19.835114)
				)
				(arc
					(start 287.837626 -21.227542)
					(mid 288.08576 -22.078995)
					(end 288.935414 -21.82495)
				)
			)
		)
		(polygon
			(pts
				(arc
					(start 138.93546 -20.424902)
					(mid 138.679428 -19.579082)
					(end 137.833608 -19.835114)
				)
				(xy 137.831576 -19.833844) (xy 137.081514 -21.233638) (xy 137.081768 -21.233892)
				(arc
					(start 137.0838 -21.234908)
					(mid 137.339476 -22.080809)
					(end 138.185398 -21.82495)
				)
				(xy 138.18743 -21.82622) (xy 138.937492 -20.426172)
			)
		)
		(polygon
			(pts
				(arc
					(start 136.685274 -20.424902)
					(mid 136.429242 -19.579082)
					(end 135.583422 -19.835114)
				)
				(arc
					(start 134.837678 -21.227542)
					(mid 135.085812 -22.078995)
					(end 135.935466 -21.82495)
				)
			)
		)
		(polygon
			(pts
				(arc
					(start 147.681188 -20.432522)
					(mid 147.433054 -19.581069)
					(end 146.5834 -19.835114)
				)
				(arc
					(start 145.833592 -21.235162)
					(mid 146.089624 -22.080982)
					(end 146.935444 -21.82495)
				)
			)
		)
		(polygon
			(pts
				(arc
					(start 300.681136 -20.432522)
					(mid 300.433002 -19.581069)
					(end 299.583348 -19.835114)
				)
				(arc
					(start 298.83354 -21.235162)
					(mid 299.089572 -22.080982)
					(end 299.935392 -21.82495)
				)
			)
		)
		(polygon
			(pts
				(arc
					(start 182.3974 -19.6088)
					(mid 182.360203 -19.518997)
					(end 182.2704 -19.4818)
				)
				(arc
					(start 180.9496 -19.4818)
					(mid 180.859797 -19.518997)
					(end 180.8226 -19.6088)
				)
				(arc
					(start 180.8226 -20.9042)
					(mid 180.859797 -20.994003)
					(end 180.9496 -21.0312)
				)
				(arc
					(start 182.2704 -21.0312)
					(mid 182.360203 -20.994003)
					(end 182.3974 -20.9042)
				)
			)
		)
		(polygon
			(pts
				(arc
					(start 183.59374 -19.849846)
					(mid 183.083073 -19.33956)
					(end 182.57266 -19.8501)
				)
				(arc
					(start 182.57266 -20.6629)
					(mid 183.0832 -21.17344)
					(end 183.59374 -20.6629)
				)
			)
		)
		(polygon
			(pts
				(arc
					(start 280.761186 -17.965928)
					(mid 280.258647 -17.447516)
					(end 279.740106 -17.949926)
				)
				(xy 279.73401 -18.354802)
				(arc
					(start 279.72766 -18.762726)
					(mid 280.230326 -19.28114)
					(end 280.74874 -18.778474)
				)
			)
		)
		(polygon
			(pts
				(arc
					(start 324.935088 -16.625316)
					(mid 324.679564 -15.779496)
					(end 323.833744 -16.03502)
				)
				(xy 323.831458 -16.03375) (xy 323.081396 -17.433544) (xy 323.08165 -17.433798)
				(arc
					(start 323.083682 -17.434814)
					(mid 323.339206 -18.280634)
					(end 324.185026 -18.02511)
				)
				(xy 324.187312 -18.02638) (xy 324.937374 -16.626586)
			)
		)
		(polygon
			(pts
				(arc
					(start 322.685156 -16.625316)
					(mid 322.429632 -15.779496)
					(end 321.583812 -16.03502)
				)
				(xy 321.581526 -16.03375) (xy 320.831464 -17.433544) (xy 320.831718 -17.433798)
				(arc
					(start 320.83375 -17.434814)
					(mid 321.089274 -18.280634)
					(end 321.935094 -18.02511)
				)
				(xy 321.93738 -18.02638) (xy 322.687442 -16.626586)
			)
		)
		(polygon
			(pts
				(arc
					(start 313.93511 -16.625316)
					(mid 313.679586 -15.779496)
					(end 312.833766 -16.03502)
				)
				(xy 312.83148 -16.03375) (xy 312.081418 -17.433544) (xy 312.081672 -17.433798)
				(arc
					(start 312.083704 -17.434814)
					(mid 312.339228 -18.280634)
					(end 313.185048 -18.02511)
				)
				(xy 313.187334 -18.02638) (xy 313.937396 -16.626586)
			)
		)
		(polygon
			(pts
				(arc
					(start 311.685178 -16.625316)
					(mid 311.429654 -15.779496)
					(end 310.583834 -16.03502)
				)
				(xy 310.581548 -16.03375) (xy 309.831486 -17.433544) (xy 309.83174 -17.433798)
				(arc
					(start 309.833772 -17.434814)
					(mid 310.089296 -18.280634)
					(end 310.935116 -18.02511)
				)
				(xy 310.937402 -18.02638) (xy 311.687464 -16.626586)
			)
		)
		(polygon
			(pts
				(arc
					(start 302.935132 -16.625316)
					(mid 302.679608 -15.779496)
					(end 301.833788 -16.03502)
				)
				(xy 301.831502 -16.03375) (xy 301.08144 -17.433544) (xy 301.081694 -17.433798)
				(arc
					(start 301.083726 -17.434814)
					(mid 301.33925 -18.280634)
					(end 302.18507 -18.02511)
				)
				(xy 302.187356 -18.02638) (xy 302.937418 -16.626586)
			)
		)
		(polygon
			(pts
				(arc
					(start 291.935154 -16.625316)
					(mid 291.67963 -15.779496)
					(end 290.83381 -16.03502)
				)
				(xy 290.831524 -16.03375) (xy 290.081462 -17.433544) (xy 290.081716 -17.433798)
				(arc
					(start 290.083748 -17.434814)
					(mid 290.339272 -18.280634)
					(end 291.185092 -18.02511)
				)
				(xy 291.187378 -18.02638) (xy 291.93744 -16.626586)
			)
		)
		(polygon
			(pts
				(arc
					(start 171.93514 -16.625316)
					(mid 171.679616 -15.779496)
					(end 170.833796 -16.03502)
				)
				(xy 170.83151 -16.03375) (xy 170.081448 -17.433544) (xy 170.081702 -17.433798)
				(arc
					(start 170.083734 -17.434814)
					(mid 170.339258 -18.280634)
					(end 171.185078 -18.02511)
				)
				(xy 171.187364 -18.02638) (xy 171.937426 -16.626586)
			)
		)
		(polygon
			(pts
				(arc
					(start 169.685208 -16.625316)
					(mid 169.429684 -15.779496)
					(end 168.583864 -16.03502)
				)
				(xy 168.581578 -16.03375) (xy 167.831516 -17.433544) (xy 167.83177 -17.433798)
				(arc
					(start 167.833802 -17.434814)
					(mid 168.089326 -18.280634)
					(end 168.935146 -18.02511)
				)
				(xy 168.937432 -18.02638) (xy 169.687494 -16.626586)
			)
		)
		(polygon
			(pts
				(arc
					(start 160.935162 -16.625316)
					(mid 160.679638 -15.779496)
					(end 159.833818 -16.03502)
				)
				(xy 159.831532 -16.03375) (xy 159.08147 -17.433544) (xy 159.081724 -17.433798)
				(arc
					(start 159.083756 -17.434814)
					(mid 159.33928 -18.280634)
					(end 160.1851 -18.02511)
				)
				(xy 160.187386 -18.02638) (xy 160.937448 -16.626586)
			)
		)
		(polygon
			(pts
				(arc
					(start 158.68523 -16.625316)
					(mid 158.429706 -15.779496)
					(end 157.583886 -16.03502)
				)
				(xy 157.5816 -16.03375) (xy 156.831538 -17.433544) (xy 156.831792 -17.433798)
				(arc
					(start 156.833824 -17.434814)
					(mid 157.089348 -18.280634)
					(end 157.935168 -18.02511)
				)
				(xy 157.937454 -18.02638) (xy 158.687516 -16.626586)
			)
		)
		(polygon
			(pts
				(arc
					(start 149.935184 -16.625316)
					(mid 149.67966 -15.779496)
					(end 148.83384 -16.03502)
				)
				(xy 148.831554 -16.03375) (xy 148.081492 -17.433544) (xy 148.081746 -17.433798)
				(arc
					(start 148.083778 -17.434814)
					(mid 148.339302 -18.280634)
					(end 149.185122 -18.02511)
				)
				(xy 149.187408 -18.02638) (xy 149.93747 -16.626586)
			)
		)
		(polygon
			(pts
				(arc
					(start 138.935206 -16.625316)
					(mid 138.679682 -15.779496)
					(end 137.833862 -16.03502)
				)
				(xy 137.831576 -16.03375) (xy 137.081514 -17.433544) (xy 137.081768 -17.433798)
				(arc
					(start 137.0838 -17.434814)
					(mid 137.339324 -18.280634)
					(end 138.185144 -18.02511)
				)
				(xy 138.18743 -18.02638) (xy 138.937492 -16.626586)
			)
		)
		(polygon
			(pts
				(arc
					(start 300.6852 -16.625062)
					(mid 300.429168 -15.779242)
					(end 299.583348 -16.035274)
				)
				(xy 299.581316 -16.034004) (xy 298.831508 -17.433544) (xy 298.831762 -17.433798)
				(arc
					(start 298.833794 -17.434814)
					(mid 299.08947 -18.280715)
					(end 299.935392 -18.024856)
				)
				(xy 299.937424 -18.026126) (xy 300.687232 -16.626332)
			)
		)
		(polygon
			(pts
				(arc
					(start 289.685222 -16.625062)
					(mid 289.42919 -15.779242)
					(end 288.58337 -16.035274)
				)
				(xy 288.581338 -16.034004) (xy 287.83153 -17.433544) (xy 287.831784 -17.433798)
				(arc
					(start 287.833816 -17.434814)
					(mid 288.089492 -18.280715)
					(end 288.935414 -18.024856)
				)
				(xy 288.937446 -18.026126) (xy 289.687254 -16.626332)
			)
		)
		(polygon
			(pts
				(arc
					(start 147.685252 -16.625062)
					(mid 147.42922 -15.779242)
					(end 146.5834 -16.035274)
				)
				(xy 146.581368 -16.034004) (xy 145.83156 -17.433544) (xy 145.831814 -17.433798)
				(arc
					(start 145.833846 -17.434814)
					(mid 146.089522 -18.280715)
					(end 146.935444 -18.024856)
				)
				(xy 146.937476 -18.026126) (xy 147.687284 -16.626332)
			)
		)
		(polygon
			(pts
				(arc
					(start 136.685274 -16.625062)
					(mid 136.429242 -15.779242)
					(end 135.583422 -16.035274)
				)
				(xy 135.58139 -16.034004) (xy 134.831582 -17.433544) (xy 134.831836 -17.433798)
				(arc
					(start 134.833868 -17.434814)
					(mid 135.089544 -18.280715)
					(end 135.935466 -18.024856)
				)
				(xy 135.937498 -18.026126) (xy 136.687306 -16.626332)
			)
		)
		(polygon
			(pts
				(arc
					(start 274.7264 -14.2748)
					(mid 274.689203 -14.184997)
					(end 274.5994 -14.1478)
				)
				(arc
					(start 273.2786 -14.1478)
					(mid 273.188797 -14.184997)
					(end 273.1516 -14.2748)
				)
				(arc
					(start 273.1516 -15.5702)
					(mid 273.188797 -15.660003)
					(end 273.2786 -15.6972)
				)
				(arc
					(start 274.5994 -15.6972)
					(mid 274.689203 -15.660003)
					(end 274.7264 -15.5702)
				)
			)
		)
		(polygon
			(pts
				(arc
					(start 272.57883 -14.52245)
					(mid 272.06829 -14.01191)
					(end 271.55775 -14.52245)
				)
				(arc
					(start 271.55775 -15.335504)
					(mid 272.068417 -15.84579)
					(end 272.57883 -15.33525)
				)
			)
		)
		(polygon
			(pts
				(arc
					(start 268.98854 -13.842746)
					(mid 268.477873 -13.33246)
					(end 267.96746 -13.843)
				)
				(arc
					(start 267.96746 -14.6558)
					(mid 268.478 -15.16634)
					(end 268.98854 -14.6558)
				)
			)
		)
		(polygon
			(pts
				(arc
					(start 274.7264 -12.4968)
					(mid 274.689203 -12.406997)
					(end 274.5994 -12.3698)
				)
				(arc
					(start 273.2786 -12.3698)
					(mid 273.188797 -12.406997)
					(end 273.1516 -12.4968)
				)
				(arc
					(start 273.1516 -13.7922)
					(mid 273.188797 -13.882003)
					(end 273.2786 -13.9192)
				)
				(arc
					(start 274.5994 -13.9192)
					(mid 274.689203 -13.882003)
					(end 274.7264 -13.7922)
				)
			)
		)
		(polygon
			(pts
				(arc
					(start 291.935154 -12.825222)
					(mid 291.679478 -11.979321)
					(end 290.833556 -12.23518)
				)
				(xy 290.831524 -12.23391) (xy 290.081462 -13.633958)
				(arc
					(start 290.083494 -13.635228)
					(mid 290.339526 -14.481048)
					(end 291.185346 -14.225016)
				)
				(xy 291.187378 -14.226286) (xy 291.93744 -12.826492) (xy 291.937186 -12.826238)
			)
		)
		(polygon
			(pts
				(arc
					(start 287.435036 -12.825222)
					(mid 287.17936 -11.979321)
					(end 286.333438 -12.23518)
				)
				(xy 286.331406 -12.23391) (xy 285.581344 -13.633958)
				(arc
					(start 285.583376 -13.635228)
					(mid 285.839408 -14.481048)
					(end 286.685228 -14.225016)
				)
				(xy 286.68726 -14.226286) (xy 287.437322 -12.826492) (xy 287.437068 -12.826238)
			)
		)
		(polygon
			(pts
				(arc
					(start 138.935206 -12.825222)
					(mid 138.67953 -11.979321)
					(end 137.833608 -12.23518)
				)
				(xy 137.831576 -12.23391) (xy 137.081514 -13.633958)
				(arc
					(start 137.083546 -13.635228)
					(mid 137.339578 -14.481048)
					(end 138.185398 -14.225016)
				)
				(xy 138.18743 -14.226286) (xy 138.937492 -12.826492) (xy 138.937238 -12.826238)
			)
		)
		(polygon
			(pts
				(arc
					(start 134.435088 -12.825222)
					(mid 134.179412 -11.979321)
					(end 133.33349 -12.23518)
				)
				(xy 133.331458 -12.23391) (xy 132.581396 -13.633958)
				(arc
					(start 132.583428 -13.635228)
					(mid 132.83946 -14.481048)
					(end 133.68528 -14.225016)
				)
				(xy 133.687312 -14.226286) (xy 134.437374 -12.826492) (xy 134.43712 -12.826238)
			)
		)
		(polygon
			(pts
				(arc
					(start 324.935342 -12.824968)
					(mid 324.67931 -11.979148)
					(end 323.83349 -12.23518)
				)
				(xy 323.831458 -12.23391) (xy 323.081396 -13.633704) (xy 323.08165 -13.633958)
				(arc
					(start 323.083682 -13.634974)
					(mid 323.339358 -14.480875)
					(end 324.18528 -14.225016)
				)
				(xy 324.187312 -14.226286) (xy 324.937374 -12.826238)
			)
		)
		(polygon
			(pts
				(arc
					(start 322.68541 -12.824968)
					(mid 322.429378 -11.979148)
					(end 321.583558 -12.23518)
				)
				(xy 321.581526 -12.23391) (xy 320.831464 -13.633704) (xy 320.831718 -13.633958)
				(arc
					(start 320.83375 -13.634974)
					(mid 321.089426 -14.480875)
					(end 321.935348 -14.225016)
				)
				(xy 321.93738 -14.226286) (xy 322.687442 -12.826238)
			)
		)
		(polygon
			(pts
				(arc
					(start 320.435224 -12.824968)
					(mid 320.179192 -11.979148)
					(end 319.333372 -12.23518)
				)
				(arc
					(start 318.587628 -13.627608)
					(mid 318.835762 -14.479061)
					(end 319.685416 -14.225016)
				)
			)
		)
		(polygon
			(pts
				(arc
					(start 313.935364 -12.824968)
					(mid 313.679332 -11.979148)
					(end 312.833512 -12.23518)
				)
				(xy 312.83148 -12.23391) (xy 312.081418 -13.633704) (xy 312.081672 -13.633958)
				(arc
					(start 312.083704 -13.634974)
					(mid 312.33938 -14.480875)
					(end 313.185302 -14.225016)
				)
				(xy 313.187334 -14.226286) (xy 313.937396 -12.826238)
			)
		)
		(polygon
			(pts
				(arc
					(start 311.685432 -12.824968)
					(mid 311.4294 -11.979148)
					(end 310.58358 -12.23518)
				)
				(xy 310.581548 -12.23391) (xy 309.831486 -13.633704) (xy 309.83174 -13.633958)
				(arc
					(start 309.833772 -13.634974)
					(mid 310.089448 -14.480875)
					(end 310.93537 -14.225016)
				)
				(xy 310.937402 -14.226286) (xy 311.687464 -12.826238)
			)
		)
		(polygon
			(pts
				(arc
					(start 309.435246 -12.824968)
					(mid 309.179214 -11.979148)
					(end 308.333394 -12.23518)
				)
				(arc
					(start 307.58765 -13.627608)
					(mid 307.835784 -14.479061)
					(end 308.685438 -14.225016)
				)
			)
		)
		(polygon
			(pts
				(arc
					(start 302.935386 -12.824968)
					(mid 302.679354 -11.979148)
					(end 301.833534 -12.23518)
				)
				(xy 301.831502 -12.23391) (xy 301.08144 -13.633704) (xy 301.081694 -13.633958)
				(arc
					(start 301.083726 -13.634974)
					(mid 301.339402 -14.480875)
					(end 302.185324 -14.225016)
				)
				(xy 302.187356 -14.226286) (xy 302.937418 -12.826238)
			)
		)
		(polygon
			(pts
				(arc
					(start 300.6852 -12.824968)
					(mid 300.429168 -11.979148)
					(end 299.583348 -12.23518)
				)
				(arc
					(start 298.837604 -13.627608)
					(mid 299.085738 -14.479061)
					(end 299.935392 -14.225016)
				)
			)
		)
		(polygon
			(pts
				(arc
					(start 298.435268 -12.824968)
					(mid 298.179236 -11.979148)
					(end 297.333416 -12.23518)
				)
				(xy 297.331384 -12.23391) (xy 296.581322 -13.633704) (xy 296.581576 -13.633958)
				(arc
					(start 296.583608 -13.634974)
					(mid 296.839284 -14.480875)
					(end 297.685206 -14.225016)
				)
				(xy 297.687238 -14.226286) (xy 298.4373 -12.826238)
			)
		)
		(polygon
			(pts
				(arc
					(start 171.935394 -12.824968)
					(mid 171.679362 -11.979148)
					(end 170.833542 -12.23518)
				)
				(xy 170.83151 -12.23391) (xy 170.081448 -13.633704) (xy 170.081702 -13.633958)
				(arc
					(start 170.083734 -13.634974)
					(mid 170.33941 -14.480875)
					(end 171.185332 -14.225016)
				)
				(xy 171.187364 -14.226286) (xy 171.937426 -12.826238)
			)
		)
		(polygon
			(pts
				(arc
					(start 169.685462 -12.824968)
					(mid 169.42943 -11.979148)
					(end 168.58361 -12.23518)
				)
				(xy 168.581578 -12.23391) (xy 167.831516 -13.633704) (xy 167.83177 -13.633958)
				(arc
					(start 167.833802 -13.634974)
					(mid 168.089478 -14.480875)
					(end 168.9354 -14.225016)
				)
				(xy 168.937432 -14.226286) (xy 169.687494 -12.826238)
			)
		)
		(polygon
			(pts
				(arc
					(start 167.435276 -12.824968)
					(mid 167.179244 -11.979148)
					(end 166.333424 -12.23518)
				)
				(arc
					(start 165.58768 -13.627608)
					(mid 165.835814 -14.479061)
					(end 166.685468 -14.225016)
				)
			)
		)
		(polygon
			(pts
				(arc
					(start 160.935416 -12.824968)
					(mid 160.679384 -11.979148)
					(end 159.833564 -12.23518)
				)
				(xy 159.831532 -12.23391) (xy 159.08147 -13.633704) (xy 159.081724 -13.633958)
				(arc
					(start 159.083756 -13.634974)
					(mid 159.339432 -14.480875)
					(end 160.185354 -14.225016)
				)
				(xy 160.187386 -14.226286) (xy 160.937448 -12.826238)
			)
		)
		(polygon
			(pts
				(arc
					(start 158.685484 -12.824968)
					(mid 158.429452 -11.979148)
					(end 157.583632 -12.23518)
				)
				(xy 157.5816 -12.23391) (xy 156.831538 -13.633704) (xy 156.831792 -13.633958)
				(arc
					(start 156.833824 -13.634974)
					(mid 157.0895 -14.480875)
					(end 157.935422 -14.225016)
				)
				(xy 157.937454 -14.226286) (xy 158.687516 -12.826238)
			)
		)
		(polygon
			(pts
				(arc
					(start 156.435298 -12.824968)
					(mid 156.179266 -11.979148)
					(end 155.333446 -12.23518)
				)
				(arc
					(start 154.587702 -13.627608)
					(mid 154.835836 -14.479061)
					(end 155.68549 -14.225016)
				)
			)
		)
		(polygon
			(pts
				(arc
					(start 149.935438 -12.824968)
					(mid 149.679406 -11.979148)
					(end 148.833586 -12.23518)
				)
				(xy 148.831554 -12.23391) (xy 148.081492 -13.633704) (xy 148.081746 -13.633958)
				(arc
					(start 148.083778 -13.634974)
					(mid 148.339454 -14.480875)
					(end 149.185376 -14.225016)
				)
				(xy 149.187408 -14.226286) (xy 149.93747 -12.826238)
			)
		)
		(polygon
			(pts
				(arc
					(start 147.685252 -12.824968)
					(mid 147.42922 -11.979148)
					(end 146.5834 -12.23518)
				)
				(arc
					(start 145.837656 -13.627608)
					(mid 146.08579 -14.479061)
					(end 146.935444 -14.225016)
				)
			)
		)
		(polygon
			(pts
				(arc
					(start 145.43532 -12.824968)
					(mid 145.179288 -11.979148)
					(end 144.333468 -12.23518)
				)
				(xy 144.331436 -12.23391) (xy 143.581374 -13.633704) (xy 143.581628 -13.633958)
				(arc
					(start 143.58366 -13.634974)
					(mid 143.839336 -14.480875)
					(end 144.685258 -14.225016)
				)
				(xy 144.68729 -14.226286) (xy 145.437352 -12.826238)
			)
		)
		(polygon
			(pts
				(arc
					(start 289.681158 -12.832588)
					(mid 289.433024 -11.981135)
					(end 288.58337 -12.23518)
				)
				(arc
					(start 287.833562 -13.635228)
					(mid 288.089594 -14.481048)
					(end 288.935414 -14.225016)
				)
			)
		)
		(polygon
			(pts
				(arc
					(start 136.68121 -12.832588)
					(mid 136.433076 -11.981135)
					(end 135.583422 -12.23518)
				)
				(arc
					(start 134.833614 -13.635228)
					(mid 135.089646 -14.481048)
					(end 135.935466 -14.225016)
				)
			)
		)
		(polygon
			(pts
				(arc
					(start 185.069226 -11.6967)
					(mid 184.558559 -11.186414)
					(end 184.048146 -11.696954)
				)
				(arc
					(start 184.048146 -12.509754)
					(mid 184.558686 -13.020294)
					(end 185.069226 -12.509754)
				)
			)
		)
		(polygon
			(pts
				(arc
					(start 184.443624 -8.91667)
					(mid 184.95391 -8.406003)
					(end 184.44337 -7.89559)
				)
				(arc
					(start 183.63057 -7.89559)
					(mid 183.12003 -8.40613)
					(end 183.63057 -8.91667)
				)
			)
		)
		(polygon
			(pts
				(arc
					(start 271.19834 -8.353298)
					(mid 270.687673 -7.843012)
					(end 270.17726 -8.353552)
				)
				(arc
					(start 270.17726 -9.166352)
					(mid 270.6878 -9.676892)
					(end 271.19834 -9.166352)
				)
			)
		)
		(polygon
			(pts
				(arc
					(start 270.05534 -5.305298)
					(mid 269.544673 -4.795012)
					(end 269.03426 -5.305552)
				)
				(arc
					(start 269.03426 -6.118352)
					(mid 269.5448 -6.628892)
					(end 270.05534 -6.118352)
				)
			)
		)
	)
	(zone
		(net "GND")
		(layer "In1.Cu")
		(hatch none 0.5)
		(connect_pads
			(clearance 0.5)
		)
		(min_thickness 0.25)
		(fill yes
			(thermal_gap 0.5)
			(thermal_bridge_width 0.5)
			(island_removal_mode 0)
		)
		(polygon
			(pts
				(xy 24.132794 -145.0467) (xy 23.6855 -145.493994) (xy 23.6855 -149.425406) (xy 23.726394 -149.4663)
				(xy 26.260806 -149.4663) (xy 26.3271 -149.400006) (xy 26.3271 -145.722594) (xy 25.651206 -145.0467)
			)
		)
	)
	(zone
		(layer "In1.Cu")
		(hatch none 0.5)
		(connect_pads
			(clearance 0)
		)
		(min_thickness 0.25)
		(keepout
			(tracks not_allowed)
			(vias allowed)
			(pads allowed)
			(copperpour not_allowed)
			(footprints allowed)
		)
		(placement
			(enabled no)
			(sheetname "")
		)
		(fill
			(thermal_gap 0.5)
			(thermal_bridge_width 0.5)
			(island_removal_mode 0)
		)
		(polygon
			(pts
				(arc
					(start 66.588894 -211.633054)
					(mid 66.499091 -211.670251)
					(end 66.461894 -211.760054)
				)
				(arc
					(start 66.461894 -213.080854)
					(mid 66.499091 -213.170657)
					(end 66.588894 -213.207854)
				)
				(arc
					(start 68.011294 -213.207854)
					(mid 68.101097 -213.170657)
					(end 68.138294 -213.080854)
				)
				(arc
					(start 68.138294 -211.760054)
					(mid 68.101097 -211.670251)
					(end 68.011294 -211.633054)
				)
			)
		)
	)
	(zone
		(layer "In1.Cu")
		(hatch none 0.5)
		(connect_pads
			(clearance 0)
		)
		(min_thickness 0.25)
		(keepout
			(tracks not_allowed)
			(vias allowed)
			(pads allowed)
			(copperpour not_allowed)
			(footprints allowed)
		)
		(placement
			(enabled no)
			(sheetname "")
		)
		(fill
			(thermal_gap 0.5)
			(thermal_bridge_width 0.5)
			(island_removal_mode 0)
		)
		(polygon
			(pts
				(arc
					(start 298.588938 -211.633054)
					(mid 298.499135 -211.670251)
					(end 298.461938 -211.760054)
				)
				(arc
					(start 298.461938 -213.080854)
					(mid 298.499135 -213.170657)
					(end 298.588938 -213.207854)
				)
				(arc
					(start 300.011338 -213.207854)
					(mid 300.101141 -213.170657)
					(end 300.138338 -213.080854)
				)
				(arc
					(start 300.138338 -211.760054)
					(mid 300.101141 -211.670251)
					(end 300.011338 -211.633054)
				)
			)
		)
	)
	(zone
		(layer "In1.Cu")
		(hatch none 0.5)
		(connect_pads
			(clearance 0)
		)
		(min_thickness 0.25)
		(keepout
			(tracks not_allowed)
			(vias allowed)
			(pads allowed)
			(copperpour not_allowed)
			(footprints allowed)
		)
		(placement
			(enabled no)
			(sheetname "")
		)
		(fill
			(thermal_gap 0.5)
			(thermal_bridge_width 0.5)
			(island_removal_mode 0)
		)
		(polygon
			(pts
				(arc
					(start 289.788854 -211.633054)
					(mid 289.699051 -211.670251)
					(end 289.661854 -211.760054)
				)
				(arc
					(start 289.661854 -213.080854)
					(mid 289.699051 -213.170657)
					(end 289.788854 -213.207854)
				)
				(arc
					(start 291.211254 -213.207854)
					(mid 291.301057 -213.170657)
					(end 291.338254 -213.080854)
				)
				(arc
					(start 291.338254 -211.760054)
					(mid 291.301057 -211.670251)
					(end 291.211254 -211.633054)
				)
			)
		)
	)
	(zone
		(layer "In1.Cu")
		(hatch none 0.5)
		(connect_pads
			(clearance 0)
		)
		(min_thickness 0.25)
		(keepout
			(tracks not_allowed)
			(vias allowed)
			(pads allowed)
			(copperpour not_allowed)
			(footprints allowed)
		)
		(placement
			(enabled no)
			(sheetname "")
		)
		(fill
			(thermal_gap 0.5)
			(thermal_bridge_width 0.5)
			(island_removal_mode 0)
		)
		(polygon
			(pts
				(arc
					(start 135.16102 -32.76092)
					(mid 135.071217 -32.798117)
					(end 135.03402 -32.88792)
				)
				(arc
					(start 135.03402 -34.20872)
					(mid 135.071217 -34.298523)
					(end 135.16102 -34.33572)
				)
				(arc
					(start 136.45642 -34.33572)
					(mid 136.546223 -34.298523)
					(end 136.58342 -34.20872)
				)
				(arc
					(start 136.58342 -32.88792)
					(mid 136.546223 -32.798117)
					(end 136.45642 -32.76092)
				)
			)
		)
	)
	(zone
		(layer "In1.Cu")
		(hatch none 0.5)
		(connect_pads
			(clearance 0)
		)
		(min_thickness 0.25)
		(keepout
			(tracks not_allowed)
			(vias allowed)
			(pads allowed)
			(copperpour not_allowed)
			(footprints allowed)
		)
		(placement
			(enabled no)
			(sheetname "")
		)
		(fill
			(thermal_gap 0.5)
			(thermal_bridge_width 0.5)
			(island_removal_mode 0)
		)
		(polygon
			(pts
				(arc
					(start 133.00964 -32.75584)
					(mid 132.919837 -32.793037)
					(end 132.88264 -32.88284)
				)
				(arc
					(start 132.88264 -34.20364)
					(mid 132.919837 -34.293443)
					(end 133.00964 -34.33064)
				)
				(arc
					(start 134.30504 -34.33064)
					(mid 134.394843 -34.293443)
					(end 134.43204 -34.20364)
				)
				(arc
					(start 134.43204 -32.88284)
					(mid 134.394843 -32.793037)
					(end 134.30504 -32.75584)
				)
			)
		)
	)
	(zone
		(layer "In1.Cu")
		(hatch none 0.5)
		(connect_pads
			(clearance 0)
		)
		(min_thickness 0.25)
		(keepout
			(tracks not_allowed)
			(vias allowed)
			(pads allowed)
			(copperpour not_allowed)
			(footprints allowed)
		)
		(placement
			(enabled no)
			(sheetname "")
		)
		(fill
			(thermal_gap 0.5)
			(thermal_bridge_width 0.5)
			(island_removal_mode 0)
		)
		(polygon
			(pts
				(arc
					(start 141.388846 -211.633054)
					(mid 141.299043 -211.670251)
					(end 141.261846 -211.760054)
				)
				(arc
					(start 141.261846 -213.080854)
					(mid 141.299043 -213.170657)
					(end 141.388846 -213.207854)
				)
				(arc
					(start 142.811246 -213.207854)
					(mid 142.901049 -213.170657)
					(end 142.938246 -213.080854)
				)
				(arc
					(start 142.938246 -211.760054)
					(mid 142.901049 -211.670251)
					(end 142.811246 -211.633054)
				)
			)
		)
	)
	(zone
		(layer "In1.Cu")
		(hatch none 0.5)
		(connect_pads
			(clearance 0)
		)
		(min_thickness 0.25)
		(keepout
			(tracks not_allowed)
			(vias allowed)
			(pads allowed)
			(copperpour not_allowed)
			(footprints allowed)
		)
		(placement
			(enabled no)
			(sheetname "")
		)
		(fill
			(thermal_gap 0.5)
			(thermal_bridge_width 0.5)
			(island_removal_mode 0)
		)
		(polygon
			(pts
				(arc
					(start 51.388772 -211.633054)
					(mid 51.298969 -211.670251)
					(end 51.261772 -211.760054)
				)
				(arc
					(start 51.261772 -213.080854)
					(mid 51.298969 -213.170657)
					(end 51.388772 -213.207854)
				)
				(arc
					(start 52.811172 -213.207854)
					(mid 52.900975 -213.170657)
					(end 52.938172 -213.080854)
				)
				(arc
					(start 52.938172 -211.760054)
					(mid 52.900975 -211.670251)
					(end 52.811172 -211.633054)
				)
			)
		)
	)
	(zone
		(layer "In1.Cu")
		(hatch none 0.5)
		(connect_pads
			(clearance 0)
		)
		(min_thickness 0.25)
		(keepout
			(tracks not_allowed)
			(vias allowed)
			(pads allowed)
			(copperpour not_allowed)
			(footprints allowed)
		)
		(placement
			(enabled no)
			(sheetname "")
		)
		(fill
			(thermal_gap 0.5)
			(thermal_bridge_width 0.5)
			(island_removal_mode 0)
		)
		(polygon
			(pts
				(arc
					(start 57.78881 -211.633054)
					(mid 57.699007 -211.670251)
					(end 57.66181 -211.760054)
				)
				(arc
					(start 57.66181 -213.080854)
					(mid 57.699007 -213.170657)
					(end 57.78881 -213.207854)
				)
				(arc
					(start 59.21121 -213.207854)
					(mid 59.301013 -213.170657)
					(end 59.33821 -213.080854)
				)
				(arc
					(start 59.33821 -211.760054)
					(mid 59.301013 -211.670251)
					(end 59.21121 -211.633054)
				)
			)
		)
	)
	(zone
		(layer "In1.Cu")
		(hatch none 0.5)
		(connect_pads
			(clearance 0)
		)
		(min_thickness 0.25)
		(keepout
			(tracks not_allowed)
			(vias allowed)
			(pads allowed)
			(copperpour not_allowed)
			(footprints allowed)
		)
		(placement
			(enabled no)
			(sheetname "")
		)
		(fill
			(thermal_gap 0.5)
			(thermal_bridge_width 0.5)
			(island_removal_mode 0)
		)
		(polygon
			(pts
				(arc
					(start 27.549348 -109.63402)
					(mid 27.622986 -109.603518)
					(end 27.653488 -109.52988)
				)
				(arc
					(start 27.653488 -109.12348)
					(mid 27.622986 -109.049842)
					(end 27.549348 -109.01934)
				)
				(arc
					(start 27.142948 -109.01934)
					(mid 27.06931 -109.049842)
					(end 27.038808 -109.12348)
				)
				(arc
					(start 27.038808 -109.52988)
					(mid 27.06931 -109.603518)
					(end 27.142948 -109.63402)
				)
			)
		)
	)
	(zone
		(layer "In1.Cu")
		(hatch none 0.5)
		(connect_pads
			(clearance 0)
		)
		(min_thickness 0.25)
		(keepout
			(tracks not_allowed)
			(vias allowed)
			(pads allowed)
			(copperpour not_allowed)
			(footprints allowed)
		)
		(placement
			(enabled no)
			(sheetname "")
		)
		(fill
			(thermal_gap 0.5)
			(thermal_bridge_width 0.5)
			(island_removal_mode 0)
		)
		(polygon
			(pts
				(arc
					(start 280.188924 -211.633054)
					(mid 280.099121 -211.670251)
					(end 280.061924 -211.760054)
				)
				(arc
					(start 280.061924 -213.080854)
					(mid 280.099121 -213.170657)
					(end 280.188924 -213.207854)
				)
				(arc
					(start 281.611324 -213.207854)
					(mid 281.701127 -213.170657)
					(end 281.738324 -213.080854)
				)
				(arc
					(start 281.738324 -211.760054)
					(mid 281.701127 -211.670251)
					(end 281.611324 -211.633054)
				)
			)
		)
	)
	(zone
		(layer "In1.Cu")
		(hatch none 0.5)
		(connect_pads
			(clearance 0)
		)
		(min_thickness 0.25)
		(keepout
			(tracks not_allowed)
			(vias allowed)
			(pads allowed)
			(copperpour not_allowed)
			(footprints allowed)
		)
		(placement
			(enabled no)
			(sheetname "")
		)
		(fill
			(thermal_gap 0.5)
			(thermal_bridge_width 0.5)
			(island_removal_mode 0)
		)
		(polygon
			(pts
				(arc
					(start 199.78878 -211.633054)
					(mid 199.698977 -211.670251)
					(end 199.66178 -211.760054)
				)
				(arc
					(start 199.66178 -213.080854)
					(mid 199.698977 -213.170657)
					(end 199.78878 -213.207854)
				)
				(arc
					(start 201.21118 -213.207854)
					(mid 201.300983 -213.170657)
					(end 201.33818 -213.080854)
				)
				(arc
					(start 201.33818 -211.760054)
					(mid 201.300983 -211.670251)
					(end 201.21118 -211.633054)
				)
			)
		)
	)
	(zone
		(layer "In1.Cu")
		(hatch none 0.5)
		(connect_pads
			(clearance 0)
		)
		(min_thickness 0.25)
		(keepout
			(tracks not_allowed)
			(vias allowed)
			(pads allowed)
			(copperpour not_allowed)
			(footprints allowed)
		)
		(placement
			(enabled no)
			(sheetname "")
		)
		(fill
			(thermal_gap 0.5)
			(thermal_bridge_width 0.5)
			(island_removal_mode 0)
		)
		(polygon
			(pts
				(arc
					(start 312.98896 -211.633054)
					(mid 312.899157 -211.670251)
					(end 312.86196 -211.760054)
				)
				(arc
					(start 312.86196 -213.080854)
					(mid 312.899157 -213.170657)
					(end 312.98896 -213.207854)
				)
				(arc
					(start 314.41136 -213.207854)
					(mid 314.501163 -213.170657)
					(end 314.53836 -213.080854)
				)
				(arc
					(start 314.53836 -211.760054)
					(mid 314.501163 -211.670251)
					(end 314.41136 -211.633054)
				)
			)
		)
	)
	(zone
		(layer "In1.Cu")
		(hatch none 0.5)
		(connect_pads
			(clearance 0)
		)
		(min_thickness 0.25)
		(keepout
			(tracks not_allowed)
			(vias allowed)
			(pads allowed)
			(copperpour not_allowed)
			(footprints allowed)
		)
		(placement
			(enabled no)
			(sheetname "")
		)
		(fill
			(thermal_gap 0.5)
			(thermal_bridge_width 0.5)
			(island_removal_mode 0)
		)
		(polygon
			(pts
				(arc
					(start 301.78883 -211.633054)
					(mid 301.699027 -211.670251)
					(end 301.66183 -211.760054)
				)
				(arc
					(start 301.66183 -213.080854)
					(mid 301.699027 -213.170657)
					(end 301.78883 -213.207854)
				)
				(arc
					(start 303.21123 -213.207854)
					(mid 303.301033 -213.170657)
					(end 303.33823 -213.080854)
				)
				(arc
					(start 303.33823 -211.760054)
					(mid 303.301033 -211.670251)
					(end 303.21123 -211.633054)
				)
			)
		)
	)
	(zone
		(layer "In1.Cu")
		(hatch none 0.5)
		(connect_pads
			(clearance 0)
		)
		(min_thickness 0.25)
		(keepout
			(tracks not_allowed)
			(vias allowed)
			(pads allowed)
			(copperpour not_allowed)
			(footprints allowed)
		)
		(placement
			(enabled no)
			(sheetname "")
		)
		(fill
			(thermal_gap 0.5)
			(thermal_bridge_width 0.5)
			(island_removal_mode 0)
		)
		(polygon
			(pts
				(arc
					(start 196.588888 -211.633054)
					(mid 196.499085 -211.670251)
					(end 196.461888 -211.760054)
				)
				(arc
					(start 196.461888 -213.080854)
					(mid 196.499085 -213.170657)
					(end 196.588888 -213.207854)
				)
				(arc
					(start 198.011288 -213.207854)
					(mid 198.101091 -213.170657)
					(end 198.138288 -213.080854)
				)
				(arc
					(start 198.138288 -211.760054)
					(mid 198.101091 -211.670251)
					(end 198.011288 -211.633054)
				)
			)
		)
	)
	(zone
		(layer "In1.Cu")
		(hatch none 0.5)
		(connect_pads
			(clearance 0)
		)
		(min_thickness 0.25)
		(keepout
			(tracks not_allowed)
			(vias allowed)
			(pads allowed)
			(copperpour not_allowed)
			(footprints allowed)
		)
		(placement
			(enabled no)
			(sheetname "")
		)
		(fill
			(thermal_gap 0.5)
			(thermal_bridge_width 0.5)
			(island_removal_mode 0)
		)
		(polygon
			(pts
				(arc
					(start 319.388998 -211.633054)
					(mid 319.299195 -211.670251)
					(end 319.261998 -211.760054)
				)
				(arc
					(start 319.261998 -213.080854)
					(mid 319.299195 -213.170657)
					(end 319.388998 -213.207854)
				)
				(arc
					(start 320.811398 -213.207854)
					(mid 320.901201 -213.170657)
					(end 320.938398 -213.080854)
				)
				(arc
					(start 320.938398 -211.760054)
					(mid 320.901201 -211.670251)
					(end 320.811398 -211.633054)
				)
			)
		)
	)
	(zone
		(layer "In1.Cu")
		(hatch none 0.5)
		(connect_pads
			(clearance 0)
		)
		(min_thickness 0.25)
		(keepout
			(tracks not_allowed)
			(vias allowed)
			(pads allowed)
			(copperpour not_allowed)
			(footprints allowed)
		)
		(placement
			(enabled no)
			(sheetname "")
		)
		(fill
			(thermal_gap 0.5)
			(thermal_bridge_width 0.5)
			(island_removal_mode 0)
		)
		(polygon
			(pts
				(arc
					(start 169.38879 -211.633054)
					(mid 169.298987 -211.670251)
					(end 169.26179 -211.760054)
				)
				(arc
					(start 169.26179 -213.080854)
					(mid 169.298987 -213.170657)
					(end 169.38879 -213.207854)
				)
				(arc
					(start 170.81119 -213.207854)
					(mid 170.900993 -213.170657)
					(end 170.93819 -213.080854)
				)
				(arc
					(start 170.93819 -211.760054)
					(mid 170.900993 -211.670251)
					(end 170.81119 -211.633054)
				)
			)
		)
	)
	(zone
		(layer "In1.Cu")
		(hatch none 0.5)
		(connect_pads
			(clearance 0)
		)
		(min_thickness 0.25)
		(keepout
			(tracks not_allowed)
			(vias allowed)
			(pads allowed)
			(copperpour not_allowed)
			(footprints allowed)
		)
		(placement
			(enabled no)
			(sheetname "")
		)
		(fill
			(thermal_gap 0.5)
			(thermal_bridge_width 0.5)
			(island_removal_mode 0)
		)
		(polygon
			(pts
				(arc
					(start 104.189022 -211.633054)
					(mid 104.099219 -211.670251)
					(end 104.062022 -211.760054)
				)
				(arc
					(start 104.062022 -213.080854)
					(mid 104.099219 -213.170657)
					(end 104.189022 -213.207854)
				)
				(arc
					(start 105.611422 -213.207854)
					(mid 105.701225 -213.170657)
					(end 105.738422 -213.080854)
				)
				(arc
					(start 105.738422 -211.760054)
					(mid 105.701225 -211.670251)
					(end 105.611422 -211.633054)
				)
			)
		)
	)
	(zone
		(layer "In1.Cu")
		(hatch none 0.5)
		(connect_pads
			(clearance 0)
		)
		(min_thickness 0.25)
		(keepout
			(tracks not_allowed)
			(vias allowed)
			(pads allowed)
			(copperpour not_allowed)
			(footprints allowed)
		)
		(placement
			(enabled no)
			(sheetname "")
		)
		(fill
			(thermal_gap 0.5)
			(thermal_bridge_width 0.5)
			(island_removal_mode 0)
		)
		(polygon
			(pts
				(arc
					(start 27.548332 -108.766356)
					(mid 27.62197 -108.735854)
					(end 27.652472 -108.662216)
				)
				(arc
					(start 27.652472 -108.255816)
					(mid 27.62197 -108.182178)
					(end 27.548332 -108.151676)
				)
				(arc
					(start 27.141932 -108.151676)
					(mid 27.068294 -108.182178)
					(end 27.037792 -108.255816)
				)
				(arc
					(start 27.037792 -108.662216)
					(mid 27.068294 -108.735854)
					(end 27.141932 -108.766356)
				)
			)
		)
	)
	(zone
		(layer "In1.Cu")
		(hatch none 0.5)
		(connect_pads
			(clearance 0)
		)
		(min_thickness 0.25)
		(keepout
			(tracks not_allowed)
			(vias allowed)
			(pads allowed)
			(copperpour not_allowed)
			(footprints allowed)
		)
		(placement
			(enabled no)
			(sheetname "")
		)
		(fill
			(thermal_gap 0.5)
			(thermal_bridge_width 0.5)
			(island_removal_mode 0)
		)
		(polygon
			(pts
				(arc
					(start 270.588994 -211.633054)
					(mid 270.499191 -211.670251)
					(end 270.461994 -211.760054)
				)
				(arc
					(start 270.461994 -213.080854)
					(mid 270.499191 -213.170657)
					(end 270.588994 -213.207854)
				)
				(arc
					(start 272.011394 -213.207854)
					(mid 272.101197 -213.170657)
					(end 272.138394 -213.080854)
				)
				(arc
					(start 272.138394 -211.760054)
					(mid 272.101197 -211.670251)
					(end 272.011394 -211.633054)
				)
			)
		)
	)
	(zone
		(net "GND")
		(layer "In1.Cu")
		(hatch none 0.5)
		(connect_pads
			(clearance 0.5)
		)
		(min_thickness 0.25)
		(fill yes
			(thermal_gap 0.5)
			(thermal_bridge_width 0.5)
			(island_removal_mode 0)
		)
		(polygon
			(pts
				(xy 151.386794 -89.9795) (xy 151.1935 -90.172794) (xy 151.1935 -93.697806) (xy 151.208994 -93.7133)
				(xy 155.013406 -93.7133) (xy 155.1051 -93.621606) (xy 155.1051 -90.147394) (xy 154.937206 -89.9795)
			)
		)
	)
	(zone
		(layer "In1.Cu")
		(hatch none 0.5)
		(connect_pads
			(clearance 0)
		)
		(min_thickness 0.25)
		(keepout
			(tracks not_allowed)
			(vias allowed)
			(pads allowed)
			(copperpour not_allowed)
			(footprints allowed)
		)
		(placement
			(enabled no)
			(sheetname "")
		)
		(fill
			(thermal_gap 0.5)
			(thermal_bridge_width 0.5)
			(island_removal_mode 0)
		)
		(polygon
			(pts
				(arc
					(start 190.189104 -211.633054)
					(mid 190.099301 -211.670251)
					(end 190.062104 -211.760054)
				)
				(arc
					(start 190.062104 -213.080854)
					(mid 190.099301 -213.170657)
					(end 190.189104 -213.207854)
				)
				(arc
					(start 191.611504 -213.207854)
					(mid 191.701307 -213.170657)
					(end 191.738504 -213.080854)
				)
				(arc
					(start 191.738504 -211.760054)
					(mid 191.701307 -211.670251)
					(end 191.611504 -211.633054)
				)
			)
		)
	)
	(zone
		(layer "In1.Cu")
		(hatch none 0.5)
		(connect_pads
			(clearance 0)
		)
		(min_thickness 0.25)
		(keepout
			(tracks not_allowed)
			(vias allowed)
			(pads allowed)
			(copperpour not_allowed)
			(footprints allowed)
		)
		(placement
			(enabled no)
			(sheetname "")
		)
		(fill
			(thermal_gap 0.5)
			(thermal_bridge_width 0.5)
			(island_removal_mode 0)
		)
		(polygon
			(pts
				(arc
					(start 335.388966 -211.633054)
					(mid 335.299163 -211.670251)
					(end 335.261966 -211.760054)
				)
				(arc
					(start 335.261966 -213.080854)
					(mid 335.299163 -213.170657)
					(end 335.388966 -213.207854)
				)
				(arc
					(start 336.811366 -213.207854)
					(mid 336.901169 -213.170657)
					(end 336.938366 -213.080854)
				)
				(arc
					(start 336.938366 -211.760054)
					(mid 336.901169 -211.670251)
					(end 336.811366 -211.633054)
				)
			)
		)
	)
	(zone
		(layer "In1.Cu")
		(hatch none 0.5)
		(connect_pads
			(clearance 0)
		)
		(min_thickness 0.25)
		(keepout
			(tracks not_allowed)
			(vias allowed)
			(pads allowed)
			(copperpour not_allowed)
			(footprints allowed)
		)
		(placement
			(enabled no)
			(sheetname "")
		)
		(fill
			(thermal_gap 0.5)
			(thermal_bridge_width 0.5)
			(island_removal_mode 0)
		)
		(polygon
			(pts
				(arc
					(start 293.90594 -32.89554)
					(mid 293.816137 -32.932737)
					(end 293.77894 -33.02254)
				)
				(arc
					(start 293.77894 -34.34334)
					(mid 293.816137 -34.433143)
					(end 293.90594 -34.47034)
				)
				(arc
					(start 295.20134 -34.47034)
					(mid 295.291143 -34.433143)
					(end 295.32834 -34.34334)
				)
				(arc
					(start 295.32834 -33.02254)
					(mid 295.291143 -32.932737)
					(end 295.20134 -32.89554)
				)
			)
		)
	)
	(zone
		(layer "In1.Cu")
		(hatch none 0.5)
		(connect_pads
			(clearance 0)
		)
		(min_thickness 0.25)
		(keepout
			(tracks not_allowed)
			(vias allowed)
			(pads allowed)
			(copperpour not_allowed)
			(footprints allowed)
		)
		(placement
			(enabled no)
			(sheetname "")
		)
		(fill
			(thermal_gap 0.5)
			(thermal_bridge_width 0.5)
			(island_removal_mode 0)
		)
		(polygon
			(pts
				(arc
					(start 79.388716 -211.633054)
					(mid 79.298913 -211.670251)
					(end 79.261716 -211.760054)
				)
				(arc
					(start 79.261716 -213.080854)
					(mid 79.298913 -213.170657)
					(end 79.388716 -213.207854)
				)
				(arc
					(start 80.811116 -213.207854)
					(mid 80.900919 -213.170657)
					(end 80.938116 -213.080854)
				)
				(arc
					(start 80.938116 -211.760054)
					(mid 80.900919 -211.670251)
					(end 80.811116 -211.633054)
				)
			)
		)
	)
	(zone
		(layer "In1.Cu")
		(hatch none 0.5)
		(connect_pads
			(clearance 0)
		)
		(min_thickness 0.25)
		(keepout
			(tracks not_allowed)
			(vias allowed)
			(pads allowed)
			(copperpour not_allowed)
			(footprints allowed)
		)
		(placement
			(enabled no)
			(sheetname "")
		)
		(fill
			(thermal_gap 0.5)
			(thermal_bridge_width 0.5)
			(island_removal_mode 0)
		)
		(polygon
			(pts
				(arc
					(start 48.18888 -211.633054)
					(mid 48.099077 -211.670251)
					(end 48.06188 -211.760054)
				)
				(arc
					(start 48.06188 -213.080854)
					(mid 48.099077 -213.170657)
					(end 48.18888 -213.207854)
				)
				(arc
					(start 49.61128 -213.207854)
					(mid 49.701083 -213.170657)
					(end 49.73828 -213.080854)
				)
				(arc
					(start 49.73828 -211.760054)
					(mid 49.701083 -211.670251)
					(end 49.61128 -211.633054)
				)
			)
		)
	)
	(zone
		(layer "In1.Cu")
		(hatch none 0.5)
		(connect_pads
			(clearance 0)
		)
		(min_thickness 0.25)
		(keepout
			(tracks not_allowed)
			(vias allowed)
			(pads allowed)
			(copperpour not_allowed)
			(footprints allowed)
		)
		(placement
			(enabled no)
			(sheetname "")
		)
		(fill
			(thermal_gap 0.5)
			(thermal_bridge_width 0.5)
			(island_removal_mode 0)
		)
		(polygon
			(pts
				(arc
					(start 276.988778 -211.633054)
					(mid 276.898975 -211.670251)
					(end 276.861778 -211.760054)
				)
				(arc
					(start 276.861778 -213.080854)
					(mid 276.898975 -213.170657)
					(end 276.988778 -213.207854)
				)
				(arc
					(start 278.411178 -213.207854)
					(mid 278.500981 -213.170657)
					(end 278.538178 -213.080854)
				)
				(arc
					(start 278.538178 -211.760054)
					(mid 278.500981 -211.670251)
					(end 278.411178 -211.633054)
				)
			)
		)
	)
	(zone
		(layer "In1.Cu")
		(hatch none 0.5)
		(connect_pads
			(clearance 0)
		)
		(min_thickness 0.25)
		(keepout
			(tracks not_allowed)
			(vias allowed)
			(pads allowed)
			(copperpour not_allowed)
			(footprints allowed)
		)
		(placement
			(enabled no)
			(sheetname "")
		)
		(fill
			(thermal_gap 0.5)
			(thermal_bridge_width 0.5)
			(island_removal_mode 0)
		)
		(polygon
			(pts
				(arc
					(start 332.18882 -211.633054)
					(mid 332.099017 -211.670251)
					(end 332.06182 -211.760054)
				)
				(arc
					(start 332.06182 -213.080854)
					(mid 332.099017 -213.170657)
					(end 332.18882 -213.207854)
				)
				(arc
					(start 333.61122 -213.207854)
					(mid 333.701023 -213.170657)
					(end 333.73822 -213.080854)
				)
				(arc
					(start 333.73822 -211.760054)
					(mid 333.701023 -211.670251)
					(end 333.61122 -211.633054)
				)
			)
		)
	)
	(zone
		(layer "In1.Cu")
		(hatch none 0.5)
		(connect_pads
			(clearance 0)
		)
		(min_thickness 0.25)
		(keepout
			(tracks not_allowed)
			(vias allowed)
			(pads allowed)
			(copperpour not_allowed)
			(footprints allowed)
		)
		(placement
			(enabled no)
			(sheetname "")
		)
		(fill
			(thermal_gap 0.5)
			(thermal_bridge_width 0.5)
			(island_removal_mode 0)
		)
		(polygon
			(pts
				(arc
					(start 88.9889 -211.633054)
					(mid 88.899097 -211.670251)
					(end 88.8619 -211.760054)
				)
				(arc
					(start 88.8619 -213.080854)
					(mid 88.899097 -213.170657)
					(end 88.9889 -213.207854)
				)
				(arc
					(start 90.4113 -213.207854)
					(mid 90.501103 -213.170657)
					(end 90.5383 -213.080854)
				)
				(arc
					(start 90.5383 -211.760054)
					(mid 90.501103 -211.670251)
					(end 90.4113 -211.633054)
				)
			)
		)
	)
	(zone
		(layer "In1.Cu")
		(hatch none 0.5)
		(connect_pads
			(clearance 0)
		)
		(min_thickness 0.25)
		(keepout
			(tracks not_allowed)
			(vias allowed)
			(pads allowed)
			(copperpour not_allowed)
			(footprints allowed)
		)
		(placement
			(enabled no)
			(sheetname "")
		)
		(fill
			(thermal_gap 0.5)
			(thermal_bridge_width 0.5)
			(island_removal_mode 0)
		)
		(polygon
			(pts
				(arc
					(start 26.634948 -109.63402)
					(mid 26.708586 -109.603518)
					(end 26.739088 -109.52988)
				)
				(arc
					(start 26.739088 -109.12348)
					(mid 26.708586 -109.049842)
					(end 26.634948 -109.01934)
				)
				(arc
					(start 26.228548 -109.01934)
					(mid 26.15491 -109.049842)
					(end 26.124408 -109.12348)
				)
				(arc
					(start 26.124408 -109.52988)
					(mid 26.15491 -109.603518)
					(end 26.228548 -109.63402)
				)
			)
		)
	)
	(zone
		(layer "In1.Cu")
		(hatch none 0.5)
		(connect_pads
			(clearance 0)
		)
		(min_thickness 0.25)
		(keepout
			(tracks not_allowed)
			(vias allowed)
			(pads allowed)
			(copperpour not_allowed)
			(footprints allowed)
		)
		(placement
			(enabled no)
			(sheetname "")
		)
		(fill
			(thermal_gap 0.5)
			(thermal_bridge_width 0.5)
			(island_removal_mode 0)
		)
		(polygon
			(pts
				(arc
					(start 82.588862 -211.633054)
					(mid 82.499059 -211.670251)
					(end 82.461862 -211.760054)
				)
				(arc
					(start 82.461862 -213.080854)
					(mid 82.499059 -213.170657)
					(end 82.588862 -213.207854)
				)
				(arc
					(start 84.011262 -213.207854)
					(mid 84.101065 -213.170657)
					(end 84.138262 -213.080854)
				)
				(arc
					(start 84.138262 -211.760054)
					(mid 84.101065 -211.670251)
					(end 84.011262 -211.633054)
				)
			)
		)
	)
	(zone
		(layer "In1.Cu")
		(hatch none 0.5)
		(connect_pads
			(clearance 0)
		)
		(min_thickness 0.25)
		(keepout
			(tracks not_allowed)
			(vias allowed)
			(pads allowed)
			(copperpour not_allowed)
			(footprints allowed)
		)
		(placement
			(enabled no)
			(sheetname "")
		)
		(fill
			(thermal_gap 0.5)
			(thermal_bridge_width 0.5)
			(island_removal_mode 0)
		)
		(polygon
			(pts
				(arc
					(start 286.588962 -211.633054)
					(mid 286.499159 -211.670251)
					(end 286.461962 -211.760054)
				)
				(arc
					(start 286.461962 -213.080854)
					(mid 286.499159 -213.170657)
					(end 286.588962 -213.207854)
				)
				(arc
					(start 288.011362 -213.207854)
					(mid 288.101165 -213.170657)
					(end 288.138362 -213.080854)
				)
				(arc
					(start 288.138362 -211.760054)
					(mid 288.101165 -211.670251)
					(end 288.011362 -211.633054)
				)
			)
		)
	)
	(zone
		(layer "In1.Cu")
		(hatch none 0.5)
		(connect_pads
			(clearance 0)
		)
		(min_thickness 0.25)
		(keepout
			(tracks not_allowed)
			(vias allowed)
			(pads allowed)
			(copperpour not_allowed)
			(footprints allowed)
		)
		(placement
			(enabled no)
			(sheetname "")
		)
		(fill
			(thermal_gap 0.5)
			(thermal_bridge_width 0.5)
			(island_removal_mode 0)
		)
		(polygon
			(pts
				(arc
					(start 264.188956 -211.633054)
					(mid 264.099153 -211.670251)
					(end 264.061956 -211.760054)
				)
				(arc
					(start 264.061956 -213.080854)
					(mid 264.099153 -213.170657)
					(end 264.188956 -213.207854)
				)
				(arc
					(start 265.611356 -213.207854)
					(mid 265.701159 -213.170657)
					(end 265.738356 -213.080854)
				)
				(arc
					(start 265.738356 -211.760054)
					(mid 265.701159 -211.670251)
					(end 265.611356 -211.633054)
				)
			)
		)
	)
	(zone
		(layer "In1.Cu")
		(hatch none 0.5)
		(connect_pads
			(clearance 0)
		)
		(min_thickness 0.25)
		(keepout
			(tracks not_allowed)
			(vias allowed)
			(pads allowed)
			(copperpour not_allowed)
			(footprints allowed)
		)
		(placement
			(enabled no)
			(sheetname "")
		)
		(fill
			(thermal_gap 0.5)
			(thermal_bridge_width 0.5)
			(island_removal_mode 0)
		)
		(polygon
			(pts
				(arc
					(start 130.84556 -32.76346)
					(mid 130.755757 -32.800657)
					(end 130.71856 -32.89046)
				)
				(arc
					(start 130.71856 -34.21126)
					(mid 130.755757 -34.301063)
					(end 130.84556 -34.33826)
				)
				(arc
					(start 132.14096 -34.33826)
					(mid 132.230763 -34.301063)
					(end 132.26796 -34.21126)
				)
				(arc
					(start 132.26796 -32.89046)
					(mid 132.230763 -32.800657)
					(end 132.14096 -32.76346)
				)
			)
		)
	)
	(zone
		(layer "In1.Cu")
		(hatch none 0.5)
		(connect_pads
			(clearance 0)
		)
		(min_thickness 0.25)
		(keepout
			(tracks not_allowed)
			(vias allowed)
			(pads allowed)
			(copperpour not_allowed)
			(footprints allowed)
		)
		(placement
			(enabled no)
			(sheetname "")
		)
		(fill
			(thermal_gap 0.5)
			(thermal_bridge_width 0.5)
			(island_removal_mode 0)
		)
		(polygon
			(pts
				(arc
					(start 273.788886 -211.633054)
					(mid 273.699083 -211.670251)
					(end 273.661886 -211.760054)
				)
				(arc
					(start 273.661886 -213.080854)
					(mid 273.699083 -213.170657)
					(end 273.788886 -213.207854)
				)
				(arc
					(start 275.211286 -213.207854)
					(mid 275.301089 -213.170657)
					(end 275.338286 -213.080854)
				)
				(arc
					(start 275.338286 -211.760054)
					(mid 275.301089 -211.670251)
					(end 275.211286 -211.633054)
				)
			)
		)
	)
	(zone
		(layer "In1.Cu")
		(hatch none 0.5)
		(connect_pads
			(clearance 0)
		)
		(min_thickness 0.25)
		(keepout
			(tracks not_allowed)
			(vias allowed)
			(pads allowed)
			(copperpour not_allowed)
			(footprints allowed)
		)
		(placement
			(enabled no)
			(sheetname "")
		)
		(fill
			(thermal_gap 0.5)
			(thermal_bridge_width 0.5)
			(island_removal_mode 0)
		)
		(polygon
			(pts
				(arc
					(start 172.588936 -211.633054)
					(mid 172.499133 -211.670251)
					(end 172.461936 -211.760054)
				)
				(arc
					(start 172.461936 -213.080854)
					(mid 172.499133 -213.170657)
					(end 172.588936 -213.207854)
				)
				(arc
					(start 174.011336 -213.207854)
					(mid 174.101139 -213.170657)
					(end 174.138336 -213.080854)
				)
				(arc
					(start 174.138336 -211.760054)
					(mid 174.101139 -211.670251)
					(end 174.011336 -211.633054)
				)
			)
		)
	)
	(zone
		(layer "In1.Cu")
		(hatch none 0.5)
		(connect_pads
			(clearance 0)
		)
		(min_thickness 0.25)
		(keepout
			(tracks not_allowed)
			(vias allowed)
			(pads allowed)
			(copperpour not_allowed)
			(footprints allowed)
		)
		(placement
			(enabled no)
			(sheetname "")
		)
		(fill
			(thermal_gap 0.5)
			(thermal_bridge_width 0.5)
			(island_removal_mode 0)
		)
		(polygon
			(pts
				(arc
					(start 309.788814 -211.633054)
					(mid 309.699011 -211.670251)
					(end 309.661814 -211.760054)
				)
				(arc
					(start 309.661814 -213.080854)
					(mid 309.699011 -213.170657)
					(end 309.788814 -213.207854)
				)
				(arc
					(start 311.211214 -213.207854)
					(mid 311.301017 -213.170657)
					(end 311.338214 -213.080854)
				)
				(arc
					(start 311.338214 -211.760054)
					(mid 311.301017 -211.670251)
					(end 311.211214 -211.633054)
				)
			)
		)
	)
	(zone
		(net "AGND_CURRENT_MON")
		(layer "In1.Cu")
		(hatch none 0.5)
		(connect_pads
			(clearance 0.5)
		)
		(min_thickness 0.25)
		(fill yes
			(thermal_gap 0.5)
			(thermal_bridge_width 0.5)
			(island_removal_mode 0)
		)
		(polygon
			(pts
				(xy 8.206994 -178.3715) (xy 7.3025 -179.275994) (xy 7.3025 -181.404006) (xy 7.825994 -181.9275)
				(xy 9.222994 -181.9275) (xy 10.365994 -183.0705) (xy 12.270994 -183.0705) (xy 12.6365 -183.436006)
				(xy 12.6365 -184.609994) (xy 12.0015 -185.244994) (xy 12.0015 -187.022994) (xy 11.127994 -187.8965)
				(xy 10.111994 -187.8965) (xy 8.714994 -189.2935) (xy 6.174994 -189.2935) (xy 5.6515 -189.816994)
				(xy 5.6515 -195.501006) (xy 9.095994 -198.9455) (xy 22.654006 -198.9455) (xy 24.4475 -197.152006)
				(xy 24.4475 -187.784994) (xy 23.416006 -186.7535) (xy 19.382994 -186.7535) (xy 18.493994 -187.6425)
				(xy 15.669006 -187.6425) (xy 15.3035 -187.276994) (xy 15.3035 -185.371994) (xy 15.161006 -185.2295)
				(xy 14.780006 -185.2295) (xy 14.4145 -184.863994) (xy 14.4145 -183.309006) (xy 16.0655 -181.658006)
				(xy 16.0655 -179.275994) (xy 15.161006 -178.3715)
			)
		)
	)
	(zone
		(layer "In1.Cu")
		(hatch none 0.5)
		(connect_pads
			(clearance 0)
		)
		(min_thickness 0.25)
		(keepout
			(tracks not_allowed)
			(vias allowed)
			(pads allowed)
			(copperpour not_allowed)
			(footprints allowed)
		)
		(placement
			(enabled no)
			(sheetname "")
		)
		(fill
			(thermal_gap 0.5)
			(thermal_bridge_width 0.5)
			(island_removal_mode 0)
		)
		(polygon
			(pts
				(arc
					(start 267.388848 -211.633054)
					(mid 267.299045 -211.670251)
					(end 267.261848 -211.760054)
				)
				(arc
					(start 267.261848 -213.080854)
					(mid 267.299045 -213.170657)
					(end 267.388848 -213.207854)
				)
				(arc
					(start 268.811248 -213.207854)
					(mid 268.901051 -213.170657)
					(end 268.938248 -213.080854)
				)
				(arc
					(start 268.938248 -211.760054)
					(mid 268.901051 -211.670251)
					(end 268.811248 -211.633054)
				)
			)
		)
	)
	(zone
		(layer "In1.Cu")
		(hatch none 0.5)
		(connect_pads
			(clearance 0)
		)
		(min_thickness 0.25)
		(keepout
			(tracks not_allowed)
			(vias allowed)
			(pads allowed)
			(copperpour not_allowed)
			(footprints allowed)
		)
		(placement
			(enabled no)
			(sheetname "")
		)
		(fill
			(thermal_gap 0.5)
			(thermal_bridge_width 0.5)
			(island_removal_mode 0)
		)
		(polygon
			(pts
				(arc
					(start 305.732434 -32.727138)
					(mid 305.642631 -32.764335)
					(end 305.605434 -32.854138)
				)
				(arc
					(start 305.605434 -34.174938)
					(mid 305.642631 -34.264741)
					(end 305.732434 -34.301938)
				)
				(arc
					(start 307.027834 -34.301938)
					(mid 307.117637 -34.264741)
					(end 307.154834 -34.174938)
				)
				(arc
					(start 307.154834 -32.854138)
					(mid 307.117637 -32.764335)
					(end 307.027834 -32.727138)
				)
			)
		)
	)
	(zone
		(layer "In1.Cu")
		(hatch none 0.5)
		(connect_pads
			(clearance 0)
		)
		(min_thickness 0.25)
		(keepout
			(tracks not_allowed)
			(vias allowed)
			(pads allowed)
			(copperpour not_allowed)
			(footprints allowed)
		)
		(placement
			(enabled no)
			(sheetname "")
		)
		(fill
			(thermal_gap 0.5)
			(thermal_bridge_width 0.5)
			(island_removal_mode 0)
		)
		(polygon
			(pts
				(arc
					(start 322.58889 -211.633054)
					(mid 322.499087 -211.670251)
					(end 322.46189 -211.760054)
				)
				(arc
					(start 322.46189 -213.080854)
					(mid 322.499087 -213.170657)
					(end 322.58889 -213.207854)
				)
				(arc
					(start 324.01129 -213.207854)
					(mid 324.101093 -213.170657)
					(end 324.13829 -213.080854)
				)
				(arc
					(start 324.13829 -211.760054)
					(mid 324.101093 -211.670251)
					(end 324.01129 -211.633054)
				)
			)
		)
	)
	(zone
		(layer "In1.Cu")
		(hatch none 0.5)
		(connect_pads
			(clearance 0)
		)
		(min_thickness 0.25)
		(keepout
			(tracks not_allowed)
			(vias allowed)
			(pads allowed)
			(copperpour not_allowed)
			(footprints allowed)
		)
		(placement
			(enabled no)
			(sheetname "")
		)
		(fill
			(thermal_gap 0.5)
			(thermal_bridge_width 0.5)
			(island_removal_mode 0)
		)
		(polygon
			(pts
				(arc
					(start 100.988876 -211.633054)
					(mid 100.899073 -211.670251)
					(end 100.861876 -211.760054)
				)
				(arc
					(start 100.861876 -213.080854)
					(mid 100.899073 -213.170657)
					(end 100.988876 -213.207854)
				)
				(arc
					(start 102.411276 -213.207854)
					(mid 102.501079 -213.170657)
					(end 102.538276 -213.080854)
				)
				(arc
					(start 102.538276 -211.760054)
					(mid 102.501079 -211.670251)
					(end 102.411276 -211.633054)
				)
			)
		)
	)
	(zone
		(layer "In1.Cu")
		(hatch none 0.5)
		(connect_pads
			(clearance 0)
		)
		(min_thickness 0.25)
		(keepout
			(tracks not_allowed)
			(vias allowed)
			(pads allowed)
			(copperpour not_allowed)
			(footprints allowed)
		)
		(placement
			(enabled no)
			(sheetname "")
		)
		(fill
			(thermal_gap 0.5)
			(thermal_bridge_width 0.5)
			(island_removal_mode 0)
		)
		(polygon
			(pts
				(arc
					(start 206.188818 -211.633054)
					(mid 206.099015 -211.670251)
					(end 206.061818 -211.760054)
				)
				(arc
					(start 206.061818 -213.080854)
					(mid 206.099015 -213.170657)
					(end 206.188818 -213.207854)
				)
				(arc
					(start 207.611218 -213.207854)
					(mid 207.701021 -213.170657)
					(end 207.738218 -213.080854)
				)
				(arc
					(start 207.738218 -211.760054)
					(mid 207.701021 -211.670251)
					(end 207.611218 -211.633054)
				)
			)
		)
	)
	(zone
		(layer "In1.Cu")
		(hatch none 0.5)
		(connect_pads
			(clearance 0)
		)
		(min_thickness 0.25)
		(keepout
			(tracks not_allowed)
			(vias allowed)
			(pads allowed)
			(copperpour not_allowed)
			(footprints allowed)
		)
		(placement
			(enabled no)
			(sheetname "")
		)
		(fill
			(thermal_gap 0.5)
			(thermal_bridge_width 0.5)
			(island_removal_mode 0)
		)
		(polygon
			(pts
				(arc
					(start 138.188954 -211.633054)
					(mid 138.099151 -211.670251)
					(end 138.061954 -211.760054)
				)
				(arc
					(start 138.061954 -213.080854)
					(mid 138.099151 -213.170657)
					(end 138.188954 -213.207854)
				)
				(arc
					(start 139.611354 -213.207854)
					(mid 139.701157 -213.170657)
					(end 139.738354 -213.080854)
				)
				(arc
					(start 139.738354 -211.760054)
					(mid 139.701157 -211.670251)
					(end 139.611354 -211.633054)
				)
			)
		)
	)
	(zone
		(layer "In1.Cu")
		(hatch none 0.5)
		(connect_pads
			(clearance 0)
		)
		(min_thickness 0.25)
		(keepout
			(tracks not_allowed)
			(vias allowed)
			(pads allowed)
			(copperpour not_allowed)
			(footprints allowed)
		)
		(placement
			(enabled no)
			(sheetname "")
		)
		(fill
			(thermal_gap 0.5)
			(thermal_bridge_width 0.5)
			(island_removal_mode 0)
		)
		(polygon
			(pts
				(arc
					(start 273.2786 -12.3698)
					(mid 273.188797 -12.406997)
					(end 273.1516 -12.4968)
				)
				(arc
					(start 273.1516 -13.7922)
					(mid 273.188797 -13.882003)
					(end 273.2786 -13.9192)
				)
				(arc
					(start 274.5994 -13.9192)
					(mid 274.689203 -13.882003)
					(end 274.7264 -13.7922)
				)
				(arc
					(start 274.7264 -12.4968)
					(mid 274.689203 -12.406997)
					(end 274.5994 -12.3698)
				)
			)
		)
	)
	(zone
		(net "GND")
		(layer "In1.Cu")
		(hatch none 0.5)
		(connect_pads
			(clearance 0.5)
		)
		(min_thickness 0.25)
		(fill yes
			(thermal_gap 0.5)
			(thermal_bridge_width 0.5)
			(island_removal_mode 0)
		)
		(polygon
			(pts
				(xy 6.047994 -67.5767) (xy 5.9055 -67.719194) (xy 5.9055 -74.266806) (xy 6.073394 -74.4347) (xy 8.963406 -74.4347)
				(xy 10.0457 -73.352406) (xy 10.0457 -68.811394) (xy 8.811006 -67.5767)
			)
		)
	)
	(zone
		(layer "In1.Cu")
		(hatch none 0.5)
		(connect_pads
			(clearance 0)
		)
		(min_thickness 0.25)
		(keepout
			(tracks not_allowed)
			(vias allowed)
			(pads allowed)
			(copperpour not_allowed)
			(footprints allowed)
		)
		(placement
			(enabled no)
			(sheetname "")
		)
		(fill
			(thermal_gap 0.5)
			(thermal_bridge_width 0.5)
			(island_removal_mode 0)
		)
		(polygon
			(pts
				(arc
					(start 26.633932 -108.766356)
					(mid 26.70757 -108.735854)
					(end 26.738072 -108.662216)
				)
				(arc
					(start 26.738072 -108.255816)
					(mid 26.70757 -108.182178)
					(end 26.633932 -108.151676)
				)
				(arc
					(start 26.227532 -108.151676)
					(mid 26.153894 -108.182178)
					(end 26.123392 -108.255816)
				)
				(arc
					(start 26.123392 -108.662216)
					(mid 26.153894 -108.735854)
					(end 26.227532 -108.766356)
				)
			)
		)
	)
	(zone
		(layer "In1.Cu")
		(hatch none 0.5)
		(connect_pads
			(clearance 0)
		)
		(min_thickness 0.25)
		(keepout
			(tracks not_allowed)
			(vias allowed)
			(pads allowed)
			(copperpour not_allowed)
			(footprints allowed)
		)
		(placement
			(enabled no)
			(sheetname "")
		)
		(fill
			(thermal_gap 0.5)
			(thermal_bridge_width 0.5)
			(island_removal_mode 0)
		)
		(polygon
			(pts
				(arc
					(start 147.788884 -211.633054)
					(mid 147.699081 -211.670251)
					(end 147.661884 -211.760054)
				)
				(arc
					(start 147.661884 -213.080854)
					(mid 147.699081 -213.170657)
					(end 147.788884 -213.207854)
				)
				(arc
					(start 149.211284 -213.207854)
					(mid 149.301087 -213.170657)
					(end 149.338284 -213.080854)
				)
				(arc
					(start 149.338284 -211.760054)
					(mid 149.301087 -211.670251)
					(end 149.211284 -211.633054)
				)
			)
		)
	)
	(zone
		(layer "In1.Cu")
		(hatch none 0.5)
		(connect_pads
			(clearance 0)
		)
		(min_thickness 0.25)
		(keepout
			(tracks not_allowed)
			(vias allowed)
			(pads allowed)
			(copperpour not_allowed)
			(footprints allowed)
		)
		(placement
			(enabled no)
			(sheetname "")
		)
		(fill
			(thermal_gap 0.5)
			(thermal_bridge_width 0.5)
			(island_removal_mode 0)
		)
		(polygon
			(pts
				(arc
					(start 316.188852 -211.633054)
					(mid 316.099049 -211.670251)
					(end 316.061852 -211.760054)
				)
				(arc
					(start 316.061852 -213.080854)
					(mid 316.099049 -213.170657)
					(end 316.188852 -213.207854)
				)
				(arc
					(start 317.611252 -213.207854)
					(mid 317.701055 -213.170657)
					(end 317.738252 -213.080854)
				)
				(arc
					(start 317.738252 -211.760054)
					(mid 317.701055 -211.670251)
					(end 317.611252 -211.633054)
				)
			)
		)
	)
	(zone
		(layer "In1.Cu")
		(hatch none 0.5)
		(connect_pads
			(clearance 0)
		)
		(min_thickness 0.25)
		(keepout
			(tracks not_allowed)
			(vias allowed)
			(pads allowed)
			(copperpour not_allowed)
			(footprints allowed)
		)
		(placement
			(enabled no)
			(sheetname "")
		)
		(fill
			(thermal_gap 0.5)
			(thermal_bridge_width 0.5)
			(island_removal_mode 0)
		)
		(polygon
			(pts
				(arc
					(start 150.98903 -211.633054)
					(mid 150.899227 -211.670251)
					(end 150.86203 -211.760054)
				)
				(arc
					(start 150.86203 -213.080854)
					(mid 150.899227 -213.170657)
					(end 150.98903 -213.207854)
				)
				(arc
					(start 152.41143 -213.207854)
					(mid 152.501233 -213.170657)
					(end 152.53843 -213.080854)
				)
				(arc
					(start 152.53843 -211.760054)
					(mid 152.501233 -211.670251)
					(end 152.41143 -211.633054)
				)
			)
		)
	)
	(zone
		(layer "In1.Cu")
		(hatch none 0.5)
		(connect_pads
			(clearance 0)
		)
		(min_thickness 0.25)
		(keepout
			(tracks not_allowed)
			(vias allowed)
			(pads allowed)
			(copperpour not_allowed)
			(footprints allowed)
		)
		(placement
			(enabled no)
			(sheetname "")
		)
		(fill
			(thermal_gap 0.5)
			(thermal_bridge_width 0.5)
			(island_removal_mode 0)
		)
		(polygon
			(pts
				(arc
					(start 215.788748 -211.633054)
					(mid 215.698945 -211.670251)
					(end 215.661748 -211.760054)
				)
				(arc
					(start 215.661748 -213.080854)
					(mid 215.698945 -213.170657)
					(end 215.788748 -213.207854)
				)
				(arc
					(start 217.211148 -213.207854)
					(mid 217.300951 -213.170657)
					(end 217.338148 -213.080854)
				)
				(arc
					(start 217.338148 -211.760054)
					(mid 217.300951 -211.670251)
					(end 217.211148 -211.633054)
				)
			)
		)
	)
	(zone
		(layer "In1.Cu")
		(hatch none 0.5)
		(connect_pads
			(clearance 0)
		)
		(min_thickness 0.25)
		(keepout
			(tracks not_allowed)
			(vias allowed)
			(pads allowed)
			(copperpour not_allowed)
			(footprints allowed)
		)
		(placement
			(enabled no)
			(sheetname "")
		)
		(fill
			(thermal_gap 0.5)
			(thermal_bridge_width 0.5)
			(island_removal_mode 0)
		)
		(polygon
			(pts
				(arc
					(start 285.8262 -32.639)
					(mid 285.736397 -32.676197)
					(end 285.6992 -32.766)
				)
				(arc
					(start 285.6992 -34.0614)
					(mid 285.736397 -34.151203)
					(end 285.8262 -34.1884)
				)
				(arc
					(start 287.147 -34.1884)
					(mid 287.236803 -34.151203)
					(end 287.274 -34.0614)
				)
				(arc
					(start 287.274 -32.766)
					(mid 287.236803 -32.676197)
					(end 287.147 -32.639)
				)
			)
		)
	)
	(zone
		(layer "In1.Cu")
		(hatch none 0.5)
		(connect_pads
			(clearance 0)
		)
		(min_thickness 0.25)
		(keepout
			(tracks not_allowed)
			(vias allowed)
			(pads allowed)
			(copperpour not_allowed)
			(footprints allowed)
		)
		(placement
			(enabled no)
			(sheetname "")
		)
		(fill
			(thermal_gap 0.5)
			(thermal_bridge_width 0.5)
			(island_removal_mode 0)
		)
		(polygon
			(pts
				(arc
					(start 27.0764 -143.3322)
					(mid 26.986597 -143.369397)
					(end 26.9494 -143.4592)
				)
				(arc
					(start 26.9494 -143.8148)
					(mid 26.986597 -143.904603)
					(end 27.0764 -143.9418)
				)
				(arc
					(start 28.2956 -143.9418)
					(mid 28.385403 -143.904603)
					(end 28.4226 -143.8148)
				)
				(arc
					(start 28.4226 -143.4592)
					(mid 28.385403 -143.369397)
					(end 28.2956 -143.3322)
				)
			)
		)
	)
	(zone
		(layers "In1.Cu" "In2.Cu")
		(hatch none 0.5)
		(connect_pads
			(clearance 0)
		)
		(min_thickness 0.25)
		(keepout
			(tracks not_allowed)
			(vias allowed)
			(pads allowed)
			(copperpour not_allowed)
			(footprints allowed)
		)
		(placement
			(enabled no)
			(sheetname "")
		)
		(fill yes
			(thermal_gap 0.5)
			(thermal_bridge_width 0.5)
			(island_removal_mode 0)
		)
		(polygon
			(pts
				(arc
					(start 180.9496 -21.2598)
					(mid 180.859797 -21.296997)
					(end 180.8226 -21.3868)
				)
				(arc
					(start 180.8226 -22.6822)
					(mid 180.859797 -22.772003)
					(end 180.9496 -22.8092)
				)
				(arc
					(start 182.2704 -22.8092)
					(mid 182.360203 -22.772003)
					(end 182.3974 -22.6822)
				)
				(arc
					(start 182.3974 -21.3868)
					(mid 182.360203 -21.296997)
					(end 182.2704 -21.2598)
				)
			)
		)
	)
	(zone
		(layers "In1.Cu" "In2.Cu")
		(hatch none 0.5)
		(connect_pads
			(clearance 0)
		)
		(min_thickness 0.25)
		(keepout
			(tracks not_allowed)
			(vias allowed)
			(pads allowed)
			(copperpour not_allowed)
			(footprints allowed)
		)
		(placement
			(enabled no)
			(sheetname "")
		)
		(fill yes
			(thermal_gap 0.5)
			(thermal_bridge_width 0.5)
			(island_removal_mode 0)
		)
		(polygon
			(pts
				(arc
					(start 303.5808 -32.7406)
					(mid 303.490997 -32.777797)
					(end 303.4538 -32.8676)
				)
				(arc
					(start 303.4538 -34.1884)
					(mid 303.490997 -34.278203)
					(end 303.5808 -34.3154)
				)
				(arc
					(start 304.8762 -34.3154)
					(mid 304.966003 -34.278203)
					(end 305.0032 -34.1884)
				)
				(arc
					(start 305.0032 -32.8676)
					(mid 304.966003 -32.777797)
					(end 304.8762 -32.7406)
				)
			)
		)
	)
	(zone
		(layers "In1.Cu" "In2.Cu")
		(hatch none 0.5)
		(connect_pads
			(clearance 0)
		)
		(min_thickness 0.25)
		(keepout
			(tracks not_allowed)
			(vias allowed)
			(pads allowed)
			(copperpour not_allowed)
			(footprints allowed)
		)
		(placement
			(enabled no)
			(sheetname "")
		)
		(fill yes
			(thermal_gap 0.5)
			(thermal_bridge_width 0.5)
			(island_removal_mode 0)
		)
		(polygon
			(pts
				(arc
					(start 310.171592 -32.768286)
					(mid 310.081789 -32.805483)
					(end 310.044592 -32.895286)
				)
				(arc
					(start 310.044592 -34.216086)
					(mid 310.081789 -34.305889)
					(end 310.171592 -34.343086)
				)
				(arc
					(start 311.466992 -34.343086)
					(mid 311.556795 -34.305889)
					(end 311.593992 -34.216086)
				)
				(arc
					(start 311.593992 -32.895286)
					(mid 311.556795 -32.805483)
					(end 311.466992 -32.768286)
				)
			)
		)
	)
	(zone
		(layers "In1.Cu" "In2.Cu")
		(hatch none 0.5)
		(connect_pads
			(clearance 0)
		)
		(min_thickness 0.25)
		(keepout
			(tracks not_allowed)
			(vias allowed)
			(pads allowed)
			(copperpour not_allowed)
			(footprints allowed)
		)
		(placement
			(enabled no)
			(sheetname "")
		)
		(fill yes
			(thermal_gap 0.5)
			(thermal_bridge_width 0.5)
			(island_removal_mode 0)
		)
		(polygon
			(pts
				(xy 163.790122 -89.174066) (xy 163.790122 -89.978738) (xy 163.790122 -90.168222) (xy 162.748722 -90.168222)
				(xy 162.748722 -89.978738) (xy 162.748722 -89.174066) (xy 162.748722 -88.980518) (xy 163.790122 -88.980518)
			)
		)
	)
	(zone
		(layers "In1.Cu" "In2.Cu")
		(hatch none 0.5)
		(connect_pads
			(clearance 0)
		)
		(min_thickness 0.25)
		(keepout
			(tracks not_allowed)
			(vias allowed)
			(pads allowed)
			(copperpour not_allowed)
			(footprints allowed)
		)
		(placement
			(enabled no)
			(sheetname "")
		)
		(fill yes
			(thermal_gap 0.5)
			(thermal_bridge_width 0.5)
			(island_removal_mode 0)
		)
		(polygon
			(pts
				(arc
					(start 25.241504 -109.12348)
					(mid 25.167866 -109.153982)
					(end 25.137364 -109.22762)
				)
				(arc
					(start 25.137364 -109.58322)
					(mid 25.167866 -109.656858)
					(end 25.241504 -109.68736)
				)
				(arc
					(start 25.597104 -109.68736)
					(mid 25.670742 -109.656858)
					(end 25.701244 -109.58322)
				)
				(arc
					(start 25.701244 -109.22762)
					(mid 25.670742 -109.153982)
					(end 25.597104 -109.12348)
				)
			)
		)
	)
	(zone
		(layers "In1.Cu" "In2.Cu")
		(hatch none 0.5)
		(connect_pads
			(clearance 0)
		)
		(min_thickness 0.25)
		(keepout
			(tracks not_allowed)
			(vias allowed)
			(pads allowed)
			(copperpour not_allowed)
			(footprints allowed)
		)
		(placement
			(enabled no)
			(sheetname "")
		)
		(fill yes
			(thermal_gap 0.5)
			(thermal_bridge_width 0.5)
			(island_removal_mode 0)
		)
		(polygon
			(pts
				(arc
					(start 152.4 -32.7152)
					(mid 152.310197 -32.752397)
					(end 152.273 -32.8422)
				)
				(arc
					(start 152.273 -34.163)
					(mid 152.310197 -34.252803)
					(end 152.4 -34.29)
				)
				(arc
					(start 153.6954 -34.29)
					(mid 153.785203 -34.252803)
					(end 153.8224 -34.163)
				)
				(arc
					(start 153.8224 -32.8422)
					(mid 153.785203 -32.752397)
					(end 153.6954 -32.7152)
				)
			)
		)
	)
	(zone
		(layers "In1.Cu" "In2.Cu")
		(hatch none 0.5)
		(connect_pads
			(clearance 0)
		)
		(min_thickness 0.25)
		(keepout
			(tracks not_allowed)
			(vias allowed)
			(pads allowed)
			(copperpour not_allowed)
			(footprints allowed)
		)
		(placement
			(enabled no)
			(sheetname "")
		)
		(fill yes
			(thermal_gap 0.5)
			(thermal_bridge_width 0.5)
			(island_removal_mode 0)
		)
		(polygon
			(pts
				(arc
					(start 161.3662 -84.5312)
					(mid 161.294358 -84.560958)
					(end 161.2646 -84.6328)
				)
				(arc
					(start 161.2646 -85.852)
					(mid 161.294358 -85.923842)
					(end 161.3662 -85.9536)
				)
				(arc
					(start 162.7378 -85.9536)
					(mid 162.809642 -85.923842)
					(end 162.8394 -85.852)
				)
				(arc
					(start 162.8394 -84.6328)
					(mid 162.809642 -84.560958)
					(end 162.7378 -84.5312)
				)
				(arc
					(start 162.3822 -84.5312)
					(mid 162.370698 -84.531824)
					(end 162.35934 -84.53374)
				)
				(xy 162.3568 -84.5312)
			)
		)
	)
	(zone
		(layers "In1.Cu" "In2.Cu")
		(hatch none 0.5)
		(connect_pads
			(clearance 0)
		)
		(min_thickness 0.25)
		(keepout
			(tracks not_allowed)
			(vias allowed)
			(pads allowed)
			(copperpour not_allowed)
			(footprints allowed)
		)
		(placement
			(enabled no)
			(sheetname "")
		)
		(fill yes
			(thermal_gap 0.5)
			(thermal_bridge_width 0.5)
			(island_removal_mode 0)
		)
		(polygon
			(pts
				(arc
					(start 301.40529 -32.752792)
					(mid 301.315487 -32.789989)
					(end 301.27829 -32.879792)
				)
				(arc
					(start 301.27829 -34.200592)
					(mid 301.315487 -34.290395)
					(end 301.40529 -34.327592)
				)
				(arc
					(start 302.70069 -34.327592)
					(mid 302.790493 -34.290395)
					(end 302.82769 -34.200592)
				)
				(arc
					(start 302.82769 -32.879792)
					(mid 302.790493 -32.789989)
					(end 302.70069 -32.752792)
				)
			)
		)
	)
	(zone
		(layers "In1.Cu" "In2.Cu")
		(hatch none 0.5)
		(connect_pads
			(clearance 0)
		)
		(min_thickness 0.25)
		(keepout
			(tracks not_allowed)
			(vias allowed)
			(pads allowed)
			(copperpour not_allowed)
			(footprints allowed)
		)
		(placement
			(enabled no)
			(sheetname "")
		)
		(fill yes
			(thermal_gap 0.5)
			(thermal_bridge_width 0.5)
			(island_removal_mode 0)
		)
		(polygon
			(pts
				(xy 160.879536 -87.568278) (xy 161.684462 -87.568278) (xy 161.878264 -87.568278) (xy 161.878264 -88.609678)
				(xy 161.684462 -88.609678) (xy 160.879536 -88.609678) (xy 160.879536 -88.608662) (xy 160.685226 -88.608662)
				(xy 160.685226 -87.568024) (xy 160.879536 -87.568024)
			)
		)
	)
	(zone
		(layers "In1.Cu" "In2.Cu")
		(hatch none 0.5)
		(connect_pads
			(clearance 0)
		)
		(min_thickness 0.25)
		(keepout
			(tracks not_allowed)
			(vias allowed)
			(pads allowed)
			(copperpour not_allowed)
			(footprints allowed)
		)
		(placement
			(enabled no)
			(sheetname "")
		)
		(fill yes
			(thermal_gap 0.5)
			(thermal_bridge_width 0.5)
			(island_removal_mode 0)
		)
		(polygon
			(pts
				(arc
					(start 325.715122 -32.67202)
					(mid 325.625319 -32.709217)
					(end 325.588122 -32.79902)
				)
				(arc
					(start 325.588122 -34.11982)
					(mid 325.625319 -34.209623)
					(end 325.715122 -34.24682)
				)
				(arc
					(start 327.010522 -34.24682)
					(mid 327.100325 -34.209623)
					(end 327.137522 -34.11982)
				)
				(arc
					(start 327.137522 -32.79902)
					(mid 327.100325 -32.709217)
					(end 327.010522 -32.67202)
				)
			)
		)
	)
	(zone
		(layers "In1.Cu" "In2.Cu")
		(hatch none 0.5)
		(connect_pads
			(clearance 0)
		)
		(min_thickness 0.25)
		(keepout
			(tracks not_allowed)
			(vias allowed)
			(pads allowed)
			(copperpour not_allowed)
			(footprints allowed)
		)
		(placement
			(enabled no)
			(sheetname "")
		)
		(fill yes
			(thermal_gap 0.5)
			(thermal_bridge_width 0.5)
			(island_removal_mode 0)
		)
		(polygon
			(pts
				(arc
					(start 180.9496 -28.6258)
					(mid 180.859797 -28.662997)
					(end 180.8226 -28.7528)
				)
				(arc
					(start 180.8226 -30.0482)
					(mid 180.859797 -30.138003)
					(end 180.9496 -30.1752)
				)
				(arc
					(start 182.2704 -30.1752)
					(mid 182.360203 -30.138003)
					(end 182.3974 -30.0482)
				)
				(arc
					(start 182.3974 -28.7528)
					(mid 182.360203 -28.662997)
					(end 182.2704 -28.6258)
				)
			)
		)
	)
	(zone
		(layers "In1.Cu" "In2.Cu")
		(hatch none 0.5)
		(connect_pads
			(clearance 0)
		)
		(min_thickness 0.25)
		(keepout
			(tracks not_allowed)
			(vias allowed)
			(pads allowed)
			(copperpour not_allowed)
			(footprints allowed)
		)
		(placement
			(enabled no)
			(sheetname "")
		)
		(fill yes
			(thermal_gap 0.5)
			(thermal_bridge_width 0.5)
			(island_removal_mode 0)
		)
		(polygon
			(pts
				(arc
					(start 26.227532 -108.151676)
					(mid 26.153894 -108.182178)
					(end 26.123392 -108.255816)
				)
				(xy 26.123392 -109.521244) (xy 26.124408 -109.52226)
				(arc
					(start 26.124408 -109.52988)
					(mid 26.15491 -109.603518)
					(end 26.228548 -109.63402)
				)
				(arc
					(start 27.549348 -109.63402)
					(mid 27.622986 -109.603518)
					(end 27.653488 -109.52988)
				)
				(xy 27.653488 -109.12348) (xy 27.652472 -109.109002)
				(arc
					(start 27.652472 -108.255816)
					(mid 27.62197 -108.182178)
					(end 27.548332 -108.151676)
				)
			)
		)
	)
	(zone
		(layers "In1.Cu" "In2.Cu")
		(hatch none 0.5)
		(connect_pads
			(clearance 0)
		)
		(min_thickness 0.25)
		(keepout
			(tracks not_allowed)
			(vias allowed)
			(pads allowed)
			(copperpour not_allowed)
			(footprints allowed)
		)
		(placement
			(enabled no)
			(sheetname "")
		)
		(fill yes
			(thermal_gap 0.5)
			(thermal_bridge_width 0.5)
			(island_removal_mode 0)
		)
		(polygon
			(pts
				(arc
					(start 180.9496 -23.2918)
					(mid 180.859797 -23.328997)
					(end 180.8226 -23.4188)
				)
				(arc
					(start 180.8226 -24.7142)
					(mid 180.859797 -24.804003)
					(end 180.9496 -24.8412)
				)
				(arc
					(start 182.2704 -24.8412)
					(mid 182.360203 -24.804003)
					(end 182.3974 -24.7142)
				)
				(arc
					(start 182.3974 -23.4188)
					(mid 182.360203 -23.328997)
					(end 182.2704 -23.2918)
				)
			)
		)
	)
	(zone
		(layers "In1.Cu" "In2.Cu")
		(hatch none 0.5)
		(connect_pads
			(clearance 0)
		)
		(min_thickness 0.25)
		(keepout
			(tracks not_allowed)
			(vias allowed)
			(pads allowed)
			(copperpour not_allowed)
			(footprints allowed)
		)
		(placement
			(enabled no)
			(sheetname "")
		)
		(fill yes
			(thermal_gap 0.5)
			(thermal_bridge_width 0.5)
			(island_removal_mode 0)
		)
		(polygon
			(pts
				(arc
					(start 145.669 -32.73552)
					(mid 145.579197 -32.772717)
					(end 145.542 -32.86252)
				)
				(arc
					(start 145.542 -34.18332)
					(mid 145.579197 -34.273123)
					(end 145.669 -34.31032)
				)
				(arc
					(start 146.9644 -34.31032)
					(mid 147.054203 -34.273123)
					(end 147.0914 -34.18332)
				)
				(arc
					(start 147.0914 -32.86252)
					(mid 147.054203 -32.772717)
					(end 146.9644 -32.73552)
				)
			)
		)
	)
	(zone
		(layers "In1.Cu" "In2.Cu")
		(hatch none 0.5)
		(connect_pads
			(clearance 0)
		)
		(min_thickness 0.25)
		(keepout
			(tracks not_allowed)
			(vias allowed)
			(pads allowed)
			(copperpour not_allowed)
			(footprints allowed)
		)
		(placement
			(enabled no)
			(sheetname "")
		)
		(fill yes
			(thermal_gap 0.5)
			(thermal_bridge_width 0.5)
			(island_removal_mode 0)
		)
		(polygon
			(pts
				(arc
					(start 24.217884 -108.10748)
					(mid 24.144246 -108.137982)
					(end 24.113744 -108.21162)
				)
				(arc
					(start 24.113744 -108.56722)
					(mid 24.144246 -108.640858)
					(end 24.217884 -108.67136)
				)
				(arc
					(start 24.573484 -108.67136)
					(mid 24.647122 -108.640858)
					(end 24.677624 -108.56722)
				)
				(arc
					(start 24.677624 -108.21162)
					(mid 24.647122 -108.137982)
					(end 24.573484 -108.10748)
				)
			)
		)
	)
	(zone
		(layers "In1.Cu" "In2.Cu")
		(hatch none 0.5)
		(connect_pads
			(clearance 0)
		)
		(min_thickness 0.25)
		(keepout
			(tracks not_allowed)
			(vias allowed)
			(pads allowed)
			(copperpour not_allowed)
			(footprints allowed)
		)
		(placement
			(enabled no)
			(sheetname "")
		)
		(fill yes
			(thermal_gap 0.5)
			(thermal_bridge_width 0.5)
			(island_removal_mode 0)
		)
		(polygon
			(pts
				(arc
					(start 24.572722 -109.690662)
					(mid 24.64636 -109.66016)
					(end 24.676862 -109.586522)
				)
				(arc
					(start 24.676862 -109.230922)
					(mid 24.64636 -109.157284)
					(end 24.572722 -109.126782)
				)
				(arc
					(start 24.217122 -109.126782)
					(mid 24.143484 -109.157284)
					(end 24.112982 -109.230922)
				)
				(arc
					(start 24.112982 -109.586522)
					(mid 24.143484 -109.66016)
					(end 24.217122 -109.690662)
				)
			)
		)
	)
	(zone
		(layers "In1.Cu" "In2.Cu")
		(hatch none 0.5)
		(connect_pads
			(clearance 0)
		)
		(min_thickness 0.25)
		(keepout
			(tracks not_allowed)
			(vias allowed)
			(pads allowed)
			(copperpour not_allowed)
			(footprints allowed)
		)
		(placement
			(enabled no)
			(sheetname "")
		)
		(fill yes
			(thermal_gap 0.5)
			(thermal_bridge_width 0.5)
			(island_removal_mode 0)
		)
		(polygon
			(pts
				(arc
					(start 180.9496 -19.4818)
					(mid 180.859797 -19.518997)
					(end 180.8226 -19.6088)
				)
				(arc
					(start 180.8226 -20.9042)
					(mid 180.859797 -20.994003)
					(end 180.9496 -21.0312)
				)
				(arc
					(start 182.2704 -21.0312)
					(mid 182.360203 -20.994003)
					(end 182.3974 -20.9042)
				)
				(arc
					(start 182.3974 -19.6088)
					(mid 182.360203 -19.518997)
					(end 182.2704 -19.4818)
				)
			)
		)
	)
	(zone
		(layers "In1.Cu" "In2.Cu")
		(hatch none 0.5)
		(connect_pads
			(clearance 0)
		)
		(min_thickness 0.25)
		(keepout
			(tracks not_allowed)
			(vias allowed)
			(pads allowed)
			(copperpour not_allowed)
			(footprints allowed)
		)
		(placement
			(enabled no)
			(sheetname "")
		)
		(fill yes
			(thermal_gap 0.5)
			(thermal_bridge_width 0.5)
			(island_removal_mode 0)
		)
		(polygon
			(pts
				(arc
					(start 54.4322 -127.3302)
					(mid 54.402442 -127.258358)
					(end 54.3306 -127.2286)
				)
				(arc
					(start 53.1114 -127.2286)
					(mid 53.039558 -127.258358)
					(end 53.0098 -127.3302)
				)
				(arc
					(start 53.0098 -128.70434)
					(mid 53.039558 -128.776182)
					(end 53.1114 -128.80594)
				)
				(arc
					(start 54.3306 -128.80594)
					(mid 54.402442 -128.776182)
					(end 54.4322 -128.70434)
				)
			)
		)
	)
	(zone
		(layers "In1.Cu" "In2.Cu")
		(hatch none 0.5)
		(connect_pads
			(clearance 0)
		)
		(min_thickness 0.25)
		(keepout
			(tracks not_allowed)
			(vias allowed)
			(pads allowed)
			(copperpour not_allowed)
			(footprints allowed)
		)
		(placement
			(enabled no)
			(sheetname "")
		)
		(fill yes
			(thermal_gap 0.5)
			(thermal_bridge_width 0.5)
			(island_removal_mode 0)
		)
		(polygon
			(pts
				(arc
					(start 319.466976 -32.720026)
					(mid 319.377173 -32.757223)
					(end 319.339976 -32.847026)
				)
				(arc
					(start 319.339976 -34.167826)
					(mid 319.377173 -34.257629)
					(end 319.466976 -34.294826)
				)
				(arc
					(start 320.762376 -34.294826)
					(mid 320.852179 -34.257629)
					(end 320.889376 -34.167826)
				)
				(arc
					(start 320.889376 -32.847026)
					(mid 320.852179 -32.757223)
					(end 320.762376 -32.720026)
				)
			)
		)
	)
	(zone
		(layers "In1.Cu" "In2.Cu")
		(hatch none 0.5)
		(connect_pads
			(clearance 0)
		)
		(min_thickness 0.25)
		(keepout
			(tracks not_allowed)
			(vias allowed)
			(pads allowed)
			(copperpour not_allowed)
			(footprints allowed)
		)
		(placement
			(enabled no)
			(sheetname "")
		)
		(fill yes
			(thermal_gap 0.5)
			(thermal_bridge_width 0.5)
			(island_removal_mode 0)
		)
		(polygon
			(pts
				(arc
					(start 180.9496 -25.5778)
					(mid 180.859797 -25.614997)
					(end 180.8226 -25.7048)
				)
				(arc
					(start 180.8226 -27.0002)
					(mid 180.859797 -27.090003)
					(end 180.9496 -27.1272)
				)
				(arc
					(start 182.2704 -27.1272)
					(mid 182.360203 -27.090003)
					(end 182.3974 -27.0002)
				)
				(arc
					(start 182.3974 -25.7048)
					(mid 182.360203 -25.614997)
					(end 182.2704 -25.5778)
				)
			)
		)
	)
	(zone
		(layers "In1.Cu" "In2.Cu")
		(hatch none 0.5)
		(connect_pads
			(clearance 0)
		)
		(min_thickness 0.25)
		(keepout
			(tracks not_allowed)
			(vias allowed)
			(pads allowed)
			(copperpour not_allowed)
			(footprints allowed)
		)
		(placement
			(enabled no)
			(sheetname "")
		)
		(fill yes
			(thermal_gap 0.5)
			(thermal_bridge_width 0.5)
			(island_removal_mode 0)
		)
		(polygon
			(pts
				(arc
					(start 299.176694 -32.772858)
					(mid 299.086891 -32.810055)
					(end 299.049694 -32.899858)
				)
				(arc
					(start 299.049694 -34.220658)
					(mid 299.086891 -34.310461)
					(end 299.176694 -34.347658)
				)
				(arc
					(start 300.472094 -34.347658)
					(mid 300.561897 -34.310461)
					(end 300.599094 -34.220658)
				)
				(arc
					(start 300.599094 -32.899858)
					(mid 300.561897 -32.810055)
					(end 300.472094 -32.772858)
				)
			)
		)
	)
	(zone
		(layers "In1.Cu" "In2.Cu")
		(hatch none 0.5)
		(connect_pads
			(clearance 0)
		)
		(min_thickness 0.25)
		(keepout
			(tracks not_allowed)
			(vias allowed)
			(pads allowed)
			(copperpour not_allowed)
			(footprints allowed)
		)
		(placement
			(enabled no)
			(sheetname "")
		)
		(fill yes
			(thermal_gap 0.5)
			(thermal_bridge_width 0.5)
			(island_removal_mode 0)
		)
		(polygon
			(pts
				(arc
					(start 162.9918 -32.7406)
					(mid 162.901997 -32.777797)
					(end 162.8648 -32.8676)
				)
				(arc
					(start 162.8648 -34.1884)
					(mid 162.901997 -34.278203)
					(end 162.9918 -34.3154)
				)
				(arc
					(start 164.2872 -34.3154)
					(mid 164.377003 -34.278203)
					(end 164.4142 -34.1884)
				)
				(arc
					(start 164.4142 -32.8676)
					(mid 164.377003 -32.777797)
					(end 164.2872 -32.7406)
				)
			)
		)
	)
	(zone
		(layers "In1.Cu" "In2.Cu")
		(hatch none 0.5)
		(connect_pads
			(clearance 0)
		)
		(min_thickness 0.25)
		(keepout
			(tracks not_allowed)
			(vias allowed)
			(pads allowed)
			(copperpour not_allowed)
			(footprints allowed)
		)
		(placement
			(enabled no)
			(sheetname "")
		)
		(fill yes
			(thermal_gap 0.5)
			(thermal_bridge_width 0.5)
			(island_removal_mode 0)
		)
		(polygon
			(pts
				(arc
					(start 323.35851 -32.695388)
					(mid 323.268707 -32.732585)
					(end 323.23151 -32.822388)
				)
				(arc
					(start 323.23151 -34.143188)
					(mid 323.268707 -34.232991)
					(end 323.35851 -34.270188)
				)
				(arc
					(start 324.65391 -34.270188)
					(mid 324.743713 -34.232991)
					(end 324.78091 -34.143188)
				)
				(arc
					(start 324.78091 -32.822388)
					(mid 324.743713 -32.732585)
					(end 324.65391 -32.695388)
				)
			)
		)
	)
	(zone
		(layers "In1.Cu" "In2.Cu")
		(hatch none 0.5)
		(connect_pads
			(clearance 0)
		)
		(min_thickness 0.25)
		(keepout
			(tracks not_allowed)
			(vias allowed)
			(pads allowed)
			(copperpour not_allowed)
			(footprints allowed)
		)
		(placement
			(enabled no)
			(sheetname "")
		)
		(fill yes
			(thermal_gap 0.5)
			(thermal_bridge_width 0.5)
			(island_removal_mode 0)
		)
		(polygon
			(pts
				(arc
					(start 24.4475 -126.188978)
					(mid 24.463123 -126.226695)
					(end 24.50084 -126.242318)
				)
				(arc
					(start 24.70404 -126.242318)
					(mid 24.741757 -126.226695)
					(end 24.75738 -126.188978)
				)
				(arc
					(start 24.75738 -125.934978)
					(mid 24.741757 -125.897261)
					(end 24.70404 -125.881638)
				)
				(arc
					(start 24.50084 -125.881638)
					(mid 24.463123 -125.897261)
					(end 24.4475 -125.934978)
				)
			)
		)
	)
	(zone
		(layers "In1.Cu" "In2.Cu")
		(hatch none 0.5)
		(connect_pads
			(clearance 0)
		)
		(min_thickness 0.25)
		(keepout
			(tracks not_allowed)
			(vias allowed)
			(pads allowed)
			(copperpour not_allowed)
			(footprints allowed)
		)
		(placement
			(enabled no)
			(sheetname "")
		)
		(fill yes
			(thermal_gap 0.5)
			(thermal_bridge_width 0.5)
			(island_removal_mode 0)
		)
		(polygon
			(pts
				(arc
					(start 148.2598 -32.7406)
					(mid 148.169997 -32.777797)
					(end 148.1328 -32.8676)
				)
				(arc
					(start 148.1328 -34.1884)
					(mid 148.169997 -34.278203)
					(end 148.2598 -34.3154)
				)
				(arc
					(start 149.5552 -34.3154)
					(mid 149.645003 -34.278203)
					(end 149.6822 -34.1884)
				)
				(arc
					(start 149.6822 -32.8676)
					(mid 149.645003 -32.777797)
					(end 149.5552 -32.7406)
				)
			)
		)
	)
	(zone
		(layers "In1.Cu" "In2.Cu")
		(hatch none 0.5)
		(connect_pads
			(clearance 0)
		)
		(min_thickness 0.25)
		(keepout
			(tracks not_allowed)
			(vias allowed)
			(pads allowed)
			(copperpour not_allowed)
			(footprints allowed)
		)
		(placement
			(enabled no)
			(sheetname "")
		)
		(fill yes
			(thermal_gap 0.5)
			(thermal_bridge_width 0.5)
			(island_removal_mode 0)
		)
		(polygon
			(pts
				(arc
					(start 288.9758 -32.7406)
					(mid 288.885997 -32.777797)
					(end 288.8488 -32.8676)
				)
				(arc
					(start 288.8488 -34.1884)
					(mid 288.885997 -34.278203)
					(end 288.9758 -34.3154)
				)
				(arc
					(start 290.2712 -34.3154)
					(mid 290.361003 -34.278203)
					(end 290.3982 -34.1884)
				)
				(arc
					(start 290.3982 -32.8676)
					(mid 290.361003 -32.777797)
					(end 290.2712 -32.7406)
				)
			)
		)
	)
	(zone
		(layers "In1.Cu" "In2.Cu")
		(hatch none 0.5)
		(connect_pads
			(clearance 0)
		)
		(min_thickness 0.25)
		(keepout
			(tracks not_allowed)
			(vias allowed)
			(pads allowed)
			(copperpour not_allowed)
			(footprints allowed)
		)
		(placement
			(enabled no)
			(sheetname "")
		)
		(fill yes
			(thermal_gap 0.5)
			(thermal_bridge_width 0.5)
			(island_removal_mode 0)
		)
		(polygon
			(pts
				(arc
					(start 314.6298 -32.7406)
					(mid 314.539997 -32.777797)
					(end 314.5028 -32.8676)
				)
				(arc
					(start 314.5028 -34.1884)
					(mid 314.539997 -34.278203)
					(end 314.6298 -34.3154)
				)
				(arc
					(start 315.9252 -34.3154)
					(mid 316.015003 -34.278203)
					(end 316.0522 -34.1884)
				)
				(arc
					(start 316.0522 -32.8676)
					(mid 316.015003 -32.777797)
					(end 315.9252 -32.7406)
				)
			)
		)
	)
	(zone
		(layers "In1.Cu" "In2.Cu")
		(hatch none 0.5)
		(connect_pads
			(clearance 0)
		)
		(min_thickness 0.25)
		(keepout
			(tracks not_allowed)
			(vias allowed)
			(pads allowed)
			(copperpour not_allowed)
			(footprints allowed)
		)
		(placement
			(enabled no)
			(sheetname "")
		)
		(fill yes
			(thermal_gap 0.5)
			(thermal_bridge_width 0.5)
			(island_removal_mode 0)
		)
		(polygon
			(pts
				(arc
					(start 312.422286 -32.769048)
					(mid 312.332483 -32.806245)
					(end 312.295286 -32.896048)
				)
				(arc
					(start 312.295286 -34.216848)
					(mid 312.332483 -34.306651)
					(end 312.422286 -34.343848)
				)
				(arc
					(start 313.717686 -34.343848)
					(mid 313.807489 -34.306651)
					(end 313.844686 -34.216848)
				)
				(arc
					(start 313.844686 -32.896048)
					(mid 313.807489 -32.806245)
					(end 313.717686 -32.769048)
				)
			)
		)
	)
	(zone
		(layers "In1.Cu" "In2.Cu")
		(hatch none 0.5)
		(connect_pads
			(clearance 0)
		)
		(min_thickness 0.25)
		(keepout
			(tracks not_allowed)
			(vias allowed)
			(pads allowed)
			(copperpour not_allowed)
			(footprints allowed)
		)
		(placement
			(enabled no)
			(sheetname "")
		)
		(fill yes
			(thermal_gap 0.5)
			(thermal_bridge_width 0.5)
			(island_removal_mode 0)
		)
		(polygon
			(pts
				(arc
					(start 126.882652 -32.8803)
					(mid 126.81081 -32.910058)
					(end 126.781052 -32.9819)
				)
				(arc
					(start 126.781052 -34.2011)
					(mid 126.81081 -34.272942)
					(end 126.882652 -34.3027)
				)
				(arc
					(start 128.256792 -34.3027)
					(mid 128.328634 -34.272942)
					(end 128.358392 -34.2011)
				)
				(arc
					(start 128.358392 -32.9819)
					(mid 128.328634 -32.910058)
					(end 128.256792 -32.8803)
				)
			)
		)
	)
	(zone
		(layers "In1.Cu" "In2.Cu")
		(hatch none 0.5)
		(connect_pads
			(clearance 0)
		)
		(min_thickness 0.25)
		(keepout
			(tracks not_allowed)
			(vias allowed)
			(pads allowed)
			(copperpour not_allowed)
			(footprints allowed)
		)
		(placement
			(enabled no)
			(sheetname "")
		)
		(fill yes
			(thermal_gap 0.5)
			(thermal_bridge_width 0.5)
			(island_removal_mode 0)
		)
		(polygon
			(pts
				(arc
					(start 22.060154 -123.1011)
					(mid 21.970351 -123.138297)
					(end 21.933154 -123.2281)
				)
				(arc
					(start 21.933154 -124.5235)
					(mid 21.970351 -124.613303)
					(end 22.060154 -124.6505)
				)
				(arc
					(start 23.380954 -124.6505)
					(mid 23.470757 -124.613303)
					(end 23.507954 -124.5235)
				)
				(arc
					(start 23.507954 -123.2281)
					(mid 23.470757 -123.138297)
					(end 23.380954 -123.1011)
				)
			)
		)
	)
	(zone
		(layers "In1.Cu" "In2.Cu")
		(hatch none 0.5)
		(connect_pads
			(clearance 0)
		)
		(min_thickness 0.25)
		(keepout
			(tracks not_allowed)
			(vias allowed)
			(pads allowed)
			(copperpour not_allowed)
			(footprints allowed)
		)
		(placement
			(enabled no)
			(sheetname "")
		)
		(fill yes
			(thermal_gap 0.5)
			(thermal_bridge_width 0.5)
			(island_removal_mode 0)
		)
		(polygon
			(pts
				(arc
					(start 25.597866 -108.668058)
					(mid 25.671504 -108.637556)
					(end 25.702006 -108.563918)
				)
				(arc
					(start 25.702006 -108.208318)
					(mid 25.671504 -108.13468)
					(end 25.597866 -108.104178)
				)
				(arc
					(start 25.242266 -108.104178)
					(mid 25.168628 -108.13468)
					(end 25.138126 -108.208318)
				)
				(arc
					(start 25.138126 -108.563918)
					(mid 25.168628 -108.637556)
					(end 25.242266 -108.668058)
				)
			)
		)
	)
	(zone
		(layers "In1.Cu" "In2.Cu")
		(hatch none 0.5)
		(connect_pads
			(clearance 0)
		)
		(min_thickness 0.25)
		(keepout
			(tracks not_allowed)
			(vias allowed)
			(pads allowed)
			(copperpour not_allowed)
			(footprints allowed)
		)
		(placement
			(enabled no)
			(sheetname "")
		)
		(fill yes
			(thermal_gap 0.5)
			(thermal_bridge_width 0.5)
			(island_removal_mode 0)
		)
		(polygon
			(pts
				(arc
					(start 150.4188 -32.7406)
					(mid 150.328997 -32.777797)
					(end 150.2918 -32.8676)
				)
				(arc
					(start 150.2918 -34.1884)
					(mid 150.328997 -34.278203)
					(end 150.4188 -34.3154)
				)
				(arc
					(start 151.7142 -34.3154)
					(mid 151.804003 -34.278203)
					(end 151.8412 -34.1884)
				)
				(arc
					(start 151.8412 -32.8676)
					(mid 151.804003 -32.777797)
					(end 151.7142 -32.7406)
				)
			)
		)
	)
	(zone
		(layers "In1.Cu" "In2.Cu")
		(hatch none 0.5)
		(connect_pads
			(clearance 0)
		)
		(min_thickness 0.25)
		(keepout
			(tracks not_allowed)
			(vias allowed)
			(pads allowed)
			(copperpour not_allowed)
			(footprints allowed)
		)
		(placement
			(enabled no)
			(sheetname "")
		)
		(fill yes
			(thermal_gap 0.5)
			(thermal_bridge_width 0.5)
			(island_removal_mode 0)
		)
		(polygon
			(pts
				(arc
					(start 160.9598 -32.7406)
					(mid 160.869997 -32.777797)
					(end 160.8328 -32.8676)
				)
				(arc
					(start 160.8328 -34.1884)
					(mid 160.869997 -34.278203)
					(end 160.9598 -34.3154)
				)
				(arc
					(start 162.2552 -34.3154)
					(mid 162.345003 -34.278203)
					(end 162.3822 -34.1884)
				)
				(arc
					(start 162.3822 -32.8676)
					(mid 162.345003 -32.777797)
					(end 162.2552 -32.7406)
				)
			)
		)
	)
	(zone
		(layers "In1.Cu" "In2.Cu")
		(hatch none 0.5)
		(connect_pads
			(clearance 0)
		)
		(min_thickness 0.25)
		(keepout
			(tracks not_allowed)
			(vias allowed)
			(pads allowed)
			(copperpour not_allowed)
			(footprints allowed)
		)
		(placement
			(enabled no)
			(sheetname "")
		)
		(fill yes
			(thermal_gap 0.5)
			(thermal_bridge_width 0.5)
			(island_removal_mode 0)
		)
		(polygon
			(pts
				(arc
					(start 24.4475 -125.630178)
					(mid 24.463123 -125.667895)
					(end 24.50084 -125.683518)
				)
				(arc
					(start 24.70404 -125.683518)
					(mid 24.741757 -125.667895)
					(end 24.75738 -125.630178)
				)
				(arc
					(start 24.75738 -125.376178)
					(mid 24.741757 -125.338461)
					(end 24.70404 -125.322838)
				)
				(arc
					(start 24.50084 -125.322838)
					(mid 24.463123 -125.338461)
					(end 24.4475 -125.376178)
				)
			)
		)
	)
	(zone
		(layers "In1.Cu" "In2.Cu")
		(hatch none 0.5)
		(connect_pads
			(clearance 0)
		)
		(min_thickness 0.25)
		(keepout
			(tracks not_allowed)
			(vias allowed)
			(pads allowed)
			(copperpour not_allowed)
			(footprints allowed)
		)
		(placement
			(enabled no)
			(sheetname "")
		)
		(fill yes
			(thermal_gap 0.5)
			(thermal_bridge_width 0.5)
			(island_removal_mode 0)
		)
		(polygon
			(pts
				(arc
					(start 213.381844 -39.98976)
					(mid 213.344647 -39.899957)
					(end 213.254844 -39.86276)
				)
				(arc
					(start 211.934044 -39.86276)
					(mid 211.844241 -39.899957)
					(end 211.807044 -39.98976)
				)
				(arc
					(start 211.807044 -41.28516)
					(mid 211.844241 -41.374963)
					(end 211.934044 -41.41216)
				)
				(arc
					(start 213.254844 -41.41216)
					(mid 213.344647 -41.374963)
					(end 213.381844 -41.28516)
				)
			)
		)
	)
	(zone
		(layers "In1.Cu" "In2.Cu")
		(hatch none 0.5)
		(connect_pads
			(clearance 0)
		)
		(min_thickness 0.25)
		(keepout
			(tracks not_allowed)
			(vias allowed)
			(pads allowed)
			(copperpour not_allowed)
			(footprints allowed)
		)
		(placement
			(enabled no)
			(sheetname "")
		)
		(fill yes
			(thermal_gap 0.5)
			(thermal_bridge_width 0.5)
			(island_removal_mode 0)
		)
		(polygon
			(pts
				(arc
					(start 165.5064 -88.265)
					(mid 165.434558 -88.294758)
					(end 165.4048 -88.3666)
				)
				(arc
					(start 165.4048 -89.7382)
					(mid 165.434558 -89.810042)
					(end 165.5064 -89.8398)
				)
				(arc
					(start 166.7256 -89.8398)
					(mid 166.797442 -89.810042)
					(end 166.8272 -89.7382)
				)
				(arc
					(start 166.8272 -88.3666)
					(mid 166.797442 -88.294758)
					(end 166.7256 -88.265)
				)
			)
		)
	)
	(zone
		(layers "In1.Cu" "In2.Cu")
		(hatch none 0.5)
		(connect_pads
			(clearance 0)
		)
		(min_thickness 0.25)
		(keepout
			(tracks not_allowed)
			(vias allowed)
			(pads allowed)
			(copperpour not_allowed)
			(footprints allowed)
		)
		(placement
			(enabled no)
			(sheetname "")
		)
		(fill yes
			(thermal_gap 0.5)
			(thermal_bridge_width 0.5)
			(island_removal_mode 0)
		)
		(polygon
			(pts
				(arc
					(start 158.337504 -32.7406)
					(mid 158.247701 -32.777797)
					(end 158.210504 -32.8676)
				)
				(arc
					(start 158.210504 -34.1884)
					(mid 158.247701 -34.278203)
					(end 158.337504 -34.3154)
				)
				(arc
					(start 159.632904 -34.3154)
					(mid 159.722707 -34.278203)
					(end 159.759904 -34.1884)
				)
				(arc
					(start 159.759904 -32.8676)
					(mid 159.722707 -32.777797)
					(end 159.632904 -32.7406)
				)
			)
		)
	)
	(zone
		(layers "In1.Cu" "In2.Cu")
		(hatch none 0.5)
		(connect_pads
			(clearance 0)
		)
		(min_thickness 0.25)
		(keepout
			(tracks not_allowed)
			(vias allowed)
			(pads allowed)
			(copperpour not_allowed)
			(footprints allowed)
		)
		(placement
			(enabled no)
			(sheetname "")
		)
		(fill yes
			(thermal_gap 0.5)
			(thermal_bridge_width 0.5)
			(island_removal_mode 0)
		)
		(polygon
			(pts
				(arc
					(start 27.0764 -142.3162)
					(mid 26.986597 -142.353397)
					(end 26.9494 -142.4432)
				)
				(arc
					(start 26.9494 -143.8148)
					(mid 26.986597 -143.904603)
					(end 27.0764 -143.9418)
				)
				(arc
					(start 28.2956 -143.9418)
					(mid 28.385403 -143.904603)
					(end 28.4226 -143.8148)
				)
				(xy 28.4226 -142.804134) (xy 28.4226 -142.7988)
				(arc
					(start 28.4226 -142.4432)
					(mid 28.385403 -142.353397)
					(end 28.2956 -142.3162)
				)
			)
		)
	)
	(zone
		(layers "In1.Cu" "In2.Cu" "In3.Cu" "In4.Cu" "In5.Cu" "In6.Cu")
		(hatch none 0.5)
		(connect_pads
			(clearance 0)
		)
		(min_thickness 0.25)
		(keepout
			(tracks not_allowed)
			(vias allowed)
			(pads allowed)
			(copperpour not_allowed)
			(footprints allowed)
		)
		(placement
			(enabled no)
			(sheetname "")
		)
		(fill yes
			(thermal_gap 0.5)
			(thermal_bridge_width 0.5)
			(island_removal_mode 0)
		)
		(polygon
			(pts
				(arc
					(start 342.750648 -14.19987)
					(mid 334.74914 -14.19987)
					(end 342.750648 -14.19987)
				)
			)
		)
	)
	(zone
		(layers "In1.Cu" "In2.Cu" "In3.Cu" "In4.Cu" "In5.Cu" "In6.Cu")
		(hatch none 0.5)
		(connect_pads
			(clearance 0)
		)
		(min_thickness 0.25)
		(keepout
			(tracks not_allowed)
			(vias allowed)
			(pads allowed)
			(copperpour not_allowed)
			(footprints allowed)
		)
		(placement
			(enabled no)
			(sheetname "")
		)
		(fill yes
			(thermal_gap 0.5)
			(thermal_bridge_width 0.5)
			(island_removal_mode 0)
		)
		(polygon
			(pts
				(arc
					(start 204.622654 -59.99988)
					(mid 196.621146 -59.99988)
					(end 204.622654 -59.99988)
				)
			)
		)
	)
	(zone
		(layers "In1.Cu" "In2.Cu" "In3.Cu" "In4.Cu" "In5.Cu" "In6.Cu")
		(hatch none 0.5)
		(connect_pads
			(clearance 0)
		)
		(min_thickness 0.25)
		(keepout
			(tracks not_allowed)
			(vias allowed)
			(pads allowed)
			(copperpour not_allowed)
			(footprints allowed)
		)
		(placement
			(enabled no)
			(sheetname "")
		)
		(fill yes
			(thermal_gap 0.5)
			(thermal_bridge_width 0.5)
			(island_removal_mode 0)
		)
		(polygon
			(pts
				(arc
					(start 204.622654 -71.999856)
					(mid 196.621146 -71.999856)
					(end 204.622654 -71.999856)
				)
			)
		)
	)
	(zone
		(layers "In1.Cu" "In2.Cu" "In3.Cu" "In4.Cu" "In5.Cu" "In6.Cu")
		(hatch none 0.5)
		(connect_pads
			(clearance 0)
		)
		(min_thickness 0.25)
		(keepout
			(tracks not_allowed)
			(vias allowed)
			(pads allowed)
			(copperpour not_allowed)
			(footprints allowed)
		)
		(placement
			(enabled no)
			(sheetname "")
		)
		(fill yes
			(thermal_gap 0.5)
			(thermal_bridge_width 0.5)
			(island_removal_mode 0)
		)
		(polygon
			(pts
				(arc
					(start 78.453996 -14.200124)
					(mid 70.445884 -14.200124)
					(end 78.453996 -14.200124)
				)
			)
		)
	)
	(zone
		(layers "In1.Cu" "In2.Cu" "In3.Cu" "In4.Cu" "In5.Cu" "In6.Cu")
		(hatch none 0.5)
		(connect_pads
			(clearance 0)
		)
		(min_thickness 0.25)
		(keepout
			(tracks not_allowed)
			(vias allowed)
			(pads allowed)
			(copperpour not_allowed)
			(footprints allowed)
		)
		(placement
			(enabled no)
			(sheetname "")
		)
		(fill yes
			(thermal_gap 0.5)
			(thermal_bridge_width 0.5)
			(island_removal_mode 0)
		)
		(polygon
			(pts
				(arc
					(start 89.454228 -22.999954)
					(mid 81.445608 -22.999954)
					(end 89.454228 -22.999954)
				)
			)
		)
	)
	(zone
		(layers "In1.Cu" "In2.Cu" "In3.Cu" "In4.Cu" "In5.Cu" "In6.Cu")
		(hatch none 0.5)
		(connect_pads
			(clearance 0)
		)
		(min_thickness 0.25)
		(keepout
			(tracks not_allowed)
			(vias allowed)
			(pads allowed)
			(copperpour not_allowed)
			(footprints allowed)
		)
		(placement
			(enabled no)
			(sheetname "")
		)
		(fill yes
			(thermal_gap 0.5)
			(thermal_bridge_width 0.5)
			(island_removal_mode 0)
		)
		(polygon
			(pts
				(arc
					(start 89.45118 -5.40004)
					(mid 81.448656 -5.40004)
					(end 89.45118 -5.40004)
				)
			)
		)
	)
	(zone
		(layers "In1.Cu" "In2.Cu" "In3.Cu" "In4.Cu" "In5.Cu" "In6.Cu")
		(hatch none 0.5)
		(connect_pads
			(clearance 0)
		)
		(min_thickness 0.25)
		(keepout
			(tracks not_allowed)
			(vias allowed)
			(pads allowed)
			(copperpour not_allowed)
			(footprints allowed)
		)
		(placement
			(enabled no)
			(sheetname "")
		)
		(fill yes
			(thermal_gap 0.5)
			(thermal_bridge_width 0.5)
			(island_removal_mode 0)
		)
		(polygon
			(pts
				(xy 24.892 -229.4636) (xy 24.892 -224.8916) (xy 25.4 -224.3836) (xy 346.202 -224.3836) (xy 347.218 -225.3996)
				(xy 347.218 -229.0826) (xy 346.075 -230.2256) (xy 25.654 -230.2256)
			)
		)
	)
	(zone
		(layers "In1.Cu" "In2.Cu" "In3.Cu" "In4.Cu" "In5.Cu" "In6.Cu")
		(hatch none 0.5)
		(connect_pads
			(clearance 0)
		)
		(min_thickness 0.25)
		(keepout
			(tracks not_allowed)
			(vias allowed)
			(pads allowed)
			(copperpour not_allowed)
			(footprints allowed)
		)
		(placement
			(enabled no)
			(sheetname "")
		)
		(fill yes
			(thermal_gap 0.5)
			(thermal_bridge_width 0.5)
			(island_removal_mode 0)
		)
		(polygon
			(pts
				(arc
					(start 353.750626 -22.999954)
					(mid 345.749118 -22.999954)
					(end 353.750626 -22.999954)
				)
			)
		)
	)
	(zone
		(layers "In1.Cu" "In2.Cu" "In3.Cu" "In4.Cu" "In5.Cu" "In6.Cu")
		(hatch none 0.5)
		(connect_pads
			(clearance 0)
		)
		(min_thickness 0.25)
		(keepout
			(tracks not_allowed)
			(vias allowed)
			(pads allowed)
			(copperpour not_allowed)
			(footprints allowed)
		)
		(placement
			(enabled no)
			(sheetname "")
		)
		(fill yes
			(thermal_gap 0.5)
			(thermal_bridge_width 0.5)
			(island_removal_mode 0)
		)
		(polygon
			(pts
				(arc
					(start 353.750626 -5.399786)
					(mid 345.749118 -5.399786)
					(end 353.750626 -5.399786)
				)
			)
		)
	)
	(zone
		(layers "In1.Cu" "In3.Cu" "In4.Cu" "In6.Cu")
		(hatch none 0.5)
		(connect_pads
			(clearance 0)
		)
		(min_thickness 0.25)
		(keepout
			(tracks not_allowed)
			(vias allowed)
			(pads allowed)
			(copperpour not_allowed)
			(footprints allowed)
		)
		(placement
			(enabled no)
			(sheetname "")
		)
		(fill yes
			(thermal_gap 0.5)
			(thermal_bridge_width 0.5)
			(island_removal_mode 0)
		)
		(polygon
			(pts
				(xy 302.187356 -14.226286) (xy 302.937418 -12.826238)
				(arc
					(start 302.935386 -12.824968)
					(mid 302.679354 -11.979148)
					(end 301.833534 -12.23518)
				)
				(xy 301.831502 -12.23391) (xy 301.08144 -13.633704) (xy 301.081694 -13.633958)
				(arc
					(start 301.083726 -13.634974)
					(mid 301.339402 -14.480875)
					(end 302.185324 -14.225016)
				)
			)
		)
	)
	(zone
		(layers "In1.Cu" "In3.Cu" "In4.Cu" "In6.Cu")
		(hatch none 0.5)
		(connect_pads
			(clearance 0)
		)
		(min_thickness 0.25)
		(keepout
			(tracks not_allowed)
			(vias allowed)
			(pads allowed)
			(copperpour not_allowed)
			(footprints allowed)
		)
		(placement
			(enabled no)
			(sheetname "")
		)
		(fill yes
			(thermal_gap 0.5)
			(thermal_bridge_width 0.5)
			(island_removal_mode 0)
		)
		(polygon
			(pts
				(arc
					(start 147.685252 -24.224996)
					(mid 147.42922 -23.379176)
					(end 146.5834 -23.635208)
				)
				(arc
					(start 145.837656 -25.027636)
					(mid 146.08579 -25.879089)
					(end 146.935444 -25.625044)
				)
			)
		)
	)
	(zone
		(layers "In1.Cu" "In3.Cu" "In4.Cu" "In6.Cu")
		(hatch none 0.5)
		(connect_pads
			(clearance 0)
		)
		(min_thickness 0.25)
		(keepout
			(tracks not_allowed)
			(vias allowed)
			(pads allowed)
			(copperpour not_allowed)
			(footprints allowed)
		)
		(placement
			(enabled no)
			(sheetname "")
		)
		(fill yes
			(thermal_gap 0.5)
			(thermal_bridge_width 0.5)
			(island_removal_mode 0)
		)
		(polygon
			(pts
				(xy 138.18743 -18.02638) (xy 138.937492 -16.626586)
				(arc
					(start 138.935206 -16.625316)
					(mid 138.679682 -15.779496)
					(end 137.833862 -16.03502)
				)
				(xy 137.831576 -16.03375) (xy 137.081514 -17.433544) (xy 137.081768 -17.433798)
				(arc
					(start 137.0838 -17.434814)
					(mid 137.339324 -18.280634)
					(end 138.185144 -18.02511)
				)
			)
		)
	)
	(zone
		(layers "In1.Cu" "In3.Cu" "In4.Cu" "In6.Cu")
		(hatch none 0.5)
		(connect_pads
			(clearance 0)
		)
		(min_thickness 0.25)
		(keepout
			(tracks not_allowed)
			(vias allowed)
			(pads allowed)
			(copperpour not_allowed)
			(footprints allowed)
		)
		(placement
			(enabled no)
			(sheetname "")
		)
		(fill yes
			(thermal_gap 0.5)
			(thermal_bridge_width 0.5)
			(island_removal_mode 0)
		)
		(polygon
			(pts
				(arc
					(start 92.332048 -184.941718)
					(mid 91.61018 -184.941718)
					(end 91.61018 -185.663586)
				)
				(xy 91.608402 -185.665364) (xy 92.18295 -186.240166) (xy 92.183204 -186.240166)
				(arc
					(start 92.184982 -186.238388)
					(mid 92.90685 -186.238388)
					(end 92.90685 -185.51652)
				)
				(xy 92.908628 -185.514742) (xy 92.333826 -184.93994)
			)
		)
	)
	(zone
		(layers "In1.Cu" "In3.Cu" "In4.Cu" "In6.Cu")
		(hatch none 0.5)
		(connect_pads
			(clearance 0)
		)
		(min_thickness 0.25)
		(keepout
			(tracks not_allowed)
			(vias allowed)
			(pads allowed)
			(copperpour not_allowed)
			(footprints allowed)
		)
		(placement
			(enabled no)
			(sheetname "")
		)
		(fill yes
			(thermal_gap 0.5)
			(thermal_bridge_width 0.5)
			(island_removal_mode 0)
		)
		(polygon
			(pts
				(arc
					(start 14.68374 -67.638676)
					(mid 14.173327 -67.127882)
					(end 13.66266 -67.638422)
				)
				(arc
					(start 13.66266 -68.451222)
					(mid 14.1732 -68.961762)
					(end 14.68374 -68.451222)
				)
			)
		)
	)
	(zone
		(layers "In1.Cu" "In3.Cu" "In4.Cu" "In6.Cu")
		(hatch none 0.5)
		(connect_pads
			(clearance 0)
		)
		(min_thickness 0.25)
		(keepout
			(tracks not_allowed)
			(vias allowed)
			(pads allowed)
			(copperpour not_allowed)
			(footprints allowed)
		)
		(placement
			(enabled no)
			(sheetname "")
		)
		(fill yes
			(thermal_gap 0.5)
			(thermal_bridge_width 0.5)
			(island_removal_mode 0)
		)
		(polygon
			(pts
				(arc
					(start 103.2383 -81.000854)
					(mid 102.626287 -80.38846)
					(end 102.01402 -81.0006)
				)
				(arc
					(start 102.01402 -82.1182)
					(mid 102.62616 -82.73034)
					(end 103.2383 -82.1182)
				)
			)
		)
	)
	(zone
		(layers "In1.Cu" "In3.Cu" "In4.Cu" "In6.Cu")
		(hatch none 0.5)
		(connect_pads
			(clearance 0)
		)
		(min_thickness 0.25)
		(keepout
			(tracks not_allowed)
			(vias allowed)
			(pads allowed)
			(copperpour not_allowed)
			(footprints allowed)
		)
		(placement
			(enabled no)
			(sheetname "")
		)
		(fill yes
			(thermal_gap 0.5)
			(thermal_bridge_width 0.5)
			(island_removal_mode 0)
		)
		(polygon
			(pts
				(arc
					(start 304.647346 -36.794694)
					(mid 305.15814 -36.284281)
					(end 304.6476 -35.773614)
				)
				(arc
					(start 303.8348 -35.773614)
					(mid 303.32426 -36.284154)
					(end 303.8348 -36.794694)
				)
			)
		)
	)
	(zone
		(layers "In1.Cu" "In3.Cu" "In4.Cu" "In6.Cu")
		(hatch none 0.5)
		(connect_pads
			(clearance 0)
		)
		(min_thickness 0.25)
		(keepout
			(tracks not_allowed)
			(vias allowed)
			(pads allowed)
			(copperpour not_allowed)
			(footprints allowed)
		)
		(placement
			(enabled no)
			(sheetname "")
		)
		(fill yes
			(thermal_gap 0.5)
			(thermal_bridge_width 0.5)
			(island_removal_mode 0)
		)
		(polygon
			(pts
				(xy 288.937446 -18.026126) (xy 289.687254 -16.626332)
				(arc
					(start 289.685222 -16.625062)
					(mid 289.42919 -15.779242)
					(end 288.58337 -16.035274)
				)
				(xy 288.581338 -16.034004) (xy 287.83153 -17.433544) (xy 287.831784 -17.433798)
				(arc
					(start 287.833816 -17.434814)
					(mid 288.089492 -18.280715)
					(end 288.935414 -18.024856)
				)
			)
		)
	)
	(zone
		(layers "In1.Cu" "In3.Cu" "In4.Cu" "In6.Cu")
		(hatch none 0.5)
		(connect_pads
			(clearance 0)
		)
		(min_thickness 0.25)
		(keepout
			(tracks not_allowed)
			(vias allowed)
			(pads allowed)
			(copperpour not_allowed)
			(footprints allowed)
		)
		(placement
			(enabled no)
			(sheetname "")
		)
		(fill yes
			(thermal_gap 0.5)
			(thermal_bridge_width 0.5)
			(island_removal_mode 0)
		)
		(polygon
			(pts
				(xy 149.187408 -14.226286) (xy 149.93747 -12.826238)
				(arc
					(start 149.935438 -12.824968)
					(mid 149.679406 -11.979148)
					(end 148.833586 -12.23518)
				)
				(xy 148.831554 -12.23391) (xy 148.081492 -13.633704) (xy 148.081746 -13.633958)
				(arc
					(start 148.083778 -13.634974)
					(mid 148.339454 -14.480875)
					(end 149.185376 -14.225016)
				)
			)
		)
	)
	(zone
		(layers "In1.Cu" "In3.Cu" "In4.Cu" "In6.Cu")
		(hatch none 0.5)
		(connect_pads
			(clearance 0)
		)
		(min_thickness 0.25)
		(keepout
			(tracks not_allowed)
			(vias allowed)
			(pads allowed)
			(copperpour not_allowed)
			(footprints allowed)
		)
		(placement
			(enabled no)
			(sheetname "")
		)
		(fill yes
			(thermal_gap 0.5)
			(thermal_bridge_width 0.5)
			(island_removal_mode 0)
		)
		(polygon
			(pts
				(arc
					(start 158.655258 -34.51098)
					(mid 158.144464 -35.021393)
					(end 158.655004 -35.53206)
				)
				(arc
					(start 159.467804 -35.53206)
					(mid 159.978344 -35.02152)
					(end 159.467804 -34.51098)
				)
			)
		)
	)
	(zone
		(layers "In1.Cu" "In3.Cu" "In4.Cu" "In6.Cu")
		(hatch none 0.5)
		(connect_pads
			(clearance 0)
		)
		(min_thickness 0.25)
		(keepout
			(tracks not_allowed)
			(vias allowed)
			(pads allowed)
			(copperpour not_allowed)
			(footprints allowed)
		)
		(placement
			(enabled no)
			(sheetname "")
		)
		(fill yes
			(thermal_gap 0.5)
			(thermal_bridge_width 0.5)
			(island_removal_mode 0)
		)
		(polygon
			(pts
				(arc
					(start 326.781668 -36.472114)
					(mid 327.292462 -35.961701)
					(end 326.781922 -35.451034)
				)
				(arc
					(start 325.969122 -35.451034)
					(mid 325.458582 -35.961574)
					(end 325.969122 -36.472114)
				)
			)
		)
	)
	(zone
		(layers "In1.Cu" "In3.Cu" "In4.Cu" "In6.Cu")
		(hatch none 0.5)
		(connect_pads
			(clearance 0)
		)
		(min_thickness 0.25)
		(keepout
			(tracks not_allowed)
			(vias allowed)
			(pads allowed)
			(copperpour not_allowed)
			(footprints allowed)
		)
		(placement
			(enabled no)
			(sheetname "")
		)
		(fill yes
			(thermal_gap 0.5)
			(thermal_bridge_width 0.5)
			(island_removal_mode 0)
		)
		(polygon
			(pts
				(xy 321.93738 -21.82622) (xy 322.687442 -20.426426) (xy 322.687188 -20.426172)
				(arc
					(start 322.685156 -20.425156)
					(mid 322.42948 -19.579255)
					(end 321.583558 -19.835114)
				)
				(xy 321.581526 -19.833844) (xy 320.831464 -21.233892)
				(arc
					(start 320.833496 -21.235162)
					(mid 321.089528 -22.080982)
					(end 321.935348 -21.82495)
				)
			)
		)
	)
	(zone
		(layers "In1.Cu" "In3.Cu" "In4.Cu" "In6.Cu")
		(hatch none 0.5)
		(connect_pads
			(clearance 0)
		)
		(min_thickness 0.25)
		(keepout
			(tracks not_allowed)
			(vias allowed)
			(pads allowed)
			(copperpour not_allowed)
			(footprints allowed)
		)
		(placement
			(enabled no)
			(sheetname "")
		)
		(fill yes
			(thermal_gap 0.5)
			(thermal_bridge_width 0.5)
			(island_removal_mode 0)
		)
		(polygon
			(pts
				(arc
					(start 186.56554 -24.999188)
					(mid 186.055127 -24.488394)
					(end 185.54446 -24.998934)
				)
				(arc
					(start 185.54446 -25.811734)
					(mid 186.055 -26.322274)
					(end 186.56554 -25.811734)
				)
			)
		)
	)
	(zone
		(layers "In1.Cu" "In3.Cu" "In4.Cu" "In6.Cu")
		(hatch none 0.5)
		(connect_pads
			(clearance 0)
		)
		(min_thickness 0.25)
		(keepout
			(tracks not_allowed)
			(vias allowed)
			(pads allowed)
			(copperpour not_allowed)
			(footprints allowed)
		)
		(placement
			(enabled no)
			(sheetname "")
		)
		(fill yes
			(thermal_gap 0.5)
			(thermal_bridge_width 0.5)
			(island_removal_mode 0)
		)
		(polygon
			(pts
				(xy 313.187334 -21.82622) (xy 313.937396 -20.426426) (xy 313.937142 -20.426172)
				(arc
					(start 313.93511 -20.425156)
					(mid 313.679434 -19.579255)
					(end 312.833512 -19.835114)
				)
				(xy 312.83148 -19.833844) (xy 312.081418 -21.233892)
				(arc
					(start 312.08345 -21.235162)
					(mid 312.339482 -22.080982)
					(end 313.185302 -21.82495)
				)
			)
		)
	)
	(zone
		(layers "In1.Cu" "In3.Cu" "In4.Cu" "In6.Cu")
		(hatch none 0.5)
		(connect_pads
			(clearance 0)
		)
		(min_thickness 0.25)
		(keepout
			(tracks not_allowed)
			(vias allowed)
			(pads allowed)
			(copperpour not_allowed)
			(footprints allowed)
		)
		(placement
			(enabled no)
			(sheetname "")
		)
		(fill yes
			(thermal_gap 0.5)
			(thermal_bridge_width 0.5)
			(island_removal_mode 0)
		)
		(polygon
			(pts
				(arc
					(start 58.051954 -195.75526)
					(mid 57.54116 -196.265673)
					(end 58.0517 -196.77634)
				)
				(arc
					(start 58.8645 -196.77634)
					(mid 59.37504 -196.2658)
					(end 58.8645 -195.75526)
				)
			)
		)
	)
	(zone
		(layers "In1.Cu" "In3.Cu" "In4.Cu" "In6.Cu")
		(hatch none 0.5)
		(connect_pads
			(clearance 0)
		)
		(min_thickness 0.25)
		(keepout
			(tracks not_allowed)
			(vias allowed)
			(pads allowed)
			(copperpour not_allowed)
			(footprints allowed)
		)
		(placement
			(enabled no)
			(sheetname "")
		)
		(fill yes
			(thermal_gap 0.5)
			(thermal_bridge_width 0.5)
			(island_removal_mode 0)
		)
		(polygon
			(pts
				(arc
					(start 23.77694 -113.995454)
					(mid 23.164927 -113.38306)
					(end 22.55266 -113.9952)
				)
				(arc
					(start 22.55266 -115.1128)
					(mid 23.1648 -115.72494)
					(end 23.77694 -115.1128)
				)
			)
		)
	)
	(zone
		(layers "In1.Cu" "In3.Cu" "In4.Cu" "In6.Cu")
		(hatch none 0.5)
		(connect_pads
			(clearance 0)
		)
		(min_thickness 0.25)
		(keepout
			(tracks not_allowed)
			(vias allowed)
			(pads allowed)
			(copperpour not_allowed)
			(footprints allowed)
		)
		(placement
			(enabled no)
			(sheetname "")
		)
		(fill yes
			(thermal_gap 0.5)
			(thermal_bridge_width 0.5)
			(island_removal_mode 0)
		)
		(polygon
			(pts
				(arc
					(start 163.512246 -82.17154)
					(mid 164.02304 -81.661127)
					(end 163.5125 -81.15046)
				)
				(arc
					(start 162.6997 -81.15046)
					(mid 162.18916 -81.661)
					(end 162.6997 -82.17154)
				)
			)
		)
	)
	(zone
		(layers "In1.Cu" "In3.Cu" "In4.Cu" "In6.Cu")
		(hatch none 0.5)
		(connect_pads
			(clearance 0)
		)
		(min_thickness 0.25)
		(keepout
			(tracks not_allowed)
			(vias allowed)
			(pads allowed)
			(copperpour not_allowed)
			(footprints allowed)
		)
		(placement
			(enabled no)
			(sheetname "")
		)
		(fill yes
			(thermal_gap 0.5)
			(thermal_bridge_width 0.5)
			(island_removal_mode 0)
		)
		(polygon
			(pts
				(xy 299.937424 -18.026126) (xy 300.687232 -16.626332)
				(arc
					(start 300.6852 -16.625062)
					(mid 300.429168 -15.779242)
					(end 299.583348 -16.035274)
				)
				(xy 299.581316 -16.034004) (xy 298.831508 -17.433544) (xy 298.831762 -17.433798)
				(arc
					(start 298.833794 -17.434814)
					(mid 299.08947 -18.280715)
					(end 299.935392 -18.024856)
				)
			)
		)
	)
	(zone
		(layers "In1.Cu" "In3.Cu" "In4.Cu" "In6.Cu")
		(hatch none 0.5)
		(connect_pads
			(clearance 0)
		)
		(min_thickness 0.25)
		(keepout
			(tracks not_allowed)
			(vias allowed)
			(pads allowed)
			(copperpour not_allowed)
			(footprints allowed)
		)
		(placement
			(enabled no)
			(sheetname "")
		)
		(fill yes
			(thermal_gap 0.5)
			(thermal_bridge_width 0.5)
			(island_removal_mode 0)
		)
		(polygon
			(pts
				(arc
					(start 151.726646 -38.59784)
					(mid 152.23744 -38.087427)
					(end 151.7269 -37.57676)
				)
				(arc
					(start 150.9141 -37.57676)
					(mid 150.40356 -38.0873)
					(end 150.9141 -38.59784)
				)
			)
		)
	)
	(zone
		(layers "In1.Cu" "In3.Cu" "In4.Cu" "In6.Cu")
		(hatch none 0.5)
		(connect_pads
			(clearance 0)
		)
		(min_thickness 0.25)
		(keepout
			(tracks not_allowed)
			(vias allowed)
			(pads allowed)
			(copperpour not_allowed)
			(footprints allowed)
		)
		(placement
			(enabled no)
			(sheetname "")
		)
		(fill yes
			(thermal_gap 0.5)
			(thermal_bridge_width 0.5)
			(island_removal_mode 0)
		)
		(polygon
			(pts
				(arc
					(start 16.69034 -66.224404)
					(mid 16.179927 -65.71361)
					(end 15.66926 -66.22415)
				)
				(arc
					(start 15.66926 -67.03695)
					(mid 16.1798 -67.54749)
					(end 16.69034 -67.03695)
				)
			)
		)
	)
	(zone
		(layers "In1.Cu" "In3.Cu" "In4.Cu" "In6.Cu")
		(hatch none 0.5)
		(connect_pads
			(clearance 0)
		)
		(min_thickness 0.25)
		(keepout
			(tracks not_allowed)
			(vias allowed)
			(pads allowed)
			(copperpour not_allowed)
			(footprints allowed)
		)
		(placement
			(enabled no)
			(sheetname "")
		)
		(fill yes
			(thermal_gap 0.5)
			(thermal_bridge_width 0.5)
			(island_removal_mode 0)
		)
		(polygon
			(pts
				(arc
					(start 26.74112 -142.580614)
					(mid 26.129107 -141.96822)
					(end 25.51684 -142.58036)
				)
				(arc
					(start 25.51684 -143.69796)
					(mid 26.12898 -144.3101)
					(end 26.74112 -143.69796)
				)
			)
		)
	)
	(zone
		(layers "In1.Cu" "In3.Cu" "In4.Cu" "In6.Cu")
		(hatch none 0.5)
		(connect_pads
			(clearance 0)
		)
		(min_thickness 0.25)
		(keepout
			(tracks not_allowed)
			(vias allowed)
			(pads allowed)
			(copperpour not_allowed)
			(footprints allowed)
		)
		(placement
			(enabled no)
			(sheetname "")
		)
		(fill yes
			(thermal_gap 0.5)
			(thermal_bridge_width 0.5)
			(island_removal_mode 0)
		)
		(polygon
			(pts
				(arc
					(start 145.833592 -21.235162)
					(mid 146.089624 -22.080982)
					(end 146.935444 -21.82495)
				)
				(arc
					(start 147.681188 -20.432522)
					(mid 147.433054 -19.581069)
					(end 146.5834 -19.835114)
				)
			)
		)
	)
	(zone
		(layers "In1.Cu" "In3.Cu" "In4.Cu" "In6.Cu")
		(hatch none 0.5)
		(connect_pads
			(clearance 0)
		)
		(min_thickness 0.25)
		(keepout
			(tracks not_allowed)
			(vias allowed)
			(pads allowed)
			(copperpour not_allowed)
			(footprints allowed)
		)
		(placement
			(enabled no)
			(sheetname "")
		)
		(fill yes
			(thermal_gap 0.5)
			(thermal_bridge_width 0.5)
			(island_removal_mode 0)
		)
		(polygon
			(pts
				(arc
					(start 312.67654 -35.675062)
					(mid 312.165746 -36.185475)
					(end 312.676286 -36.696142)
				)
				(arc
					(start 313.489086 -36.696142)
					(mid 313.999626 -36.185602)
					(end 313.489086 -35.675062)
				)
			)
		)
	)
	(zone
		(layers "In1.Cu" "In3.Cu" "In4.Cu" "In6.Cu")
		(hatch none 0.5)
		(connect_pads
			(clearance 0)
		)
		(min_thickness 0.25)
		(keepout
			(tracks not_allowed)
			(vias allowed)
			(pads allowed)
			(copperpour not_allowed)
			(footprints allowed)
		)
		(placement
			(enabled no)
			(sheetname "")
		)
		(fill yes
			(thermal_gap 0.5)
			(thermal_bridge_width 0.5)
			(island_removal_mode 0)
		)
		(polygon
			(pts
				(arc
					(start 18.574004 -72.700134)
					(mid 18.06321 -73.210547)
					(end 18.57375 -73.721214)
				)
				(arc
					(start 19.38655 -73.721214)
					(mid 19.89709 -73.210674)
					(end 19.38655 -72.700134)
				)
			)
		)
	)
	(zone
		(layers "In1.Cu" "In3.Cu" "In4.Cu" "In6.Cu")
		(hatch none 0.5)
		(connect_pads
			(clearance 0)
		)
		(min_thickness 0.25)
		(keepout
			(tracks not_allowed)
			(vias allowed)
			(pads allowed)
			(copperpour not_allowed)
			(footprints allowed)
		)
		(placement
			(enabled no)
			(sheetname "")
		)
		(fill yes
			(thermal_gap 0.5)
			(thermal_bridge_width 0.5)
			(island_removal_mode 0)
		)
		(polygon
			(pts
				(arc
					(start 185.069226 -11.697208)
					(mid 184.558813 -11.186414)
					(end 184.048146 -11.696954)
				)
				(arc
					(start 184.048146 -12.509754)
					(mid 184.558686 -13.020294)
					(end 185.069226 -12.509754)
				)
			)
		)
	)
	(zone
		(layers "In1.Cu" "In3.Cu" "In4.Cu" "In6.Cu")
		(hatch none 0.5)
		(connect_pads
			(clearance 0)
		)
		(min_thickness 0.25)
		(keepout
			(tracks not_allowed)
			(vias allowed)
			(pads allowed)
			(copperpour not_allowed)
			(footprints allowed)
		)
		(placement
			(enabled no)
			(sheetname "")
		)
		(fill yes
			(thermal_gap 0.5)
			(thermal_bridge_width 0.5)
			(island_removal_mode 0)
		)
		(polygon
			(pts
				(xy 310.937402 -18.02638) (xy 311.687464 -16.626586)
				(arc
					(start 311.685178 -16.625316)
					(mid 311.429654 -15.779496)
					(end 310.583834 -16.03502)
				)
				(xy 310.581548 -16.03375) (xy 309.831486 -17.433544) (xy 309.83174 -17.433798)
				(arc
					(start 309.833772 -17.434814)
					(mid 310.089296 -18.280634)
					(end 310.935116 -18.02511)
				)
			)
		)
	)
	(zone
		(layers "In1.Cu" "In3.Cu" "In4.Cu" "In6.Cu")
		(hatch none 0.5)
		(connect_pads
			(clearance 0)
		)
		(min_thickness 0.25)
		(keepout
			(tracks not_allowed)
			(vias allowed)
			(pads allowed)
			(copperpour not_allowed)
			(footprints allowed)
		)
		(placement
			(enabled no)
			(sheetname "")
		)
		(fill yes
			(thermal_gap 0.5)
			(thermal_bridge_width 0.5)
			(island_removal_mode 0)
		)
		(polygon
			(pts
				(xy 168.937432 -14.226286) (xy 169.687494 -12.826238)
				(arc
					(start 169.685462 -12.824968)
					(mid 169.42943 -11.979148)
					(end 168.58361 -12.23518)
				)
				(xy 168.581578 -12.23391) (xy 167.831516 -13.633704) (xy 167.83177 -13.633958)
				(arc
					(start 167.833802 -13.634974)
					(mid 168.089478 -14.480875)
					(end 168.9354 -14.225016)
				)
			)
		)
	)
	(zone
		(layers "In1.Cu" "In3.Cu" "In4.Cu" "In6.Cu")
		(hatch none 0.5)
		(connect_pads
			(clearance 0)
		)
		(min_thickness 0.25)
		(keepout
			(tracks not_allowed)
			(vias allowed)
			(pads allowed)
			(copperpour not_allowed)
			(footprints allowed)
		)
		(placement
			(enabled no)
			(sheetname "")
		)
		(fill yes
			(thermal_gap 0.5)
			(thermal_bridge_width 0.5)
			(island_removal_mode 0)
		)
		(polygon
			(pts
				(arc
					(start 19.812 -58.851546)
					(mid 20.42414 -58.239406)
					(end 19.812 -57.627266)
				)
				(arc
					(start 18.6944 -57.627266)
					(mid 18.08226 -58.239406)
					(end 18.6944 -58.851546)
				)
			)
		)
	)
	(zone
		(layers "In1.Cu" "In3.Cu" "In4.Cu" "In6.Cu")
		(hatch none 0.5)
		(connect_pads
			(clearance 0)
		)
		(min_thickness 0.25)
		(keepout
			(tracks not_allowed)
			(vias allowed)
			(pads allowed)
			(copperpour not_allowed)
			(footprints allowed)
		)
		(placement
			(enabled no)
			(sheetname "")
		)
		(fill yes
			(thermal_gap 0.5)
			(thermal_bridge_width 0.5)
			(island_removal_mode 0)
		)
		(polygon
			(pts
				(arc
					(start 319.72123 -36.51504)
					(mid 319.210436 -37.025453)
					(end 319.720976 -37.53612)
				)
				(arc
					(start 320.533776 -37.53612)
					(mid 321.044316 -37.02558)
					(end 320.533776 -36.51504)
				)
			)
		)
	)
	(zone
		(layers "In1.Cu" "In3.Cu" "In4.Cu" "In6.Cu")
		(hatch none 0.5)
		(connect_pads
			(clearance 0)
		)
		(min_thickness 0.25)
		(keepout
			(tracks not_allowed)
			(vias allowed)
			(pads allowed)
			(copperpour not_allowed)
			(footprints allowed)
		)
		(placement
			(enabled no)
			(sheetname "")
		)
		(fill yes
			(thermal_gap 0.5)
			(thermal_bridge_width 0.5)
			(island_removal_mode 0)
		)
		(polygon
			(pts
				(arc
					(start 287.837626 -21.227542)
					(mid 288.08576 -22.078995)
					(end 288.935414 -21.82495)
				)
				(arc
					(start 289.685222 -20.424902)
					(mid 289.42919 -19.579082)
					(end 288.58337 -19.835114)
				)
			)
		)
	)
	(zone
		(layers "In1.Cu" "In3.Cu" "In4.Cu" "In6.Cu")
		(hatch none 0.5)
		(connect_pads
			(clearance 0)
		)
		(min_thickness 0.25)
		(keepout
			(tracks not_allowed)
			(vias allowed)
			(pads allowed)
			(copperpour not_allowed)
			(footprints allowed)
		)
		(placement
			(enabled no)
			(sheetname "")
		)
		(fill yes
			(thermal_gap 0.5)
			(thermal_bridge_width 0.5)
			(island_removal_mode 0)
		)
		(polygon
			(pts
				(arc
					(start 132.358384 -41.605454)
					(mid 131.746371 -40.99306)
					(end 131.134104 -41.6052)
				)
				(arc
					(start 131.134104 -42.7228)
					(mid 131.746244 -43.33494)
					(end 132.358384 -42.7228)
				)
			)
		)
	)
	(zone
		(layers "In1.Cu" "In3.Cu" "In4.Cu" "In6.Cu")
		(hatch none 0.5)
		(connect_pads
			(clearance 0)
		)
		(min_thickness 0.25)
		(keepout
			(tracks not_allowed)
			(vias allowed)
			(pads allowed)
			(copperpour not_allowed)
			(footprints allowed)
		)
		(placement
			(enabled no)
			(sheetname "")
		)
		(fill yes
			(thermal_gap 0.5)
			(thermal_bridge_width 0.5)
			(island_removal_mode 0)
		)
		(polygon
			(pts
				(arc
					(start 287.833562 -13.635228)
					(mid 288.089594 -14.481048)
					(end 288.935414 -14.225016)
				)
				(arc
					(start 289.681158 -12.832588)
					(mid 289.433024 -11.981135)
					(end 288.58337 -12.23518)
				)
			)
		)
	)
	(zone
		(layers "In1.Cu" "In3.Cu" "In4.Cu" "In6.Cu")
		(hatch none 0.5)
		(connect_pads
			(clearance 0)
		)
		(min_thickness 0.25)
		(keepout
			(tracks not_allowed)
			(vias allowed)
			(pads allowed)
			(copperpour not_allowed)
			(footprints allowed)
		)
		(placement
			(enabled no)
			(sheetname "")
		)
		(fill yes
			(thermal_gap 0.5)
			(thermal_bridge_width 0.5)
			(island_removal_mode 0)
		)
		(polygon
			(pts
				(arc
					(start 183.59374 -25.946354)
					(mid 183.083327 -25.43556)
					(end 182.57266 -25.9461)
				)
				(arc
					(start 182.57266 -26.7589)
					(mid 183.0832 -27.26944)
					(end 183.59374 -26.7589)
				)
			)
		)
	)
	(zone
		(layers "In1.Cu" "In3.Cu" "In4.Cu" "In6.Cu")
		(hatch none 0.5)
		(connect_pads
			(clearance 0)
		)
		(min_thickness 0.25)
		(keepout
			(tracks not_allowed)
			(vias allowed)
			(pads allowed)
			(copperpour not_allowed)
			(footprints allowed)
		)
		(placement
			(enabled no)
			(sheetname "")
		)
		(fill yes
			(thermal_gap 0.5)
			(thermal_bridge_width 0.5)
			(island_removal_mode 0)
		)
		(polygon
			(pts
				(arc
					(start 271.19834 -8.353806)
					(mid 270.687927 -7.843012)
					(end 270.17726 -8.353552)
				)
				(arc
					(start 270.17726 -9.166352)
					(mid 270.6878 -9.676892)
					(end 271.19834 -9.166352)
				)
			)
		)
	)
	(zone
		(layers "In1.Cu" "In3.Cu" "In4.Cu" "In6.Cu")
		(hatch none 0.5)
		(connect_pads
			(clearance 0)
		)
		(min_thickness 0.25)
		(keepout
			(tracks not_allowed)
			(vias allowed)
			(pads allowed)
			(copperpour not_allowed)
			(footprints allowed)
		)
		(placement
			(enabled no)
			(sheetname "")
		)
		(fill yes
			(thermal_gap 0.5)
			(thermal_bridge_width 0.5)
			(island_removal_mode 0)
		)
		(polygon
			(pts
				(xy 313.187334 -25.626314) (xy 313.937396 -24.226266)
				(arc
					(start 313.935364 -24.224996)
					(mid 313.679332 -23.379176)
					(end 312.833512 -23.635208)
				)
				(xy 312.83148 -23.633938) (xy 312.081418 -25.033732) (xy 312.081672 -25.033986)
				(arc
					(start 312.083704 -25.035002)
					(mid 312.33938 -25.880903)
					(end 313.185302 -25.625044)
				)
			)
		)
	)
	(zone
		(layers "In1.Cu" "In3.Cu" "In4.Cu" "In6.Cu")
		(hatch none 0.5)
		(connect_pads
			(clearance 0)
		)
		(min_thickness 0.25)
		(keepout
			(tracks not_allowed)
			(vias allowed)
			(pads allowed)
			(copperpour not_allowed)
			(footprints allowed)
		)
		(placement
			(enabled no)
			(sheetname "")
		)
		(fill yes
			(thermal_gap 0.5)
			(thermal_bridge_width 0.5)
			(island_removal_mode 0)
		)
		(polygon
			(pts
				(arc
					(start 145.910554 -34.48558)
					(mid 145.39976 -34.995993)
					(end 145.9103 -35.50666)
				)
				(arc
					(start 146.7231 -35.50666)
					(mid 147.23364 -34.99612)
					(end 146.7231 -34.48558)
				)
			)
		)
	)
	(zone
		(layers "In1.Cu" "In3.Cu" "In4.Cu" "In6.Cu")
		(hatch none 0.5)
		(connect_pads
			(clearance 0)
		)
		(min_thickness 0.25)
		(keepout
			(tracks not_allowed)
			(vias allowed)
			(pads allowed)
			(copperpour not_allowed)
			(footprints allowed)
		)
		(placement
			(enabled no)
			(sheetname "")
		)
		(fill yes
			(thermal_gap 0.5)
			(thermal_bridge_width 0.5)
			(island_removal_mode 0)
		)
		(polygon
			(pts
				(arc
					(start 299.430948 -35.678872)
					(mid 298.920154 -36.189285)
					(end 299.430694 -36.699952)
				)
				(arc
					(start 300.243494 -36.699952)
					(mid 300.754034 -36.189412)
					(end 300.243494 -35.678872)
				)
			)
		)
	)
	(zone
		(layers "In1.Cu" "In3.Cu" "In4.Cu" "In6.Cu")
		(hatch none 0.5)
		(connect_pads
			(clearance 0)
		)
		(min_thickness 0.25)
		(keepout
			(tracks not_allowed)
			(vias allowed)
			(pads allowed)
			(copperpour not_allowed)
			(footprints allowed)
		)
		(placement
			(enabled no)
			(sheetname "")
		)
		(fill yes
			(thermal_gap 0.5)
			(thermal_bridge_width 0.5)
			(island_removal_mode 0)
		)
		(polygon
			(pts
				(arc
					(start 162.597846 -38.52164)
					(mid 163.10864 -38.011227)
					(end 162.5981 -37.50056)
				)
				(arc
					(start 161.7853 -37.50056)
					(mid 161.27476 -38.0111)
					(end 161.7853 -38.52164)
				)
			)
		)
	)
	(zone
		(layers "In1.Cu" "In3.Cu" "In4.Cu" "In6.Cu")
		(hatch none 0.5)
		(connect_pads
			(clearance 0)
		)
		(min_thickness 0.25)
		(keepout
			(tracks not_allowed)
			(vias allowed)
			(pads allowed)
			(copperpour not_allowed)
			(footprints allowed)
		)
		(placement
			(enabled no)
			(sheetname "")
		)
		(fill yes
			(thermal_gap 0.5)
			(thermal_bridge_width 0.5)
			(island_removal_mode 0)
		)
		(polygon
			(pts
				(arc
					(start 165.58768 -13.627608)
					(mid 165.835814 -14.479061)
					(end 166.685468 -14.225016)
				)
				(arc
					(start 167.435276 -12.824968)
					(mid 167.179244 -11.979148)
					(end 166.333424 -12.23518)
				)
			)
		)
	)
	(zone
		(layers "In1.Cu" "In3.Cu" "In4.Cu" "In6.Cu")
		(hatch none 0.5)
		(connect_pads
			(clearance 0)
		)
		(min_thickness 0.25)
		(keepout
			(tracks not_allowed)
			(vias allowed)
			(pads allowed)
			(copperpour not_allowed)
			(footprints allowed)
		)
		(placement
			(enabled no)
			(sheetname "")
		)
		(fill yes
			(thermal_gap 0.5)
			(thermal_bridge_width 0.5)
			(island_removal_mode 0)
		)
		(polygon
			(pts
				(xy 310.937402 -14.226286) (xy 311.687464 -12.826238)
				(arc
					(start 311.685432 -12.824968)
					(mid 311.4294 -11.979148)
					(end 310.58358 -12.23518)
				)
				(xy 310.581548 -12.23391) (xy 309.831486 -13.633704) (xy 309.83174 -13.633958)
				(arc
					(start 309.833772 -13.634974)
					(mid 310.089448 -14.480875)
					(end 310.93537 -14.225016)
				)
			)
		)
	)
	(zone
		(layers "In1.Cu" "In3.Cu" "In4.Cu" "In6.Cu")
		(hatch none 0.5)
		(connect_pads
			(clearance 0)
		)
		(min_thickness 0.25)
		(keepout
			(tracks not_allowed)
			(vias allowed)
			(pads allowed)
			(copperpour not_allowed)
			(footprints allowed)
		)
		(placement
			(enabled no)
			(sheetname "")
		)
		(fill yes
			(thermal_gap 0.5)
			(thermal_bridge_width 0.5)
			(island_removal_mode 0)
		)
		(polygon
			(pts
				(xy 138.18743 -14.226286) (xy 138.937492 -12.826492) (xy 138.937238 -12.826238)
				(arc
					(start 138.935206 -12.825222)
					(mid 138.67953 -11.979321)
					(end 137.833608 -12.23518)
				)
				(xy 137.831576 -12.23391) (xy 137.081514 -13.633958)
				(arc
					(start 137.083546 -13.635228)
					(mid 137.339578 -14.481048)
					(end 138.185398 -14.225016)
				)
			)
		)
	)
	(zone
		(layers "In1.Cu" "In3.Cu" "In4.Cu" "In6.Cu")
		(hatch none 0.5)
		(connect_pads
			(clearance 0)
		)
		(min_thickness 0.25)
		(keepout
			(tracks not_allowed)
			(vias allowed)
			(pads allowed)
			(copperpour not_allowed)
			(footprints allowed)
		)
		(placement
			(enabled no)
			(sheetname "")
		)
		(fill yes
			(thermal_gap 0.5)
			(thermal_bridge_width 0.5)
			(island_removal_mode 0)
		)
		(polygon
			(pts
				(arc
					(start 268.98854 -13.843254)
					(mid 268.478127 -13.33246)
					(end 267.96746 -13.843)
				)
				(arc
					(start 267.96746 -14.6558)
					(mid 268.478 -15.16634)
					(end 268.98854 -14.6558)
				)
			)
		)
	)
	(zone
		(layers "In1.Cu" "In3.Cu" "In4.Cu" "In6.Cu")
		(hatch none 0.5)
		(connect_pads
			(clearance 0)
		)
		(min_thickness 0.25)
		(keepout
			(tracks not_allowed)
			(vias allowed)
			(pads allowed)
			(copperpour not_allowed)
			(footprints allowed)
		)
		(placement
			(enabled no)
			(sheetname "")
		)
		(fill yes
			(thermal_gap 0.5)
			(thermal_bridge_width 0.5)
			(island_removal_mode 0)
		)
		(polygon
			(pts
				(arc
					(start 161.277554 -34.51098)
					(mid 160.76676 -35.021393)
					(end 161.2773 -35.53206)
				)
				(arc
					(start 162.0901 -35.53206)
					(mid 162.60064 -35.02152)
					(end 162.0901 -34.51098)
				)
			)
		)
	)
	(zone
		(layers "In1.Cu" "In3.Cu" "In4.Cu" "In6.Cu")
		(hatch none 0.5)
		(connect_pads
			(clearance 0)
		)
		(min_thickness 0.25)
		(keepout
			(tracks not_allowed)
			(vias allowed)
			(pads allowed)
			(copperpour not_allowed)
			(footprints allowed)
		)
		(placement
			(enabled no)
			(sheetname "")
		)
		(fill yes
			(thermal_gap 0.5)
			(thermal_bridge_width 0.5)
			(island_removal_mode 0)
		)
		(polygon
			(pts
				(arc
					(start 298.837604 -25.027636)
					(mid 299.085738 -25.879089)
					(end 299.935392 -25.625044)
				)
				(arc
					(start 300.6852 -24.224996)
					(mid 300.429168 -23.379176)
					(end 299.583348 -23.635208)
				)
			)
		)
	)
	(zone
		(layers "In1.Cu" "In3.Cu" "In4.Cu" "In6.Cu")
		(hatch none 0.5)
		(connect_pads
			(clearance 0)
		)
		(min_thickness 0.25)
		(keepout
			(tracks not_allowed)
			(vias allowed)
			(pads allowed)
			(copperpour not_allowed)
			(footprints allowed)
		)
		(placement
			(enabled no)
			(sheetname "")
		)
		(fill yes
			(thermal_gap 0.5)
			(thermal_bridge_width 0.5)
			(island_removal_mode 0)
		)
		(polygon
			(pts
				(arc
					(start 154.587702 -13.627608)
					(mid 154.835836 -14.479061)
					(end 155.68549 -14.225016)
				)
				(arc
					(start 156.435298 -12.824968)
					(mid 156.179266 -11.979148)
					(end 155.333446 -12.23518)
				)
			)
		)
	)
	(zone
		(layers "In1.Cu" "In3.Cu" "In4.Cu" "In6.Cu")
		(hatch none 0.5)
		(connect_pads
			(clearance 0)
		)
		(min_thickness 0.25)
		(keepout
			(tracks not_allowed)
			(vias allowed)
			(pads allowed)
			(copperpour not_allowed)
			(footprints allowed)
		)
		(placement
			(enabled no)
			(sheetname "")
		)
		(fill yes
			(thermal_gap 0.5)
			(thermal_bridge_width 0.5)
			(island_removal_mode 0)
		)
		(polygon
			(pts
				(xy 291.187378 -25.626314) (xy 291.93744 -24.226266)
				(arc
					(start 291.935408 -24.224996)
					(mid 291.679376 -23.379176)
					(end 290.833556 -23.635208)
				)
				(xy 290.831524 -23.633938) (xy 290.081462 -25.033732) (xy 290.081716 -25.033986)
				(arc
					(start 290.083748 -25.035002)
					(mid 290.339424 -25.880903)
					(end 291.185346 -25.625044)
				)
			)
		)
	)
	(zone
		(layers "In1.Cu" "In3.Cu" "In4.Cu" "In6.Cu")
		(hatch none 0.5)
		(connect_pads
			(clearance 0)
		)
		(min_thickness 0.25)
		(keepout
			(tracks not_allowed)
			(vias allowed)
			(pads allowed)
			(copperpour not_allowed)
			(footprints allowed)
		)
		(placement
			(enabled no)
			(sheetname "")
		)
		(fill yes
			(thermal_gap 0.5)
			(thermal_bridge_width 0.5)
			(island_removal_mode 0)
		)
		(polygon
			(pts
				(xy 160.187386 -14.226286) (xy 160.937448 -12.826238)
				(arc
					(start 160.935416 -12.824968)
					(mid 160.679384 -11.979148)
					(end 159.833564 -12.23518)
				)
				(xy 159.831532 -12.23391) (xy 159.08147 -13.633704) (xy 159.081724 -13.633958)
				(arc
					(start 159.083756 -13.634974)
					(mid 159.339432 -14.480875)
					(end 160.185354 -14.225016)
				)
			)
		)
	)
	(zone
		(layers "In1.Cu" "In3.Cu" "In4.Cu" "In6.Cu")
		(hatch none 0.5)
		(connect_pads
			(clearance 0)
		)
		(min_thickness 0.25)
		(keepout
			(tracks not_allowed)
			(vias allowed)
			(pads allowed)
			(copperpour not_allowed)
			(footprints allowed)
		)
		(placement
			(enabled no)
			(sheetname "")
		)
		(fill yes
			(thermal_gap 0.5)
			(thermal_bridge_width 0.5)
			(island_removal_mode 0)
		)
		(polygon
			(pts
				(arc
					(start 18.852388 -81.39684)
					(mid 18.341594 -81.907253)
					(end 18.852134 -82.41792)
				)
				(arc
					(start 19.664934 -82.41792)
					(mid 20.175474 -81.90738)
					(end 19.664934 -81.39684)
				)
			)
		)
	)
	(zone
		(layers "In1.Cu" "In3.Cu" "In4.Cu" "In6.Cu")
		(hatch none 0.5)
		(connect_pads
			(clearance 0)
		)
		(min_thickness 0.25)
		(keepout
			(tracks not_allowed)
			(vias allowed)
			(pads allowed)
			(copperpour not_allowed)
			(footprints allowed)
		)
		(placement
			(enabled no)
			(sheetname "")
		)
		(fill yes
			(thermal_gap 0.5)
			(thermal_bridge_width 0.5)
			(island_removal_mode 0)
		)
		(polygon
			(pts
				(xy 171.187364 -14.226286) (xy 171.937426 -12.826238)
				(arc
					(start 171.935394 -12.824968)
					(mid 171.679362 -11.979148)
					(end 170.833542 -12.23518)
				)
				(xy 170.83151 -12.23391) (xy 170.081448 -13.633704) (xy 170.081702 -13.633958)
				(arc
					(start 170.083734 -13.634974)
					(mid 170.33941 -14.480875)
					(end 171.185332 -14.225016)
				)
			)
		)
	)
	(zone
		(layers "In1.Cu" "In3.Cu" "In4.Cu" "In6.Cu")
		(hatch none 0.5)
		(connect_pads
			(clearance 0)
		)
		(min_thickness 0.25)
		(keepout
			(tracks not_allowed)
			(vias allowed)
			(pads allowed)
			(copperpour not_allowed)
			(footprints allowed)
		)
		(placement
			(enabled no)
			(sheetname "")
		)
		(fill yes
			(thermal_gap 0.5)
			(thermal_bridge_width 0.5)
			(island_removal_mode 0)
		)
		(polygon
			(pts
				(arc
					(start 138.378946 -35.503866)
					(mid 138.88974 -34.993453)
					(end 138.3792 -34.482786)
				)
				(arc
					(start 137.5664 -34.482786)
					(mid 137.05586 -34.993326)
					(end 137.5664 -35.503866)
				)
			)
		)
	)
	(zone
		(layers "In1.Cu" "In3.Cu" "In4.Cu" "In6.Cu")
		(hatch none 0.5)
		(connect_pads
			(clearance 0)
		)
		(min_thickness 0.25)
		(keepout
			(tracks not_allowed)
			(vias allowed)
			(pads allowed)
			(copperpour not_allowed)
			(footprints allowed)
		)
		(placement
			(enabled no)
			(sheetname "")
		)
		(fill yes
			(thermal_gap 0.5)
			(thermal_bridge_width 0.5)
			(island_removal_mode 0)
		)
		(polygon
			(pts
				(arc
					(start 28.47594 -105.502202)
					(mid 27.610308 -105.502202)
					(end 27.610308 -106.367834)
				)
				(xy 27.60853 -106.369612) (xy 28.398978 -107.16006)
				(arc
					(start 28.400756 -107.158282)
					(mid 29.266388 -107.158282)
					(end 29.266388 -106.29265)
				)
				(xy 29.268166 -106.290872) (xy 28.477972 -105.500678) (xy 28.477464 -105.500678)
			)
		)
	)
	(zone
		(layers "In1.Cu" "In3.Cu" "In4.Cu" "In6.Cu")
		(hatch none 0.5)
		(connect_pads
			(clearance 0)
		)
		(min_thickness 0.25)
		(keepout
			(tracks not_allowed)
			(vias allowed)
			(pads allowed)
			(copperpour not_allowed)
			(footprints allowed)
		)
		(placement
			(enabled no)
			(sheetname "")
		)
		(fill yes
			(thermal_gap 0.5)
			(thermal_bridge_width 0.5)
			(island_removal_mode 0)
		)
		(polygon
			(pts
				(arc
					(start 52.399692 -47.366428)
					(mid 51.888898 -47.876841)
					(end 52.399438 -48.387508)
				)
				(arc
					(start 53.305964 -48.387508)
					(mid 53.816504 -47.876968)
					(end 53.305964 -47.366428)
				)
			)
		)
	)
	(zone
		(layers "In1.Cu" "In3.Cu" "In4.Cu" "In6.Cu")
		(hatch none 0.5)
		(connect_pads
			(clearance 0)
		)
		(min_thickness 0.25)
		(keepout
			(tracks not_allowed)
			(vias allowed)
			(pads allowed)
			(copperpour not_allowed)
			(footprints allowed)
		)
		(placement
			(enabled no)
			(sheetname "")
		)
		(fill yes
			(thermal_gap 0.5)
			(thermal_bridge_width 0.5)
			(island_removal_mode 0)
		)
		(polygon
			(pts
				(arc
					(start 201.97318 -44.714922)
					(mid 201.36104 -44.102782)
					(end 200.7489 -44.714922)
				)
				(arc
					(start 200.7489 -45.832268)
					(mid 201.360913 -46.444662)
					(end 201.97318 -45.832522)
				)
			)
		)
	)
	(zone
		(layers "In1.Cu" "In3.Cu" "In4.Cu" "In6.Cu")
		(hatch none 0.5)
		(connect_pads
			(clearance 0)
		)
		(min_thickness 0.25)
		(keepout
			(tracks not_allowed)
			(vias allowed)
			(pads allowed)
			(copperpour not_allowed)
			(footprints allowed)
		)
		(placement
			(enabled no)
			(sheetname "")
		)
		(fill yes
			(thermal_gap 0.5)
			(thermal_bridge_width 0.5)
			(island_removal_mode 0)
		)
		(polygon
			(pts
				(arc
					(start 153.530046 -35.50666)
					(mid 154.04084 -34.996247)
					(end 153.5303 -34.48558)
				)
				(arc
					(start 152.7175 -34.48558)
					(mid 152.20696 -34.99612)
					(end 152.7175 -35.50666)
				)
			)
		)
	)
	(zone
		(layers "In1.Cu" "In3.Cu" "In4.Cu" "In6.Cu")
		(hatch none 0.5)
		(connect_pads
			(clearance 0)
		)
		(min_thickness 0.25)
		(keepout
			(tracks not_allowed)
			(vias allowed)
			(pads allowed)
			(copperpour not_allowed)
			(footprints allowed)
		)
		(placement
			(enabled no)
			(sheetname "")
		)
		(fill yes
			(thermal_gap 0.5)
			(thermal_bridge_width 0.5)
			(island_removal_mode 0)
		)
		(polygon
			(pts
				(xy 168.937432 -18.02638) (xy 169.687494 -16.626586)
				(arc
					(start 169.685208 -16.625316)
					(mid 169.429684 -15.779496)
					(end 168.583864 -16.03502)
				)
				(xy 168.581578 -16.03375) (xy 167.831516 -17.433544) (xy 167.83177 -17.433798)
				(arc
					(start 167.833802 -17.434814)
					(mid 168.089326 -18.280634)
					(end 168.935146 -18.02511)
				)
			)
		)
	)
	(zone
		(layers "In1.Cu" "In3.Cu" "In4.Cu" "In6.Cu")
		(hatch none 0.5)
		(connect_pads
			(clearance 0)
		)
		(min_thickness 0.25)
		(keepout
			(tracks not_allowed)
			(vias allowed)
			(pads allowed)
			(copperpour not_allowed)
			(footprints allowed)
		)
		(placement
			(enabled no)
			(sheetname "")
		)
		(fill yes
			(thermal_gap 0.5)
			(thermal_bridge_width 0.5)
			(island_removal_mode 0)
		)
		(polygon
			(pts
				(xy 157.937454 -14.226286) (xy 158.687516 -12.826238)
				(arc
					(start 158.685484 -12.824968)
					(mid 158.429452 -11.979148)
					(end 157.583632 -12.23518)
				)
				(xy 157.5816 -12.23391) (xy 156.831538 -13.633704) (xy 156.831792 -13.633958)
				(arc
					(start 156.833824 -13.634974)
					(mid 157.0895 -14.480875)
					(end 157.935422 -14.225016)
				)
			)
		)
	)
	(zone
		(layers "In1.Cu" "In3.Cu" "In4.Cu" "In6.Cu")
		(hatch none 0.5)
		(connect_pads
			(clearance 0)
		)
		(min_thickness 0.25)
		(keepout
			(tracks not_allowed)
			(vias allowed)
			(pads allowed)
			(copperpour not_allowed)
			(footprints allowed)
		)
		(placement
			(enabled no)
			(sheetname "")
		)
		(fill yes
			(thermal_gap 0.5)
			(thermal_bridge_width 0.5)
			(island_removal_mode 0)
		)
		(polygon
			(pts
				(arc
					(start 138.93546 -20.424902)
					(mid 138.679428 -19.579082)
					(end 137.833608 -19.835114)
				)
				(xy 137.831576 -19.833844) (xy 137.081514 -21.233638) (xy 137.081768 -21.233892)
				(arc
					(start 137.0838 -21.234908)
					(mid 137.339476 -22.080809)
					(end 138.185398 -21.82495)
				)
				(xy 138.18743 -21.82622) (xy 138.937492 -20.426172)
			)
		)
	)
	(zone
		(layers "In1.Cu" "In3.Cu" "In4.Cu" "In6.Cu")
		(hatch none 0.5)
		(connect_pads
			(clearance 0)
		)
		(min_thickness 0.25)
		(keepout
			(tracks not_allowed)
			(vias allowed)
			(pads allowed)
			(copperpour not_allowed)
			(footprints allowed)
		)
		(placement
			(enabled no)
			(sheetname "")
		)
		(fill yes
			(thermal_gap 0.5)
			(thermal_bridge_width 0.5)
			(island_removal_mode 0)
		)
		(polygon
			(pts
				(arc
					(start 134.833614 -13.635228)
					(mid 135.089646 -14.481048)
					(end 135.935466 -14.225016)
				)
				(arc
					(start 136.68121 -12.832588)
					(mid 136.433076 -11.981135)
					(end 135.583422 -12.23518)
				)
			)
		)
	)
	(zone
		(layers "In1.Cu" "In3.Cu" "In4.Cu" "In6.Cu")
		(hatch none 0.5)
		(connect_pads
			(clearance 0)
		)
		(min_thickness 0.25)
		(keepout
			(tracks not_allowed)
			(vias allowed)
			(pads allowed)
			(copperpour not_allowed)
			(footprints allowed)
		)
		(placement
			(enabled no)
			(sheetname "")
		)
		(fill yes
			(thermal_gap 0.5)
			(thermal_bridge_width 0.5)
			(island_removal_mode 0)
		)
		(polygon
			(pts
				(xy 160.187386 -18.02638) (xy 160.937448 -16.626586)
				(arc
					(start 160.935162 -16.625316)
					(mid 160.679638 -15.779496)
					(end 159.833818 -16.03502)
				)
				(xy 159.831532 -16.03375) (xy 159.08147 -17.433544) (xy 159.081724 -17.433798)
				(arc
					(start 159.083756 -17.434814)
					(mid 159.33928 -18.280634)
					(end 160.1851 -18.02511)
				)
			)
		)
	)
	(zone
		(layers "In1.Cu" "In3.Cu" "In4.Cu" "In6.Cu")
		(hatch none 0.5)
		(connect_pads
			(clearance 0)
		)
		(min_thickness 0.25)
		(keepout
			(tracks not_allowed)
			(vias allowed)
			(pads allowed)
			(copperpour not_allowed)
			(footprints allowed)
		)
		(placement
			(enabled no)
			(sheetname "")
		)
		(fill yes
			(thermal_gap 0.5)
			(thermal_bridge_width 0.5)
			(island_removal_mode 0)
		)
		(polygon
			(pts
				(arc
					(start 145.837656 -13.627608)
					(mid 146.08579 -14.479061)
					(end 146.935444 -14.225016)
				)
				(arc
					(start 147.685252 -12.824968)
					(mid 147.42922 -11.979148)
					(end 146.5834 -12.23518)
				)
			)
		)
	)
	(zone
		(layers "In1.Cu" "In3.Cu" "In4.Cu" "In6.Cu")
		(hatch none 0.5)
		(connect_pads
			(clearance 0)
		)
		(min_thickness 0.25)
		(keepout
			(tracks not_allowed)
			(vias allowed)
			(pads allowed)
			(copperpour not_allowed)
			(footprints allowed)
		)
		(placement
			(enabled no)
			(sheetname "")
		)
		(fill yes
			(thermal_gap 0.5)
			(thermal_bridge_width 0.5)
			(island_removal_mode 0)
		)
		(polygon
			(pts
				(arc
					(start 329.188064 -35.429952)
					(mid 329.698858 -34.919539)
					(end 329.188318 -34.408872)
				)
				(arc
					(start 328.375518 -34.408872)
					(mid 327.864978 -34.919412)
					(end 328.375518 -35.429952)
				)
			)
		)
	)
	(zone
		(layers "In1.Cu" "In3.Cu" "In4.Cu" "In6.Cu")
		(hatch none 0.5)
		(connect_pads
			(clearance 0)
		)
		(min_thickness 0.25)
		(keepout
			(tracks not_allowed)
			(vias allowed)
			(pads allowed)
			(copperpour not_allowed)
			(footprints allowed)
		)
		(placement
			(enabled no)
			(sheetname "")
		)
		(fill yes
			(thermal_gap 0.5)
			(thermal_bridge_width 0.5)
			(island_removal_mode 0)
		)
		(polygon
			(pts
				(xy 313.187334 -18.02638) (xy 313.937396 -16.626586)
				(arc
					(start 313.93511 -16.625316)
					(mid 313.679586 -15.779496)
					(end 312.833766 -16.03502)
				)
				(xy 312.83148 -16.03375) (xy 312.081418 -17.433544) (xy 312.081672 -17.433798)
				(arc
					(start 312.083704 -17.434814)
					(mid 312.339228 -18.280634)
					(end 313.185048 -18.02511)
				)
			)
		)
	)
	(zone
		(layers "In1.Cu" "In3.Cu" "In4.Cu" "In6.Cu")
		(hatch none 0.5)
		(connect_pads
			(clearance 0)
		)
		(min_thickness 0.25)
		(keepout
			(tracks not_allowed)
			(vias allowed)
			(pads allowed)
			(copperpour not_allowed)
			(footprints allowed)
		)
		(placement
			(enabled no)
			(sheetname "")
		)
		(fill yes
			(thermal_gap 0.5)
			(thermal_bridge_width 0.5)
			(island_removal_mode 0)
		)
		(polygon
			(pts
				(xy 171.187364 -18.02638) (xy 171.937426 -16.626586)
				(arc
					(start 171.93514 -16.625316)
					(mid 171.679616 -15.779496)
					(end 170.833796 -16.03502)
				)
				(xy 170.83151 -16.03375) (xy 170.081448 -17.433544) (xy 170.081702 -17.433798)
				(arc
					(start 170.083734 -17.434814)
					(mid 170.339258 -18.280634)
					(end 171.185078 -18.02511)
				)
			)
		)
	)
	(zone
		(layers "In1.Cu" "In3.Cu" "In4.Cu" "In6.Cu")
		(hatch none 0.5)
		(connect_pads
			(clearance 0)
		)
		(min_thickness 0.25)
		(keepout
			(tracks not_allowed)
			(vias allowed)
			(pads allowed)
			(copperpour not_allowed)
			(footprints allowed)
		)
		(placement
			(enabled no)
			(sheetname "")
		)
		(fill yes
			(thermal_gap 0.5)
			(thermal_bridge_width 0.5)
			(island_removal_mode 0)
		)
		(polygon
			(pts
				(arc
					(start 323.612764 -34.458402)
					(mid 323.10197 -34.968815)
					(end 323.61251 -35.479482)
				)
				(arc
					(start 324.42531 -35.479482)
					(mid 324.93585 -34.968942)
					(end 324.42531 -34.458402)
				)
			)
		)
	)
	(zone
		(layers "In1.Cu" "In3.Cu" "In4.Cu" "In6.Cu")
		(hatch none 0.5)
		(connect_pads
			(clearance 0)
		)
		(min_thickness 0.25)
		(keepout
			(tracks not_allowed)
			(vias allowed)
			(pads allowed)
			(copperpour not_allowed)
			(footprints allowed)
		)
		(placement
			(enabled no)
			(sheetname "")
		)
		(fill yes
			(thermal_gap 0.5)
			(thermal_bridge_width 0.5)
			(island_removal_mode 0)
		)
		(polygon
			(pts
				(xy 321.93738 -18.02638) (xy 322.687442 -16.626586)
				(arc
					(start 322.685156 -16.625316)
					(mid 322.429632 -15.779496)
					(end 321.583812 -16.03502)
				)
				(xy 321.581526 -16.03375) (xy 320.831464 -17.433544) (xy 320.831718 -17.433798)
				(arc
					(start 320.83375 -17.434814)
					(mid 321.089274 -18.280634)
					(end 321.935094 -18.02511)
				)
			)
		)
	)
	(zone
		(layers "In1.Cu" "In3.Cu" "In4.Cu" "In6.Cu")
		(hatch none 0.5)
		(connect_pads
			(clearance 0)
		)
		(min_thickness 0.25)
		(keepout
			(tracks not_allowed)
			(vias allowed)
			(pads allowed)
			(copperpour not_allowed)
			(footprints allowed)
		)
		(placement
			(enabled no)
			(sheetname "")
		)
		(fill yes
			(thermal_gap 0.5)
			(thermal_bridge_width 0.5)
			(island_removal_mode 0)
		)
		(polygon
			(pts
				(xy 157.937454 -18.02638) (xy 158.687516 -16.626586)
				(arc
					(start 158.68523 -16.625316)
					(mid 158.429706 -15.779496)
					(end 157.583886 -16.03502)
				)
				(xy 157.5816 -16.03375) (xy 156.831538 -17.433544) (xy 156.831792 -17.433798)
				(arc
					(start 156.833824 -17.434814)
					(mid 157.089348 -18.280634)
					(end 157.935168 -18.02511)
				)
			)
		)
	)
	(zone
		(layers "In1.Cu" "In3.Cu" "In4.Cu" "In6.Cu")
		(hatch none 0.5)
		(connect_pads
			(clearance 0)
		)
		(min_thickness 0.25)
		(keepout
			(tracks not_allowed)
			(vias allowed)
			(pads allowed)
			(copperpour not_allowed)
			(footprints allowed)
		)
		(placement
			(enabled no)
			(sheetname "")
		)
		(fill yes
			(thermal_gap 0.5)
			(thermal_bridge_width 0.5)
			(island_removal_mode 0)
		)
		(polygon
			(pts
				(arc
					(start 149.313646 -35.51174)
					(mid 149.82444 -35.001327)
					(end 149.3139 -34.49066)
				)
				(arc
					(start 148.5011 -34.49066)
					(mid 147.99056 -35.0012)
					(end 148.5011 -35.51174)
				)
			)
		)
	)
	(zone
		(layers "In1.Cu" "In3.Cu" "In4.Cu" "In6.Cu")
		(hatch none 0.5)
		(connect_pads
			(clearance 0)
		)
		(min_thickness 0.25)
		(keepout
			(tracks not_allowed)
			(vias allowed)
			(pads allowed)
			(copperpour not_allowed)
			(footprints allowed)
		)
		(placement
			(enabled no)
			(sheetname "")
		)
		(fill yes
			(thermal_gap 0.5)
			(thermal_bridge_width 0.5)
			(island_removal_mode 0)
		)
		(polygon
			(pts
				(arc
					(start 19.659346 -55.508652)
					(mid 20.17014 -54.998239)
					(end 19.6596 -54.487572)
				)
				(arc
					(start 18.8468 -54.487572)
					(mid 18.33626 -54.998112)
					(end 18.8468 -55.508652)
				)
			)
		)
	)
	(zone
		(layers "In1.Cu" "In3.Cu" "In4.Cu" "In6.Cu")
		(hatch none 0.5)
		(connect_pads
			(clearance 0)
		)
		(min_thickness 0.25)
		(keepout
			(tracks not_allowed)
			(vias allowed)
			(pads allowed)
			(copperpour not_allowed)
			(footprints allowed)
		)
		(placement
			(enabled no)
			(sheetname "")
		)
		(fill yes
			(thermal_gap 0.5)
			(thermal_bridge_width 0.5)
			(island_removal_mode 0)
		)
		(polygon
			(pts
				(xy 291.187378 -14.226286) (xy 291.93744 -12.826492) (xy 291.937186 -12.826238)
				(arc
					(start 291.935154 -12.825222)
					(mid 291.679478 -11.979321)
					(end 290.833556 -12.23518)
				)
				(xy 290.831524 -12.23391) (xy 290.081462 -13.633958)
				(arc
					(start 290.083494 -13.635228)
					(mid 290.339526 -14.481048)
					(end 291.185346 -14.225016)
				)
			)
		)
	)
	(zone
		(layers "In1.Cu" "In3.Cu" "In4.Cu" "In6.Cu")
		(hatch none 0.5)
		(connect_pads
			(clearance 0)
		)
		(min_thickness 0.25)
		(keepout
			(tracks not_allowed)
			(vias allowed)
			(pads allowed)
			(copperpour not_allowed)
			(footprints allowed)
		)
		(placement
			(enabled no)
			(sheetname "")
		)
		(fill yes
			(thermal_gap 0.5)
			(thermal_bridge_width 0.5)
			(island_removal_mode 0)
		)
		(polygon
			(pts
				(arc
					(start 294.159432 -34.66973)
					(mid 293.648638 -35.180143)
					(end 294.159178 -35.69081)
				)
				(arc
					(start 294.971978 -35.69081)
					(mid 295.482518 -35.18027)
					(end 294.971978 -34.66973)
				)
			)
		)
	)
	(zone
		(layers "In1.Cu" "In3.Cu" "In4.Cu" "In6.Cu")
		(hatch none 0.5)
		(connect_pads
			(clearance 0)
		)
		(min_thickness 0.25)
		(keepout
			(tracks not_allowed)
			(vias allowed)
			(pads allowed)
			(copperpour not_allowed)
			(footprints allowed)
		)
		(placement
			(enabled no)
			(sheetname "")
		)
		(fill yes
			(thermal_gap 0.5)
			(thermal_bridge_width 0.5)
			(island_removal_mode 0)
		)
		(polygon
			(pts
				(arc
					(start 298.837604 -13.627608)
					(mid 299.085738 -14.479061)
					(end 299.935392 -14.225016)
				)
				(arc
					(start 300.6852 -12.824968)
					(mid 300.429168 -11.979148)
					(end 299.583348 -12.23518)
				)
			)
		)
	)
	(zone
		(layers "In1.Cu" "In3.Cu" "In4.Cu" "In6.Cu")
		(hatch none 0.5)
		(connect_pads
			(clearance 0)
		)
		(min_thickness 0.25)
		(keepout
			(tracks not_allowed)
			(vias allowed)
			(pads allowed)
			(copperpour not_allowed)
			(footprints allowed)
		)
		(placement
			(enabled no)
			(sheetname "")
		)
		(fill yes
			(thermal_gap 0.5)
			(thermal_bridge_width 0.5)
			(island_removal_mode 0)
		)
		(polygon
			(pts
				(arc
					(start 318.587628 -13.627608)
					(mid 318.835762 -14.479061)
					(end 319.685416 -14.225016)
				)
				(arc
					(start 320.435224 -12.824968)
					(mid 320.179192 -11.979148)
					(end 319.333372 -12.23518)
				)
			)
		)
	)
	(zone
		(layers "In1.Cu" "In3.Cu" "In4.Cu" "In6.Cu")
		(hatch none 0.5)
		(connect_pads
			(clearance 0)
		)
		(min_thickness 0.25)
		(keepout
			(tracks not_allowed)
			(vias allowed)
			(pads allowed)
			(copperpour not_allowed)
			(footprints allowed)
		)
		(placement
			(enabled no)
			(sheetname "")
		)
		(fill yes
			(thermal_gap 0.5)
			(thermal_bridge_width 0.5)
			(island_removal_mode 0)
		)
		(polygon
			(pts
				(arc
					(start 25.085294 -111.4044)
					(mid 24.473154 -110.79226)
					(end 23.861014 -111.4044)
				)
				(arc
					(start 23.861014 -112.521746)
					(mid 24.473027 -113.13414)
					(end 25.085294 -112.522)
				)
			)
		)
	)
	(zone
		(layers "In1.Cu" "In3.Cu" "In4.Cu" "In6.Cu")
		(hatch none 0.5)
		(connect_pads
			(clearance 0)
		)
		(min_thickness 0.25)
		(keepout
			(tracks not_allowed)
			(vias allowed)
			(pads allowed)
			(copperpour not_allowed)
			(footprints allowed)
		)
		(placement
			(enabled no)
			(sheetname "")
		)
		(fill yes
			(thermal_gap 0.5)
			(thermal_bridge_width 0.5)
			(island_removal_mode 0)
		)
		(polygon
			(pts
				(xy 324.187312 -25.626314) (xy 324.937374 -24.226266)
				(arc
					(start 324.935342 -24.224996)
					(mid 324.67931 -23.379176)
					(end 323.83349 -23.635208)
				)
				(xy 323.831458 -23.633938) (xy 323.081396 -25.033732) (xy 323.08165 -25.033986)
				(arc
					(start 323.083682 -25.035002)
					(mid 323.339358 -25.880903)
					(end 324.18528 -25.625044)
				)
			)
		)
	)
	(zone
		(layers "In1.Cu" "In3.Cu" "In4.Cu" "In6.Cu")
		(hatch none 0.5)
		(connect_pads
			(clearance 0)
		)
		(min_thickness 0.25)
		(keepout
			(tracks not_allowed)
			(vias allowed)
			(pads allowed)
			(copperpour not_allowed)
			(footprints allowed)
		)
		(placement
			(enabled no)
			(sheetname "")
		)
		(fill yes
			(thermal_gap 0.5)
			(thermal_bridge_width 0.5)
			(island_removal_mode 0)
		)
		(polygon
			(pts
				(xy 313.187334 -14.226286) (xy 313.937396 -12.826238)
				(arc
					(start 313.935364 -12.824968)
					(mid 313.679332 -11.979148)
					(end 312.833512 -12.23518)
				)
				(xy 312.83148 -12.23391) (xy 312.081418 -13.633704) (xy 312.081672 -13.633958)
				(arc
					(start 312.083704 -13.634974)
					(mid 312.33938 -14.480875)
					(end 313.185302 -14.225016)
				)
			)
		)
	)
	(zone
		(layers "In1.Cu" "In3.Cu" "In4.Cu" "In6.Cu")
		(hatch none 0.5)
		(connect_pads
			(clearance 0)
		)
		(min_thickness 0.25)
		(keepout
			(tracks not_allowed)
			(vias allowed)
			(pads allowed)
			(copperpour not_allowed)
			(footprints allowed)
		)
		(placement
			(enabled no)
			(sheetname "")
		)
		(fill yes
			(thermal_gap 0.5)
			(thermal_bridge_width 0.5)
			(island_removal_mode 0)
		)
		(polygon
			(pts
				(arc
					(start 22.555454 -53.045614)
					(mid 22.04466 -53.556027)
					(end 22.5552 -54.066694)
				)
				(arc
					(start 23.368 -54.066694)
					(mid 23.87854 -53.556154)
					(end 23.368 -53.045614)
				)
			)
		)
	)
	(zone
		(layers "In1.Cu" "In3.Cu" "In4.Cu" "In6.Cu")
		(hatch none 0.5)
		(connect_pads
			(clearance 0)
		)
		(min_thickness 0.25)
		(keepout
			(tracks not_allowed)
			(vias allowed)
			(pads allowed)
			(copperpour not_allowed)
			(footprints allowed)
		)
		(placement
			(enabled no)
			(sheetname "")
		)
		(fill yes
			(thermal_gap 0.5)
			(thermal_bridge_width 0.5)
			(island_removal_mode 0)
		)
		(polygon
			(pts
				(arc
					(start 200.046844 -49.122076)
					(mid 199.43826 -49.737772)
					(end 200.053956 -50.346356)
				)
				(arc
					(start 201.171302 -50.339752)
					(mid 201.780139 -49.724183)
					(end 201.164444 -49.115472)
				)
			)
		)
	)
	(zone
		(layers "In1.Cu" "In3.Cu" "In4.Cu" "In6.Cu")
		(hatch none 0.5)
		(connect_pads
			(clearance 0)
		)
		(min_thickness 0.25)
		(keepout
			(tracks not_allowed)
			(vias allowed)
			(pads allowed)
			(copperpour not_allowed)
			(footprints allowed)
		)
		(placement
			(enabled no)
			(sheetname "")
		)
		(fill yes
			(thermal_gap 0.5)
			(thermal_bridge_width 0.5)
			(island_removal_mode 0)
		)
		(polygon
			(pts
				(xy 135.937498 -18.026126) (xy 136.687306 -16.626332)
				(arc
					(start 136.685274 -16.625062)
					(mid 136.429242 -15.779242)
					(end 135.583422 -16.035274)
				)
				(xy 135.58139 -16.034004) (xy 134.831582 -17.433544) (xy 134.831836 -17.433798)
				(arc
					(start 134.833868 -17.434814)
					(mid 135.089544 -18.280715)
					(end 135.935466 -18.024856)
				)
			)
		)
	)
	(zone
		(layers "In1.Cu" "In3.Cu" "In4.Cu" "In6.Cu")
		(hatch none 0.5)
		(connect_pads
			(clearance 0)
		)
		(min_thickness 0.25)
		(keepout
			(tracks not_allowed)
			(vias allowed)
			(pads allowed)
			(copperpour not_allowed)
			(footprints allowed)
		)
		(placement
			(enabled no)
			(sheetname "")
		)
		(fill yes
			(thermal_gap 0.5)
			(thermal_bridge_width 0.5)
			(island_removal_mode 0)
		)
		(polygon
			(pts
				(xy 321.93738 -14.226286) (xy 322.687442 -12.826238)
				(arc
					(start 322.68541 -12.824968)
					(mid 322.429378 -11.979148)
					(end 321.583558 -12.23518)
				)
				(xy 321.581526 -12.23391) (xy 320.831464 -13.633704) (xy 320.831718 -13.633958)
				(arc
					(start 320.83375 -13.634974)
					(mid 321.089426 -14.480875)
					(end 321.935348 -14.225016)
				)
			)
		)
	)
	(zone
		(layers "In1.Cu" "In3.Cu" "In4.Cu" "In6.Cu")
		(hatch none 0.5)
		(connect_pads
			(clearance 0)
		)
		(min_thickness 0.25)
		(keepout
			(tracks not_allowed)
			(vias allowed)
			(pads allowed)
			(copperpour not_allowed)
			(footprints allowed)
		)
		(placement
			(enabled no)
			(sheetname "")
		)
		(fill yes
			(thermal_gap 0.5)
			(thermal_bridge_width 0.5)
			(island_removal_mode 0)
		)
		(polygon
			(pts
				(arc
					(start 23.535386 -57.300876)
					(mid 24.147526 -56.688736)
					(end 23.535386 -56.076596)
				)
				(arc
					(start 22.417786 -56.076596)
					(mid 21.805646 -56.688736)
					(end 22.417786 -57.300876)
				)
			)
		)
	)
	(zone
		(layers "In1.Cu" "In3.Cu" "In4.Cu" "In6.Cu")
		(hatch none 0.5)
		(connect_pads
			(clearance 0)
		)
		(min_thickness 0.25)
		(keepout
			(tracks not_allowed)
			(vias allowed)
			(pads allowed)
			(copperpour not_allowed)
			(footprints allowed)
		)
		(placement
			(enabled no)
			(sheetname "")
		)
		(fill yes
			(thermal_gap 0.5)
			(thermal_bridge_width 0.5)
			(island_removal_mode 0)
		)
		(polygon
			(pts
				(arc
					(start 65.330832 -127.168656)
					(mid 64.820038 -127.679069)
					(end 65.330578 -128.189736)
				)
				(arc
					(start 66.143378 -128.189736)
					(mid 66.653918 -127.679196)
					(end 66.143378 -127.168656)
				)
			)
		)
	)
	(zone
		(layers "In1.Cu" "In3.Cu" "In4.Cu" "In6.Cu")
		(hatch none 0.5)
		(connect_pads
			(clearance 0)
		)
		(min_thickness 0.25)
		(keepout
			(tracks not_allowed)
			(vias allowed)
			(pads allowed)
			(copperpour not_allowed)
			(footprints allowed)
		)
		(placement
			(enabled no)
			(sheetname "")
		)
		(fill yes
			(thermal_gap 0.5)
			(thermal_bridge_width 0.5)
			(island_removal_mode 0)
		)
		(polygon
			(pts
				(arc
					(start 16.9672 -87.65794)
					(mid 17.57934 -87.0458)
					(end 16.9672 -86.43366)
				)
				(arc
					(start 15.8496 -86.43366)
					(mid 15.23746 -87.0458)
					(end 15.8496 -87.65794)
				)
			)
		)
	)
	(zone
		(layers "In1.Cu" "In3.Cu" "In4.Cu" "In6.Cu")
		(hatch none 0.5)
		(connect_pads
			(clearance 0)
		)
		(min_thickness 0.25)
		(keepout
			(tracks not_allowed)
			(vias allowed)
			(pads allowed)
			(copperpour not_allowed)
			(footprints allowed)
		)
		(placement
			(enabled no)
			(sheetname "")
		)
		(fill yes
			(thermal_gap 0.5)
			(thermal_bridge_width 0.5)
			(island_removal_mode 0)
		)
		(polygon
			(pts
				(xy 310.937402 -21.82622) (xy 311.687464 -20.426426) (xy 311.68721 -20.426172)
				(arc
					(start 311.685178 -20.425156)
					(mid 311.429502 -19.579255)
					(end 310.58358 -19.835114)
				)
				(xy 310.581548 -19.833844) (xy 309.831486 -21.233892)
				(arc
					(start 309.833518 -21.235162)
					(mid 310.08955 -22.080982)
					(end 310.93537 -21.82495)
				)
			)
		)
	)
	(zone
		(layers "In1.Cu" "In3.Cu" "In4.Cu" "In6.Cu")
		(hatch none 0.5)
		(connect_pads
			(clearance 0)
		)
		(min_thickness 0.25)
		(keepout
			(tracks not_allowed)
			(vias allowed)
			(pads allowed)
			(copperpour not_allowed)
			(footprints allowed)
		)
		(placement
			(enabled no)
			(sheetname "")
		)
		(fill yes
			(thermal_gap 0.5)
			(thermal_bridge_width 0.5)
			(island_removal_mode 0)
		)
		(polygon
			(pts
				(arc
					(start 307.58765 -13.627608)
					(mid 307.835784 -14.479061)
					(end 308.685438 -14.225016)
				)
				(arc
					(start 309.435246 -12.824968)
					(mid 309.179214 -11.979148)
					(end 308.333394 -12.23518)
				)
			)
		)
	)
	(zone
		(layers "In1.Cu" "In3.Cu" "In4.Cu" "In6.Cu")
		(hatch none 0.5)
		(connect_pads
			(clearance 0)
		)
		(min_thickness 0.25)
		(keepout
			(tracks not_allowed)
			(vias allowed)
			(pads allowed)
			(copperpour not_allowed)
			(footprints allowed)
		)
		(placement
			(enabled no)
			(sheetname "")
		)
		(fill yes
			(thermal_gap 0.5)
			(thermal_bridge_width 0.5)
			(island_removal_mode 0)
		)
		(polygon
			(pts
				(xy 291.187378 -18.02638) (xy 291.93744 -16.626586)
				(arc
					(start 291.935154 -16.625316)
					(mid 291.67963 -15.779496)
					(end 290.83381 -16.03502)
				)
				(xy 290.831524 -16.03375) (xy 290.081462 -17.433544) (xy 290.081716 -17.433798)
				(arc
					(start 290.083748 -17.434814)
					(mid 290.339272 -18.280634)
					(end 291.185092 -18.02511)
				)
			)
		)
	)
	(zone
		(layers "In1.Cu" "In3.Cu" "In4.Cu" "In6.Cu")
		(hatch none 0.5)
		(connect_pads
			(clearance 0)
		)
		(min_thickness 0.25)
		(keepout
			(tracks not_allowed)
			(vias allowed)
			(pads allowed)
			(copperpour not_allowed)
			(footprints allowed)
		)
		(placement
			(enabled no)
			(sheetname "")
		)
		(fill yes
			(thermal_gap 0.5)
			(thermal_bridge_width 0.5)
			(island_removal_mode 0)
		)
		(polygon
			(pts
				(xy 302.187356 -18.02638) (xy 302.937418 -16.626586)
				(arc
					(start 302.935132 -16.625316)
					(mid 302.679608 -15.779496)
					(end 301.833788 -16.03502)
				)
				(xy 301.831502 -16.03375) (xy 301.08144 -17.433544) (xy 301.081694 -17.433798)
				(arc
					(start 301.083726 -17.434814)
					(mid 301.33925 -18.280634)
					(end 302.18507 -18.02511)
				)
			)
		)
	)
	(zone
		(layers "In1.Cu" "In3.Cu" "In4.Cu" "In6.Cu")
		(hatch none 0.5)
		(connect_pads
			(clearance 0)
		)
		(min_thickness 0.25)
		(keepout
			(tracks not_allowed)
			(vias allowed)
			(pads allowed)
			(copperpour not_allowed)
			(footprints allowed)
		)
		(placement
			(enabled no)
			(sheetname "")
		)
		(fill yes
			(thermal_gap 0.5)
			(thermal_bridge_width 0.5)
			(island_removal_mode 0)
		)
		(polygon
			(pts
				(arc
					(start 287.837626 -25.027636)
					(mid 288.08576 -25.879089)
					(end 288.935414 -25.625044)
				)
				(arc
					(start 289.685222 -24.224996)
					(mid 289.42919 -23.379176)
					(end 288.58337 -23.635208)
				)
			)
		)
	)
	(zone
		(layers "In1.Cu" "In3.Cu" "In4.Cu" "In6.Cu")
		(hatch none 0.5)
		(connect_pads
			(clearance 0)
		)
		(min_thickness 0.25)
		(keepout
			(tracks not_allowed)
			(vias allowed)
			(pads allowed)
			(copperpour not_allowed)
			(footprints allowed)
		)
		(placement
			(enabled no)
			(sheetname "")
		)
		(fill yes
			(thermal_gap 0.5)
			(thermal_bridge_width 0.5)
			(island_removal_mode 0)
		)
		(polygon
			(pts
				(arc
					(start 87.290148 -76.589636)
					(mid 86.779608 -76.079096)
					(end 86.269068 -76.589636)
				)
				(arc
					(start 86.269068 -77.478382)
					(mid 86.779481 -77.989176)
					(end 87.290148 -77.478636)
				)
			)
		)
	)
	(zone
		(layers "In1.Cu" "In3.Cu" "In4.Cu" "In6.Cu")
		(hatch none 0.5)
		(connect_pads
			(clearance 0)
		)
		(min_thickness 0.25)
		(keepout
			(tracks not_allowed)
			(vias allowed)
			(pads allowed)
			(copperpour not_allowed)
			(footprints allowed)
		)
		(placement
			(enabled no)
			(sheetname "")
		)
		(fill yes
			(thermal_gap 0.5)
			(thermal_bridge_width 0.5)
			(island_removal_mode 0)
		)
		(polygon
			(pts
				(arc
					(start 270.05534 -5.305806)
					(mid 269.544927 -4.795012)
					(end 269.03426 -5.305552)
				)
				(arc
					(start 269.03426 -6.118352)
					(mid 269.5448 -6.628892)
					(end 270.05534 -6.118352)
				)
			)
		)
	)
	(zone
		(layers "In1.Cu" "In3.Cu" "In4.Cu" "In6.Cu")
		(hatch none 0.5)
		(connect_pads
			(clearance 0)
		)
		(min_thickness 0.25)
		(keepout
			(tracks not_allowed)
			(vias allowed)
			(pads allowed)
			(copperpour not_allowed)
			(footprints allowed)
		)
		(placement
			(enabled no)
			(sheetname "")
		)
		(fill yes
			(thermal_gap 0.5)
			(thermal_bridge_width 0.5)
			(island_removal_mode 0)
		)
		(polygon
			(pts
				(arc
					(start 20.396454 -86.91626)
					(mid 19.88566 -87.426673)
					(end 20.3962 -87.93734)
				)
				(arc
					(start 21.209 -87.93734)
					(mid 21.71954 -87.4268)
					(end 21.209 -86.91626)
				)
			)
		)
	)
	(zone
		(layers "In1.Cu" "In3.Cu" "In4.Cu" "In6.Cu")
		(hatch none 0.5)
		(connect_pads
			(clearance 0)
		)
		(min_thickness 0.25)
		(keepout
			(tracks not_allowed)
			(vias allowed)
			(pads allowed)
			(copperpour not_allowed)
			(footprints allowed)
		)
		(placement
			(enabled no)
			(sheetname "")
		)
		(fill yes
			(thermal_gap 0.5)
			(thermal_bridge_width 0.5)
			(island_removal_mode 0)
		)
		(polygon
			(pts
				(arc
					(start 184.443116 -8.91667)
					(mid 184.95391 -8.406257)
					(end 184.44337 -7.89559)
				)
				(arc
					(start 183.63057 -7.89559)
					(mid 183.12003 -8.40613)
					(end 183.63057 -8.91667)
				)
			)
		)
	)
	(zone
		(layers "In1.Cu" "In3.Cu" "In4.Cu" "In6.Cu")
		(hatch none 0.5)
		(connect_pads
			(clearance 0)
		)
		(min_thickness 0.25)
		(keepout
			(tracks not_allowed)
			(vias allowed)
			(pads allowed)
			(copperpour not_allowed)
			(footprints allowed)
		)
		(placement
			(enabled no)
			(sheetname "")
		)
		(fill yes
			(thermal_gap 0.5)
			(thermal_bridge_width 0.5)
			(island_removal_mode 0)
		)
		(polygon
			(pts
				(arc
					(start 272.57883 -14.52245)
					(mid 272.06829 -14.01191)
					(end 271.55775 -14.52245)
				)
				(arc
					(start 271.55775 -15.334996)
					(mid 272.068163 -15.84579)
					(end 272.57883 -15.33525)
				)
			)
		)
	)
	(zone
		(layers "In1.Cu" "In3.Cu" "In4.Cu" "In6.Cu")
		(hatch none 0.5)
		(connect_pads
			(clearance 0)
		)
		(min_thickness 0.25)
		(keepout
			(tracks not_allowed)
			(vias allowed)
			(pads allowed)
			(copperpour not_allowed)
			(footprints allowed)
		)
		(placement
			(enabled no)
			(sheetname "")
		)
		(fill yes
			(thermal_gap 0.5)
			(thermal_bridge_width 0.5)
			(island_removal_mode 0)
		)
		(polygon
			(pts
				(arc
					(start 138.557254 -38.14826)
					(mid 138.04646 -38.658673)
					(end 138.557 -39.16934)
				)
				(arc
					(start 139.3698 -39.16934)
					(mid 139.88034 -38.6588)
					(end 139.3698 -38.14826)
				)
			)
		)
	)
	(zone
		(layers "In1.Cu" "In3.Cu" "In4.Cu" "In6.Cu")
		(hatch none 0.5)
		(connect_pads
			(clearance 0)
		)
		(min_thickness 0.25)
		(keepout
			(tracks not_allowed)
			(vias allowed)
			(pads allowed)
			(copperpour not_allowed)
			(footprints allowed)
		)
		(placement
			(enabled no)
			(sheetname "")
		)
		(fill yes
			(thermal_gap 0.5)
			(thermal_bridge_width 0.5)
			(island_removal_mode 0)
		)
		(polygon
			(pts
				(arc
					(start 10.477246 -55.559452)
					(mid 10.98804 -55.049039)
					(end 10.4775 -54.538372)
				)
				(arc
					(start 9.6647 -54.538372)
					(mid 9.15416 -55.048912)
					(end 9.6647 -55.559452)
				)
			)
		)
	)
	(zone
		(layers "In1.Cu" "In3.Cu" "In4.Cu" "In6.Cu")
		(hatch none 0.5)
		(connect_pads
			(clearance 0)
		)
		(min_thickness 0.25)
		(keepout
			(tracks not_allowed)
			(vias allowed)
			(pads allowed)
			(copperpour not_allowed)
			(footprints allowed)
		)
		(placement
			(enabled no)
			(sheetname "")
		)
		(fill yes
			(thermal_gap 0.5)
			(thermal_bridge_width 0.5)
			(island_removal_mode 0)
		)
		(polygon
			(pts
				(xy 160.187386 -21.82622) (xy 160.937448 -20.426426) (xy 160.937194 -20.426172)
				(arc
					(start 160.935162 -20.425156)
					(mid 160.679486 -19.579255)
					(end 159.833564 -19.835114)
				)
				(xy 159.831532 -19.833844) (xy 159.08147 -21.233892)
				(arc
					(start 159.083502 -21.235162)
					(mid 159.339534 -22.080982)
					(end 160.185354 -21.82495)
				)
			)
		)
	)
	(zone
		(layers "In1.Cu" "In3.Cu" "In4.Cu" "In6.Cu")
		(hatch none 0.5)
		(connect_pads
			(clearance 0)
		)
		(min_thickness 0.25)
		(keepout
			(tracks not_allowed)
			(vias allowed)
			(pads allowed)
			(copperpour not_allowed)
			(footprints allowed)
		)
		(placement
			(enabled no)
			(sheetname "")
		)
		(fill yes
			(thermal_gap 0.5)
			(thermal_bridge_width 0.5)
			(island_removal_mode 0)
		)
		(polygon
			(pts
				(arc
					(start 158.68523 -20.425156)
					(mid 158.429554 -19.579255)
					(end 157.583632 -19.835114)
				)
				(xy 157.5816 -19.833844) (xy 156.831538 -21.233892)
				(arc
					(start 156.83357 -21.235162)
					(mid 157.089602 -22.080982)
					(end 157.935422 -21.82495)
				)
				(xy 157.937454 -21.82622) (xy 158.687516 -20.426426) (xy 158.687262 -20.426172)
			)
		)
	)
	(zone
		(layers "In1.Cu" "In3.Cu" "In4.Cu" "In6.Cu")
		(hatch none 0.5)
		(connect_pads
			(clearance 0)
		)
		(min_thickness 0.25)
		(keepout
			(tracks not_allowed)
			(vias allowed)
			(pads allowed)
			(copperpour not_allowed)
			(footprints allowed)
		)
		(placement
			(enabled no)
			(sheetname "")
		)
		(fill yes
			(thermal_gap 0.5)
			(thermal_bridge_width 0.5)
			(island_removal_mode 0)
		)
		(polygon
			(pts
				(xy 321.93738 -25.626314) (xy 322.687442 -24.226266)
				(arc
					(start 322.68541 -24.224996)
					(mid 322.429378 -23.379176)
					(end 321.583558 -23.635208)
				)
				(xy 321.581526 -23.633938) (xy 320.831464 -25.033732) (xy 320.831718 -25.033986)
				(arc
					(start 320.83375 -25.035002)
					(mid 321.089426 -25.880903)
					(end 321.935348 -25.625044)
				)
			)
		)
	)
	(zone
		(layers "In1.Cu" "In3.Cu" "In4.Cu" "In6.Cu")
		(hatch none 0.5)
		(connect_pads
			(clearance 0)
		)
		(min_thickness 0.25)
		(keepout
			(tracks not_allowed)
			(vias allowed)
			(pads allowed)
			(copperpour not_allowed)
			(footprints allowed)
		)
		(placement
			(enabled no)
			(sheetname "")
		)
		(fill yes
			(thermal_gap 0.5)
			(thermal_bridge_width 0.5)
			(island_removal_mode 0)
		)
		(polygon
			(pts
				(xy 149.187408 -18.02638) (xy 149.93747 -16.626586)
				(arc
					(start 149.935184 -16.625316)
					(mid 149.67966 -15.779496)
					(end 148.83384 -16.03502)
				)
				(xy 148.831554 -16.03375) (xy 148.081492 -17.433544) (xy 148.081746 -17.433798)
				(arc
					(start 148.083778 -17.434814)
					(mid 148.339302 -18.280634)
					(end 149.185122 -18.02511)
				)
			)
		)
	)
	(zone
		(layers "In1.Cu" "In3.Cu" "In4.Cu" "In6.Cu")
		(hatch none 0.5)
		(connect_pads
			(clearance 0)
		)
		(min_thickness 0.25)
		(keepout
			(tracks not_allowed)
			(vias allowed)
			(pads allowed)
			(copperpour not_allowed)
			(footprints allowed)
		)
		(placement
			(enabled no)
			(sheetname "")
		)
		(fill yes
			(thermal_gap 0.5)
			(thermal_bridge_width 0.5)
			(island_removal_mode 0)
		)
		(polygon
			(pts
				(arc
					(start 198.429118 -45.590714)
					(mid 197.817105 -44.97832)
					(end 197.204838 -45.59046)
				)
				(arc
					(start 197.204838 -46.70806)
					(mid 197.816978 -47.3202)
					(end 198.429118 -46.70806)
				)
			)
		)
	)
	(zone
		(layers "In1.Cu" "In3.Cu" "In4.Cu" "In6.Cu")
		(hatch none 0.5)
		(connect_pads
			(clearance 0)
		)
		(min_thickness 0.25)
		(keepout
			(tracks not_allowed)
			(vias allowed)
			(pads allowed)
			(copperpour not_allowed)
			(footprints allowed)
		)
		(placement
			(enabled no)
			(sheetname "")
		)
		(fill yes
			(thermal_gap 0.5)
			(thermal_bridge_width 0.5)
			(island_removal_mode 0)
		)
		(polygon
			(pts
				(xy 324.187312 -14.226286) (xy 324.937374 -12.826238)
				(arc
					(start 324.935342 -12.824968)
					(mid 324.67931 -11.979148)
					(end 323.83349 -12.23518)
				)
				(xy 323.831458 -12.23391) (xy 323.081396 -13.633704) (xy 323.08165 -13.633958)
				(arc
					(start 323.083682 -13.634974)
					(mid 323.339358 -14.480875)
					(end 324.18528 -14.225016)
				)
			)
		)
	)
	(zone
		(layers "In1.Cu" "In3.Cu" "In4.Cu" "In6.Cu")
		(hatch none 0.5)
		(connect_pads
			(clearance 0)
		)
		(min_thickness 0.25)
		(keepout
			(tracks not_allowed)
			(vias allowed)
			(pads allowed)
			(copperpour not_allowed)
			(footprints allowed)
		)
		(placement
			(enabled no)
			(sheetname "")
		)
		(fill yes
			(thermal_gap 0.5)
			(thermal_bridge_width 0.5)
			(island_removal_mode 0)
		)
		(polygon
			(pts
				(arc
					(start 285.498794 -33.051496)
					(mid 284.988254 -32.540956)
					(end 284.477714 -33.051496)
				)
				(arc
					(start 284.477714 -33.864042)
					(mid 284.988127 -34.374836)
					(end 285.498794 -33.864296)
				)
			)
		)
	)
	(zone
		(layers "In1.Cu" "In3.Cu" "In4.Cu" "In6.Cu")
		(hatch none 0.5)
		(connect_pads
			(clearance 0)
		)
		(min_thickness 0.25)
		(keepout
			(tracks not_allowed)
			(vias allowed)
			(pads allowed)
			(copperpour not_allowed)
			(footprints allowed)
		)
		(placement
			(enabled no)
			(sheetname "")
		)
		(fill yes
			(thermal_gap 0.5)
			(thermal_bridge_width 0.5)
			(island_removal_mode 0)
		)
		(polygon
			(pts
				(xy 146.937476 -18.026126) (xy 147.687284 -16.626332)
				(arc
					(start 147.685252 -16.625062)
					(mid 147.42922 -15.779242)
					(end 146.5834 -16.035274)
				)
				(xy 146.581368 -16.034004) (xy 145.83156 -17.433544) (xy 145.831814 -17.433798)
				(arc
					(start 145.833846 -17.434814)
					(mid 146.089522 -18.280715)
					(end 146.935444 -18.024856)
				)
			)
		)
	)
	(zone
		(layers "In1.Cu" "In3.Cu" "In4.Cu" "In6.Cu")
		(hatch none 0.5)
		(connect_pads
			(clearance 0)
		)
		(min_thickness 0.25)
		(keepout
			(tracks not_allowed)
			(vias allowed)
			(pads allowed)
			(copperpour not_allowed)
			(footprints allowed)
		)
		(placement
			(enabled no)
			(sheetname "")
		)
		(fill yes
			(thermal_gap 0.5)
			(thermal_bridge_width 0.5)
			(island_removal_mode 0)
		)
		(polygon
			(pts
				(arc
					(start 134.664704 -36.250372)
					(mid 135.175498 -35.739959)
					(end 134.664958 -35.229292)
				)
				(arc
					(start 133.852158 -35.229292)
					(mid 133.341618 -35.739832)
					(end 133.852158 -36.250372)
				)
			)
		)
	)
	(zone
		(layers "In1.Cu" "In3.Cu" "In4.Cu" "In6.Cu")
		(hatch none 0.5)
		(connect_pads
			(clearance 0)
		)
		(min_thickness 0.25)
		(keepout
			(tracks not_allowed)
			(vias allowed)
			(pads allowed)
			(copperpour not_allowed)
			(footprints allowed)
		)
		(placement
			(enabled no)
			(sheetname "")
		)
		(fill yes
			(thermal_gap 0.5)
			(thermal_bridge_width 0.5)
			(island_removal_mode 0)
		)
		(polygon
			(pts
				(xy 286.68726 -25.626314) (xy 287.437322 -24.226266)
				(arc
					(start 287.43529 -24.224996)
					(mid 287.179258 -23.379176)
					(end 286.333438 -23.635208)
				)
				(xy 286.331406 -23.633938) (xy 285.581344 -25.033732) (xy 285.581598 -25.033986)
				(arc
					(start 285.58363 -25.035002)
					(mid 285.839306 -25.880903)
					(end 286.685228 -25.625044)
				)
			)
		)
	)
	(zone
		(layers "In1.Cu" "In3.Cu" "In4.Cu" "In6.Cu")
		(hatch none 0.5)
		(connect_pads
			(clearance 0)
		)
		(min_thickness 0.25)
		(keepout
			(tracks not_allowed)
			(vias allowed)
			(pads allowed)
			(copperpour not_allowed)
			(footprints allowed)
		)
		(placement
			(enabled no)
			(sheetname "")
		)
		(fill yes
			(thermal_gap 0.5)
			(thermal_bridge_width 0.5)
			(island_removal_mode 0)
		)
		(polygon
			(pts
				(arc
					(start 56.86298 -85.210904)
					(mid 56.250967 -84.59851)
					(end 55.6387 -85.21065)
				)
				(arc
					(start 55.6387 -86.32825)
					(mid 56.25084 -86.94039)
					(end 56.86298 -86.32825)
				)
			)
		)
	)
	(zone
		(layers "In1.Cu" "In3.Cu" "In4.Cu" "In6.Cu")
		(hatch none 0.5)
		(connect_pads
			(clearance 0)
		)
		(min_thickness 0.25)
		(keepout
			(tracks not_allowed)
			(vias allowed)
			(pads allowed)
			(copperpour not_allowed)
			(footprints allowed)
		)
		(placement
			(enabled no)
			(sheetname "")
		)
		(fill yes
			(thermal_gap 0.5)
			(thermal_bridge_width 0.5)
			(island_removal_mode 0)
		)
		(polygon
			(pts
				(arc
					(start 172.745654 -95.683832)
					(mid 172.23486 -96.194245)
					(end 172.7454 -96.704912)
				)
				(arc
					(start 173.6344 -96.704912)
					(mid 174.14494 -96.194372)
					(end 173.6344 -95.683832)
				)
			)
		)
	)
	(zone
		(layers "In1.Cu" "In3.Cu" "In4.Cu" "In6.Cu")
		(hatch none 0.5)
		(connect_pads
			(clearance 0)
		)
		(min_thickness 0.25)
		(keepout
			(tracks not_allowed)
			(vias allowed)
			(pads allowed)
			(copperpour not_allowed)
			(footprints allowed)
		)
		(placement
			(enabled no)
			(sheetname "")
		)
		(fill yes
			(thermal_gap 0.5)
			(thermal_bridge_width 0.5)
			(island_removal_mode 0)
		)
		(polygon
			(pts
				(arc
					(start 102.44074 -38.916864)
					(mid 101.930327 -38.40607)
					(end 101.41966 -38.91661)
				)
				(arc
					(start 101.41966 -39.80561)
					(mid 101.9302 -40.31615)
					(end 102.44074 -39.80561)
				)
			)
		)
	)
	(zone
		(layers "In1.Cu" "In3.Cu" "In4.Cu" "In6.Cu")
		(hatch none 0.5)
		(connect_pads
			(clearance 0)
		)
		(min_thickness 0.25)
		(keepout
			(tracks not_allowed)
			(vias allowed)
			(pads allowed)
			(copperpour not_allowed)
			(footprints allowed)
		)
		(placement
			(enabled no)
			(sheetname "")
		)
		(fill yes
			(thermal_gap 0.5)
			(thermal_bridge_width 0.5)
			(island_removal_mode 0)
		)
		(polygon
			(pts
				(xy 283.551122 -20.758404) (xy 283.007308 -20.154646) (xy 283.0068 -20.154646)
				(arc
					(start 283.005276 -20.15617)
					(mid 282.284107 -20.118381)
					(end 282.246578 -20.83943)
				)
				(xy 282.244546 -20.841208) (xy 282.788614 -21.44522)
				(arc
					(start 282.790646 -21.443442)
					(mid 283.511498 -21.481034)
					(end 283.54909 -20.760182)
				)
			)
		)
	)
	(zone
		(layers "In1.Cu" "In3.Cu" "In4.Cu" "In6.Cu")
		(hatch none 0.5)
		(connect_pads
			(clearance 0)
		)
		(min_thickness 0.25)
		(keepout
			(tracks not_allowed)
			(vias allowed)
			(pads allowed)
			(copperpour not_allowed)
			(footprints allowed)
		)
		(placement
			(enabled no)
			(sheetname "")
		)
		(fill yes
			(thermal_gap 0.5)
			(thermal_bridge_width 0.5)
			(island_removal_mode 0)
		)
		(polygon
			(pts
				(arc
					(start 13.563854 -53.319172)
					(mid 13.05306 -53.829585)
					(end 13.5636 -54.340252)
				)
				(arc
					(start 14.3764 -54.340252)
					(mid 14.88694 -53.829712)
					(end 14.3764 -53.319172)
				)
			)
		)
	)
	(zone
		(layers "In1.Cu" "In3.Cu" "In4.Cu" "In6.Cu")
		(hatch none 0.5)
		(connect_pads
			(clearance 0)
		)
		(min_thickness 0.25)
		(keepout
			(tracks not_allowed)
			(vias allowed)
			(pads allowed)
			(copperpour not_allowed)
			(footprints allowed)
		)
		(placement
			(enabled no)
			(sheetname "")
		)
		(fill yes
			(thermal_gap 0.5)
			(thermal_bridge_width 0.5)
			(island_removal_mode 0)
		)
		(polygon
			(pts
				(arc
					(start 183.59374 -19.850354)
					(mid 183.083327 -19.33956)
					(end 182.57266 -19.8501)
				)
				(arc
					(start 182.57266 -20.6629)
					(mid 183.0832 -21.17344)
					(end 183.59374 -20.6629)
				)
			)
		)
	)
	(zone
		(layers "In1.Cu" "In3.Cu" "In4.Cu" "In6.Cu")
		(hatch none 0.5)
		(connect_pads
			(clearance 0)
		)
		(min_thickness 0.25)
		(keepout
			(tracks not_allowed)
			(vias allowed)
			(pads allowed)
			(copperpour not_allowed)
			(footprints allowed)
		)
		(placement
			(enabled no)
			(sheetname "")
		)
		(fill yes
			(thermal_gap 0.5)
			(thermal_bridge_width 0.5)
			(island_removal_mode 0)
		)
		(polygon
			(pts
				(xy 324.187312 -21.82622) (xy 324.937374 -20.426426) (xy 324.93712 -20.426172)
				(arc
					(start 324.935088 -20.425156)
					(mid 324.679412 -19.579255)
					(end 323.83349 -19.835114)
				)
				(xy 323.831458 -19.833844) (xy 323.081396 -21.233892)
				(arc
					(start 323.083428 -21.235162)
					(mid 323.33946 -22.080982)
					(end 324.18528 -21.82495)
				)
			)
		)
	)
	(zone
		(layers "In1.Cu" "In3.Cu" "In4.Cu" "In6.Cu")
		(hatch none 0.5)
		(connect_pads
			(clearance 0)
		)
		(min_thickness 0.25)
		(keepout
			(tracks not_allowed)
			(vias allowed)
			(pads allowed)
			(copperpour not_allowed)
			(footprints allowed)
		)
		(placement
			(enabled no)
			(sheetname "")
		)
		(fill yes
			(thermal_gap 0.5)
			(thermal_bridge_width 0.5)
			(island_removal_mode 0)
		)
		(polygon
			(pts
				(xy 286.68726 -14.226286) (xy 287.437322 -12.826492) (xy 287.437068 -12.826238)
				(arc
					(start 287.435036 -12.825222)
					(mid 287.17936 -11.979321)
					(end 286.333438 -12.23518)
				)
				(xy 286.331406 -12.23391) (xy 285.581344 -13.633958)
				(arc
					(start 285.583376 -13.635228)
					(mid 285.839408 -14.481048)
					(end 286.685228 -14.225016)
				)
			)
		)
	)
	(zone
		(layers "In1.Cu" "In3.Cu" "In4.Cu" "In6.Cu")
		(hatch none 0.5)
		(connect_pads
			(clearance 0)
		)
		(min_thickness 0.25)
		(keepout
			(tracks not_allowed)
			(vias allowed)
			(pads allowed)
			(copperpour not_allowed)
			(footprints allowed)
		)
		(placement
			(enabled no)
			(sheetname "")
		)
		(fill yes
			(thermal_gap 0.5)
			(thermal_bridge_width 0.5)
			(island_removal_mode 0)
		)
		(polygon
			(pts
				(arc
					(start 131.089654 -34.762694)
					(mid 130.57886 -35.273107)
					(end 131.0894 -35.783774)
				)
				(arc
					(start 131.9022 -35.783774)
					(mid 132.41274 -35.273234)
					(end 131.9022 -34.762694)
				)
			)
		)
	)
	(zone
		(layers "In1.Cu" "In3.Cu" "In4.Cu" "In6.Cu")
		(hatch none 0.5)
		(connect_pads
			(clearance 0)
		)
		(min_thickness 0.25)
		(keepout
			(tracks not_allowed)
			(vias allowed)
			(pads allowed)
			(copperpour not_allowed)
			(footprints allowed)
		)
		(placement
			(enabled no)
			(sheetname "")
		)
		(fill yes
			(thermal_gap 0.5)
			(thermal_bridge_width 0.5)
			(island_removal_mode 0)
		)
		(polygon
			(pts
				(arc
					(start 168.212516 -88.646254)
					(mid 167.702103 -88.13546)
					(end 167.191436 -88.646)
				)
				(arc
					(start 167.191436 -89.4588)
					(mid 167.701976 -89.96934)
					(end 168.212516 -89.4588)
				)
			)
		)
	)
	(zone
		(layers "In1.Cu" "In3.Cu" "In4.Cu" "In6.Cu")
		(hatch none 0.5)
		(connect_pads
			(clearance 0)
		)
		(min_thickness 0.25)
		(keepout
			(tracks not_allowed)
			(vias allowed)
			(pads allowed)
			(copperpour not_allowed)
			(footprints allowed)
		)
		(placement
			(enabled no)
			(sheetname "")
		)
		(fill yes
			(thermal_gap 0.5)
			(thermal_bridge_width 0.5)
			(island_removal_mode 0)
		)
		(polygon
			(pts
				(xy 324.187312 -18.02638) (xy 324.937374 -16.626586)
				(arc
					(start 324.935088 -16.625316)
					(mid 324.679564 -15.779496)
					(end 323.833744 -16.03502)
				)
				(xy 323.831458 -16.03375) (xy 323.081396 -17.433544) (xy 323.08165 -17.433798)
				(arc
					(start 323.083682 -17.434814)
					(mid 323.339206 -18.280634)
					(end 324.185026 -18.02511)
				)
			)
		)
	)
	(zone
		(layers "In1.Cu" "In3.Cu" "In4.Cu" "In6.Cu")
		(hatch none 0.5)
		(connect_pads
			(clearance 0)
		)
		(min_thickness 0.25)
		(keepout
			(tracks not_allowed)
			(vias allowed)
			(pads allowed)
			(copperpour not_allowed)
			(footprints allowed)
		)
		(placement
			(enabled no)
			(sheetname "")
		)
		(fill yes
			(thermal_gap 0.5)
			(thermal_bridge_width 0.5)
			(island_removal_mode 0)
		)
		(polygon
			(pts
				(arc
					(start 103.02494 -36.205668)
					(mid 102.5144 -35.695128)
					(end 102.00386 -36.205668)
				)
				(arc
					(start 102.00386 -37.094414)
					(mid 102.514273 -37.605208)
					(end 103.02494 -37.094668)
				)
			)
		)
	)
	(zone
		(layers "In1.Cu" "In3.Cu" "In4.Cu" "In6.Cu")
		(hatch none 0.5)
		(connect_pads
			(clearance 0)
		)
		(min_thickness 0.25)
		(keepout
			(tracks not_allowed)
			(vias allowed)
			(pads allowed)
			(copperpour not_allowed)
			(footprints allowed)
		)
		(placement
			(enabled no)
			(sheetname "")
		)
		(fill yes
			(thermal_gap 0.5)
			(thermal_bridge_width 0.5)
			(island_removal_mode 0)
		)
		(polygon
			(pts
				(arc
					(start 306.57546 -40.31996)
					(mid 307.086254 -39.809547)
					(end 306.575714 -39.29888)
				)
				(arc
					(start 305.762914 -39.29888)
					(mid 305.252374 -39.80942)
					(end 305.762914 -40.31996)
				)
			)
		)
	)
	(zone
		(layers "In1.Cu" "In3.Cu" "In4.Cu" "In6.Cu")
		(hatch none 0.5)
		(connect_pads
			(clearance 0)
		)
		(min_thickness 0.25)
		(keepout
			(tracks allowed)
			(vias allowed)
			(pads allowed)
			(copperpour allowed)
			(footprints allowed)
		)
		(placement
			(enabled no)
			(sheetname "")
		)
		(fill yes
			(thermal_gap 0.5)
			(thermal_bridge_width 0.5)
			(island_removal_mode 0)
		)
		(polygon
			(pts
				(arc
					(start 13.285216 -54.448964)
					(mid 12.63905 -53.838733)
					(end 13.267182 -53.209952)
				)
				(xy 14.375384 -53.209952) (xy 14.38529 -53.209698)
				(arc
					(start 14.428724 -53.21046)
					(mid 15.016094 -53.845592)
					(end 14.396466 -54.449218)
				)
				(xy 13.28547 -54.449218)
			)
		)
	)
	(zone
		(layers "In1.Cu" "In3.Cu" "In4.Cu" "In6.Cu")
		(hatch none 0.5)
		(connect_pads
			(clearance 0)
		)
		(min_thickness 0.25)
		(keepout
			(tracks not_allowed)
			(vias allowed)
			(pads allowed)
			(copperpour not_allowed)
			(footprints allowed)
		)
		(placement
			(enabled no)
			(sheetname "")
		)
		(fill yes
			(thermal_gap 0.5)
			(thermal_bridge_width 0.5)
			(island_removal_mode 0)
		)
		(polygon
			(pts
				(xy 133.687312 -14.226286) (xy 134.437374 -12.826492) (xy 134.43712 -12.826238)
				(arc
					(start 134.435088 -12.825222)
					(mid 134.179412 -11.979321)
					(end 133.33349 -12.23518)
				)
				(xy 133.331458 -12.23391) (xy 132.581396 -13.633958)
				(arc
					(start 132.583428 -13.635228)
					(mid 132.83946 -14.481048)
					(end 133.68528 -14.225016)
				)
			)
		)
	)
	(zone
		(layers "In1.Cu" "In3.Cu" "In4.Cu" "In6.Cu")
		(hatch none 0.5)
		(connect_pads
			(clearance 0)
		)
		(min_thickness 0.25)
		(keepout
			(tracks not_allowed)
			(vias allowed)
			(pads allowed)
			(copperpour not_allowed)
			(footprints allowed)
		)
		(placement
			(enabled no)
			(sheetname "")
		)
		(fill yes
			(thermal_gap 0.5)
			(thermal_bridge_width 0.5)
			(island_removal_mode 0)
		)
		(polygon
			(pts
				(arc
					(start 15.799054 -72.706484)
					(mid 15.28826 -73.216897)
					(end 15.7988 -73.727564)
				)
				(arc
					(start 16.6116 -73.727564)
					(mid 17.12214 -73.217024)
					(end 16.6116 -72.706484)
				)
			)
		)
	)
	(zone
		(layer "In2.Cu")
		(hatch none 0.5)
		(connect_pads
			(clearance 0)
		)
		(min_thickness 0.25)
		(keepout
			(tracks not_allowed)
			(vias allowed)
			(pads allowed)
			(copperpour not_allowed)
			(footprints allowed)
		)
		(placement
			(enabled no)
			(sheetname "")
		)
		(fill
			(thermal_gap 0.5)
			(thermal_bridge_width 0.5)
			(island_removal_mode 0)
		)
		(polygon
			(pts
				(arc
					(start 130.8481 -32.75584)
					(mid 130.758297 -32.793037)
					(end 130.7211 -32.88284)
				)
				(arc
					(start 130.7211 -34.20364)
					(mid 130.758297 -34.293443)
					(end 130.8481 -34.33064)
				)
				(arc
					(start 132.1435 -34.33064)
					(mid 132.233303 -34.293443)
					(end 132.2705 -34.20364)
				)
				(arc
					(start 132.2705 -32.88284)
					(mid 132.233303 -32.793037)
					(end 132.1435 -32.75584)
				)
			)
		)
	)
	(zone
		(layer "In2.Cu")
		(hatch none 0.5)
		(connect_pads
			(clearance 0)
		)
		(min_thickness 0.25)
		(keepout
			(tracks not_allowed)
			(vias allowed)
			(pads allowed)
			(copperpour not_allowed)
			(footprints allowed)
		)
		(placement
			(enabled no)
			(sheetname "")
		)
		(fill
			(thermal_gap 0.5)
			(thermal_bridge_width 0.5)
			(island_removal_mode 0)
		)
		(polygon
			(pts
				(arc
					(start 146.809206 -12.728702)
					(mid 146.605751 -12.717916)
					(end 146.412204 -12.65428)
				)
				(xy 146.370548 -12.63269) (xy 146.29257 -12.778486) (xy 146.340068 -12.803124) (xy 146.641566 -12.94892)
				(arc
					(start 146.642074 -12.950444)
					(mid 146.926687 -13.373083)
					(end 146.757898 -13.853922)
				)
				(arc
					(start 146.757898 -13.853922)
					(mid 146.03947 -14.091865)
					(end 146.681952 -13.69187)
				)
				(arc
					(start 146.681952 -13.69187)
					(mid 146.755625 -13.35321)
					(end 146.53895 -13.082778)
				)
				(xy 146.237452 -12.936982) (xy 146.237198 -12.93622) (xy 146.214592 -12.924028)
				(arc
					(start 145.837656 -13.627608)
					(mid 146.08579 -14.479061)
					(end 146.935444 -14.225016)
				)
				(arc
					(start 147.685252 -12.824968)
					(mid 147.42922 -11.979148)
					(end 146.5834 -12.23518)
				)
				(xy 146.448526 -12.487148)
				(arc
					(start 146.483832 -12.505436)
					(mid 146.61596 -12.551409)
					(end 146.755104 -12.565888)
				)
				(arc
					(start 146.755104 -12.565888)
					(mid 147.495795 -12.41027)
					(end 146.809206 -12.728702)
				)
			)
		)
	)
	(zone
		(layer "In2.Cu")
		(hatch none 0.5)
		(connect_pads
			(clearance 0)
		)
		(min_thickness 0.25)
		(keepout
			(tracks not_allowed)
			(vias allowed)
			(pads allowed)
			(copperpour not_allowed)
			(footprints allowed)
		)
		(placement
			(enabled no)
			(sheetname "")
		)
		(fill
			(thermal_gap 0.5)
			(thermal_bridge_width 0.5)
			(island_removal_mode 0)
		)
		(polygon
			(pts
				(xy 169.212768 -13.71219) (xy 169.299382 -13.5509) (xy 169.219626 -13.442696)
				(arc
					(start 169.220642 -13.436346)
					(mid 169.145764 -13.261394)
					(end 169.098976 -13.076936)
				)
				(arc
					(start 169.098976 -13.076936)
					(mid 169.085381 -12.991759)
					(end 169.074084 -12.906248)
				)
				(arc
					(start 169.074084 -12.906248)
					(mid 169.111389 -12.149802)
					(end 169.239184 -12.896342)
				)
				(arc
					(start 169.239184 -12.896342)
					(mid 169.249391 -12.972811)
					(end 169.261536 -13.048996)
				)
				(arc
					(start 169.261536 -13.048996)
					(mid 169.305276 -13.217558)
					(end 169.37609 -13.376656)
				)
				(xy 169.385742 -13.38961) (xy 169.568114 -13.048996) (xy 169.687494 -12.826238)
				(arc
					(start 169.685462 -12.824968)
					(mid 169.42943 -11.979148)
					(end 168.58361 -12.23518)
				)
				(xy 168.581578 -12.23391) (xy 167.831516 -13.633704) (xy 167.83177 -13.633958)
				(arc
					(start 167.833802 -13.634974)
					(mid 168.089478 -14.480875)
					(end 168.9354 -14.225016)
				)
				(xy 168.937432 -14.226286) (xy 169.126408 -13.873226) (xy 168.904412 -13.571728) (xy 168.897046 -13.569188)
				(xy 168.884854 -13.544804) (xy 168.868598 -13.52296) (xy 168.869868 -13.515086) (xy 168.867074 -13.509498)
				(xy 168.750996 -13.277596)
				(arc
					(start 168.712388 -13.200126)
					(mid 168.585762 -13.090218)
					(end 168.418256 -13.09624)
				)
				(xy 168.404032 -13.110464)
				(arc
					(start 168.391078 -13.110464)
					(mid 168.290243 -13.242117)
					(end 168.303702 -13.40739)
				)
				(xy 168.319704 -13.439394) (xy 168.32199 -13.44422) (xy 168.334944 -13.470128) (xy 168.334436 -13.471906)
				(xy 168.335706 -13.475462) (xy 168.337738 -13.476732) (xy 168.34739 -13.509498)
				(arc
					(start 168.359328 -13.549884)
					(mid 168.491929 -14.295819)
					(end 168.200832 -13.596366)
				)
				(arc
					(start 168.188894 -13.55598)
					(mid 168.1822 -13.536116)
					(end 168.173908 -13.516864)
				)
				(xy 168.158414 -13.48613) (xy 168.15562 -13.480034) (xy 168.143174 -13.455142)
				(arc
					(start 168.143682 -13.453364)
					(mid 168.138927 -13.173868)
					(end 168.319958 -12.960858)
				)
				(xy 168.335706 -12.94511)
				(arc
					(start 168.351708 -12.94511)
					(mid 168.628592 -12.930602)
					(end 168.8465 -13.102082)
				)
				(xy 168.848024 -13.10259) (xy 168.859454 -13.125196) (xy 168.863518 -13.133578) (xy 168.88333 -13.172948)
				(xy 168.898824 -13.203428) (xy 168.914064 -13.234162) (xy 169.026078 -13.458444)
			)
		)
	)
	(zone
		(layer "In2.Cu")
		(hatch none 0.5)
		(connect_pads
			(clearance 0)
		)
		(min_thickness 0.25)
		(keepout
			(tracks not_allowed)
			(vias allowed)
			(pads allowed)
			(copperpour not_allowed)
			(footprints allowed)
		)
		(placement
			(enabled no)
			(sheetname "")
		)
		(fill
			(thermal_gap 0.5)
			(thermal_bridge_width 0.5)
			(island_removal_mode 0)
		)
		(polygon
			(pts
				(arc
					(start 135.756396 -17.812512)
					(mid 135.624695 -18.025625)
					(end 135.389112 -18.110962)
				)
				(arc
					(start 135.882126 -18.108168)
					(mid 135.910436 -18.067563)
					(end 135.935466 -18.024856)
				)
				(xy 135.937498 -18.026126)
				(arc
					(start 136.043416 -17.82826)
					(mid 135.966858 -17.816433)
					(end 135.889492 -17.812512)
				)
			)
		)
	)
	(zone
		(layer "In2.Cu")
		(hatch none 0.5)
		(connect_pads
			(clearance 0)
		)
		(min_thickness 0.25)
		(keepout
			(tracks not_allowed)
			(vias allowed)
			(pads allowed)
			(copperpour not_allowed)
			(footprints allowed)
		)
		(placement
			(enabled no)
			(sheetname "")
		)
		(fill
			(thermal_gap 0.5)
			(thermal_bridge_width 0.5)
			(island_removal_mode 0)
		)
		(polygon
			(pts
				(arc
					(start 198.429118 -45.590714)
					(mid 197.817105 -44.97832)
					(end 197.204838 -45.59046)
				)
				(xy 197.204838 -45.90161)
				(arc
					(start 197.423278 -45.90161)
					(mid 197.548572 -45.875157)
					(end 197.65264 -45.800518)
				)
				(arc
					(start 197.65264 -45.800518)
					(mid 197.903531 -45.338191)
					(end 197.81774 -45.85716)
				)
				(arc
					(start 197.81774 -45.85716)
					(mid 197.662167 -46.002455)
					(end 197.458838 -46.06544)
				)
				(xy 197.457568 -46.06671) (xy 197.204838 -46.06671) (xy 197.204838 -46.23181) (xy 197.457568 -46.23181)
				(arc
					(start 197.458838 -46.23308)
					(mid 197.662145 -46.296102)
					(end 197.81774 -46.44136)
				)
				(arc
					(start 197.81774 -46.44136)
					(mid 197.90353 -46.960326)
					(end 197.65264 -46.498002)
				)
				(arc
					(start 197.65264 -46.498002)
					(mid 197.548593 -46.423314)
					(end 197.423278 -46.39691)
				)
				(xy 197.204838 -46.39691)
				(arc
					(start 197.204838 -46.70806)
					(mid 197.816978 -47.3202)
					(end 198.429118 -46.70806)
				)
			)
		)
	)
	(zone
		(layer "In2.Cu")
		(hatch none 0.5)
		(connect_pads
			(clearance 0)
		)
		(min_thickness 0.25)
		(keepout
			(tracks not_allowed)
			(vias allowed)
			(pads allowed)
			(copperpour not_allowed)
			(footprints allowed)
		)
		(placement
			(enabled no)
			(sheetname "")
		)
		(fill
			(thermal_gap 0.5)
			(thermal_bridge_width 0.5)
			(island_removal_mode 0)
		)
		(polygon
			(pts
				(arc
					(start 103.02494 -36.205668)
					(mid 102.5144 -35.695128)
					(end 102.00386 -36.205668)
				)
				(arc
					(start 102.00386 -37.094414)
					(mid 102.514273 -37.605208)
					(end 103.02494 -37.094668)
				)
				(xy 103.02494 -36.897818) (xy 102.82809 -36.897818)
				(arc
					(start 102.752144 -36.973764)
					(mid 102.3258 -37.283268)
					(end 102.635304 -36.856924)
				)
				(xy 102.71125 -36.780978) (xy 102.75951 -36.732718) (xy 102.82809 -36.732718) (xy 103.02494 -36.732718)
				(xy 103.02494 -36.567618) (xy 102.82809 -36.567618) (xy 102.75951 -36.567618) (xy 102.71125 -36.519358)
				(arc
					(start 102.635304 -36.443412)
					(mid 102.3258 -36.017068)
					(end 102.752144 -36.326572)
				)
				(xy 102.82809 -36.402518) (xy 103.02494 -36.402518)
			)
		)
	)
	(zone
		(layer "In2.Cu")
		(hatch none 0.5)
		(connect_pads
			(clearance 0)
		)
		(min_thickness 0.25)
		(keepout
			(tracks not_allowed)
			(vias allowed)
			(pads allowed)
			(copperpour not_allowed)
			(footprints allowed)
		)
		(placement
			(enabled no)
			(sheetname "")
		)
		(fill
			(thermal_gap 0.5)
			(thermal_bridge_width 0.5)
			(island_removal_mode 0)
		)
		(polygon
			(pts
				(arc
					(start 171.29379 -221.784164)
					(mid 170.78325 -222.294704)
					(end 171.29379 -222.805244)
				)
				(arc
					(start 172.106336 -222.805244)
					(mid 172.61713 -222.294831)
					(end 172.10659 -221.784164)
				)
				(arc
					(start 171.951396 -221.784164)
					(mid 171.976457 -221.915887)
					(end 172.024802 -222.040958)
				)
				(arc
					(start 172.024802 -222.040958)
					(mid 172.26337 -222.510053)
					(end 171.889674 -222.13951)
				)
				(arc
					(start 171.889674 -222.13951)
					(mid 171.819276 -221.967209)
					(end 171.785534 -221.784164)
				)
				(arc
					(start 171.614846 -221.784164)
					(mid 171.581119 -221.967213)
					(end 171.510706 -222.13951)
				)
				(arc
					(start 171.510706 -222.13951)
					(mid 171.137018 -222.510042)
					(end 171.375578 -222.040958)
				)
				(arc
					(start 171.375578 -222.040958)
					(mid 171.423957 -221.915897)
					(end 171.448984 -221.784164)
				)
			)
		)
	)
	(zone
		(net "GND")
		(layer "In2.Cu")
		(hatch none 0.5)
		(connect_pads
			(clearance 0.5)
		)
		(min_thickness 0.25)
		(fill yes
			(thermal_gap 0.5)
			(thermal_bridge_width 0.5)
			(island_removal_mode 0)
		)
		(polygon
			(pts
				(xy 254.490474 -118.445026) (xy 246.79275 -127.280162) (xy 215.91397 -172.06722) (xy 213.868 -180.975)
				(xy 213.868 -184.023) (xy 214.376 -184.531) (xy 220.98 -184.531) (xy 223.9391 -187.4901) (xy 223.9391 -188.8617)
				(xy 224.2566 -189.1792) (xy 229.392226 -189.1792) (xy 232.110026 -191.897)
				(arc
					(start 232.110026 -208.499964)
					(mid 231.240722 -210.59865)
					(end 229.142036 -211.467954)
				)
				(arc
					(start 221.600014 -211.467954)
					(mid 219.243954 -212.443866)
					(end 218.268042 -214.799926)
				)
				(xy 218.268042 -219.64777) (xy 219.537026 -219.64777)
				(arc
					(start 219.537026 -214.799926)
					(mid 220.141261 -213.341173)
					(end 221.600014 -212.736938)
				)
				(arc
					(start 229.142036 -212.736938)
					(mid 232.138029 -211.495957)
					(end 233.37901 -208.499964)
				)
				(arc
					(start 233.37901 -165.269926)
					(mid 233.974467 -163.832367)
					(end 235.412026 -163.23691)
				)
				(arc
					(start 249.871992 -163.23691)
					(mid 251.309551 -163.832367)
					(end 251.905008 -165.269926)
				)
				(arc
					(start 251.905008 -208.499964)
					(mid 253.145989 -211.495957)
					(end 256.141982 -212.736938)
				)
				(arc
					(start 257.400044 -212.736938)
					(mid 258.858797 -213.341173)
					(end 259.463032 -214.799926)
				)
				(xy 259.463032 -220.232732) (xy 260.4262 -220.232732) (xy 260.694932 -219.964) (xy 260.732016 -219.964)
				(arc
					(start 260.732016 -214.799926)
					(mid 260.565547 -213.759912)
					(end 260.082792 -212.823806)
				)
				(xy 262.800592 -190.08725) (xy 269.186406 -154.31008) (xy 262.45058 -122.381518) (xy 258.514088 -118.445026)
			)
		)
	)
	(zone
		(layer "In2.Cu")
		(hatch none 0.5)
		(connect_pads
			(clearance 0)
		)
		(min_thickness 0.25)
		(keepout
			(tracks not_allowed)
			(vias allowed)
			(pads allowed)
			(copperpour not_allowed)
			(footprints allowed)
		)
		(placement
			(enabled no)
			(sheetname "")
		)
		(fill
			(thermal_gap 0.5)
			(thermal_bridge_width 0.5)
			(island_removal_mode 0)
		)
		(polygon
			(pts
				(xy 138.503406 -17.436846) (xy 138.36015 -17.29359)
				(arc
					(start 138.36015 -17.29232)
					(mid 138.228876 -17.098364)
					(end 138.159236 -16.874744)
				)
				(xy 138.154664 -16.870172) (xy 138.154664 -16.651478) (xy 138.15568 -16.650462)
				(arc
					(start 138.156696 -16.63573)
					(mid 138.533933 -15.979585)
					(end 138.319764 -16.70558)
				)
				(arc
					(start 138.319764 -16.830802)
					(mid 138.379625 -17.030947)
					(end 138.50112 -17.20088)
				)
				(xy 138.58494 -17.2847) (xy 138.937492 -16.626586)
				(arc
					(start 138.935206 -16.625316)
					(mid 138.679682 -15.779496)
					(end 137.833862 -16.03502)
				)
				(xy 137.831576 -16.03375) (xy 137.081514 -17.433544) (xy 137.081768 -17.433798)
				(arc
					(start 137.0838 -17.434814)
					(mid 137.339324 -18.280634)
					(end 138.185144 -18.02511)
				)
				(xy 138.18743 -18.02638)
				(arc
					(start 138.27633 -17.860264)
					(mid 138.142655 -17.828574)
					(end 138.006074 -17.813782)
				)
				(arc
					(start 138.006074 -17.813782)
					(mid 137.253536 -17.728791)
					(end 138.006582 -17.648428)
				)
				(arc
					(start 138.006582 -17.648428)
					(mid 138.183447 -17.668028)
					(end 138.355832 -17.712182)
				)
			)
		)
	)
	(zone
		(layer "In2.Cu")
		(hatch none 0.5)
		(connect_pads
			(clearance 0)
		)
		(min_thickness 0.25)
		(keepout
			(tracks not_allowed)
			(vias allowed)
			(pads allowed)
			(copperpour not_allowed)
			(footprints allowed)
		)
		(placement
			(enabled no)
			(sheetname "")
		)
		(fill
			(thermal_gap 0.5)
			(thermal_bridge_width 0.5)
			(island_removal_mode 0)
		)
		(polygon
			(pts
				(arc
					(start 214.493602 -221.784164)
					(mid 213.983062 -222.294704)
					(end 214.493602 -222.805244)
				)
				(arc
					(start 215.306148 -222.805244)
					(mid 215.816942 -222.294831)
					(end 215.306402 -221.784164)
				)
				(arc
					(start 215.151208 -221.784164)
					(mid 215.176269 -221.915887)
					(end 215.224614 -222.040958)
				)
				(arc
					(start 215.224614 -222.040958)
					(mid 215.463182 -222.510053)
					(end 215.089486 -222.13951)
				)
				(arc
					(start 215.089486 -222.13951)
					(mid 215.019088 -221.967209)
					(end 214.985346 -221.784164)
				)
				(arc
					(start 214.814658 -221.784164)
					(mid 214.780931 -221.967213)
					(end 214.710518 -222.13951)
				)
				(arc
					(start 214.710518 -222.13951)
					(mid 214.33683 -222.510042)
					(end 214.57539 -222.040958)
				)
				(arc
					(start 214.57539 -222.040958)
					(mid 214.623769 -221.915897)
					(end 214.648796 -221.784164)
				)
			)
		)
	)
	(zone
		(layer "In2.Cu")
		(hatch none 0.5)
		(connect_pads
			(clearance 0)
		)
		(min_thickness 0.25)
		(keepout
			(tracks not_allowed)
			(vias allowed)
			(pads allowed)
			(copperpour not_allowed)
			(footprints allowed)
		)
		(placement
			(enabled no)
			(sheetname "")
		)
		(fill
			(thermal_gap 0.5)
			(thermal_bridge_width 0.5)
			(island_removal_mode 0)
		)
		(polygon
			(pts
				(arc
					(start 311.28462 -17.378426)
					(mid 311.268877 -17.346026)
					(end 311.2516 -17.314418)
				)
				(arc
					(start 311.2516 -17.314418)
					(mid 311.118823 -17.018419)
					(end 311.049416 -16.701516)
				)
				(arc
					(start 311.049416 -16.701516)
					(mid 311.136978 -15.949146)
					(end 311.215786 -16.702532)
				)
				(arc
					(start 311.215786 -16.702532)
					(mid 311.273533 -16.960612)
					(end 311.378346 -17.20342)
				)
				(xy 311.687464 -16.626586)
				(arc
					(start 311.685178 -16.625316)
					(mid 311.429654 -15.779496)
					(end 310.583834 -16.03502)
				)
				(xy 310.581548 -16.03375) (xy 309.831486 -17.433544) (xy 309.83174 -17.433798)
				(arc
					(start 309.833772 -17.434814)
					(mid 310.089296 -18.280634)
					(end 310.935116 -18.02511)
				)
				(xy 310.937402 -18.02638)
				(arc
					(start 311.0103 -17.889982)
					(mid 311.021716 -17.782969)
					(end 311.022492 -17.675352)
				)
				(arc
					(start 311.022492 -17.675352)
					(mid 311.005906 -17.574232)
					(end 310.965596 -17.480026)
				)
				(arc
					(start 310.965596 -17.480026)
					(mid 310.924637 -17.421311)
					(end 310.87441 -17.370298)
				)
				(arc
					(start 310.87441 -17.370298)
					(mid 310.696684 -17.305751)
					(end 310.520334 -17.374108)
				)
				(arc
					(start 310.520334 -17.374108)
					(mid 310.344367 -18.108765)
					(end 310.326024 -17.353534)
				)
				(arc
					(start 310.326024 -17.353534)
					(mid 310.628466 -17.146481)
					(end 310.981598 -17.244822)
				)
				(arc
					(start 310.981598 -17.244822)
					(mid 311.051414 -17.315664)
					(end 311.108344 -17.397222)
				)
				(arc
					(start 311.108344 -17.397222)
					(mid 311.150182 -17.485438)
					(end 311.176924 -17.57934)
				)
			)
		)
	)
	(zone
		(layer "In2.Cu")
		(hatch none 0.5)
		(connect_pads
			(clearance 0)
		)
		(min_thickness 0.25)
		(keepout
			(tracks not_allowed)
			(vias allowed)
			(pads allowed)
			(copperpour not_allowed)
			(footprints allowed)
		)
		(placement
			(enabled no)
			(sheetname "")
		)
		(fill
			(thermal_gap 0.5)
			(thermal_bridge_width 0.5)
			(island_removal_mode 0)
		)
		(polygon
			(pts
				(arc
					(start 211.29371 -221.784164)
					(mid 210.78317 -222.294704)
					(end 211.29371 -222.805244)
				)
				(arc
					(start 212.106256 -222.805244)
					(mid 212.61705 -222.294831)
					(end 212.10651 -221.784164)
				)
				(arc
					(start 211.951316 -221.784164)
					(mid 211.976377 -221.915887)
					(end 212.024722 -222.040958)
				)
				(arc
					(start 212.024722 -222.040958)
					(mid 212.26329 -222.510053)
					(end 211.889594 -222.13951)
				)
				(arc
					(start 211.889594 -222.13951)
					(mid 211.819196 -221.967209)
					(end 211.785454 -221.784164)
				)
				(arc
					(start 211.614766 -221.784164)
					(mid 211.581039 -221.967213)
					(end 211.510626 -222.13951)
				)
				(arc
					(start 211.510626 -222.13951)
					(mid 211.136938 -222.510042)
					(end 211.375498 -222.040958)
				)
				(arc
					(start 211.375498 -222.040958)
					(mid 211.423877 -221.915897)
					(end 211.448904 -221.784164)
				)
			)
		)
	)
	(zone
		(layer "In2.Cu")
		(hatch none 0.5)
		(connect_pads
			(clearance 0)
		)
		(min_thickness 0.25)
		(keepout
			(tracks not_allowed)
			(vias allowed)
			(pads allowed)
			(copperpour not_allowed)
			(footprints allowed)
		)
		(placement
			(enabled no)
			(sheetname "")
		)
		(fill
			(thermal_gap 0.5)
			(thermal_bridge_width 0.5)
			(island_removal_mode 0)
		)
		(polygon
			(pts
				(arc
					(start 321.293744 -221.784164)
					(mid 320.783204 -222.294704)
					(end 321.293744 -222.805244)
				)
				(arc
					(start 322.10629 -222.805244)
					(mid 322.617084 -222.294831)
					(end 322.106544 -221.784164)
				)
				(xy 321.947794 -221.784164)
				(arc
					(start 321.947794 -221.793308)
					(mid 321.963634 -221.923436)
					(end 322.010024 -222.046038)
				)
				(arc
					(start 322.010024 -222.046038)
					(mid 322.276524 -222.500271)
					(end 321.880484 -222.153226)
				)
				(arc
					(start 321.880484 -222.153226)
					(mid 321.812297 -221.996407)
					(end 321.783456 -221.827852)
				)
				(xy 321.782694 -221.82709) (xy 321.782694 -221.784164) (xy 321.617594 -221.784164) (xy 321.617594 -221.82709)
				(arc
					(start 321.616832 -221.827852)
					(mid 321.588015 -221.996414)
					(end 321.519804 -222.153226)
				)
				(arc
					(start 321.519804 -222.153226)
					(mid 321.123802 -222.500225)
					(end 321.390264 -222.046038)
				)
				(arc
					(start 321.390264 -222.046038)
					(mid 321.436628 -221.92343)
					(end 321.452494 -221.793308)
				)
				(xy 321.452494 -221.784164)
			)
		)
	)
	(zone
		(layer "In2.Cu")
		(hatch none 0.5)
		(connect_pads
			(clearance 0)
		)
		(min_thickness 0.25)
		(keepout
			(tracks not_allowed)
			(vias allowed)
			(pads allowed)
			(copperpour not_allowed)
			(footprints allowed)
		)
		(placement
			(enabled no)
			(sheetname "")
		)
		(fill
			(thermal_gap 0.5)
			(thermal_bridge_width 0.5)
			(island_removal_mode 0)
		)
		(polygon
			(pts
				(arc
					(start 185.069226 -11.697208)
					(mid 184.558813 -11.186414)
					(end 184.048146 -11.696954)
				)
				(arc
					(start 184.048146 -12.509754)
					(mid 184.558686 -13.020294)
					(end 185.069226 -12.509754)
				)
				(xy 185.069226 -12.351004) (xy 184.834276 -12.351004)
				(arc
					(start 184.79643 -12.38885)
					(mid 184.370086 -12.698354)
					(end 184.67959 -12.27201)
				)
				(xy 184.717436 -12.234164) (xy 184.765696 -12.185904) (xy 184.834276 -12.185904) (xy 185.069226 -12.185904)
				(xy 185.069226 -12.020804) (xy 184.834276 -12.020804) (xy 184.765696 -12.020804) (xy 184.717436 -11.972544)
				(arc
					(start 184.67959 -11.934698)
					(mid 184.370086 -11.508354)
					(end 184.79643 -11.817858)
				)
				(xy 184.834276 -11.855704) (xy 185.069226 -11.855704)
			)
		)
	)
	(zone
		(layer "In2.Cu")
		(hatch none 0.5)
		(connect_pads
			(clearance 0)
		)
		(min_thickness 0.25)
		(keepout
			(tracks not_allowed)
			(vias allowed)
			(pads allowed)
			(copperpour not_allowed)
			(footprints allowed)
		)
		(placement
			(enabled no)
			(sheetname "")
		)
		(fill
			(thermal_gap 0.5)
			(thermal_bridge_width 0.5)
			(island_removal_mode 0)
		)
		(polygon
			(pts
				(arc
					(start 149.69363 -221.784164)
					(mid 149.18309 -222.294704)
					(end 149.69363 -222.805244)
				)
				(arc
					(start 150.506176 -222.805244)
					(mid 151.01697 -222.294831)
					(end 150.50643 -221.784164)
				)
				(arc
					(start 150.351236 -221.784164)
					(mid 150.376297 -221.915887)
					(end 150.424642 -222.040958)
				)
				(arc
					(start 150.424642 -222.040958)
					(mid 150.66321 -222.510053)
					(end 150.289514 -222.13951)
				)
				(arc
					(start 150.289514 -222.13951)
					(mid 150.219116 -221.967209)
					(end 150.185374 -221.784164)
				)
				(arc
					(start 150.014686 -221.784164)
					(mid 149.980959 -221.967213)
					(end 149.910546 -222.13951)
				)
				(arc
					(start 149.910546 -222.13951)
					(mid 149.536858 -222.510042)
					(end 149.775418 -222.040958)
				)
				(arc
					(start 149.775418 -222.040958)
					(mid 149.823797 -221.915897)
					(end 149.848824 -221.784164)
				)
			)
		)
	)
	(zone
		(net "P3V3_STBY")
		(layer "In2.Cu")
		(hatch none 0.5)
		(connect_pads
			(clearance 0.5)
		)
		(min_thickness 0.25)
		(fill yes
			(thermal_gap 0.5)
			(thermal_bridge_width 0.5)
			(island_removal_mode 0)
		)
		(polygon
			(pts
				(xy 332.232 -100.584) (xy 332.232 -99.568) (xy 332.74 -99.06) (xy 334.01 -99.06) (xy 336.042 -101.092)
				(xy 336.042 -167.767) (xy 336.042 -168.656) (xy 331.724 -172.974) (xy 331.724 -174.752) (xy 332.994 -176.022)
				(xy 339.725 -176.022) (xy 340.106 -176.403) (xy 340.106 -178.181) (xy 339.471 -178.816) (xy 331.343 -178.816)
				(xy 329.057 -181.102) (xy 329.057 -184.658) (xy 328.803 -184.912) (xy 327.279 -184.912) (xy 327.152 -184.785)
				(xy 327.152 -180.213) (xy 329.057 -178.308) (xy 329.057 -169.672) (xy 333.248 -165.481) (xy 333.248 -101.6)
			)
		)
	)
	(zone
		(net "GND")
		(layer "In2.Cu")
		(hatch none 0.5)
		(connect_pads
			(clearance 0.5)
		)
		(min_thickness 0.25)
		(fill yes
			(thermal_gap 0.5)
			(thermal_bridge_width 0.5)
			(island_removal_mode 0)
		)
		(polygon
			(pts
				(xy 329.717908 1.575562)
				(arc
					(start 329.717908 0.999998)
					(mid 330.60596 -1.143948)
					(end 332.749906 -2.032)
				)
				(xy 353.568 -2.032)
				(arc
					(start 353.568 -7.960868)
					(mid 352.581565 -8.89262)
					(end 352.21799 -10.199878)
				)
				(arc
					(start 352.21799 -18.200116)
					(mid 352.581688 -19.5073)
					(end 353.568 -20.439126)
				)
				(xy 353.568 -211.467954)
				(arc
					(start 347.600016 -211.467954)
					(mid 345.243956 -212.443866)
					(end 344.268044 -214.799926)
				)
				(arc
					(start 344.268044 -219.976192)
					(mid 344.19118 -220.000756)
					(end 344.115136 -220.027754)
				)
				(xy 345.537028 -220.027754)
				(arc
					(start 345.537028 -214.799926)
					(mid 346.141263 -213.341173)
					(end 347.600016 -212.736938)
				)
				(arc
					(start 354.600002 -212.736938)
					(mid 354.767574 -212.667528)
					(end 354.836984 -212.499956)
				)
				(arc
					(start 354.836984 -19.459956)
					(mid 353.888159 -19.123385)
					(end 353.486974 -18.200116)
				)
				(arc
					(start 353.486974 -10.199878)
					(mid 353.888305 -9.276765)
					(end 354.836984 -8.940038)
				)
				(arc
					(start 354.836984 -0.999998)
					(mid 354.767574 -0.832426)
					(end 354.600002 -0.763016)
				)
				(arc
					(start 332.749906 -0.763016)
					(mid 331.503267 -0.246641)
					(end 330.986892 0.999998)
				)
				(xy 330.986892 1.575562)
			)
		)
	)
	(zone
		(net "P3V3_STBY")
		(layer "In2.Cu")
		(hatch none 0.5)
		(connect_pads
			(clearance 0.5)
		)
		(min_thickness 0.25)
		(fill yes
			(thermal_gap 0.5)
			(thermal_bridge_width 0.5)
			(island_removal_mode 0)
		)
		(polygon
			(pts
				(xy 280.677366 1.016) (xy 322.276216 1.016) (xy 330.835 -7.542784) (xy 330.835 -38.1) (xy 330.835 -43.365166)
				(xy 334.569308 -47.099474) (xy 343.883488 -47.099474) (xy 345.418664 -45.564298) (xy 345.418664 -45.067728)
				(xy 345.34348 -44.992544) (xy 345.34348 -43.788838) (xy 344.95232 -43.397678) (xy 342.981026 -43.397678)
				(xy 341.716868 -42.13352) (xy 335.336896 -42.13352) (xy 333.121 -39.917624) (xy 333.121 -37.592)
				(xy 333.121 -7.153656) (xy 323.681344 2.286) (xy 279.407366 2.286) (xy 275.07057 2.286) (xy 272.409412 -0.375412)
				(xy 263.987788 -0.375412) (xy 263.140444 -1.222756) (xy 263.140444 -2.096516) (xy 263.140444 -2.2098)
				(xy 264.004044 -3.0734) (xy 266.827 -3.0734) (xy 267.9446 -1.9558) (xy 269.7226 -1.9558) (xy 270.1036 -2.3368)
				(xy 270.1036 -2.9464) (xy 270.6624 -3.5052) (xy 270.6624 -3.885184) (xy 272.16608 -5.388864) (xy 273.039586 -5.388864)
				(xy 279.44445 1.016)
			)
		)
	)
	(zone
		(layer "In2.Cu")
		(hatch none 0.5)
		(connect_pads
			(clearance 0)
		)
		(min_thickness 0.25)
		(keepout
			(tracks not_allowed)
			(vias allowed)
			(pads allowed)
			(copperpour not_allowed)
			(footprints allowed)
		)
		(placement
			(enabled no)
			(sheetname "")
		)
		(fill
			(thermal_gap 0.5)
			(thermal_bridge_width 0.5)
			(island_removal_mode 0)
		)
		(polygon
			(pts
				(arc
					(start 59.693302 -221.784164)
					(mid 59.182762 -222.294704)
					(end 59.693302 -222.805244)
				)
				(arc
					(start 60.505848 -222.805244)
					(mid 61.016642 -222.294831)
					(end 60.506102 -221.784164)
				)
				(arc
					(start 60.350908 -221.784164)
					(mid 60.375969 -221.915887)
					(end 60.424314 -222.040958)
				)
				(arc
					(start 60.424314 -222.040958)
					(mid 60.662882 -222.510053)
					(end 60.289186 -222.13951)
				)
				(arc
					(start 60.289186 -222.13951)
					(mid 60.218788 -221.967209)
					(end 60.185046 -221.784164)
				)
				(arc
					(start 60.014358 -221.784164)
					(mid 59.980631 -221.967213)
					(end 59.910218 -222.13951)
				)
				(arc
					(start 59.910218 -222.13951)
					(mid 59.53653 -222.510042)
					(end 59.77509 -222.040958)
				)
				(arc
					(start 59.77509 -222.040958)
					(mid 59.823469 -221.915897)
					(end 59.848496 -221.784164)
				)
			)
		)
	)
	(zone
		(layer "In2.Cu")
		(hatch none 0.5)
		(connect_pads
			(clearance 0)
		)
		(min_thickness 0.25)
		(keepout
			(tracks not_allowed)
			(vias allowed)
			(pads allowed)
			(copperpour not_allowed)
			(footprints allowed)
		)
		(placement
			(enabled no)
			(sheetname "")
		)
		(fill
			(thermal_gap 0.5)
			(thermal_bridge_width 0.5)
			(island_removal_mode 0)
		)
		(polygon
			(pts
				(arc
					(start 201.97318 -44.714922)
					(mid 201.36104 -44.102782)
					(end 200.7489 -44.714922)
				)
				(xy 200.7489 -45.026072)
				(arc
					(start 200.96734 -45.026072)
					(mid 201.092634 -44.999619)
					(end 201.196702 -44.92498)
				)
				(arc
					(start 201.196702 -44.92498)
					(mid 201.447593 -44.462653)
					(end 201.361802 -44.981622)
				)
				(arc
					(start 201.361802 -44.981622)
					(mid 201.206229 -45.126917)
					(end 201.0029 -45.189902)
				)
				(xy 201.00163 -45.191172) (xy 200.7489 -45.191172) (xy 200.7489 -45.356272) (xy 201.00163 -45.356272)
				(arc
					(start 201.0029 -45.357542)
					(mid 201.206207 -45.420564)
					(end 201.361802 -45.565822)
				)
				(arc
					(start 201.361802 -45.565822)
					(mid 201.447592 -46.084788)
					(end 201.196702 -45.622464)
				)
				(arc
					(start 201.196702 -45.622464)
					(mid 201.092655 -45.547776)
					(end 200.96734 -45.521372)
				)
				(xy 200.7489 -45.521372)
				(arc
					(start 200.7489 -45.832268)
					(mid 201.360913 -46.444662)
					(end 201.97318 -45.832522)
				)
			)
		)
	)
	(zone
		(layer "In2.Cu")
		(hatch none 0.5)
		(connect_pads
			(clearance 0)
		)
		(min_thickness 0.25)
		(keepout
			(tracks not_allowed)
			(vias allowed)
			(pads allowed)
			(copperpour not_allowed)
			(footprints allowed)
		)
		(placement
			(enabled no)
			(sheetname "")
		)
		(fill
			(thermal_gap 0.5)
			(thermal_bridge_width 0.5)
			(island_removal_mode 0)
		)
		(polygon
			(pts
				(arc
					(start 102.44074 -38.916864)
					(mid 101.930327 -38.40607)
					(end 101.41966 -38.91661)
				)
				(arc
					(start 101.41966 -39.80561)
					(mid 101.9302 -40.31615)
					(end 102.44074 -39.80561)
				)
				(xy 102.44074 -39.60876) (xy 102.24389 -39.60876)
				(arc
					(start 102.167944 -39.684706)
					(mid 101.7416 -39.99421)
					(end 102.051104 -39.567866)
				)
				(xy 102.12705 -39.49192) (xy 102.17531 -39.44366) (xy 102.24389 -39.44366) (xy 102.44074 -39.44366)
				(xy 102.44074 -39.27856) (xy 102.24389 -39.27856) (xy 102.17531 -39.27856) (xy 102.12705 -39.2303)
				(arc
					(start 102.051104 -39.154354)
					(mid 101.7416 -38.72801)
					(end 102.167944 -39.037514)
				)
				(xy 102.24389 -39.11346) (xy 102.44074 -39.11346)
			)
		)
	)
	(zone
		(layer "In2.Cu")
		(hatch none 0.5)
		(connect_pads
			(clearance 0)
		)
		(min_thickness 0.25)
		(keepout
			(tracks not_allowed)
			(vias allowed)
			(pads allowed)
			(copperpour not_allowed)
			(footprints allowed)
		)
		(placement
			(enabled no)
			(sheetname "")
		)
		(fill
			(thermal_gap 0.5)
			(thermal_bridge_width 0.5)
			(island_removal_mode 0)
		)
		(polygon
			(pts
				(arc
					(start 174.493682 -221.784164)
					(mid 173.983142 -222.294704)
					(end 174.493682 -222.805244)
				)
				(arc
					(start 175.306228 -222.805244)
					(mid 175.817022 -222.294831)
					(end 175.306482 -221.784164)
				)
				(arc
					(start 175.151288 -221.784164)
					(mid 175.176349 -221.915887)
					(end 175.224694 -222.040958)
				)
				(arc
					(start 175.224694 -222.040958)
					(mid 175.463262 -222.510053)
					(end 175.089566 -222.13951)
				)
				(arc
					(start 175.089566 -222.13951)
					(mid 175.019168 -221.967209)
					(end 174.985426 -221.784164)
				)
				(arc
					(start 174.814738 -221.784164)
					(mid 174.781011 -221.967213)
					(end 174.710598 -222.13951)
				)
				(arc
					(start 174.710598 -222.13951)
					(mid 174.33691 -222.510042)
					(end 174.57547 -222.040958)
				)
				(arc
					(start 174.57547 -222.040958)
					(mid 174.623849 -221.915897)
					(end 174.648876 -221.784164)
				)
			)
		)
	)
	(zone
		(layer "In2.Cu")
		(hatch none 0.5)
		(connect_pads
			(clearance 0)
		)
		(min_thickness 0.25)
		(keepout
			(tracks not_allowed)
			(vias allowed)
			(pads allowed)
			(copperpour not_allowed)
			(footprints allowed)
		)
		(placement
			(enabled no)
			(sheetname "")
		)
		(fill
			(thermal_gap 0.5)
			(thermal_bridge_width 0.5)
			(island_removal_mode 0)
		)
		(polygon
			(pts
				(arc
					(start 302.27524 -14.062202)
					(mid 302.151039 -13.993903)
					(end 302.014382 -13.956284)
				)
				(arc
					(start 302.014382 -13.956284)
					(mid 301.258262 -13.99007)
					(end 301.987458 -13.78712)
				)
				(arc
					(start 301.987458 -13.78712)
					(mid 302.178804 -13.827982)
					(end 302.353726 -13.915644)
				)
				(xy 302.442372 -13.75029) (xy 302.003968 -13.311632) (xy 302.003968 -13.311378) (xy 301.979838 -13.287502)
				(arc
					(start 301.979838 -13.285724)
					(mid 301.856067 -12.932739)
					(end 302.008286 -12.591034)
				)
				(arc
					(start 302.008286 -12.591034)
					(mid 302.734791 -12.380104)
					(end 302.080676 -12.760198)
				)
				(arc
					(start 302.080676 -12.760198)
					(mid 302.022118 -12.984696)
					(end 302.120554 -13.194792)
				)
				(xy 302.523906 -13.598144) (xy 302.937418 -12.826238)
				(arc
					(start 302.935386 -12.824968)
					(mid 302.679354 -11.979148)
					(end 301.833534 -12.23518)
				)
				(xy 301.831502 -12.23391) (xy 301.08144 -13.633704) (xy 301.081694 -13.633958)
				(arc
					(start 301.083726 -13.634974)
					(mid 301.339402 -14.480875)
					(end 302.185324 -14.225016)
				)
				(xy 302.187356 -14.226286)
			)
		)
	)
	(zone
		(layer "In2.Cu")
		(hatch none 0.5)
		(connect_pads
			(clearance 0)
		)
		(min_thickness 0.25)
		(keepout
			(tracks not_allowed)
			(vias allowed)
			(pads allowed)
			(copperpour not_allowed)
			(footprints allowed)
		)
		(placement
			(enabled no)
			(sheetname "")
		)
		(fill
			(thermal_gap 0.5)
			(thermal_bridge_width 0.5)
			(island_removal_mode 0)
		)
		(polygon
			(pts
				(arc
					(start 164.893752 -221.784164)
					(mid 164.383212 -222.294704)
					(end 164.893752 -222.805244)
				)
				(arc
					(start 165.706298 -222.805244)
					(mid 166.217092 -222.294831)
					(end 165.706552 -221.784164)
				)
				(arc
					(start 165.551358 -221.784164)
					(mid 165.576419 -221.915887)
					(end 165.624764 -222.040958)
				)
				(arc
					(start 165.624764 -222.040958)
					(mid 165.863332 -222.510053)
					(end 165.489636 -222.13951)
				)
				(arc
					(start 165.489636 -222.13951)
					(mid 165.419238 -221.967209)
					(end 165.385496 -221.784164)
				)
				(arc
					(start 165.214808 -221.784164)
					(mid 165.181081 -221.967213)
					(end 165.110668 -222.13951)
				)
				(arc
					(start 165.110668 -222.13951)
					(mid 164.73698 -222.510042)
					(end 164.97554 -222.040958)
				)
				(arc
					(start 164.97554 -222.040958)
					(mid 165.023919 -221.915897)
					(end 165.048946 -221.784164)
				)
			)
		)
	)
	(zone
		(layer "In2.Cu")
		(hatch none 0.5)
		(connect_pads
			(clearance 0)
		)
		(min_thickness 0.25)
		(keepout
			(tracks not_allowed)
			(vias allowed)
			(pads allowed)
			(copperpour not_allowed)
			(footprints allowed)
		)
		(placement
			(enabled no)
			(sheetname "")
		)
		(fill
			(thermal_gap 0.5)
			(thermal_bridge_width 0.5)
			(island_removal_mode 0)
		)
		(polygon
			(pts
				(arc
					(start 102.893368 -221.784164)
					(mid 102.382828 -222.294704)
					(end 102.893368 -222.805244)
				)
				(arc
					(start 103.705914 -222.805244)
					(mid 104.216708 -222.294831)
					(end 103.706168 -221.784164)
				)
				(arc
					(start 103.550974 -221.784164)
					(mid 103.576035 -221.915887)
					(end 103.62438 -222.040958)
				)
				(arc
					(start 103.62438 -222.040958)
					(mid 103.862948 -222.510053)
					(end 103.489252 -222.13951)
				)
				(arc
					(start 103.489252 -222.13951)
					(mid 103.418854 -221.967209)
					(end 103.385112 -221.784164)
				)
				(arc
					(start 103.214424 -221.784164)
					(mid 103.180697 -221.967213)
					(end 103.110284 -222.13951)
				)
				(arc
					(start 103.110284 -222.13951)
					(mid 102.736596 -222.510042)
					(end 102.975156 -222.040958)
				)
				(arc
					(start 102.975156 -222.040958)
					(mid 103.023535 -221.915897)
					(end 103.048562 -221.784164)
				)
			)
		)
	)
	(zone
		(layer "In2.Cu")
		(hatch none 0.5)
		(connect_pads
			(clearance 0)
		)
		(min_thickness 0.25)
		(keepout
			(tracks not_allowed)
			(vias allowed)
			(pads allowed)
			(copperpour not_allowed)
			(footprints allowed)
		)
		(placement
			(enabled no)
			(sheetname "")
		)
		(fill
			(thermal_gap 0.5)
			(thermal_bridge_width 0.5)
			(island_removal_mode 0)
		)
		(polygon
			(pts
				(arc
					(start 84.493354 -221.784164)
					(mid 83.982814 -222.294704)
					(end 84.493354 -222.805244)
				)
				(arc
					(start 85.3059 -222.805244)
					(mid 85.816694 -222.294831)
					(end 85.306154 -221.784164)
				)
				(arc
					(start 85.15096 -221.784164)
					(mid 85.176021 -221.915887)
					(end 85.224366 -222.040958)
				)
				(arc
					(start 85.224366 -222.040958)
					(mid 85.462934 -222.510053)
					(end 85.089238 -222.13951)
				)
				(arc
					(start 85.089238 -222.13951)
					(mid 85.01884 -221.967209)
					(end 84.985098 -221.784164)
				)
				(arc
					(start 84.81441 -221.784164)
					(mid 84.780683 -221.967213)
					(end 84.71027 -222.13951)
				)
				(arc
					(start 84.71027 -222.13951)
					(mid 84.336582 -222.510042)
					(end 84.575142 -222.040958)
				)
				(arc
					(start 84.575142 -222.040958)
					(mid 84.623521 -221.915897)
					(end 84.648548 -221.784164)
				)
			)
		)
	)
	(zone
		(layer "In2.Cu")
		(hatch none 0.5)
		(connect_pads
			(clearance 0)
		)
		(min_thickness 0.25)
		(keepout
			(tracks not_allowed)
			(vias allowed)
			(pads allowed)
			(copperpour not_allowed)
			(footprints allowed)
		)
		(placement
			(enabled no)
			(sheetname "")
		)
		(fill
			(thermal_gap 0.5)
			(thermal_bridge_width 0.5)
			(island_removal_mode 0)
		)
		(polygon
			(pts
				(arc
					(start 25.085294 -111.4044)
					(mid 24.473154 -110.79226)
					(end 23.861014 -111.4044)
				)
				(arc
					(start 23.861014 -112.521746)
					(mid 24.473027 -113.13414)
					(end 25.085294 -112.522)
				)
				(xy 25.085294 -112.21085)
				(arc
					(start 24.924766 -112.21085)
					(mid 24.902896 -112.2152)
					(end 24.88438 -112.227614)
				)
				(arc
					(start 24.710898 -112.401096)
					(mid 24.284554 -112.7106)
					(end 24.594058 -112.284256)
				)
				(xy 24.79167 -112.086644)
				(arc
					(start 24.796242 -112.086644)
					(mid 24.839705 -112.062585)
					(end 24.887428 -112.048798)
				)
				(xy 24.890476 -112.04575) (xy 25.085294 -112.04575) (xy 25.085294 -111.88065) (xy 24.890476 -111.88065)
				(arc
					(start 24.887428 -111.877602)
					(mid 24.839715 -111.863791)
					(end 24.796242 -111.839756)
				)
				(xy 24.79167 -111.839756)
				(arc
					(start 24.594058 -111.642144)
					(mid 24.284554 -111.2158)
					(end 24.710898 -111.525304)
				)
				(arc
					(start 24.88438 -111.698786)
					(mid 24.902909 -111.711167)
					(end 24.924766 -111.71555)
				)
				(xy 25.085294 -111.71555)
			)
		)
	)
	(zone
		(layer "In2.Cu")
		(hatch none 0.5)
		(connect_pads
			(clearance 0)
		)
		(min_thickness 0.25)
		(keepout
			(tracks not_allowed)
			(vias allowed)
			(pads allowed)
			(copperpour not_allowed)
			(footprints allowed)
		)
		(placement
			(enabled no)
			(sheetname "")
		)
		(fill
			(thermal_gap 0.5)
			(thermal_bridge_width 0.5)
			(island_removal_mode 0)
		)
		(polygon
			(pts
				(arc
					(start 311.69356 -221.784164)
					(mid 311.18302 -222.294704)
					(end 311.69356 -222.805244)
				)
				(arc
					(start 312.506106 -222.805244)
					(mid 313.0169 -222.294831)
					(end 312.50636 -221.784164)
				)
				(xy 312.34761 -221.784164)
				(arc
					(start 312.34761 -221.793308)
					(mid 312.36345 -221.923436)
					(end 312.40984 -222.046038)
				)
				(arc
					(start 312.40984 -222.046038)
					(mid 312.67634 -222.500271)
					(end 312.2803 -222.153226)
				)
				(arc
					(start 312.2803 -222.153226)
					(mid 312.212113 -221.996407)
					(end 312.183272 -221.827852)
				)
				(xy 312.18251 -221.82709) (xy 312.18251 -221.784164) (xy 312.01741 -221.784164) (xy 312.01741 -221.82709)
				(arc
					(start 312.016648 -221.827852)
					(mid 311.987831 -221.996414)
					(end 311.91962 -222.153226)
				)
				(arc
					(start 311.91962 -222.153226)
					(mid 311.523618 -222.500225)
					(end 311.79008 -222.046038)
				)
				(arc
					(start 311.79008 -222.046038)
					(mid 311.836444 -221.92343)
					(end 311.85231 -221.793308)
				)
				(xy 311.85231 -221.784164)
			)
		)
	)
	(zone
		(layer "In2.Cu")
		(hatch none 0.5)
		(connect_pads
			(clearance 0)
		)
		(min_thickness 0.25)
		(keepout
			(tracks not_allowed)
			(vias allowed)
			(pads allowed)
			(copperpour not_allowed)
			(footprints allowed)
		)
		(placement
			(enabled no)
			(sheetname "")
		)
		(fill
			(thermal_gap 0.5)
			(thermal_bridge_width 0.5)
			(island_removal_mode 0)
		)
		(polygon
			(pts
				(arc
					(start 313.935364 -12.824968)
					(mid 313.679332 -11.979148)
					(end 312.833512 -12.23518)
				)
				(xy 312.83148 -12.23391) (xy 312.081418 -13.633704) (xy 312.081672 -13.633958)
				(arc
					(start 312.083704 -13.634974)
					(mid 312.33938 -14.480875)
					(end 313.185302 -14.225016)
				)
				(xy 313.187334 -14.226286) (xy 313.224672 -14.15669) (xy 313.224672 -13.971016) (xy 313.224418 -13.965428)
				(arc
					(start 313.224418 -13.961872)
					(mid 313.208778 -13.882682)
					(end 313.163966 -13.815568)
				)
				(arc
					(start 313.113166 -13.765022)
					(mid 313.068547 -13.735145)
					(end 313.015884 -13.724636)
				)
				(arc
					(start 312.955178 -13.724636)
					(mid 312.38364 -14.216949)
					(end 312.795158 -13.584682)
				)
				(arc
					(start 312.795158 -13.584682)
					(mid 312.830627 -13.570735)
					(end 312.867802 -13.56233)
				)
				(xy 312.870342 -13.559536) (xy 313.050174 -13.559536)
				(arc
					(start 313.052206 -13.561822)
					(mid 313.131647 -13.582648)
					(end 313.202574 -13.624052)
				)
				(xy 313.205876 -13.624052) (xy 313.229752 -13.648182) (xy 313.230006 -13.648182) (xy 313.280552 -13.698728)
				(xy 313.280552 -13.698982) (xy 313.304682 -13.722858)
				(arc
					(start 313.304682 -13.725398)
					(mid 313.349372 -13.793737)
					(end 313.378088 -13.870178)
				)
				(arc
					(start 313.476894 -13.685774)
					(mid 313.443314 -13.635553)
					(end 313.404504 -13.589254)
				)
				(arc
					(start 313.40171 -13.58646)
					(mid 313.33523 -13.492087)
					(end 313.30392 -13.380974)
				)
				(xy 313.301888 -13.379196)
				(arc
					(start 313.301888 -12.90193)
					(mid 313.384438 -12.149165)
					(end 313.466988 -12.90193)
				)
				(arc
					(start 313.466988 -13.344906)
					(mid 313.480445 -13.412558)
					(end 313.518804 -13.469874)
				)
				(xy 313.519312 -13.470382) (xy 313.521598 -13.472668)
				(arc
					(start 313.523884 -13.474954)
					(mid 313.544714 -13.498138)
					(end 313.564524 -13.522198)
				)
				(xy 313.937396 -12.826238)
			)
		)
	)
	(zone
		(layer "In2.Cu")
		(hatch none 0.5)
		(connect_pads
			(clearance 0)
		)
		(min_thickness 0.25)
		(keepout
			(tracks not_allowed)
			(vias allowed)
			(pads allowed)
			(copperpour not_allowed)
			(footprints allowed)
		)
		(placement
			(enabled no)
			(sheetname "")
		)
		(fill
			(thermal_gap 0.5)
			(thermal_bridge_width 0.5)
			(island_removal_mode 0)
		)
		(polygon
			(pts
				(arc
					(start 96.493584 -221.784164)
					(mid 95.983044 -222.294704)
					(end 96.493584 -222.805244)
				)
				(arc
					(start 97.30613 -222.805244)
					(mid 97.816924 -222.294831)
					(end 97.306384 -221.784164)
				)
				(arc
					(start 97.15119 -221.784164)
					(mid 97.176251 -221.915887)
					(end 97.224596 -222.040958)
				)
				(arc
					(start 97.224596 -222.040958)
					(mid 97.463164 -222.510053)
					(end 97.089468 -222.13951)
				)
				(arc
					(start 97.089468 -222.13951)
					(mid 97.01907 -221.967209)
					(end 96.985328 -221.784164)
				)
				(arc
					(start 96.81464 -221.784164)
					(mid 96.780913 -221.967213)
					(end 96.7105 -222.13951)
				)
				(arc
					(start 96.7105 -222.13951)
					(mid 96.336812 -222.510042)
					(end 96.575372 -222.040958)
				)
				(arc
					(start 96.575372 -222.040958)
					(mid 96.623751 -221.915897)
					(end 96.648778 -221.784164)
				)
			)
		)
	)
	(zone
		(layer "In2.Cu")
		(hatch none 0.5)
		(connect_pads
			(clearance 0)
		)
		(min_thickness 0.25)
		(keepout
			(tracks not_allowed)
			(vias allowed)
			(pads allowed)
			(copperpour not_allowed)
			(footprints allowed)
		)
		(placement
			(enabled no)
			(sheetname "")
		)
		(fill
			(thermal_gap 0.5)
			(thermal_bridge_width 0.5)
			(island_removal_mode 0)
		)
		(polygon
			(pts
				(arc
					(start 198.493634 -221.784164)
					(mid 197.983094 -222.294704)
					(end 198.493634 -222.805244)
				)
				(arc
					(start 199.30618 -222.805244)
					(mid 199.816974 -222.294831)
					(end 199.306434 -221.784164)
				)
				(arc
					(start 199.15124 -221.784164)
					(mid 199.176301 -221.915887)
					(end 199.224646 -222.040958)
				)
				(arc
					(start 199.224646 -222.040958)
					(mid 199.463214 -222.510053)
					(end 199.089518 -222.13951)
				)
				(arc
					(start 199.089518 -222.13951)
					(mid 199.01912 -221.967209)
					(end 198.985378 -221.784164)
				)
				(arc
					(start 198.81469 -221.784164)
					(mid 198.780963 -221.967213)
					(end 198.71055 -222.13951)
				)
				(arc
					(start 198.71055 -222.13951)
					(mid 198.336862 -222.510042)
					(end 198.575422 -222.040958)
				)
				(arc
					(start 198.575422 -222.040958)
					(mid 198.623801 -221.915897)
					(end 198.648828 -221.784164)
				)
			)
		)
	)
	(zone
		(layer "In2.Cu")
		(hatch none 0.5)
		(connect_pads
			(clearance 0)
		)
		(min_thickness 0.25)
		(keepout
			(tracks not_allowed)
			(vias allowed)
			(pads allowed)
			(copperpour not_allowed)
			(footprints allowed)
		)
		(placement
			(enabled no)
			(sheetname "")
		)
		(fill
			(thermal_gap 0.5)
			(thermal_bridge_width 0.5)
			(island_removal_mode 0)
		)
		(polygon
			(pts
				(arc
					(start 334.093566 -221.784164)
					(mid 333.583026 -222.294704)
					(end 334.093566 -222.805244)
				)
				(arc
					(start 334.906112 -222.805244)
					(mid 335.416906 -222.294831)
					(end 334.906366 -221.784164)
				)
				(xy 334.747616 -221.784164)
				(arc
					(start 334.747616 -221.793308)
					(mid 334.763456 -221.923436)
					(end 334.809846 -222.046038)
				)
				(arc
					(start 334.809846 -222.046038)
					(mid 335.076346 -222.500271)
					(end 334.680306 -222.153226)
				)
				(arc
					(start 334.680306 -222.153226)
					(mid 334.612119 -221.996407)
					(end 334.583278 -221.827852)
				)
				(xy 334.582516 -221.82709) (xy 334.582516 -221.784164) (xy 334.417416 -221.784164) (xy 334.417416 -221.82709)
				(arc
					(start 334.416654 -221.827852)
					(mid 334.387837 -221.996414)
					(end 334.319626 -222.153226)
				)
				(arc
					(start 334.319626 -222.153226)
					(mid 333.923624 -222.500225)
					(end 334.190086 -222.046038)
				)
				(arc
					(start 334.190086 -222.046038)
					(mid 334.23645 -221.92343)
					(end 334.252316 -221.793308)
				)
				(xy 334.252316 -221.784164)
			)
		)
	)
	(zone
		(layer "In2.Cu")
		(hatch none 0.5)
		(connect_pads
			(clearance 0)
		)
		(min_thickness 0.25)
		(keepout
			(tracks not_allowed)
			(vias allowed)
			(pads allowed)
			(copperpour not_allowed)
			(footprints allowed)
		)
		(placement
			(enabled no)
			(sheetname "")
		)
		(fill
			(thermal_gap 0.5)
			(thermal_bridge_width 0.5)
			(island_removal_mode 0)
		)
		(polygon
			(pts
				(arc
					(start 202.946254 -49.27346)
					(mid 202.43546 -49.783873)
					(end 202.946 -50.29454)
				)
				(arc
					(start 203.09078 -50.29454)
					(mid 203.070349 -50.163413)
					(end 203.025502 -50.038508)
				)
				(arc
					(start 203.025502 -50.038508)
					(mid 202.790603 -49.567328)
					(end 203.161646 -49.940972)
				)
				(arc
					(start 203.161646 -49.940972)
					(mid 203.227831 -50.112692)
					(end 203.256134 -50.29454)
				)
				(xy 203.42225 -50.29454) (xy 203.42225 -50.19675)
				(arc
					(start 203.423266 -50.195734)
					(mid 203.454038 -50.046643)
					(end 203.524612 -49.911762)
				)
				(arc
					(start 203.524612 -49.911762)
					(mid 203.941192 -49.58932)
					(end 203.646532 -50.026062)
				)
				(arc
					(start 203.646532 -50.026062)
					(mid 203.602426 -50.12423)
					(end 203.58735 -50.230786)
				)
				(xy 203.58735 -50.29454)
				(arc
					(start 203.7588 -50.29454)
					(mid 204.26934 -49.784)
					(end 203.7588 -49.27346)
				)
			)
		)
	)
	(zone
		(layer "In2.Cu")
		(hatch none 0.5)
		(connect_pads
			(clearance 0)
		)
		(min_thickness 0.25)
		(keepout
			(tracks not_allowed)
			(vias allowed)
			(pads allowed)
			(copperpour not_allowed)
			(footprints allowed)
		)
		(placement
			(enabled no)
			(sheetname "")
		)
		(fill
			(thermal_gap 0.5)
			(thermal_bridge_width 0.5)
			(island_removal_mode 0)
		)
		(polygon
			(pts
				(arc
					(start 136.685274 -16.625062)
					(mid 136.429242 -15.779242)
					(end 135.583422 -16.035274)
				)
				(xy 135.58139 -16.034004) (xy 134.831582 -17.433544) (xy 134.831836 -17.433798)
				(arc
					(start 134.833868 -17.434814)
					(mid 135.045363 -18.254663)
					(end 135.87984 -18.110962)
				)
				(arc
					(start 135.38454 -18.110962)
					(mid 135.08737 -17.491528)
					(end 135.756396 -17.647412)
				)
				(xy 135.923782 -17.647412)
				(arc
					(start 135.92429 -17.648174)
					(mid 136.025057 -17.657529)
					(end 136.124188 -17.677892)
				)
				(xy 136.26719 -17.41043) (xy 136.04875 -17.19199)
				(arc
					(start 136.04875 -17.190466)
					(mid 135.944449 -17.023872)
					(end 135.900414 -16.832326)
				)
				(xy 135.899398 -16.83131)
				(arc
					(start 135.899398 -16.630142)
					(mid 136.291764 -15.982885)
					(end 136.064498 -16.704818)
				)
				(arc
					(start 136.064498 -16.79702)
					(mid 136.097038 -16.96061)
					(end 136.18972 -17.09928)
				)
				(xy 136.348724 -17.258284) (xy 136.687306 -16.626332)
			)
		)
	)
	(zone
		(layer "In2.Cu")
		(hatch none 0.5)
		(connect_pads
			(clearance 0)
		)
		(min_thickness 0.25)
		(keepout
			(tracks not_allowed)
			(vias allowed)
			(pads allowed)
			(copperpour not_allowed)
			(footprints allowed)
		)
		(placement
			(enabled no)
			(sheetname "")
		)
		(fill
			(thermal_gap 0.5)
			(thermal_bridge_width 0.5)
			(island_removal_mode 0)
		)
		(polygon
			(pts
				(arc
					(start 324.477126 -17.485614)
					(mid 324.44343 -17.435378)
					(end 324.404482 -17.389094)
				)
				(arc
					(start 324.401688 -17.3863)
					(mid 324.335208 -17.291927)
					(end 324.303898 -17.180814)
				)
				(xy 324.301866 -17.179036)
				(arc
					(start 324.301866 -16.702024)
					(mid 324.384416 -15.949259)
					(end 324.466966 -16.702024)
				)
				(arc
					(start 324.466966 -17.144746)
					(mid 324.480423 -17.212398)
					(end 324.518782 -17.269714)
				)
				(xy 324.51929 -17.270222) (xy 324.521576 -17.272508)
				(arc
					(start 324.523862 -17.274794)
					(mid 324.544697 -17.298103)
					(end 324.564502 -17.322292)
				)
				(xy 324.937374 -16.626586)
				(arc
					(start 324.935088 -16.625316)
					(mid 324.679564 -15.779496)
					(end 323.833744 -16.03502)
				)
				(xy 323.831458 -16.03375) (xy 323.081396 -17.433544) (xy 323.08165 -17.433798)
				(arc
					(start 323.083682 -17.434814)
					(mid 323.339206 -18.280634)
					(end 324.185026 -18.02511)
				)
				(xy 324.187312 -18.02638) (xy 324.22465 -17.956784) (xy 324.22465 -17.770856) (xy 324.224396 -17.765268)
				(arc
					(start 324.224396 -17.761712)
					(mid 324.208756 -17.682522)
					(end 324.163944 -17.615408)
				)
				(arc
					(start 324.11289 -17.564608)
					(mid 324.085066 -17.543074)
					(end 324.052692 -17.529302)
				)
				(arc
					(start 324.052692 -17.529302)
					(mid 324.034692 -17.525684)
					(end 324.01637 -17.524476)
				)
				(arc
					(start 323.955156 -17.524476)
					(mid 323.383618 -18.016789)
					(end 323.795136 -17.384522)
				)
				(arc
					(start 323.795136 -17.384522)
					(mid 323.830605 -17.370575)
					(end 323.86778 -17.36217)
				)
				(xy 323.87032 -17.359376) (xy 324.015862 -17.359376) (xy 324.016624 -17.359376) (xy 324.050152 -17.359376)
				(arc
					(start 324.052184 -17.361408)
					(mid 324.07445 -17.365021)
					(end 324.09638 -17.370298)
				)
				(arc
					(start 324.096634 -17.370298)
					(mid 324.152371 -17.391841)
					(end 324.202806 -17.423892)
				)
				(xy 324.205854 -17.423892) (xy 324.22973 -17.447768) (xy 324.229984 -17.448022) (xy 324.28053 -17.498568)
				(xy 324.28053 -17.498822) (xy 324.30466 -17.522698)
				(arc
					(start 324.30466 -17.525238)
					(mid 324.349377 -17.593699)
					(end 324.378066 -17.670272)
				)
			)
		)
	)
	(zone
		(layer "In2.Cu")
		(hatch none 0.5)
		(connect_pads
			(clearance 0)
		)
		(min_thickness 0.25)
		(keepout
			(tracks not_allowed)
			(vias allowed)
			(pads allowed)
			(copperpour not_allowed)
			(footprints allowed)
		)
		(placement
			(enabled no)
			(sheetname "")
		)
		(fill
			(thermal_gap 0.5)
			(thermal_bridge_width 0.5)
			(island_removal_mode 0)
		)
		(polygon
			(pts
				(arc
					(start 322.685156 -16.625316)
					(mid 322.429632 -15.779496)
					(end 321.583812 -16.03502)
				)
				(xy 321.581526 -16.03375) (xy 320.831464 -17.433544) (xy 320.831718 -17.433798)
				(arc
					(start 320.83375 -17.434814)
					(mid 321.089274 -18.280634)
					(end 321.935094 -18.02511)
				)
				(xy 321.93738 -18.02638) (xy 322.004182 -17.901666)
				(arc
					(start 322.004182 -17.690592)
					(mid 321.998124 -17.616733)
					(end 321.980306 -17.544796)
				)
				(xy 321.969384 -17.533874) (xy 321.969384 -17.514824) (xy 321.941698 -17.443958) (xy 321.930014 -17.432528)
				(arc
					(start 321.930014 -17.413986)
					(mid 321.790049 -17.274027)
					(end 321.592194 -17.267428)
				)
				(xy 321.56527 -17.28089)
				(arc
					(start 321.56273 -17.279874)
					(mid 321.510822 -17.3135)
					(end 321.467988 -17.358106)
				)
				(arc
					(start 321.467988 -17.358106)
					(mid 321.397651 -18.110769)
					(end 321.277234 -17.364456)
				)
				(arc
					(start 321.277234 -17.364456)
					(mid 321.375229 -17.214039)
					(end 321.525646 -17.116044)
				)
				(xy 321.553078 -17.102328)
				(arc
					(start 321.559428 -17.10436)
					(mid 321.868373 -17.128031)
					(end 322.082922 -17.351502)
				)
				(xy 322.095114 -17.363694) (xy 322.095114 -17.383252) (xy 322.122546 -17.453356) (xy 322.134738 -17.465294)
				(arc
					(start 322.134738 -17.485868)
					(mid 322.151992 -17.544602)
					(end 322.16344 -17.60474)
				)
				(xy 322.27647 -17.393412)
				(arc
					(start 322.27647 -17.392904)
					(mid 322.161934 -17.055989)
					(end 322.086986 -16.70812)
				)
				(arc
					(start 322.086986 -16.70812)
					(mid 322.098713 -15.950926)
					(end 322.251832 -16.692626)
				)
				(arc
					(start 322.251832 -16.692626)
					(mid 322.304541 -16.949386)
					(end 322.380102 -17.200372)
				)
				(xy 322.687442 -16.626586)
			)
		)
	)
	(zone
		(layer "In2.Cu")
		(hatch none 0.5)
		(connect_pads
			(clearance 0)
		)
		(min_thickness 0.25)
		(keepout
			(tracks not_allowed)
			(vias allowed)
			(pads allowed)
			(copperpour not_allowed)
			(footprints allowed)
		)
		(placement
			(enabled no)
			(sheetname "")
		)
		(fill
			(thermal_gap 0.5)
			(thermal_bridge_width 0.5)
			(island_removal_mode 0)
		)
		(polygon
			(pts
				(arc
					(start 322.68541 -12.824968)
					(mid 322.429378 -11.979148)
					(end 321.583558 -12.23518)
				)
				(xy 321.581526 -12.23391) (xy 320.831464 -13.633704) (xy 320.831718 -13.633958)
				(arc
					(start 320.83375 -13.634974)
					(mid 320.825671 -14.209674)
					(end 321.290442 -14.54785)
				)
				(arc
					(start 321.478402 -14.54785)
					(mid 321.745006 -14.440415)
					(end 321.935348 -14.225016)
				)
				(xy 321.93738 -14.226286) (xy 321.974718 -14.15669) (xy 321.974718 -13.85062) (xy 321.974464 -13.850366)
				(arc
					(start 321.974464 -13.815822)
					(mid 321.967643 -13.746188)
					(end 321.94754 -13.67917)
				)
				(arc
					(start 321.892676 -13.554964)
					(mid 321.74485 -13.413981)
					(end 321.540632 -13.41882)
				)
				(arc
					(start 321.540632 -13.41882)
					(mid 321.461836 -13.472229)
					(end 321.406774 -13.549884)
				)
				(arc
					(start 321.406774 -13.549884)
					(mid 321.455289 -14.304333)
					(end 321.22364 -13.584682)
				)
				(arc
					(start 321.22364 -13.584682)
					(mid 321.309556 -13.395218)
					(end 321.474084 -13.267944)
				)
				(arc
					(start 321.474084 -13.267944)
					(mid 321.787878 -13.2542)
					(end 322.028058 -13.456666)
				)
				(xy 322.03009 -13.457428) (xy 322.043806 -13.488162) (xy 322.043806 -13.48867) (xy 322.08978 -13.592302)
				(xy 322.099432 -13.614146) (xy 322.104004 -13.62456)
				(arc
					(start 322.10375 -13.625068)
					(mid 322.126926 -13.701352)
					(end 322.138294 -13.780262)
				)
				(xy 322.139818 -13.781532) (xy 322.139818 -13.848334) (xy 322.175632 -13.781532)
				(arc
					(start 322.27139 -13.60297)
					(mid 322.256442 -13.561431)
					(end 322.238878 -13.520928)
				)
				(arc
					(start 322.238878 -13.520928)
					(mid 322.125406 -13.219578)
					(end 322.061586 -12.903962)
				)
				(arc
					(start 322.061586 -12.903962)
					(mid 322.124724 -12.149229)
					(end 322.227448 -12.899644)
				)
				(arc
					(start 322.227448 -12.899644)
					(mid 322.28091 -13.162599)
					(end 322.371974 -13.41501)
				)
				(xy 322.687442 -12.826238)
			)
		)
	)
	(zone
		(net "P1V53_STBY")
		(layer "In2.Cu")
		(hatch none 0.5)
		(connect_pads
			(clearance 0.5)
		)
		(min_thickness 0.25)
		(fill yes
			(thermal_gap 0.5)
			(thermal_bridge_width 0.5)
			(island_removal_mode 0)
		)
		(polygon
			(pts
				(xy 26.0858 -163.4744) (xy 54.0512 -163.4744) (xy 61.595 -155.9306) (xy 61.595 -152.4508) (xy 60.833 -151.6888)
				(xy 48.1838 -151.6888) (xy 45.2882 -148.7932) (xy 26.1366 -148.7932) (xy 23.2156 -151.7142) (xy 16.256 -151.7142)
				(xy 15.9004 -152.0698) (xy 15.9004 -153.289)
			)
		)
	)
	(zone
		(layer "In2.Cu")
		(hatch none 0.5)
		(connect_pads
			(clearance 0)
		)
		(min_thickness 0.25)
		(keepout
			(tracks not_allowed)
			(vias allowed)
			(pads allowed)
			(copperpour not_allowed)
			(footprints allowed)
		)
		(placement
			(enabled no)
			(sheetname "")
		)
		(fill
			(thermal_gap 0.5)
			(thermal_bridge_width 0.5)
			(island_removal_mode 0)
		)
		(polygon
			(pts
				(arc
					(start 328.121518 -32.645858)
					(mid 328.031715 -32.683055)
					(end 327.994518 -32.772858)
				)
				(arc
					(start 327.994518 -34.093658)
					(mid 328.031715 -34.183461)
					(end 328.121518 -34.220658)
				)
				(arc
					(start 329.416918 -34.220658)
					(mid 329.506721 -34.183461)
					(end 329.543918 -34.093658)
				)
				(arc
					(start 329.543918 -32.772858)
					(mid 329.506721 -32.683055)
					(end 329.416918 -32.645858)
				)
			)
		)
	)
	(zone
		(layer "In2.Cu")
		(hatch none 0.5)
		(connect_pads
			(clearance 0)
		)
		(min_thickness 0.25)
		(keepout
			(tracks not_allowed)
			(vias allowed)
			(pads allowed)
			(copperpour not_allowed)
			(footprints allowed)
		)
		(placement
			(enabled no)
			(sheetname "")
		)
		(fill
			(thermal_gap 0.5)
			(thermal_bridge_width 0.5)
			(island_removal_mode 0)
		)
		(polygon
			(pts
				(arc
					(start 291.6936 -221.784164)
					(mid 291.18306 -222.294704)
					(end 291.6936 -222.805244)
				)
				(arc
					(start 292.506146 -222.805244)
					(mid 293.01694 -222.294831)
					(end 292.5064 -221.784164)
				)
				(xy 292.34765 -221.784164)
				(arc
					(start 292.34765 -221.793308)
					(mid 292.36349 -221.923436)
					(end 292.40988 -222.046038)
				)
				(arc
					(start 292.40988 -222.046038)
					(mid 292.67638 -222.500271)
					(end 292.28034 -222.153226)
				)
				(arc
					(start 292.28034 -222.153226)
					(mid 292.212153 -221.996407)
					(end 292.183312 -221.827852)
				)
				(xy 292.18255 -221.82709) (xy 292.18255 -221.784164) (xy 292.01745 -221.784164) (xy 292.01745 -221.82709)
				(arc
					(start 292.016688 -221.827852)
					(mid 291.987871 -221.996414)
					(end 291.91966 -222.153226)
				)
				(arc
					(start 291.91966 -222.153226)
					(mid 291.523658 -222.500225)
					(end 291.79012 -222.046038)
				)
				(arc
					(start 291.79012 -222.046038)
					(mid 291.836484 -221.92343)
					(end 291.85235 -221.793308)
				)
				(xy 291.85235 -221.784164)
			)
		)
	)
	(zone
		(layer "In2.Cu")
		(hatch none 0.5)
		(connect_pads
			(clearance 0)
		)
		(min_thickness 0.25)
		(keepout
			(tracks not_allowed)
			(vias allowed)
			(pads allowed)
			(copperpour not_allowed)
			(footprints allowed)
		)
		(placement
			(enabled no)
			(sheetname "")
		)
		(fill
			(thermal_gap 0.5)
			(thermal_bridge_width 0.5)
			(island_removal_mode 0)
		)
		(polygon
			(pts
				(arc
					(start 188.893704 -221.784164)
					(mid 188.383164 -222.294704)
					(end 188.893704 -222.805244)
				)
				(arc
					(start 189.70625 -222.805244)
					(mid 190.217044 -222.294831)
					(end 189.706504 -221.784164)
				)
				(arc
					(start 189.55131 -221.784164)
					(mid 189.576371 -221.915887)
					(end 189.624716 -222.040958)
				)
				(arc
					(start 189.624716 -222.040958)
					(mid 189.863284 -222.510053)
					(end 189.489588 -222.13951)
				)
				(arc
					(start 189.489588 -222.13951)
					(mid 189.41919 -221.967209)
					(end 189.385448 -221.784164)
				)
				(arc
					(start 189.21476 -221.784164)
					(mid 189.181033 -221.967213)
					(end 189.11062 -222.13951)
				)
				(arc
					(start 189.11062 -222.13951)
					(mid 188.736932 -222.510042)
					(end 188.975492 -222.040958)
				)
				(arc
					(start 188.975492 -222.040958)
					(mid 189.023871 -221.915897)
					(end 189.048898 -221.784164)
				)
			)
		)
	)
	(zone
		(net "P3V3_STBY")
		(layer "In2.Cu")
		(hatch none 0.5)
		(connect_pads
			(clearance 0.5)
		)
		(min_thickness 0.25)
		(fill yes
			(thermal_gap 0.5)
			(thermal_bridge_width 0.5)
			(island_removal_mode 0)
		)
		(polygon
			(pts
				(xy 214.4776 -202.9968) (xy 214.4776 -197.3326) (xy 213.5378 -196.3928) (xy 213.5378 -191.6684)
				(xy 215.6714 -189.5348) (xy 226.1108 -189.5348) (xy 226.695 -188.9506) (xy 228.0412 -188.9506) (xy 228.6254 -189.5348)
				(xy 228.6508 -189.5602) (xy 228.6508 -198.755) (xy 226.568 -200.8378) (xy 220.091 -200.8378) (xy 217.7288 -203.2)
				(xy 214.6808 -203.2)
			)
		)
	)
	(zone
		(layer "In2.Cu")
		(hatch none 0.5)
		(connect_pads
			(clearance 0)
		)
		(min_thickness 0.25)
		(keepout
			(tracks not_allowed)
			(vias allowed)
			(pads allowed)
			(copperpour not_allowed)
			(footprints allowed)
		)
		(placement
			(enabled no)
			(sheetname "")
		)
		(fill
			(thermal_gap 0.5)
			(thermal_bridge_width 0.5)
			(island_removal_mode 0)
		)
		(polygon
			(pts
				(arc
					(start 90.893392 -221.784164)
					(mid 90.382852 -222.294704)
					(end 90.893392 -222.805244)
				)
				(arc
					(start 91.705938 -222.805244)
					(mid 92.216732 -222.294831)
					(end 91.706192 -221.784164)
				)
				(arc
					(start 91.550998 -221.784164)
					(mid 91.576059 -221.915887)
					(end 91.624404 -222.040958)
				)
				(arc
					(start 91.624404 -222.040958)
					(mid 91.862972 -222.510053)
					(end 91.489276 -222.13951)
				)
				(arc
					(start 91.489276 -222.13951)
					(mid 91.418878 -221.967209)
					(end 91.385136 -221.784164)
				)
				(arc
					(start 91.214448 -221.784164)
					(mid 91.180721 -221.967213)
					(end 91.110308 -222.13951)
				)
				(arc
					(start 91.110308 -222.13951)
					(mid 90.73662 -222.510042)
					(end 90.97518 -222.040958)
				)
				(arc
					(start 90.97518 -222.040958)
					(mid 91.023559 -221.915897)
					(end 91.048586 -221.784164)
				)
			)
		)
	)
	(zone
		(layer "In2.Cu")
		(hatch none 0.5)
		(connect_pads
			(clearance 0)
		)
		(min_thickness 0.25)
		(keepout
			(tracks not_allowed)
			(vias allowed)
			(pads allowed)
			(copperpour not_allowed)
			(footprints allowed)
		)
		(placement
			(enabled no)
			(sheetname "")
		)
		(fill
			(thermal_gap 0.5)
			(thermal_bridge_width 0.5)
			(island_removal_mode 0)
		)
		(polygon
			(pts
				(arc
					(start 28.47594 -105.502202)
					(mid 27.610308 -105.502202)
					(end 27.610308 -106.367834)
				)
				(xy 27.60853 -106.369612) (xy 28.398978 -107.16006)
				(arc
					(start 28.400756 -107.158282)
					(mid 29.266388 -107.158282)
					(end 29.266388 -106.29265)
				)
				(xy 29.268166 -106.290872) (xy 29.047694 -106.0704)
				(arc
					(start 28.891992 -106.226356)
					(mid 28.82189 -106.334009)
					(end 28.80106 -106.460798)
				)
				(arc
					(start 28.80106 -106.460798)
					(mid 28.950877 -106.964936)
					(end 28.644342 -106.537506)
				)
				(arc
					(start 28.644342 -106.537506)
					(mid 28.651528 -106.324325)
					(end 28.751022 -106.135678)
				)
				(xy 28.751022 -106.133646) (xy 28.931108 -105.953814) (xy 28.814268 -105.836974) (xy 28.633674 -106.017568)
				(arc
					(start 28.631642 -106.017568)
					(mid 28.443588 -106.116845)
					(end 28.231084 -106.124248)
				)
				(arc
					(start 28.231084 -106.124248)
					(mid 27.803547 -105.817801)
					(end 28.307792 -105.967276)
				)
				(arc
					(start 28.307792 -105.967276)
					(mid 28.433898 -105.946428)
					(end 28.540964 -105.876598)
				)
				(xy 28.697428 -105.720134) (xy 28.477972 -105.500678) (xy 28.477464 -105.500678)
			)
		)
	)
	(zone
		(layer "In2.Cu")
		(hatch none 0.5)
		(connect_pads
			(clearance 0)
		)
		(min_thickness 0.25)
		(keepout
			(tracks not_allowed)
			(vias allowed)
			(pads allowed)
			(copperpour not_allowed)
			(footprints allowed)
		)
		(placement
			(enabled no)
			(sheetname "")
		)
		(fill
			(thermal_gap 0.5)
			(thermal_bridge_width 0.5)
			(island_removal_mode 0)
		)
		(polygon
			(pts
				(arc
					(start 324.493636 -221.784164)
					(mid 323.983096 -222.294704)
					(end 324.493636 -222.805244)
				)
				(arc
					(start 325.306182 -222.805244)
					(mid 325.816976 -222.294831)
					(end 325.306436 -221.784164)
				)
				(xy 325.147686 -221.784164)
				(arc
					(start 325.147686 -221.7928)
					(mid 325.163465 -221.923189)
					(end 325.209916 -222.046038)
				)
				(arc
					(start 325.209916 -222.046038)
					(mid 325.476416 -222.500271)
					(end 325.080376 -222.153226)
				)
				(arc
					(start 325.080376 -222.153226)
					(mid 325.012189 -221.996407)
					(end 324.983348 -221.827852)
				)
				(xy 324.982586 -221.826836) (xy 324.982586 -221.784164) (xy 324.817486 -221.784164) (xy 324.817486 -221.82709)
				(arc
					(start 324.816724 -221.827852)
					(mid 324.787907 -221.996414)
					(end 324.719696 -222.153226)
				)
				(arc
					(start 324.719696 -222.153226)
					(mid 324.323694 -222.500225)
					(end 324.590156 -222.046038)
				)
				(arc
					(start 324.590156 -222.046038)
					(mid 324.63652 -221.92343)
					(end 324.652386 -221.793308)
				)
				(xy 324.652386 -221.784164)
			)
		)
	)
	(zone
		(layer "In2.Cu")
		(hatch none 0.5)
		(connect_pads
			(clearance 0)
		)
		(min_thickness 0.25)
		(keepout
			(tracks not_allowed)
			(vias allowed)
			(pads allowed)
			(copperpour not_allowed)
			(footprints allowed)
		)
		(placement
			(enabled no)
			(sheetname "")
		)
		(fill
			(thermal_gap 0.5)
			(thermal_bridge_width 0.5)
			(island_removal_mode 0)
		)
		(polygon
			(pts
				(arc
					(start 50.093372 -220.895164)
					(mid 49.582832 -221.405704)
					(end 50.093372 -221.916244)
				)
				(arc
					(start 50.905918 -221.916244)
					(mid 51.416712 -221.405831)
					(end 50.906172 -220.895164)
				)
				(xy 50.73015 -220.895164)
				(arc
					(start 50.73015 -221.03588)
					(mid 50.744409 -221.107187)
					(end 50.78476 -221.167706)
				)
				(arc
					(start 50.785014 -221.168214)
					(mid 51.094854 -221.59464)
					(end 50.668428 -221.2848)
				)
				(xy 50.64379 -221.260416)
				(arc
					(start 50.64379 -221.257622)
					(mid 50.591715 -221.170282)
					(end 50.566828 -221.071694)
				)
				(xy 50.56505 -221.069916) (xy 50.56505 -220.895164) (xy 50.39995 -220.895164) (xy 50.39995 -220.899228)
				(arc
					(start 50.399188 -220.89999)
					(mid 50.395828 -220.947747)
					(end 50.38979 -220.99524)
				)
				(arc
					(start 50.38979 -220.99524)
					(mid 50.359122 -221.124813)
					(end 50.30851 -221.24797)
				)
				(arc
					(start 50.30851 -221.24797)
					(mid 49.939131 -221.622929)
					(end 50.172112 -221.150942)
				)
				(arc
					(start 50.172112 -221.150942)
					(mid 50.205733 -221.062295)
					(end 50.226722 -220.96984)
				)
				(arc
					(start 50.226722 -220.96984)
					(mid 50.23143 -220.932603)
					(end 50.234088 -220.895164)
				)
			)
		)
	)
	(zone
		(layer "In2.Cu")
		(hatch none 0.5)
		(connect_pads
			(clearance 0)
		)
		(min_thickness 0.25)
		(keepout
			(tracks not_allowed)
			(vias allowed)
			(pads allowed)
			(copperpour not_allowed)
			(footprints allowed)
		)
		(placement
			(enabled no)
			(sheetname "")
		)
		(fill
			(thermal_gap 0.5)
			(thermal_bridge_width 0.5)
			(island_removal_mode 0)
		)
		(polygon
			(pts
				(arc
					(start 283.005276 -20.15617)
					(mid 282.284107 -20.118381)
					(end 282.246578 -20.83943)
				)
				(xy 282.244546 -20.841208)
				(arc
					(start 282.354782 -20.963636)
					(mid 282.439526 -20.855942)
					(end 282.500578 -20.733258)
				)
				(arc
					(start 282.500578 -20.733258)
					(mid 282.670743 -20.234929)
					(end 282.665678 -20.761452)
				)
				(arc
					(start 282.665678 -20.761452)
					(mid 282.584414 -20.935592)
					(end 282.465526 -21.086572)
				)
				(arc
					(start 282.575762 -21.209)
					(mid 282.686179 -21.140537)
					(end 282.804362 -21.086572)
				)
				(arc
					(start 282.804362 -21.086572)
					(mid 282.855485 -21.068574)
					(end 282.907486 -21.053298)
				)
				(arc
					(start 282.907486 -21.053298)
					(mid 283.434196 -21.065449)
					(end 282.930092 -21.218398)
				)
				(arc
					(start 282.930092 -21.218398)
					(mid 282.804194 -21.266018)
					(end 282.687268 -21.332698)
				)
				(xy 282.788614 -21.44522)
				(arc
					(start 282.790646 -21.443442)
					(mid 283.511498 -21.481034)
					(end 283.54909 -20.760182)
				)
				(xy 283.551122 -20.758404) (xy 283.007308 -20.154646) (xy 283.0068 -20.154646)
			)
		)
	)
	(zone
		(layer "In2.Cu")
		(hatch none 0.5)
		(connect_pads
			(clearance 0)
		)
		(min_thickness 0.25)
		(keepout
			(tracks allowed)
			(vias allowed)
			(pads allowed)
			(copperpour allowed)
			(footprints allowed)
		)
		(placement
			(enabled no)
			(sheetname "")
		)
		(fill
			(thermal_gap 0.5)
			(thermal_bridge_width 0.5)
			(island_removal_mode 0)
		)
		(polygon
			(pts
				(xy 309.108348 -19.959574) (xy 309.108348 -17.620234) (xy 311.921652 -17.620234) (xy 311.921652 -19.959574)
			)
		)
	)
	(zone
		(layer "In2.Cu")
		(hatch none 0.5)
		(connect_pads
			(clearance 0)
		)
		(min_thickness 0.25)
		(keepout
			(tracks not_allowed)
			(vias allowed)
			(pads allowed)
			(copperpour not_allowed)
			(footprints allowed)
		)
		(placement
			(enabled no)
			(sheetname "")
		)
		(fill
			(thermal_gap 0.5)
			(thermal_bridge_width 0.5)
			(island_removal_mode 0)
		)
		(polygon
			(pts
				(arc
					(start 50.144934 -208.201514)
					(mid 49.63414 -208.711927)
					(end 50.14468 -209.222594)
				)
				(arc
					(start 50.95748 -209.222594)
					(mid 51.46802 -208.712054)
					(end 50.95748 -208.201514)
				)
				(arc
					(start 50.799238 -208.201514)
					(mid 50.818574 -208.335175)
					(end 50.86604 -208.46161)
				)
				(arc
					(start 50.86604 -208.46161)
					(mid 51.123072 -208.921011)
					(end 50.734468 -208.56575)
				)
				(arc
					(start 50.734468 -208.56575)
					(mid 50.66381 -208.395457)
					(end 50.634392 -208.213452)
				)
				(xy 50.63363 -208.21269) (xy 50.63363 -208.201514)
				(arc
					(start 50.465736 -208.201514)
					(mid 50.432009 -208.384563)
					(end 50.361596 -208.55686)
				)
				(arc
					(start 50.361596 -208.55686)
					(mid 49.987908 -208.927392)
					(end 50.226468 -208.458308)
				)
				(arc
					(start 50.226468 -208.458308)
					(mid 50.274847 -208.333247)
					(end 50.299874 -208.201514)
				)
			)
		)
	)
	(zone
		(layer "In2.Cu")
		(hatch none 0.5)
		(connect_pads
			(clearance 0)
		)
		(min_thickness 0.25)
		(keepout
			(tracks not_allowed)
			(vias allowed)
			(pads allowed)
			(copperpour not_allowed)
			(footprints allowed)
		)
		(placement
			(enabled no)
			(sheetname "")
		)
		(fill
			(thermal_gap 0.5)
			(thermal_bridge_width 0.5)
			(island_removal_mode 0)
		)
		(polygon
			(pts
				(arc
					(start 201.69378 -221.784164)
					(mid 201.18324 -222.294704)
					(end 201.69378 -222.805244)
				)
				(arc
					(start 202.506326 -222.805244)
					(mid 203.01712 -222.294831)
					(end 202.50658 -221.784164)
				)
				(arc
					(start 202.351386 -221.784164)
					(mid 202.376447 -221.915887)
					(end 202.424792 -222.040958)
				)
				(arc
					(start 202.424792 -222.040958)
					(mid 202.66336 -222.510053)
					(end 202.289664 -222.13951)
				)
				(arc
					(start 202.289664 -222.13951)
					(mid 202.219266 -221.967209)
					(end 202.185524 -221.784164)
				)
				(arc
					(start 202.014836 -221.784164)
					(mid 201.981109 -221.967213)
					(end 201.910696 -222.13951)
				)
				(arc
					(start 201.910696 -222.13951)
					(mid 201.537008 -222.510042)
					(end 201.775568 -222.040958)
				)
				(arc
					(start 201.775568 -222.040958)
					(mid 201.823947 -221.915897)
					(end 201.848974 -221.784164)
				)
			)
		)
	)
	(zone
		(layer "In2.Cu")
		(hatch none 0.5)
		(connect_pads
			(clearance 0)
		)
		(min_thickness 0.25)
		(keepout
			(tracks not_allowed)
			(vias allowed)
			(pads allowed)
			(copperpour not_allowed)
			(footprints allowed)
		)
		(placement
			(enabled no)
			(sheetname "")
		)
		(fill
			(thermal_gap 0.5)
			(thermal_bridge_width 0.5)
			(island_removal_mode 0)
		)
		(polygon
			(pts
				(arc
					(start 177.5968 -220.16466)
					(mid 177.08626 -220.6752)
					(end 177.5968 -221.18574)
				)
				(arc
					(start 178.409346 -221.18574)
					(mid 178.92014 -220.675327)
					(end 178.4096 -220.16466)
				)
				(arc
					(start 178.254406 -220.16466)
					(mid 178.279467 -220.296383)
					(end 178.327812 -220.421454)
				)
				(arc
					(start 178.327812 -220.421454)
					(mid 178.56638 -220.890549)
					(end 178.192684 -220.520006)
				)
				(arc
					(start 178.192684 -220.520006)
					(mid 178.122286 -220.347705)
					(end 178.088544 -220.16466)
				)
				(arc
					(start 177.909728 -220.16466)
					(mid 177.870505 -220.340229)
					(end 177.80381 -220.507306)
				)
				(arc
					(start 177.80381 -220.507306)
					(mid 177.451933 -220.899329)
					(end 177.66411 -220.417136)
				)
				(arc
					(start 177.66411 -220.417136)
					(mid 177.712081 -220.293612)
					(end 177.742596 -220.16466)
				)
			)
		)
	)
	(zone
		(layer "In2.Cu")
		(hatch none 0.5)
		(connect_pads
			(clearance 0)
		)
		(min_thickness 0.25)
		(keepout
			(tracks not_allowed)
			(vias allowed)
			(pads allowed)
			(copperpour not_allowed)
			(footprints allowed)
		)
		(placement
			(enabled no)
			(sheetname "")
		)
		(fill
			(thermal_gap 0.5)
			(thermal_bridge_width 0.5)
			(island_removal_mode 0)
		)
		(polygon
			(pts
				(arc
					(start 305.726846 -32.72282)
					(mid 305.637043 -32.760017)
					(end 305.599846 -32.84982)
				)
				(arc
					(start 305.599846 -34.17062)
					(mid 305.637043 -34.260423)
					(end 305.726846 -34.29762)
				)
				(arc
					(start 307.022246 -34.29762)
					(mid 307.112049 -34.260423)
					(end 307.149246 -34.17062)
				)
				(arc
					(start 307.149246 -32.84982)
					(mid 307.112049 -32.760017)
					(end 307.022246 -32.72282)
				)
			)
		)
	)
	(zone
		(layer "In2.Cu")
		(hatch none 0.5)
		(connect_pads
			(clearance 0)
		)
		(min_thickness 0.25)
		(keepout
			(tracks not_allowed)
			(vias allowed)
			(pads allowed)
			(copperpour not_allowed)
			(footprints allowed)
		)
		(placement
			(enabled no)
			(sheetname "")
		)
		(fill
			(thermal_gap 0.5)
			(thermal_bridge_width 0.5)
			(island_removal_mode 0)
		)
		(polygon
			(pts
				(arc
					(start 99.693476 -221.784164)
					(mid 99.182936 -222.294704)
					(end 99.693476 -222.805244)
				)
				(arc
					(start 100.506022 -222.805244)
					(mid 101.016816 -222.294831)
					(end 100.506276 -221.784164)
				)
				(arc
					(start 100.351082 -221.784164)
					(mid 100.376143 -221.915887)
					(end 100.424488 -222.040958)
				)
				(arc
					(start 100.424488 -222.040958)
					(mid 100.663056 -222.510053)
					(end 100.28936 -222.13951)
				)
				(arc
					(start 100.28936 -222.13951)
					(mid 100.218962 -221.967209)
					(end 100.18522 -221.784164)
				)
				(arc
					(start 100.014532 -221.784164)
					(mid 99.980805 -221.967213)
					(end 99.910392 -222.13951)
				)
				(arc
					(start 99.910392 -222.13951)
					(mid 99.536704 -222.510042)
					(end 99.775264 -222.040958)
				)
				(arc
					(start 99.775264 -222.040958)
					(mid 99.823643 -221.915897)
					(end 99.84867 -221.784164)
				)
			)
		)
	)
	(zone
		(layer "In2.Cu")
		(hatch none 0.5)
		(connect_pads
			(clearance 0)
		)
		(min_thickness 0.25)
		(keepout
			(tracks not_allowed)
			(vias allowed)
			(pads allowed)
			(copperpour not_allowed)
			(footprints allowed)
		)
		(placement
			(enabled no)
			(sheetname "")
		)
		(fill
			(thermal_gap 0.5)
			(thermal_bridge_width 0.5)
			(island_removal_mode 0)
		)
		(polygon
			(pts
				(arc
					(start 340.493858 -221.784164)
					(mid 339.983064 -222.294577)
					(end 340.493604 -222.805244)
				)
				(arc
					(start 341.306404 -222.805244)
					(mid 341.816944 -222.294704)
					(end 341.306404 -221.784164)
				)
				(xy 341.147654 -221.784164)
				(arc
					(start 341.147654 -221.793308)
					(mid 341.163494 -221.923436)
					(end 341.209884 -222.046038)
				)
				(arc
					(start 341.209884 -222.046038)
					(mid 341.476384 -222.500271)
					(end 341.080344 -222.153226)
				)
				(arc
					(start 341.080344 -222.153226)
					(mid 341.012157 -221.996407)
					(end 340.983316 -221.827852)
				)
				(xy 340.982554 -221.82709) (xy 340.982554 -221.784164) (xy 340.817454 -221.784164) (xy 340.817454 -221.82709)
				(arc
					(start 340.816692 -221.827852)
					(mid 340.787875 -221.996414)
					(end 340.719664 -222.153226)
				)
				(arc
					(start 340.719664 -222.153226)
					(mid 340.323662 -222.500225)
					(end 340.590124 -222.046038)
				)
				(arc
					(start 340.590124 -222.046038)
					(mid 340.636488 -221.92343)
					(end 340.652354 -221.793308)
				)
				(xy 340.652354 -221.784164)
			)
		)
	)
	(zone
		(layer "In2.Cu")
		(hatch none 0.5)
		(connect_pads
			(clearance 0)
		)
		(min_thickness 0.25)
		(keepout
			(tracks not_allowed)
			(vias allowed)
			(pads allowed)
			(copperpour not_allowed)
			(footprints allowed)
		)
		(placement
			(enabled no)
			(sheetname "")
		)
		(fill
			(thermal_gap 0.5)
			(thermal_bridge_width 0.5)
			(island_removal_mode 0)
		)
		(polygon
			(pts
				(arc
					(start 146.493738 -221.784164)
					(mid 145.983198 -222.294704)
					(end 146.493738 -222.805244)
				)
				(arc
					(start 147.306284 -222.805244)
					(mid 147.817078 -222.294831)
					(end 147.306538 -221.784164)
				)
				(arc
					(start 147.15109 -221.784164)
					(mid 147.176143 -221.915891)
					(end 147.224496 -222.040958)
				)
				(arc
					(start 147.224496 -222.040958)
					(mid 147.463919 -222.509993)
					(end 147.089622 -222.13951)
				)
				(arc
					(start 147.089622 -222.13951)
					(mid 147.019106 -221.967221)
					(end 146.985228 -221.784164)
				)
				(xy 146.817588 -221.784164) (xy 146.817588 -222.00489)
				(arc
					(start 146.815302 -222.007176)
					(mid 146.796066 -222.0786)
					(end 146.758914 -222.142558)
				)
				(xy 146.758914 -222.14586) (xy 146.735292 -222.169482) (xy 146.734784 -222.170244)
				(arc
					(start 146.731228 -222.173546)
					(mid 146.304802 -222.483386)
					(end 146.614642 -222.05696)
				)
				(arc
					(start 146.618452 -222.05315)
					(mid 146.643599 -222.015233)
					(end 146.652488 -221.9706)
				)
				(xy 146.652488 -221.784164)
			)
		)
	)
	(zone
		(net "GND")
		(layer "In2.Cu")
		(hatch none 0.5)
		(connect_pads
			(clearance 0.5)
		)
		(min_thickness 0.25)
		(fill yes
			(thermal_gap 0.5)
			(thermal_bridge_width 0.5)
			(island_removal_mode 0)
		)
		(polygon
			(pts
				(xy 64.451484 -167.955976) (xy 88.288368 -167.955976) (xy 135.831834 -120.41251) (xy 135.831834 -117.50294)
				(xy 132.033772 -113.704878) (xy 99.239578 -113.704878) (xy 81.858866 -131.085336) (xy 80.732122 -132.21208)
				(xy 80.732122 -150.975314) (xy 78.00975 -153.697686) (xy 66.7258 -153.697686) (xy 62.592712 -157.830774)
				(xy 62.592712 -166.097204)
			)
		)
	)
	(zone
		(layer "In2.Cu")
		(hatch none 0.5)
		(connect_pads
			(clearance 0)
		)
		(min_thickness 0.25)
		(keepout
			(tracks not_allowed)
			(vias allowed)
			(pads allowed)
			(copperpour not_allowed)
			(footprints allowed)
		)
		(placement
			(enabled no)
			(sheetname "")
		)
		(fill
			(thermal_gap 0.5)
			(thermal_bridge_width 0.5)
			(island_removal_mode 0)
		)
		(polygon
			(pts
				(arc
					(start 137.3251 -32.75584)
					(mid 137.235297 -32.793037)
					(end 137.1981 -32.88284)
				)
				(arc
					(start 137.1981 -34.20364)
					(mid 137.235297 -34.293443)
					(end 137.3251 -34.33064)
				)
				(arc
					(start 138.6205 -34.33064)
					(mid 138.710303 -34.293443)
					(end 138.7475 -34.20364)
				)
				(arc
					(start 138.7475 -32.88284)
					(mid 138.710303 -32.793037)
					(end 138.6205 -32.75584)
				)
			)
		)
	)
	(zone
		(layer "In2.Cu")
		(hatch none 0.5)
		(connect_pads
			(clearance 0)
		)
		(min_thickness 0.25)
		(keepout
			(tracks not_allowed)
			(vias allowed)
			(pads allowed)
			(copperpour not_allowed)
			(footprints allowed)
		)
		(placement
			(enabled no)
			(sheetname "")
		)
		(fill
			(thermal_gap 0.5)
			(thermal_bridge_width 0.5)
			(island_removal_mode 0)
		)
		(polygon
			(pts
				(arc
					(start 103.2383 -81.000854)
					(mid 102.626287 -80.38846)
					(end 102.01402 -81.0006)
				)
				(arc
					(start 102.01402 -82.1182)
					(mid 102.62616 -82.73034)
					(end 103.2383 -82.1182)
				)
				(xy 103.2383 -81.75625)
				(arc
					(start 103.07066 -81.75625)
					(mid 102.908791 -81.794462)
					(end 102.7811 -81.90103)
				)
				(arc
					(start 102.7811 -81.90103)
					(mid 102.55019 -82.3737)
					(end 102.616 -81.851754)
				)
				(arc
					(start 102.616 -81.851754)
					(mid 102.793473 -81.670008)
					(end 103.035354 -81.59242)
				)
				(xy 103.03637 -81.59115) (xy 103.2383 -81.59115) (xy 103.2383 -81.42605) (xy 102.930198 -81.42605)
				(arc
					(start 102.928674 -81.424526)
					(mid 102.765601 -81.376096)
					(end 102.63505 -81.267046)
				)
				(arc
					(start 102.63505 -81.267046)
					(mid 102.529141 -80.752395)
					(end 102.801166 -81.202022)
				)
				(arc
					(start 102.801166 -81.202022)
					(mid 102.877674 -81.24577)
					(end 102.964488 -81.26095)
				)
				(xy 103.2383 -81.26095)
			)
		)
	)
	(zone
		(layer "In2.Cu")
		(hatch none 0.5)
		(connect_pads
			(clearance 0)
		)
		(min_thickness 0.25)
		(keepout
			(tracks not_allowed)
			(vias allowed)
			(pads allowed)
			(copperpour not_allowed)
			(footprints allowed)
		)
		(placement
			(enabled no)
			(sheetname "")
		)
		(fill
			(thermal_gap 0.5)
			(thermal_bridge_width 0.5)
			(island_removal_mode 0)
		)
		(polygon
			(pts
				(arc
					(start 172.745654 -95.683832)
					(mid 172.23486 -96.194245)
					(end 172.7454 -96.704912)
				)
				(arc
					(start 173.6344 -96.704912)
					(mid 174.14494 -96.194372)
					(end 173.6344 -95.683832)
				)
				(xy 173.43755 -95.683832) (xy 173.43755 -95.880682) (xy 173.505876 -95.949262)
				(arc
					(start 173.513496 -95.956628)
					(mid 173.823 -96.382972)
					(end 173.396656 -96.073468)
				)
				(xy 173.32071 -95.997522) (xy 173.27245 -95.949262) (xy 173.27245 -95.880682) (xy 173.27245 -95.683832)
				(xy 173.10735 -95.683832) (xy 173.10735 -95.880682) (xy 173.10735 -95.949262) (xy 173.05909 -95.997522)
				(arc
					(start 172.983144 -96.073468)
					(mid 172.5568 -96.382972)
					(end 172.866304 -95.956628)
				)
				(xy 172.94225 -95.880682) (xy 172.94225 -95.683832)
			)
		)
	)
	(zone
		(layer "In2.Cu")
		(hatch none 0.5)
		(connect_pads
			(clearance 0)
		)
		(min_thickness 0.25)
		(keepout
			(tracks not_allowed)
			(vias allowed)
			(pads allowed)
			(copperpour not_allowed)
			(footprints allowed)
		)
		(placement
			(enabled no)
			(sheetname "")
		)
		(fill
			(thermal_gap 0.5)
			(thermal_bridge_width 0.5)
			(island_removal_mode 0)
		)
		(polygon
			(pts
				(arc
					(start 93.38945 -183.13146)
					(mid 92.87891 -183.642)
					(end 93.38945 -184.15254)
				)
				(arc
					(start 94.201996 -184.15254)
					(mid 94.71279 -183.642127)
					(end 94.20225 -183.13146)
				)
				(arc
					(start 94.046802 -183.13146)
					(mid 94.071881 -183.263178)
					(end 94.120208 -183.388254)
				)
				(arc
					(start 94.120208 -183.388254)
					(mid 94.359631 -183.857289)
					(end 93.985334 -183.486806)
				)
				(arc
					(start 93.985334 -183.486806)
					(mid 93.914828 -183.314513)
					(end 93.88094 -183.13146)
				)
				(arc
					(start 93.710506 -183.13146)
					(mid 93.676779 -183.314509)
					(end 93.606366 -183.486806)
				)
				(arc
					(start 93.606366 -183.486806)
					(mid 93.232678 -183.857338)
					(end 93.471238 -183.388254)
				)
				(arc
					(start 93.471238 -183.388254)
					(mid 93.519617 -183.263193)
					(end 93.544644 -183.13146)
				)
			)
		)
	)
	(zone
		(net "P3V3_STBY")
		(layer "In2.Cu")
		(hatch none 0.5)
		(connect_pads
			(clearance 0.5)
		)
		(min_thickness 0.25)
		(fill yes
			(thermal_gap 0.5)
			(thermal_bridge_width 0.5)
			(island_removal_mode 0)
		)
		(polygon
			(pts
				(xy 36.322 -206.502) (xy 47.117 -206.502) (xy 64.897 -188.722) (xy 77.851 -188.722) (xy 80.645 -188.722)
				(xy 81.153 -188.214) (xy 81.153 -185.039) (xy 80.137 -184.023) (xy 80.137 -178.181) (xy 80.137 -172.9232)
				(xy 78.7654 -171.5516) (xy 58.1406 -171.5516) (xy 55.9562 -173.736) (xy 45.212 -173.736) (xy 41.656 -173.736)
				(xy 36.449 -173.736) (xy 28.448 -181.737) (xy 28.448 -186.944) (xy 28.448 -187.833) (xy 28.448 -192.151)
				(xy 33.147 -196.85) (xy 33.147 -203.327)
			)
		)
	)
	(zone
		(layer "In2.Cu")
		(hatch none 0.5)
		(connect_pads
			(clearance 0)
		)
		(min_thickness 0.25)
		(keepout
			(tracks not_allowed)
			(vias allowed)
			(pads allowed)
			(copperpour not_allowed)
			(footprints allowed)
		)
		(placement
			(enabled no)
			(sheetname "")
		)
		(fill
			(thermal_gap 0.5)
			(thermal_bridge_width 0.5)
			(island_removal_mode 0)
		)
		(polygon
			(pts
				(arc
					(start 137.526014 -13.56487)
					(mid 137.477113 -13.359174)
					(end 137.404094 -13.160756)
				)
				(xy 137.37209 -13.091668) (xy 137.081514 -13.633958)
				(arc
					(start 137.083546 -13.635228)
					(mid 137.339578 -14.481048)
					(end 138.185398 -14.225016)
				)
				(xy 138.18743 -14.226286) (xy 138.937492 -12.826492) (xy 138.937238 -12.826238)
				(arc
					(start 138.935206 -12.825222)
					(mid 138.742055 -12.017696)
					(end 137.917428 -12.115038)
				)
				(arc
					(start 137.86993 -12.175744)
					(mid 137.850936 -12.204953)
					(end 137.833608 -12.23518)
				)
				(xy 137.831576 -12.23391)
				(arc
					(start 137.735564 -12.41298)
					(mid 137.714849 -12.573875)
					(end 137.742168 -12.733782)
				)
				(arc
					(start 137.742168 -12.733782)
					(mid 137.769965 -12.7831)
					(end 137.796524 -12.833096)
				)
				(arc
					(start 137.796524 -12.833096)
					(mid 137.828403 -12.897125)
					(end 137.858246 -12.962128)
				)
				(xy 137.858246 -12.962382) (xy 137.876026 -13.004038) (xy 137.888472 -13.016484)
				(arc
					(start 137.888472 -13.033756)
					(mid 138.03435 -13.174105)
					(end 138.236706 -13.18133)
				)
				(xy 138.24839 -13.169392)
				(arc
					(start 138.265408 -13.169392)
					(mid 138.385458 -13.063034)
					(end 138.428476 -12.908534)
				)
				(arc
					(start 138.428476 -12.908534)
					(mid 138.256957 -12.171066)
					(end 138.589258 -12.851384)
				)
				(arc
					(start 138.589258 -12.851384)
					(mid 138.537784 -13.129597)
					(end 138.329924 -13.321538)
				)
				(xy 138.316716 -13.334746)
				(arc
					(start 138.297666 -13.334746)
					(mid 137.970694 -13.326456)
					(end 137.736326 -13.098272)
				)
				(xy 137.723372 -13.085318) (xy 137.723372 -13.06703)
				(arc
					(start 137.706862 -13.028676)
					(mid 137.679232 -12.968282)
					(end 137.649712 -12.908788)
				)
				(arc
					(start 137.649712 -12.908788)
					(mid 137.623198 -12.858893)
					(end 137.595356 -12.809728)
				)
				(arc
					(start 137.588752 -12.794996)
					(mid 137.577694 -12.760204)
					(end 137.568432 -12.724892)
				)
				(xy 137.46607 -12.916154)
				(arc
					(start 137.5029 -12.984226)
					(mid 137.530058 -13.039057)
					(end 137.555478 -13.094716)
				)
				(arc
					(start 137.555478 -13.094716)
					(mid 137.637732 -13.319868)
					(end 137.691622 -13.55344)
				)
				(arc
					(start 137.691622 -13.55344)
					(mid 137.660754 -14.310207)
					(end 137.526014 -13.56487)
				)
			)
		)
	)
	(zone
		(layer "In2.Cu")
		(hatch none 0.5)
		(connect_pads
			(clearance 0)
		)
		(min_thickness 0.25)
		(keepout
			(tracks not_allowed)
			(vias allowed)
			(pads allowed)
			(copperpour not_allowed)
			(footprints allowed)
		)
		(placement
			(enabled no)
			(sheetname "")
		)
		(fill
			(thermal_gap 0.5)
			(thermal_bridge_width 0.5)
			(island_removal_mode 0)
		)
		(polygon
			(pts
				(arc
					(start 314.893706 -221.784164)
					(mid 314.383166 -222.294704)
					(end 314.893706 -222.805244)
				)
				(arc
					(start 315.706252 -222.805244)
					(mid 316.217046 -222.294831)
					(end 315.706506 -221.784164)
				)
				(xy 315.547756 -221.784164)
				(arc
					(start 315.547756 -221.793308)
					(mid 315.563596 -221.923436)
					(end 315.609986 -222.046038)
				)
				(arc
					(start 315.609986 -222.046038)
					(mid 315.876486 -222.500271)
					(end 315.480446 -222.153226)
				)
				(arc
					(start 315.480446 -222.153226)
					(mid 315.412259 -221.996407)
					(end 315.383418 -221.827852)
				)
				(xy 315.382656 -221.82709) (xy 315.382656 -221.784164) (xy 315.217556 -221.784164) (xy 315.217556 -221.82709)
				(arc
					(start 315.216794 -221.827852)
					(mid 315.187977 -221.996414)
					(end 315.119766 -222.153226)
				)
				(arc
					(start 315.119766 -222.153226)
					(mid 314.723764 -222.500225)
					(end 314.990226 -222.046038)
				)
				(arc
					(start 314.990226 -222.046038)
					(mid 315.03659 -221.92343)
					(end 315.052456 -221.793308)
				)
				(xy 315.052456 -221.784164)
			)
		)
	)
	(zone
		(layer "In2.Cu")
		(hatch none 0.5)
		(connect_pads
			(clearance 0)
		)
		(min_thickness 0.25)
		(keepout
			(tracks not_allowed)
			(vias allowed)
			(pads allowed)
			(copperpour not_allowed)
			(footprints allowed)
		)
		(placement
			(enabled no)
			(sheetname "")
		)
		(fill
			(thermal_gap 0.5)
			(thermal_bridge_width 0.5)
			(island_removal_mode 0)
		)
		(polygon
			(pts
				(arc
					(start 278.893778 -221.784164)
					(mid 278.383238 -222.294704)
					(end 278.893778 -222.805244)
				)
				(arc
					(start 279.706324 -222.805244)
					(mid 280.217118 -222.294831)
					(end 279.706578 -221.784164)
				)
				(xy 279.547828 -221.784164)
				(arc
					(start 279.547828 -221.793308)
					(mid 279.563668 -221.923436)
					(end 279.610058 -222.046038)
				)
				(arc
					(start 279.610058 -222.046038)
					(mid 279.876558 -222.500271)
					(end 279.480518 -222.153226)
				)
				(arc
					(start 279.480518 -222.153226)
					(mid 279.412331 -221.996407)
					(end 279.38349 -221.827852)
				)
				(xy 279.382728 -221.82709) (xy 279.382728 -221.784164) (xy 279.217628 -221.784164) (xy 279.217628 -221.82709)
				(arc
					(start 279.216866 -221.827852)
					(mid 279.188049 -221.996414)
					(end 279.119838 -222.153226)
				)
				(arc
					(start 279.119838 -222.153226)
					(mid 278.723836 -222.500225)
					(end 278.990298 -222.046038)
				)
				(arc
					(start 278.990298 -222.046038)
					(mid 279.036662 -221.92343)
					(end 279.052528 -221.793308)
				)
				(xy 279.052528 -221.784164)
			)
		)
	)
	(zone
		(layer "In2.Cu")
		(hatch none 0.5)
		(connect_pads
			(clearance 0)
		)
		(min_thickness 0.25)
		(keepout
			(tracks not_allowed)
			(vias allowed)
			(pads allowed)
			(copperpour not_allowed)
			(footprints allowed)
		)
		(placement
			(enabled no)
			(sheetname "")
		)
		(fill
			(thermal_gap 0.5)
			(thermal_bridge_width 0.5)
			(island_removal_mode 0)
		)
		(polygon
			(pts
				(arc
					(start 324.935342 -12.824968)
					(mid 324.67931 -11.979148)
					(end 323.83349 -12.23518)
				)
				(xy 323.831458 -12.23391) (xy 323.081396 -13.633704) (xy 323.08165 -13.633958)
				(arc
					(start 323.083682 -13.634974)
					(mid 323.339358 -14.480875)
					(end 324.18528 -14.225016)
				)
				(xy 324.187312 -14.226286) (xy 324.22465 -14.15669) (xy 324.22465 -13.971016) (xy 324.224396 -13.965428)
				(arc
					(start 324.224396 -13.961872)
					(mid 324.208756 -13.882682)
					(end 324.163944 -13.815568)
				)
				(arc
					(start 324.113144 -13.764768)
					(mid 324.104449 -13.756888)
					(end 324.09511 -13.749782)
				)
				(arc
					(start 324.09511 -13.749782)
					(mid 324.057434 -13.731069)
					(end 324.015862 -13.724636)
				)
				(arc
					(start 323.955156 -13.724636)
					(mid 323.383618 -14.216949)
					(end 323.795136 -13.584682)
				)
				(arc
					(start 323.795136 -13.584682)
					(mid 323.830605 -13.570735)
					(end 323.86778 -13.56233)
				)
				(xy 323.87032 -13.559536) (xy 324.050152 -13.559536)
				(arc
					(start 324.052184 -13.561822)
					(mid 324.124412 -13.579705)
					(end 324.190106 -13.614654)
				)
				(xy 324.202552 -13.624052) (xy 324.205854 -13.624052) (xy 324.22973 -13.647928) (xy 324.229984 -13.648182)
				(xy 324.28053 -13.698728) (xy 324.28053 -13.698982) (xy 324.30466 -13.722858)
				(arc
					(start 324.30466 -13.725398)
					(mid 324.34935 -13.793737)
					(end 324.378066 -13.870178)
				)
				(arc
					(start 324.476872 -13.685774)
					(mid 324.443292 -13.635553)
					(end 324.404482 -13.589254)
				)
				(arc
					(start 324.401688 -13.58646)
					(mid 324.335208 -13.492087)
					(end 324.303898 -13.380974)
				)
				(xy 324.301866 -13.379196)
				(arc
					(start 324.301866 -12.90193)
					(mid 324.384416 -12.149165)
					(end 324.466966 -12.90193)
				)
				(arc
					(start 324.466966 -13.344906)
					(mid 324.480423 -13.412558)
					(end 324.518782 -13.469874)
				)
				(xy 324.51929 -13.470382) (xy 324.521576 -13.472668)
				(arc
					(start 324.523862 -13.474954)
					(mid 324.544692 -13.498138)
					(end 324.564502 -13.522198)
				)
				(xy 324.937374 -12.826238)
			)
		)
	)
	(zone
		(net "P5V_STBY")
		(layer "In2.Cu")
		(hatch none 0.5)
		(connect_pads
			(clearance 0.5)
		)
		(min_thickness 0.25)
		(fill yes
			(thermal_gap 0.5)
			(thermal_bridge_width 0.5)
			(island_removal_mode 0)
		)
		(polygon
			(pts
				(xy 39.5478 -67.0814) (xy 41.275 -67.0814) (xy 43.12158 -67.0814) (xy 46.495208 -67.0814) (xy 47.7393 -68.325492)
				(xy 47.7393 -70.092062) (xy 47.827438 -70.1802) (xy 59.73572 -70.1802) (xy 76.8858 -70.1802) (xy 80.7212 -66.3448)
				(xy 83.7438 -66.3448) (xy 84.0867 -66.6877) (xy 84.0867 -72.2503) (xy 79.9846 -76.3524) (xy 78.486 -77.851)
				(xy 49.2506 -77.851) (xy 39.2684 -67.8688) (xy 39.2684 -67.3608)
			)
		)
	)
	(zone
		(layer "In2.Cu")
		(hatch none 0.5)
		(connect_pads
			(clearance 0)
		)
		(min_thickness 0.25)
		(keepout
			(tracks not_allowed)
			(vias allowed)
			(pads allowed)
			(copperpour not_allowed)
			(footprints allowed)
		)
		(placement
			(enabled no)
			(sheetname "")
		)
		(fill
			(thermal_gap 0.5)
			(thermal_bridge_width 0.5)
			(island_removal_mode 0)
		)
		(polygon
			(pts
				(arc
					(start 53.293518 -221.784164)
					(mid 52.782978 -222.294704)
					(end 53.293518 -222.805244)
				)
				(arc
					(start 54.106064 -222.805244)
					(mid 54.616858 -222.294831)
					(end 54.106318 -221.784164)
				)
				(arc
					(start 53.950616 -221.784164)
					(mid 53.975344 -221.916059)
					(end 54.023768 -222.041212)
				)
				(arc
					(start 54.023768 -222.041212)
					(mid 54.264101 -222.509593)
					(end 53.889148 -222.140018)
				)
				(arc
					(start 53.889148 -222.140018)
					(mid 53.818465 -221.967539)
					(end 53.785008 -221.784164)
				)
				(arc
					(start 53.614574 -221.784164)
					(mid 53.580847 -221.967213)
					(end 53.510434 -222.13951)
				)
				(arc
					(start 53.510434 -222.13951)
					(mid 53.136746 -222.510042)
					(end 53.375306 -222.040958)
				)
				(arc
					(start 53.375306 -222.040958)
					(mid 53.423685 -221.915897)
					(end 53.448712 -221.784164)
				)
			)
		)
	)
	(zone
		(layer "In2.Cu")
		(hatch none 0.5)
		(connect_pads
			(clearance 0)
		)
		(min_thickness 0.25)
		(keepout
			(tracks not_allowed)
			(vias allowed)
			(pads allowed)
			(copperpour not_allowed)
			(footprints allowed)
		)
		(placement
			(enabled no)
			(sheetname "")
		)
		(fill
			(thermal_gap 0.5)
			(thermal_bridge_width 0.5)
			(island_removal_mode 0)
		)
		(polygon
			(pts
				(xy 171.545758 -13.55725) (xy 171.541948 -13.55344) (xy 171.528232 -13.549122) (xy 171.51858 -13.530326)
				(xy 171.503594 -13.51534) (xy 171.503594 -13.501116) (xy 171.350432 -13.20292) (xy 171.339002 -13.194538)
				(xy 171.335446 -13.173456) (xy 171.32554 -13.15466) (xy 171.329858 -13.141198)
				(arc
					(start 171.289726 -12.899136)
					(mid 171.395406 -12.149202)
					(end 171.457874 -12.903962)
				)
				(xy 171.493942 -13.121132) (xy 171.633642 -13.393166) (xy 171.937426 -12.826238)
				(arc
					(start 171.935394 -12.824968)
					(mid 171.679362 -11.979148)
					(end 170.833542 -12.23518)
				)
				(xy 170.83151 -12.23391) (xy 170.081448 -13.633704) (xy 170.081702 -13.633958)
				(arc
					(start 170.083734 -13.634974)
					(mid 170.33941 -14.480875)
					(end 171.185332 -14.225016)
				)
				(xy 171.187364 -14.226286) (xy 171.38269 -13.861542)
				(arc
					(start 171.234862 -13.713714)
					(mid 171.087634 -13.646788)
					(end 170.932602 -13.692886)
				)
				(arc
					(start 170.932602 -13.692886)
					(mid 170.395993 -14.227377)
					(end 170.801284 -13.587476)
				)
				(xy 170.816016 -13.572744)
				(arc
					(start 170.818302 -13.572744)
					(mid 171.071794 -13.480991)
					(end 171.325286 -13.572744)
				)
				(xy 171.327572 -13.572744) (xy 171.464224 -13.709396)
			)
		)
	)
	(zone
		(layer "In2.Cu")
		(hatch none 0.5)
		(connect_pads
			(clearance 0)
		)
		(min_thickness 0.25)
		(keepout
			(tracks not_allowed)
			(vias allowed)
			(pads allowed)
			(copperpour not_allowed)
			(footprints allowed)
		)
		(placement
			(enabled no)
			(sheetname "")
		)
		(fill
			(thermal_gap 0.5)
			(thermal_bridge_width 0.5)
			(island_removal_mode 0)
		)
		(polygon
			(pts
				(arc
					(start 87.290148 -76.589636)
					(mid 86.779608 -76.079096)
					(end 86.269068 -76.589636)
				)
				(xy 86.269068 -76.786486) (xy 86.465918 -76.786486)
				(arc
					(start 86.541864 -76.71054)
					(mid 86.968208 -76.401036)
					(end 86.658704 -76.82738)
				)
				(xy 86.582758 -76.903326) (xy 86.534498 -76.951586) (xy 86.465918 -76.951586) (xy 86.269068 -76.951586)
				(xy 86.269068 -77.116686) (xy 86.465918 -77.116686) (xy 86.534498 -77.116686) (xy 86.582758 -77.164946)
				(arc
					(start 86.658704 -77.240892)
					(mid 86.968208 -77.667236)
					(end 86.541864 -77.357732)
				)
				(xy 86.465918 -77.281786) (xy 86.269068 -77.281786)
				(arc
					(start 86.269068 -77.478382)
					(mid 86.779481 -77.989176)
					(end 87.290148 -77.478636)
				)
			)
		)
	)
	(zone
		(layer "In2.Cu")
		(hatch none 0.5)
		(connect_pads
			(clearance 0)
		)
		(min_thickness 0.25)
		(keepout
			(tracks not_allowed)
			(vias allowed)
			(pads allowed)
			(copperpour not_allowed)
			(footprints allowed)
		)
		(placement
			(enabled no)
			(sheetname "")
		)
		(fill
			(thermal_gap 0.5)
			(thermal_bridge_width 0.5)
			(island_removal_mode 0)
		)
		(polygon
			(pts
				(arc
					(start 302.260508 -17.889982)
					(mid 302.21417 -17.715474)
					(end 302.114204 -17.565116)
				)
				(arc
					(start 302.114204 -17.564862)
					(mid 302.081262 -17.535654)
					(end 302.043338 -17.5133)
				)
				(arc
					(start 302.043338 -17.5133)
					(mid 301.989032 -17.495795)
					(end 301.932086 -17.492218)
				)
				(arc
					(start 301.932086 -17.492218)
					(mid 301.41256 -18.039685)
					(end 301.763684 -17.371568)
				)
				(arc
					(start 301.763684 -17.371568)
					(mid 301.937538 -17.326969)
					(end 302.113188 -17.363948)
				)
				(arc
					(start 302.113442 -17.363948)
					(mid 302.178528 -17.402431)
					(end 302.235108 -17.452594)
				)
				(arc
					(start 302.235108 -17.452594)
					(mid 302.315799 -17.556976)
					(end 302.376078 -17.674336)
				)
				(arc
					(start 302.471836 -17.49552)
					(mid 302.418529 -17.415035)
					(end 302.356774 -17.340834)
				)
				(xy 302.33366 -17.31772)
				(arc
					(start 302.33366 -17.316958)
					(mid 302.262696 -17.259245)
					(end 302.183292 -17.213834)
				)
				(arc
					(start 302.183292 -17.213834)
					(mid 302.127201 -17.191179)
					(end 302.068992 -17.174718)
				)
				(arc
					(start 302.068992 -17.174718)
					(mid 302.055864 -17.170559)
					(end 302.043592 -17.164304)
				)
				(arc
					(start 302.043592 -17.164304)
					(mid 301.825211 -16.900439)
					(end 301.810674 -16.55826)
				)
				(arc
					(start 301.810674 -16.55826)
					(mid 301.884244 -16.409716)
					(end 302.004984 -16.296132)
				)
				(arc
					(start 302.004984 -16.296132)
					(mid 302.760348 -16.267971)
					(end 302.036226 -16.4846)
				)
				(arc
					(start 302.036226 -16.4846)
					(mid 301.995878 -16.540456)
					(end 301.96917 -16.60398)
				)
				(arc
					(start 301.96917 -16.60398)
					(mid 301.976863 -16.835284)
					(end 302.119792 -17.017238)
				)
				(arc
					(start 302.119792 -17.017238)
					(mid 302.187751 -17.037588)
					(end 302.253396 -17.064482)
				)
				(arc
					(start 302.253396 -17.064482)
					(mid 302.372366 -17.134621)
					(end 302.4759 -17.226026)
				)
				(xy 302.499014 -17.24914)
				(arc
					(start 302.499014 -17.251934)
					(mid 302.530794 -17.290066)
					(end 302.560736 -17.329658)
				)
				(xy 302.937418 -16.626586)
				(arc
					(start 302.935132 -16.625316)
					(mid 302.679608 -15.779496)
					(end 301.833788 -16.03502)
				)
				(xy 301.831502 -16.03375) (xy 301.08144 -17.433544) (xy 301.081694 -17.433798)
				(arc
					(start 301.083726 -17.434814)
					(mid 301.33925 -18.280634)
					(end 302.18507 -18.02511)
				)
				(xy 302.187356 -18.02638)
			)
		)
	)
	(zone
		(layer "In2.Cu")
		(hatch none 0.5)
		(connect_pads
			(clearance 0)
		)
		(min_thickness 0.25)
		(keepout
			(tracks not_allowed)
			(vias allowed)
			(pads allowed)
			(copperpour not_allowed)
			(footprints allowed)
		)
		(placement
			(enabled no)
			(sheetname "")
		)
		(fill
			(thermal_gap 0.5)
			(thermal_bridge_width 0.5)
			(island_removal_mode 0)
		)
		(polygon
			(pts
				(arc
					(start 266.093702 -221.784164)
					(mid 265.583162 -222.294704)
					(end 266.093702 -222.805244)
				)
				(arc
					(start 266.906248 -222.805244)
					(mid 267.417042 -222.294831)
					(end 266.906502 -221.784164)
				)
				(xy 266.747752 -221.784164)
				(arc
					(start 266.747752 -221.793308)
					(mid 266.763592 -221.923436)
					(end 266.809982 -222.046038)
				)
				(arc
					(start 266.809982 -222.046038)
					(mid 267.076482 -222.500271)
					(end 266.680442 -222.153226)
				)
				(arc
					(start 266.680442 -222.153226)
					(mid 266.612255 -221.996407)
					(end 266.583414 -221.827852)
				)
				(xy 266.582652 -221.82709) (xy 266.582652 -221.784164) (xy 266.417552 -221.784164) (xy 266.417552 -221.82709)
				(arc
					(start 266.41679 -221.827852)
					(mid 266.387973 -221.996414)
					(end 266.319762 -222.153226)
				)
				(arc
					(start 266.319762 -222.153226)
					(mid 265.92376 -222.500225)
					(end 266.190222 -222.046038)
				)
				(arc
					(start 266.190222 -222.046038)
					(mid 266.236586 -221.92343)
					(end 266.252452 -221.793308)
				)
				(xy 266.252452 -221.784164)
			)
		)
	)
	(zone
		(layer "In2.Cu")
		(hatch none 0.5)
		(connect_pads
			(clearance 0)
		)
		(min_thickness 0.25)
		(keepout
			(tracks not_allowed)
			(vias allowed)
			(pads allowed)
			(copperpour not_allowed)
			(footprints allowed)
		)
		(placement
			(enabled no)
			(sheetname "")
		)
		(fill
			(thermal_gap 0.5)
			(thermal_bridge_width 0.5)
			(island_removal_mode 0)
		)
		(polygon
			(pts
				(arc
					(start 313.93511 -16.625316)
					(mid 313.679586 -15.779496)
					(end 312.833766 -16.03502)
				)
				(xy 312.83148 -16.03375) (xy 312.081418 -17.433544) (xy 312.081672 -17.433798)
				(arc
					(start 312.083704 -17.434814)
					(mid 312.339228 -18.280634)
					(end 313.185048 -18.02511)
				)
				(xy 313.187334 -18.02638) (xy 313.224672 -17.956784)
				(arc
					(start 313.224672 -17.853914)
					(mid 313.218196 -17.787886)
					(end 313.199018 -17.724374)
				)
				(arc
					(start 313.16422 -17.639792)
					(mid 313.153749 -17.619613)
					(end 313.14009 -17.601438)
				)
				(arc
					(start 313.14009 -17.601438)
					(mid 313.117002 -17.580536)
					(end 313.089798 -17.56537)
				)
				(arc
					(start 313.089798 -17.56537)
					(mid 313.078211 -17.561926)
					(end 313.066176 -17.560798)
				)
				(arc
					(start 313.026298 -17.560798)
					(mid 313.002061 -17.561949)
					(end 312.978038 -17.56537)
				)
				(arc
					(start 312.978038 -17.56537)
					(mid 312.338561 -17.970144)
					(end 312.866024 -17.427448)
				)
				(arc
					(start 312.866024 -17.427448)
					(mid 312.927101 -17.407592)
					(end 312.990484 -17.397222)
				)
				(xy 312.992008 -17.395698) (xy 313.100466 -17.395698)
				(arc
					(start 313.103514 -17.398746)
					(mid 313.128557 -17.404456)
					(end 313.15279 -17.41297)
				)
				(arc
					(start 313.15279 -17.41297)
					(mid 313.212967 -17.446209)
					(end 313.264042 -17.492218)
				)
				(arc
					(start 313.264042 -17.492218)
					(mid 313.283813 -17.517161)
					(end 313.300872 -17.544034)
				)
				(xy 313.303666 -17.545304) (xy 313.351418 -17.661128) (xy 313.351672 -17.661382) (xy 313.364626 -17.692624)
				(xy 313.363864 -17.694402) (xy 313.364372 -17.695926)
				(arc
					(start 313.466226 -17.505934)
					(mid 313.44006 -17.454731)
					(end 313.407806 -17.407128)
				)
				(xy 313.364372 -17.354296) (xy 313.365388 -17.343374) (xy 313.348116 -17.316958) (xy 313.347862 -17.31645)
				(xy 313.342782 -17.307052) (xy 313.334654 -17.29105)
				(arc
					(start 313.332622 -17.286986)
					(mid 313.313831 -17.235075)
					(end 313.303666 -17.180814)
				)
				(xy 313.301888 -17.179036)
				(arc
					(start 313.301888 -16.702024)
					(mid 313.384438 -15.949259)
					(end 313.466988 -16.702024)
				)
				(arc
					(start 313.466988 -17.145254)
					(mid 313.471227 -17.18323)
					(end 313.483498 -17.219422)
				)
				(xy 313.484514 -17.221962) (xy 313.487816 -17.228566) (xy 313.488324 -17.229328) (xy 313.490864 -17.2339)
				(xy 313.497976 -17.245076) (xy 313.540902 -17.297146) (xy 313.539886 -17.308068) (xy 313.558428 -17.333722)
				(xy 313.937396 -16.626586)
			)
		)
	)
	(zone
		(layer "In2.Cu")
		(hatch none 0.5)
		(connect_pads
			(clearance 0)
		)
		(min_thickness 0.25)
		(keepout
			(tracks not_allowed)
			(vias allowed)
			(pads allowed)
			(copperpour not_allowed)
			(footprints allowed)
		)
		(placement
			(enabled no)
			(sheetname "")
		)
		(fill
			(thermal_gap 0.5)
			(thermal_bridge_width 0.5)
			(island_removal_mode 0)
		)
		(polygon
			(pts
				(arc
					(start 304.326036 -220.118178)
					(mid 304.245824 -219.948109)
					(end 304.197512 -219.766388)
				)
				(arc
					(start 304.002186 -219.772484)
					(mid 303.968936 -219.939314)
					(end 303.91735 -220.101414)
				)
				(arc
					(start 303.91735 -220.101414)
					(mid 303.61751 -220.534712)
					(end 303.767998 -220.029786)
				)
				(arc
					(start 303.767998 -220.029786)
					(mid 303.807312 -219.905397)
					(end 303.834546 -219.777818)
				)
				(xy 303.717198 -219.781374)
				(arc
					(start 303.717198 -219.783914)
					(mid 303.222914 -220.310202)
					(end 303.749202 -220.804486)
				)
				(xy 303.749202 -220.807026) (xy 304.561748 -220.781626) (xy 304.562002 -220.781372)
				(arc
					(start 304.562002 -220.779086)
					(mid 305.056286 -220.252798)
					(end 304.529998 -219.758514)
				)
				(xy 304.529998 -219.755974)
				(arc
					(start 304.36439 -219.761054)
					(mid 304.401371 -219.892621)
					(end 304.45837 -220.016832)
				)
				(arc
					(start 304.45837 -220.016832)
					(mid 304.708412 -220.480179)
					(end 304.326036 -220.118178)
				)
			)
		)
	)
	(zone
		(layer "In2.Cu")
		(hatch none 0.5)
		(connect_pads
			(clearance 0)
		)
		(min_thickness 0.25)
		(keepout
			(tracks not_allowed)
			(vias allowed)
			(pads allowed)
			(copperpour not_allowed)
			(footprints allowed)
		)
		(placement
			(enabled no)
			(sheetname "")
		)
		(fill
			(thermal_gap 0.5)
			(thermal_bridge_width 0.5)
			(island_removal_mode 0)
		)
		(polygon
			(pts
				(xy 160.433004 -13.76807) (xy 160.514538 -13.61567) (xy 160.242758 -13.344144) (xy 160.218628 -13.320014)
				(arc
					(start 160.218628 -13.317982)
					(mid 160.139536 -13.189587)
					(end 160.104582 -13.0429)
				)
				(xy 160.103312 -13.04163) (xy 160.103312 -12.915138)
				(arc
					(start 160.104328 -12.914122)
					(mid 160.109993 -12.859145)
					(end 160.120584 -12.804902)
				)
				(arc
					(start 160.120584 -12.804902)
					(mid 160.577922 -12.201804)
					(end 160.271968 -12.894056)
				)
				(arc
					(start 160.271968 -12.894056)
					(mid 160.269344 -12.921687)
					(end 160.268412 -12.949428)
				)
				(arc
					(start 160.268412 -13.00734)
					(mid 160.292112 -13.126398)
					(end 160.359598 -13.227304)
				)
				(xy 160.595818 -13.463778) (xy 160.937448 -12.826238)
				(arc
					(start 160.935416 -12.824968)
					(mid 160.679384 -11.979148)
					(end 159.833564 -12.23518)
				)
				(xy 159.831532 -12.23391) (xy 159.08147 -13.633704) (xy 159.081724 -13.633958)
				(arc
					(start 159.083756 -13.634974)
					(mid 159.339432 -14.480875)
					(end 160.185354 -14.225016)
				)
				(xy 160.187386 -14.226286) (xy 160.35147 -13.919962)
				(arc
					(start 160.104836 -13.673582)
					(mid 159.988148 -13.610033)
					(end 159.855662 -13.619988)
				)
				(arc
					(start 159.855662 -13.619988)
					(mid 159.504408 -14.288453)
					(end 159.662622 -13.550138)
				)
				(arc
					(start 159.662622 -13.550138)
					(mid 159.92559 -13.43982)
					(end 160.19526 -13.532612)
				)
				(xy 160.197546 -13.532612)
			)
		)
	)
	(zone
		(layer "In2.Cu")
		(hatch none 0.5)
		(connect_pads
			(clearance 0)
		)
		(min_thickness 0.25)
		(keepout
			(tracks not_allowed)
			(vias allowed)
			(pads allowed)
			(copperpour not_allowed)
			(footprints allowed)
		)
		(placement
			(enabled no)
			(sheetname "")
		)
		(fill
			(thermal_gap 0.5)
			(thermal_bridge_width 0.5)
			(island_removal_mode 0)
		)
		(polygon
			(pts
				(arc
					(start 330.893674 -221.784164)
					(mid 330.383134 -222.294704)
					(end 330.893674 -222.805244)
				)
				(arc
					(start 331.70622 -222.805244)
					(mid 332.217014 -222.294831)
					(end 331.706474 -221.784164)
				)
				(xy 331.547724 -221.784164)
				(arc
					(start 331.547724 -221.793308)
					(mid 331.563564 -221.923436)
					(end 331.609954 -222.046038)
				)
				(arc
					(start 331.609954 -222.046038)
					(mid 331.876454 -222.500271)
					(end 331.480414 -222.153226)
				)
				(arc
					(start 331.480414 -222.153226)
					(mid 331.412227 -221.996407)
					(end 331.383386 -221.827852)
				)
				(xy 331.382624 -221.82709) (xy 331.382624 -221.784164) (xy 331.217524 -221.784164) (xy 331.217524 -221.82709)
				(arc
					(start 331.216762 -221.827852)
					(mid 331.187945 -221.996414)
					(end 331.119734 -222.153226)
				)
				(arc
					(start 331.119734 -222.153226)
					(mid 330.723732 -222.500225)
					(end 330.990194 -222.046038)
				)
				(arc
					(start 330.990194 -222.046038)
					(mid 331.036558 -221.92343)
					(end 331.052424 -221.793308)
				)
				(xy 331.052424 -221.784164)
			)
		)
	)
	(zone
		(layer "In2.Cu")
		(hatch none 0.5)
		(connect_pads
			(clearance 0)
		)
		(min_thickness 0.25)
		(keepout
			(tracks not_allowed)
			(vias allowed)
			(pads allowed)
			(copperpour not_allowed)
			(footprints allowed)
		)
		(placement
			(enabled no)
			(sheetname "")
		)
		(fill
			(thermal_gap 0.5)
			(thermal_bridge_width 0.5)
			(island_removal_mode 0)
		)
		(polygon
			(pts
				(arc
					(start 287.274 -32.766)
					(mid 287.236803 -32.676197)
					(end 287.147 -32.639)
				)
				(arc
					(start 285.8262 -32.639)
					(mid 285.736397 -32.676197)
					(end 285.6992 -32.766)
				)
				(arc
					(start 285.6992 -34.0614)
					(mid 285.736397 -34.151203)
					(end 285.8262 -34.1884)
				)
				(arc
					(start 287.147 -34.1884)
					(mid 287.236803 -34.151203)
					(end 287.274 -34.0614)
				)
			)
		)
	)
	(zone
		(layer "In2.Cu")
		(hatch none 0.5)
		(connect_pads
			(clearance 0)
		)
		(min_thickness 0.25)
		(keepout
			(tracks allowed)
			(vias allowed)
			(pads allowed)
			(copperpour allowed)
			(footprints allowed)
		)
		(placement
			(enabled no)
			(sheetname "")
		)
		(fill
			(thermal_gap 0.5)
			(thermal_bridge_width 0.5)
			(island_removal_mode 0)
		)
		(polygon
			(pts
				(xy 219.901008 -68.707) (xy 219.901008 -53.34) (xy 219.901008 -37.6428) (xy 219.901008 -27.559)
				(xy 219.926408 -27.559) (xy 219.926408 -25.2984) (xy 261.303008 -25.2984) (xy 261.303008 -27.559)
				(xy 261.303008 -68.707)
			)
		)
	)
	(zone
		(layer "In2.Cu")
		(hatch none 0.5)
		(connect_pads
			(clearance 0)
		)
		(min_thickness 0.25)
		(keepout
			(tracks not_allowed)
			(vias allowed)
			(pads allowed)
			(copperpour not_allowed)
			(footprints allowed)
		)
		(placement
			(enabled no)
			(sheetname "")
		)
		(fill
			(thermal_gap 0.5)
			(thermal_bridge_width 0.5)
			(island_removal_mode 0)
		)
		(polygon
			(pts
				(arc
					(start 78.16977 -219.371164)
					(mid 77.65923 -219.881704)
					(end 78.16977 -220.392244)
				)
				(arc
					(start 78.982316 -220.392244)
					(mid 79.49311 -219.881831)
					(end 78.98257 -219.371164)
				)
				(arc
					(start 78.827376 -219.371164)
					(mid 78.852437 -219.502887)
					(end 78.900782 -219.627958)
				)
				(arc
					(start 78.900782 -219.627958)
					(mid 79.13935 -220.097053)
					(end 78.765654 -219.72651)
				)
				(arc
					(start 78.765654 -219.72651)
					(mid 78.695256 -219.554209)
					(end 78.661514 -219.371164)
				)
				(arc
					(start 78.490826 -219.371164)
					(mid 78.457099 -219.554213)
					(end 78.386686 -219.72651)
				)
				(arc
					(start 78.386686 -219.72651)
					(mid 78.012998 -220.097042)
					(end 78.251558 -219.627958)
				)
				(arc
					(start 78.251558 -219.627958)
					(mid 78.299937 -219.502897)
					(end 78.324964 -219.371164)
				)
			)
		)
	)
	(zone
		(layer "In2.Cu")
		(hatch none 0.5)
		(connect_pads
			(clearance 0)
		)
		(min_thickness 0.25)
		(keepout
			(tracks not_allowed)
			(vias allowed)
			(pads allowed)
			(copperpour not_allowed)
			(footprints allowed)
		)
		(placement
			(enabled no)
			(sheetname "")
		)
		(fill
			(thermal_gap 0.5)
			(thermal_bridge_width 0.5)
			(island_removal_mode 0)
		)
		(polygon
			(pts
				(arc
					(start 143.293592 -221.784164)
					(mid 142.783052 -222.294704)
					(end 143.293592 -222.805244)
				)
				(arc
					(start 144.106138 -222.805244)
					(mid 144.616932 -222.294831)
					(end 144.106392 -221.784164)
				)
				(arc
					(start 143.951198 -221.784164)
					(mid 143.976259 -221.915887)
					(end 144.024604 -222.040958)
				)
				(arc
					(start 144.024604 -222.040958)
					(mid 144.263172 -222.510053)
					(end 143.889476 -222.13951)
				)
				(arc
					(start 143.889476 -222.13951)
					(mid 143.819078 -221.967209)
					(end 143.785336 -221.784164)
				)
				(arc
					(start 143.614648 -221.784164)
					(mid 143.580921 -221.967213)
					(end 143.510508 -222.13951)
				)
				(arc
					(start 143.510508 -222.13951)
					(mid 143.13682 -222.510042)
					(end 143.37538 -222.040958)
				)
				(arc
					(start 143.37538 -222.040958)
					(mid 143.423759 -221.915897)
					(end 143.448786 -221.784164)
				)
			)
		)
	)
	(zone
		(layer "In2.Cu")
		(hatch none 0.5)
		(connect_pads
			(clearance 0)
		)
		(min_thickness 0.25)
		(keepout
			(tracks not_allowed)
			(vias allowed)
			(pads allowed)
			(copperpour not_allowed)
			(footprints allowed)
		)
		(placement
			(enabled no)
			(sheetname "")
		)
		(fill
			(thermal_gap 0.5)
			(thermal_bridge_width 0.5)
			(island_removal_mode 0)
		)
		(polygon
			(pts
				(arc
					(start 327.693782 -221.784164)
					(mid 327.183242 -222.294704)
					(end 327.693782 -222.805244)
				)
				(arc
					(start 328.506328 -222.805244)
					(mid 329.017122 -222.294831)
					(end 328.506582 -221.784164)
				)
				(xy 328.347832 -221.784164)
				(arc
					(start 328.347832 -221.793308)
					(mid 328.363672 -221.923436)
					(end 328.410062 -222.046038)
				)
				(arc
					(start 328.410062 -222.046038)
					(mid 328.676562 -222.500271)
					(end 328.280522 -222.153226)
				)
				(arc
					(start 328.280522 -222.153226)
					(mid 328.212335 -221.996407)
					(end 328.183494 -221.827852)
				)
				(xy 328.182732 -221.82709) (xy 328.182732 -221.784164) (xy 328.017632 -221.784164) (xy 328.017632 -221.82709)
				(arc
					(start 328.01687 -221.827852)
					(mid 327.988053 -221.996414)
					(end 327.919842 -222.153226)
				)
				(arc
					(start 327.919842 -222.153226)
					(mid 327.52384 -222.500225)
					(end 327.790302 -222.046038)
				)
				(arc
					(start 327.790302 -222.046038)
					(mid 327.836666 -221.92343)
					(end 327.852532 -221.793308)
				)
				(xy 327.852532 -221.784164)
			)
		)
	)
	(zone
		(layer "In2.Cu")
		(hatch none 0.5)
		(connect_pads
			(clearance 0)
		)
		(min_thickness 0.25)
		(keepout
			(tracks not_allowed)
			(vias allowed)
			(pads allowed)
			(copperpour not_allowed)
			(footprints allowed)
		)
		(placement
			(enabled no)
			(sheetname "")
		)
		(fill
			(thermal_gap 0.5)
			(thermal_bridge_width 0.5)
			(island_removal_mode 0)
		)
		(polygon
			(pts
				(arc
					(start 22.417786 -56.076596)
					(mid 21.805646 -56.688736)
					(end 22.417786 -57.300876)
				)
				(xy 22.760686 -57.300876) (xy 22.760686 -57.121552)
				(arc
					(start 22.555962 -56.916828)
					(mid 22.229214 -56.500164)
					(end 22.645878 -56.826912)
				)
				(xy 22.850602 -57.031636) (xy 22.887686 -57.06872) (xy 22.887686 -57.121552) (xy 22.887686 -57.300876)
				(xy 23.065486 -57.300876) (xy 23.065486 -57.121552) (xy 23.065486 -57.06872) (xy 23.10257 -57.031636)
				(arc
					(start 23.307294 -56.826912)
					(mid 23.723958 -56.500164)
					(end 23.39721 -56.916828)
				)
				(xy 23.192486 -57.121552) (xy 23.192486 -57.300876)
				(arc
					(start 23.535386 -57.300876)
					(mid 24.147526 -56.688736)
					(end 23.535386 -56.076596)
				)
			)
		)
	)
	(zone
		(layer "In2.Cu")
		(hatch none 0.5)
		(connect_pads
			(clearance 0)
		)
		(min_thickness 0.25)
		(keepout
			(tracks not_allowed)
			(vias allowed)
			(pads allowed)
			(copperpour not_allowed)
			(footprints allowed)
		)
		(placement
			(enabled no)
			(sheetname "")
		)
		(fill
			(thermal_gap 0.5)
			(thermal_bridge_width 0.5)
			(island_removal_mode 0)
		)
		(polygon
			(pts
				(arc
					(start 140.0937 -221.784164)
					(mid 139.58316 -222.294704)
					(end 140.0937 -222.805244)
				)
				(arc
					(start 140.906246 -222.805244)
					(mid 141.41704 -222.294831)
					(end 140.9065 -221.784164)
				)
				(arc
					(start 140.751306 -221.784164)
					(mid 140.776367 -221.915887)
					(end 140.824712 -222.040958)
				)
				(arc
					(start 140.824712 -222.040958)
					(mid 141.06328 -222.510053)
					(end 140.689584 -222.13951)
				)
				(arc
					(start 140.689584 -222.13951)
					(mid 140.619186 -221.967209)
					(end 140.585444 -221.784164)
				)
				(arc
					(start 140.414756 -221.784164)
					(mid 140.381029 -221.967213)
					(end 140.310616 -222.13951)
				)
				(arc
					(start 140.310616 -222.13951)
					(mid 139.936928 -222.510042)
					(end 140.175488 -222.040958)
				)
				(arc
					(start 140.175488 -222.040958)
					(mid 140.223867 -221.915897)
					(end 140.248894 -221.784164)
				)
			)
		)
	)
	(zone
		(layer "In2.Cu")
		(hatch none 0.5)
		(connect_pads
			(clearance 0)
		)
		(min_thickness 0.25)
		(keepout
			(tracks not_allowed)
			(vias allowed)
			(pads allowed)
			(copperpour not_allowed)
			(footprints allowed)
		)
		(placement
			(enabled no)
			(sheetname "")
		)
		(fill
			(thermal_gap 0.5)
			(thermal_bridge_width 0.5)
			(island_removal_mode 0)
		)
		(polygon
			(pts
				(arc
					(start 16.846296 -86.808056)
					(mid 17.1558 -87.2344)
					(end 16.729456 -86.924896)
				)
				(xy 16.53921 -86.73465) (xy 16.49095 -86.68639) (xy 16.49095 -86.61781) (xy 16.49095 -86.43366)
				(xy 16.32585 -86.43366) (xy 16.32585 -86.61781) (xy 16.32585 -86.68639) (xy 16.27759 -86.73465)
				(arc
					(start 16.087344 -86.924896)
					(mid 15.661 -87.2344)
					(end 15.970504 -86.808056)
				)
				(xy 16.16075 -86.61781) (xy 16.16075 -86.43366)
				(arc
					(start 15.8496 -86.43366)
					(mid 15.23746 -87.0458)
					(end 15.8496 -87.65794)
				)
				(arc
					(start 16.9672 -87.65794)
					(mid 17.57934 -87.0458)
					(end 16.9672 -86.43366)
				)
				(xy 16.65605 -86.43366) (xy 16.65605 -86.61781)
			)
		)
	)
	(zone
		(net "DUT_VDDO")
		(layer "In2.Cu")
		(hatch none 0.5)
		(connect_pads
			(clearance 0.5)
		)
		(min_thickness 0.25)
		(fill yes
			(thermal_gap 0.5)
			(thermal_bridge_width 0.5)
			(island_removal_mode 0)
		)
		(polygon
			(pts
				(xy 237.998 -41.021) (xy 246.253 -41.021) (xy 246.38 -40.894) (xy 246.38 -38.354) (xy 245.745 -37.719)
				(xy 245.745 -33.274) (xy 246.253 -32.766) (xy 249.174 -32.766) (xy 249.301 -32.639) (xy 249.301 -32.131)
				(xy 249.047 -31.877) (xy 242.57 -31.877) (xy 242.316 -32.131) (xy 242.316 -36.83) (xy 241.3 -37.846)
				(xy 240.284 -37.846) (xy 239.395 -38.735) (xy 237.871 -38.735) (xy 237.49 -39.116) (xy 237.49 -40.513)
			)
		)
	)
	(zone
		(layer "In2.Cu")
		(hatch none 0.5)
		(connect_pads
			(clearance 0)
		)
		(min_thickness 0.25)
		(keepout
			(tracks not_allowed)
			(vias allowed)
			(pads allowed)
			(copperpour not_allowed)
			(footprints allowed)
		)
		(placement
			(enabled no)
			(sheetname "")
		)
		(fill
			(thermal_gap 0.5)
			(thermal_bridge_width 0.5)
			(island_removal_mode 0)
		)
		(polygon
			(pts
				(arc
					(start 270.05534 -5.305806)
					(mid 269.544927 -4.795012)
					(end 269.03426 -5.305552)
				)
				(xy 269.03426 -5.464302) (xy 269.26921 -5.464302)
				(arc
					(start 269.307056 -5.426456)
					(mid 269.7334 -5.116952)
					(end 269.423896 -5.543296)
				)
				(xy 269.38605 -5.581142) (xy 269.33779 -5.629402) (xy 269.26921 -5.629402) (xy 269.03426 -5.629402)
				(xy 269.03426 -5.794502) (xy 269.26921 -5.794502) (xy 269.33779 -5.794502) (xy 269.38605 -5.842762)
				(arc
					(start 269.423896 -5.880608)
					(mid 269.7334 -6.306952)
					(end 269.307056 -5.997448)
				)
				(xy 269.26921 -5.959602) (xy 269.03426 -5.959602)
				(arc
					(start 269.03426 -6.118352)
					(mid 269.5448 -6.628892)
					(end 270.05534 -6.118352)
				)
			)
		)
	)
	(zone
		(net "GND")
		(layer "In2.Cu")
		(hatch none 0.5)
		(connect_pads
			(clearance 0.5)
		)
		(min_thickness 0.25)
		(fill yes
			(thermal_gap 0.5)
			(thermal_bridge_width 0.5)
			(island_removal_mode 0)
		)
		(polygon
			(pts
				(arc
					(start 123.637548 4.236974)
					(mid 122.762871 3.874671)
					(end 122.400568 2.999994)
				)
				(arc
					(start 122.400568 1.999996)
					(mid 121.591301 0.046251)
					(end 119.637556 -0.763016)
				)
				(arc
					(start 53.950108 -0.763016)
					(mid 53.075431 -1.125319)
					(end 52.713128 -1.999996)
				)
				(arc
					(start 52.713128 -24.010112)
					(mid 51.903861 -25.963857)
					(end 49.950116 -26.773124)
				)
				(arc
					(start 1.999996 -26.773124)
					(mid 1.125319 -27.135427)
					(end 0.763016 -28.010104)
				)
				(arc
					(start 0.763016 -212.499956)
					(mid 0.832426 -212.667528)
					(end 0.999998 -212.736938)
				)
				(arc
					(start 25.4 -212.736938)
					(mid 25.772521 -212.770897)
					(end 26.13279 -212.871558)
				)
				(arc
					(start 26.13279 -211.549488)
					(mid 25.768909 -211.488423)
					(end 25.400508 -211.467954)
				)
				(xy 2.032 -211.467954) (xy 2.032 -105.537) (xy 2.032 -101.6254) (xy 4.699 -98.9584) (xy 4.699 -40.9194)
				(xy 12.08278 -33.53562) (xy 37.265864 -33.53562) (xy 38.238684 -32.5628) (xy 41.753536 -29.047948)
				(xy 46.257972 -29.047948) (xy 53.1495 -29.047948) (xy 54.89194 -27.305508) (xy 54.89194 -17.0688)
				(xy 57.404 -14.55674) (xy 66.68516 -14.55674) (xy 68.5165 -16.38808) (xy 68.5165 -27.16784) (xy 69.54266 -28.194)
				(xy 94.234 -28.194)
				(arc
					(start 120.486424 -1.941576)
					(mid 122.75424 -0.557903)
					(end 123.669044 1.936242)
				)
				(xy 123.643136 1.936242) (xy 123.606052 1.973326) (xy 123.606052 2.026158) (xy 123.643136 2.063242)
				(xy 123.669552 2.063242) (xy 123.669552 2.96799) (xy 125.759718 2.96799) (xy 125.759718 4.236974)
			)
		)
	)
	(zone
		(layer "In2.Cu")
		(hatch none 0.5)
		(connect_pads
			(clearance 0)
		)
		(min_thickness 0.25)
		(keepout
			(tracks not_allowed)
			(vias allowed)
			(pads allowed)
			(copperpour not_allowed)
			(footprints allowed)
		)
		(placement
			(enabled no)
			(sheetname "")
		)
		(fill
			(thermal_gap 0.5)
			(thermal_bridge_width 0.5)
			(island_removal_mode 0)
		)
		(polygon
			(pts
				(arc
					(start 291.935154 -16.625316)
					(mid 291.67963 -15.779496)
					(end 290.83381 -16.03502)
				)
				(xy 290.831524 -16.03375) (xy 290.081462 -17.433544) (xy 290.081716 -17.433798)
				(arc
					(start 290.083748 -17.434814)
					(mid 290.210027 -18.188484)
					(end 290.971224 -18.25625)
				)
				(arc
					(start 290.971224 -18.227548)
					(mid 290.954116 -18.108552)
					(end 290.904168 -17.999202)
				)
				(arc
					(start 290.904168 -17.999202)
					(mid 290.309368 -17.531575)
					(end 290.996878 -17.847564)
				)
				(arc
					(start 290.996878 -17.847564)
					(mid 291.078547 -17.973513)
					(end 291.125656 -18.116042)
				)
				(arc
					(start 291.125656 -18.116042)
					(mid 291.15736 -18.071874)
					(end 291.185092 -18.02511)
				)
				(xy 291.187378 -18.02638) (xy 291.301932 -17.812512)
				(arc
					(start 291.301932 -16.702024)
					(mid 291.384482 -15.949259)
					(end 291.467032 -16.702024)
				)
				(xy 291.467032 -17.50441) (xy 291.93744 -16.626586)
			)
		)
	)
	(zone
		(layer "In2.Cu")
		(hatch none 0.5)
		(connect_pads
			(clearance 0)
		)
		(min_thickness 0.25)
		(keepout
			(tracks not_allowed)
			(vias allowed)
			(pads allowed)
			(copperpour not_allowed)
			(footprints allowed)
		)
		(placement
			(enabled no)
			(sheetname "")
		)
		(fill
			(thermal_gap 0.5)
			(thermal_bridge_width 0.5)
			(island_removal_mode 0)
		)
		(polygon
			(pts
				(arc
					(start 294.893746 -221.784164)
					(mid 294.383206 -222.294704)
					(end 294.893746 -222.805244)
				)
				(arc
					(start 295.706292 -222.805244)
					(mid 296.217086 -222.294831)
					(end 295.706546 -221.784164)
				)
				(xy 295.547796 -221.784164)
				(arc
					(start 295.547796 -221.793308)
					(mid 295.563636 -221.923436)
					(end 295.610026 -222.046038)
				)
				(arc
					(start 295.610026 -222.046038)
					(mid 295.876526 -222.500271)
					(end 295.480486 -222.153226)
				)
				(arc
					(start 295.480486 -222.153226)
					(mid 295.412299 -221.996407)
					(end 295.383458 -221.827852)
				)
				(xy 295.382696 -221.82709) (xy 295.382696 -221.784164) (xy 295.217596 -221.784164) (xy 295.217596 -221.82709)
				(arc
					(start 295.216834 -221.827852)
					(mid 295.188017 -221.996414)
					(end 295.119806 -222.153226)
				)
				(arc
					(start 295.119806 -222.153226)
					(mid 294.723804 -222.500225)
					(end 294.990266 -222.046038)
				)
				(arc
					(start 294.990266 -222.046038)
					(mid 295.03663 -221.92343)
					(end 295.052496 -221.793308)
				)
				(xy 295.052496 -221.784164)
			)
		)
	)
	(zone
		(layer "In2.Cu")
		(hatch none 0.5)
		(connect_pads
			(clearance 0)
		)
		(min_thickness 0.25)
		(keepout
			(tracks not_allowed)
			(vias allowed)
			(pads allowed)
			(copperpour not_allowed)
			(footprints allowed)
		)
		(placement
			(enabled no)
			(sheetname "")
		)
		(fill
			(thermal_gap 0.5)
			(thermal_bridge_width 0.5)
			(island_removal_mode 0)
		)
		(polygon
			(pts
				(arc
					(start 132.358384 -41.605454)
					(mid 131.746371 -40.99306)
					(end 131.134104 -41.6052)
				)
				(xy 131.134104 -41.90365)
				(arc
					(start 131.390644 -41.90365)
					(mid 131.497785 -41.881752)
					(end 131.587748 -41.819576)
				)
				(arc
					(start 131.587748 -41.819576)
					(mid 131.824844 -41.350445)
					(end 131.756404 -41.871646)
				)
				(arc
					(start 131.756404 -41.871646)
					(mid 131.613858 -42.007507)
					(end 131.426204 -42.067226)
				)
				(xy 131.424934 -42.06875) (xy 131.134104 -42.06875) (xy 131.134104 -42.23385) (xy 131.40309 -42.23385)
				(arc
					(start 131.40436 -42.23512)
					(mid 131.610546 -42.302371)
					(end 131.763008 -42.456608)
				)
				(arc
					(start 131.763008 -42.456608)
					(mid 131.817409 -42.979796)
					(end 131.594098 -42.503598)
				)
				(arc
					(start 131.594098 -42.503598)
					(mid 131.493004 -42.426401)
					(end 131.3688 -42.39895)
				)
				(xy 131.134104 -42.39895)
				(arc
					(start 131.134104 -42.7228)
					(mid 131.746244 -43.33494)
					(end 132.358384 -42.7228)
				)
			)
		)
	)
	(zone
		(layer "In2.Cu")
		(hatch none 0.5)
		(connect_pads
			(clearance 0)
		)
		(min_thickness 0.25)
		(keepout
			(tracks not_allowed)
			(vias allowed)
			(pads allowed)
			(copperpour not_allowed)
			(footprints allowed)
		)
		(placement
			(enabled no)
			(sheetname "")
		)
		(fill
			(thermal_gap 0.5)
			(thermal_bridge_width 0.5)
			(island_removal_mode 0)
		)
		(polygon
			(pts
				(arc
					(start 135.1661 -32.75584)
					(mid 135.076297 -32.793037)
					(end 135.0391 -32.88284)
				)
				(arc
					(start 135.0391 -34.20364)
					(mid 135.076297 -34.293443)
					(end 135.1661 -34.33064)
				)
				(arc
					(start 136.4615 -34.33064)
					(mid 136.551303 -34.293443)
					(end 136.5885 -34.20364)
				)
				(arc
					(start 136.5885 -32.88284)
					(mid 136.551303 -32.793037)
					(end 136.4615 -32.75584)
				)
			)
		)
	)
	(zone
		(net "DUT_AVD_PCIE")
		(layer "In2.Cu")
		(hatch none 0.5)
		(connect_pads
			(clearance 0.5)
		)
		(min_thickness 0.25)
		(fill yes
			(thermal_gap 0.5)
			(thermal_bridge_width 0.5)
			(island_removal_mode 0)
		)
		(polygon
			(pts
				(xy 227.203 -60.96) (xy 254 -60.96) (xy 254.254 -60.706) (xy 254.254 -60.325) (xy 253.619 -59.69)
				(xy 253.619 -52.451) (xy 254 -52.07) (xy 254.254 -52.07) (xy 254.381 -51.943) (xy 254.381 -51.435)
				(xy 254.127 -51.181) (xy 253.873 -51.181) (xy 253.619 -50.927) (xy 253.619 -42.545) (xy 254.381 -41.783)
				(xy 254.381 -41.402) (xy 253.492 -40.513) (xy 253.492 -36.576) (xy 253.238 -36.322) (xy 251.968 -36.322)
				(xy 251.333 -36.957) (xy 251.333 -39.116) (xy 251.333 -40.767) (xy 250.317 -41.783) (xy 236.347 -41.783)
				(xy 236.347 -45.72) (xy 236.347 -45.847) (xy 236.22 -45.974) (xy 227.711 -45.974) (xy 227.457 -46.228)
				(xy 227.457 -50.8) (xy 226.949 -51.308) (xy 226.949 -51.689) (xy 227.457 -52.197) (xy 227.457 -59.563)
				(xy 226.822 -60.198) (xy 226.822 -60.579)
			)
		)
	)
	(zone
		(layer "In2.Cu")
		(hatch none 0.5)
		(connect_pads
			(clearance 0)
		)
		(min_thickness 0.25)
		(keepout
			(tracks not_allowed)
			(vias allowed)
			(pads allowed)
			(copperpour not_allowed)
			(footprints allowed)
		)
		(placement
			(enabled no)
			(sheetname "")
		)
		(fill
			(thermal_gap 0.5)
			(thermal_bridge_width 0.5)
			(island_removal_mode 0)
		)
		(polygon
			(pts
				(xy 169.210736 -17.516348) (xy 169.293794 -17.361408)
				(arc
					(start 169.097706 -17.143222)
					(mid 169.049666 -17.098222)
					(end 168.994582 -17.062196)
				)
				(xy 168.891458 -17.007078)
				(arc
					(start 168.890188 -17.00276)
					(mid 168.813807 -16.891549)
					(end 168.815766 -16.756634)
				)
				(xy 168.814496 -16.752316)
				(arc
					(start 168.886124 -16.618966)
					(mid 169.315087 -15.994412)
					(end 169.031412 -16.696944)
				)
				(arc
					(start 168.97604 -16.800322)
					(mid 168.971774 -16.843842)
					(end 168.999408 -16.877792)
				)
				(xy 169.071544 -16.916146) (xy 169.07256 -16.916654) (xy 169.10177 -16.932402)
				(arc
					(start 169.102278 -16.933926)
					(mid 169.151142 -16.968074)
					(end 169.196004 -17.007332)
				)
				(xy 169.197782 -17.007586) (xy 169.376598 -17.206722) (xy 169.687494 -16.626586)
				(arc
					(start 169.685208 -16.625316)
					(mid 169.429684 -15.779496)
					(end 168.583864 -16.03502)
				)
				(xy 168.581578 -16.03375) (xy 167.831516 -17.433544) (xy 167.83177 -17.433798)
				(arc
					(start 167.833802 -17.434814)
					(mid 168.089326 -18.280634)
					(end 168.935146 -18.02511)
				)
				(xy 168.937432 -18.02638) (xy 169.127932 -17.671034) (xy 168.852342 -17.364202) (xy 168.851326 -17.363186)
				(xy 168.84269 -17.363186) (xy 168.826688 -17.347184) (xy 168.783762 -17.32407) (xy 168.7703 -17.32407)
				(arc
					(start 168.756584 -17.310354)
					(mid 168.717452 -17.311655)
					(end 168.688258 -17.337786)
				)
				(arc
					(start 168.632886 -17.441164)
					(mid 168.204556 -18.065733)
					(end 168.487344 -17.363186)
				)
				(xy 168.558972 -17.229582)
				(arc
					(start 168.56329 -17.228312)
					(mid 168.674501 -17.151931)
					(end 168.809416 -17.15389)
				)
				(xy 168.81348 -17.15262) (xy 168.825418 -17.15897) (xy 168.839134 -17.15897) (xy 168.854882 -17.174718)
				(xy 168.897808 -17.197832) (xy 168.91127 -17.197832) (xy 168.926764 -17.213326) (xy 168.946068 -17.22374)
				(xy 168.947338 -17.228058) (xy 168.952164 -17.228312)
			)
		)
	)
	(zone
		(layer "In2.Cu")
		(hatch none 0.5)
		(connect_pads
			(clearance 0)
		)
		(min_thickness 0.25)
		(keepout
			(tracks not_allowed)
			(vias allowed)
			(pads allowed)
			(copperpour not_allowed)
			(footprints allowed)
		)
		(placement
			(enabled no)
			(sheetname "")
		)
		(fill
			(thermal_gap 0.5)
			(thermal_bridge_width 0.5)
			(island_removal_mode 0)
		)
		(polygon
			(pts
				(arc
					(start 280.761186 -17.965928)
					(mid 280.258647 -17.447516)
					(end 279.740106 -17.949926)
				)
				(xy 279.738328 -18.064226)
				(arc
					(start 279.794462 -18.064226)
					(mid 279.895548 -18.05507)
					(end 279.993344 -18.027904)
				)
				(arc
					(start 279.993344 -18.027904)
					(mid 280.472668 -17.810066)
					(end 280.086562 -18.168112)
				)
				(arc
					(start 280.086562 -18.168112)
					(mid 279.960802 -18.210089)
					(end 279.829514 -18.228564)
				)
				(xy 279.828752 -18.229326) (xy 279.735788 -18.229326) (xy 279.733248 -18.395188) (xy 279.74671 -18.395188)
				(arc
					(start 279.747472 -18.396204)
					(mid 279.94125 -18.437119)
					(end 280.113486 -18.534888)
				)
				(arc
					(start 280.113486 -18.534888)
					(mid 280.430148 -18.95572)
					(end 279.99817 -18.654522)
				)
				(arc
					(start 279.99817 -18.654522)
					(mid 279.871538 -18.587325)
					(end 279.730708 -18.560542)
				)
				(arc
					(start 279.72766 -18.762726)
					(mid 280.230326 -19.28114)
					(end 280.74874 -18.778474)
				)
			)
		)
	)
	(zone
		(layer "In2.Cu")
		(hatch none 0.5)
		(connect_pads
			(clearance 0)
		)
		(min_thickness 0.25)
		(keepout
			(tracks not_allowed)
			(vias allowed)
			(pads allowed)
			(copperpour not_allowed)
			(footprints allowed)
		)
		(placement
			(enabled no)
			(sheetname "")
		)
		(fill
			(thermal_gap 0.5)
			(thermal_bridge_width 0.5)
			(island_removal_mode 0)
		)
		(polygon
			(pts
				(arc
					(start 293.905178 -32.906716)
					(mid 293.815375 -32.943913)
					(end 293.778178 -33.033716)
				)
				(arc
					(start 293.778178 -34.354516)
					(mid 293.815375 -34.444319)
					(end 293.905178 -34.481516)
				)
				(arc
					(start 295.200578 -34.481516)
					(mid 295.290381 -34.444319)
					(end 295.327578 -34.354516)
				)
				(arc
					(start 295.327578 -33.033716)
					(mid 295.290381 -32.943913)
					(end 295.200578 -32.906716)
				)
			)
		)
	)
	(zone
		(net "DUT_VDDO")
		(layer "In2.Cu")
		(hatch none 0.5)
		(connect_pads
			(clearance 0.5)
		)
		(min_thickness 0.25)
		(fill yes
			(thermal_gap 0.5)
			(thermal_bridge_width 0.5)
			(island_removal_mode 0)
		)
		(polygon
			(pts
				(xy 139.868656 -83.882738) (xy 142.543022 -83.882738) (xy 142.755112 -83.670648) (xy 142.755112 -81.947258)
				(xy 142.489936 -81.682082) (xy 140.334238 -81.682082) (xy 139.765278 -81.113122) (xy 139.765278 -74.925174)
				(xy 139.253722 -74.413618) (xy 135.902192 -74.413618) (xy 135.6614 -74.65441) (xy 135.6614 -77.198982)
				(xy 135.6614 -79.675482)
			)
		)
	)
	(zone
		(net "GND")
		(layer "In2.Cu")
		(hatch none 0.5)
		(connect_pads
			(clearance 0.5)
		)
		(min_thickness 0.25)
		(fill yes
			(thermal_gap 0.5)
			(thermal_bridge_width 0.5)
			(island_removal_mode 0)
		)
		(polygon
			(pts
				(arc
					(start 115.599972 -211.467954)
					(mid 113.243912 -212.443866)
					(end 112.268 -214.799926)
				)
				(xy 112.268 -219.976192) (xy 112.181894 -220.003878) (xy 113.536984 -220.003878)
				(arc
					(start 113.536984 -214.799926)
					(mid 114.141219 -213.341173)
					(end 115.599972 -212.736938)
				)
				(arc
					(start 131.400042 -212.736938)
					(mid 132.858795 -213.341173)
					(end 133.46303 -214.799926)
				)
				(xy 133.46303 -220.003878) (xy 134.81812 -220.003878) (xy 134.732014 -219.976192)
				(arc
					(start 134.732014 -214.799926)
					(mid 133.756102 -212.443866)
					(end 131.400042 -211.467954)
				)
			)
		)
	)
	(zone
		(layer "In2.Cu")
		(hatch none 0.5)
		(connect_pads
			(clearance 0)
		)
		(min_thickness 0.25)
		(keepout
			(tracks not_allowed)
			(vias allowed)
			(pads allowed)
			(copperpour not_allowed)
			(footprints allowed)
		)
		(placement
			(enabled no)
			(sheetname "")
		)
		(fill
			(thermal_gap 0.5)
			(thermal_bridge_width 0.5)
			(island_removal_mode 0)
		)
		(polygon
			(pts
				(arc
					(start 65.293494 -221.784164)
					(mid 64.782954 -222.294704)
					(end 65.293494 -222.805244)
				)
				(arc
					(start 66.10604 -222.805244)
					(mid 66.616834 -222.294831)
					(end 66.106294 -221.784164)
				)
				(arc
					(start 65.9511 -221.784164)
					(mid 65.976161 -221.915887)
					(end 66.024506 -222.040958)
				)
				(arc
					(start 66.024506 -222.040958)
					(mid 66.263074 -222.510053)
					(end 65.889378 -222.13951)
				)
				(arc
					(start 65.889378 -222.13951)
					(mid 65.81898 -221.967209)
					(end 65.785238 -221.784164)
				)
				(arc
					(start 65.61455 -221.784164)
					(mid 65.580823 -221.967213)
					(end 65.51041 -222.13951)
				)
				(arc
					(start 65.51041 -222.13951)
					(mid 65.136722 -222.510042)
					(end 65.375282 -222.040958)
				)
				(arc
					(start 65.375282 -222.040958)
					(mid 65.423661 -221.915897)
					(end 65.448688 -221.784164)
				)
			)
		)
	)
	(zone
		(layer "In2.Cu")
		(hatch none 0.5)
		(connect_pads
			(clearance 0)
		)
		(min_thickness 0.25)
		(keepout
			(tracks not_allowed)
			(vias allowed)
			(pads allowed)
			(copperpour not_allowed)
			(footprints allowed)
		)
		(placement
			(enabled no)
			(sheetname "")
		)
		(fill
			(thermal_gap 0.5)
			(thermal_bridge_width 0.5)
			(island_removal_mode 0)
		)
		(polygon
			(pts
				(arc
					(start 288.493708 -221.784164)
					(mid 287.983168 -222.294704)
					(end 288.493708 -222.805244)
				)
				(arc
					(start 289.306254 -222.805244)
					(mid 289.817048 -222.294831)
					(end 289.306508 -221.784164)
				)
				(xy 289.147758 -221.784164)
				(arc
					(start 289.147758 -221.9452)
					(mid 289.157758 -222.004118)
					(end 289.18662 -222.056452)
				)
				(arc
					(start 289.18662 -222.056452)
					(mid 289.494702 -222.483701)
					(end 289.068764 -222.1738)
				)
				(xy 289.059112 -222.164148)
				(arc
					(start 289.059112 -222.161354)
					(mid 289.008722 -222.07672)
					(end 288.984436 -221.981268)
				)
				(xy 288.982658 -221.97949) (xy 288.982658 -221.784164) (xy 288.817558 -221.784164) (xy 288.817558 -221.82709)
				(arc
					(start 288.816796 -221.827852)
					(mid 288.787979 -221.996414)
					(end 288.719768 -222.153226)
				)
				(arc
					(start 288.719768 -222.153226)
					(mid 288.323766 -222.500225)
					(end 288.590228 -222.046038)
				)
				(arc
					(start 288.590228 -222.046038)
					(mid 288.636592 -221.92343)
					(end 288.652458 -221.793308)
				)
				(xy 288.652458 -221.784164)
			)
		)
	)
	(zone
		(layer "In2.Cu")
		(hatch none 0.5)
		(connect_pads
			(clearance 0)
		)
		(min_thickness 0.25)
		(keepout
			(tracks not_allowed)
			(vias allowed)
			(pads allowed)
			(copperpour not_allowed)
			(footprints allowed)
		)
		(placement
			(enabled no)
			(sheetname "")
		)
		(fill
			(thermal_gap 0.5)
			(thermal_bridge_width 0.5)
			(island_removal_mode 0)
		)
		(polygon
			(pts
				(arc
					(start 192.093596 -221.784164)
					(mid 191.583056 -222.294704)
					(end 192.093596 -222.805244)
				)
				(arc
					(start 192.906142 -222.805244)
					(mid 193.416936 -222.294831)
					(end 192.906396 -221.784164)
				)
				(arc
					(start 192.751202 -221.784164)
					(mid 192.776263 -221.915887)
					(end 192.824608 -222.040958)
				)
				(arc
					(start 192.824608 -222.040958)
					(mid 193.063176 -222.510053)
					(end 192.68948 -222.13951)
				)
				(arc
					(start 192.68948 -222.13951)
					(mid 192.619082 -221.967209)
					(end 192.58534 -221.784164)
				)
				(arc
					(start 192.414652 -221.784164)
					(mid 192.380925 -221.967213)
					(end 192.310512 -222.13951)
				)
				(arc
					(start 192.310512 -222.13951)
					(mid 191.936824 -222.510042)
					(end 192.175384 -222.040958)
				)
				(arc
					(start 192.175384 -222.040958)
					(mid 192.223763 -221.915897)
					(end 192.24879 -221.784164)
				)
			)
		)
	)
	(zone
		(layer "In2.Cu")
		(hatch none 0.5)
		(connect_pads
			(clearance 0)
		)
		(min_thickness 0.25)
		(keepout
			(tracks not_allowed)
			(vias allowed)
			(pads allowed)
			(copperpour not_allowed)
			(footprints allowed)
		)
		(placement
			(enabled no)
			(sheetname "")
		)
		(fill
			(thermal_gap 0.5)
			(thermal_bridge_width 0.5)
			(island_removal_mode 0)
		)
		(polygon
			(pts
				(arc
					(start 159.29356 -221.784164)
					(mid 158.78302 -222.294704)
					(end 159.29356 -222.805244)
				)
				(arc
					(start 160.106106 -222.805244)
					(mid 160.6169 -222.294831)
					(end 160.10636 -221.784164)
				)
				(arc
					(start 159.951166 -221.784164)
					(mid 159.976227 -221.915887)
					(end 160.024572 -222.040958)
				)
				(arc
					(start 160.024572 -222.040958)
					(mid 160.26314 -222.510053)
					(end 159.889444 -222.13951)
				)
				(arc
					(start 159.889444 -222.13951)
					(mid 159.819046 -221.967209)
					(end 159.785304 -221.784164)
				)
				(arc
					(start 159.614616 -221.784164)
					(mid 159.580889 -221.967213)
					(end 159.510476 -222.13951)
				)
				(arc
					(start 159.510476 -222.13951)
					(mid 159.136788 -222.510042)
					(end 159.375348 -222.040958)
				)
				(arc
					(start 159.375348 -222.040958)
					(mid 159.423727 -221.915897)
					(end 159.448754 -221.784164)
				)
			)
		)
	)
	(zone
		(layer "In2.Cu")
		(hatch none 0.5)
		(connect_pads
			(clearance 0)
		)
		(min_thickness 0.25)
		(keepout
			(tracks not_allowed)
			(vias allowed)
			(pads allowed)
			(copperpour not_allowed)
			(footprints allowed)
		)
		(placement
			(enabled no)
			(sheetname "")
		)
		(fill
			(thermal_gap 0.5)
			(thermal_bridge_width 0.5)
			(island_removal_mode 0)
		)
		(polygon
			(pts
				(arc
					(start 285.293562 -221.784164)
					(mid 284.783022 -222.294704)
					(end 285.293562 -222.805244)
				)
				(arc
					(start 286.106108 -222.805244)
					(mid 286.616902 -222.294831)
					(end 286.106362 -221.784164)
				)
				(xy 285.947612 -221.784164)
				(arc
					(start 285.947612 -221.793308)
					(mid 285.963452 -221.923436)
					(end 286.009842 -222.046038)
				)
				(arc
					(start 286.009842 -222.046038)
					(mid 286.276342 -222.500271)
					(end 285.880302 -222.153226)
				)
				(arc
					(start 285.880302 -222.153226)
					(mid 285.812115 -221.996407)
					(end 285.783274 -221.827852)
				)
				(xy 285.782512 -221.82709) (xy 285.782512 -221.784164) (xy 285.617412 -221.784164) (xy 285.617412 -221.82709)
				(arc
					(start 285.61665 -221.827852)
					(mid 285.587833 -221.996414)
					(end 285.519622 -222.153226)
				)
				(arc
					(start 285.519622 -222.153226)
					(mid 285.12362 -222.500225)
					(end 285.390082 -222.046038)
				)
				(arc
					(start 285.390082 -222.046038)
					(mid 285.436446 -221.92343)
					(end 285.452312 -221.793308)
				)
				(xy 285.452312 -221.784164)
			)
		)
	)
	(zone
		(layer "In2.Cu")
		(hatch none 0.5)
		(connect_pads
			(clearance 0)
		)
		(min_thickness 0.25)
		(keepout
			(tracks not_allowed)
			(vias allowed)
			(pads allowed)
			(copperpour not_allowed)
			(footprints allowed)
		)
		(placement
			(enabled no)
			(sheetname "")
		)
		(fill
			(thermal_gap 0.5)
			(thermal_bridge_width 0.5)
			(island_removal_mode 0)
		)
		(polygon
			(pts
				(arc
					(start 262.893556 -221.784164)
					(mid 262.383016 -222.294704)
					(end 262.893556 -222.805244)
				)
				(arc
					(start 263.706102 -222.805244)
					(mid 264.216896 -222.294831)
					(end 263.706356 -221.784164)
				)
				(xy 263.547606 -221.784164)
				(arc
					(start 263.547606 -221.793308)
					(mid 263.563446 -221.923436)
					(end 263.609836 -222.046038)
				)
				(arc
					(start 263.609836 -222.046038)
					(mid 263.876336 -222.500271)
					(end 263.480296 -222.153226)
				)
				(arc
					(start 263.480296 -222.153226)
					(mid 263.412109 -221.996407)
					(end 263.383268 -221.827852)
				)
				(xy 263.382506 -221.82709) (xy 263.382506 -221.784164) (xy 263.217406 -221.784164) (xy 263.217406 -221.82709)
				(arc
					(start 263.216644 -221.827852)
					(mid 263.187827 -221.996414)
					(end 263.119616 -222.153226)
				)
				(arc
					(start 263.119616 -222.153226)
					(mid 262.723614 -222.500225)
					(end 262.990076 -222.046038)
				)
				(arc
					(start 262.990076 -222.046038)
					(mid 263.03644 -221.92343)
					(end 263.052306 -221.793308)
				)
				(xy 263.052306 -221.784164)
			)
		)
	)
	(zone
		(layer "In2.Cu")
		(hatch none 0.5)
		(connect_pads
			(clearance 0)
		)
		(min_thickness 0.25)
		(keepout
			(tracks not_allowed)
			(vias allowed)
			(pads allowed)
			(copperpour not_allowed)
			(footprints allowed)
		)
		(placement
			(enabled no)
			(sheetname "")
		)
		(fill
			(thermal_gap 0.5)
			(thermal_bridge_width 0.5)
			(island_removal_mode 0)
		)
		(polygon
			(pts
				(arc
					(start 156.093668 -221.784164)
					(mid 155.583128 -222.294704)
					(end 156.093668 -222.805244)
				)
				(arc
					(start 156.906214 -222.805244)
					(mid 157.417008 -222.294831)
					(end 156.906468 -221.784164)
				)
				(arc
					(start 156.751274 -221.784164)
					(mid 156.776335 -221.915887)
					(end 156.82468 -222.040958)
				)
				(arc
					(start 156.82468 -222.040958)
					(mid 157.063248 -222.510053)
					(end 156.689552 -222.13951)
				)
				(arc
					(start 156.689552 -222.13951)
					(mid 156.619154 -221.967209)
					(end 156.585412 -221.784164)
				)
				(arc
					(start 156.414724 -221.784164)
					(mid 156.380997 -221.967213)
					(end 156.310584 -222.13951)
				)
				(arc
					(start 156.310584 -222.13951)
					(mid 155.936896 -222.510042)
					(end 156.175456 -222.040958)
				)
				(arc
					(start 156.175456 -222.040958)
					(mid 156.223835 -221.915897)
					(end 156.248862 -221.784164)
				)
			)
		)
	)
	(zone
		(layer "In2.Cu")
		(hatch none 0.5)
		(connect_pads
			(clearance 0)
		)
		(min_thickness 0.25)
		(keepout
			(tracks not_allowed)
			(vias allowed)
			(pads allowed)
			(copperpour not_allowed)
			(footprints allowed)
		)
		(placement
			(enabled no)
			(sheetname "")
		)
		(fill
			(thermal_gap 0.5)
			(thermal_bridge_width 0.5)
			(island_removal_mode 0)
		)
		(polygon
			(pts
				(arc
					(start 148.496528 -13.57503)
					(mid 148.444144 -13.362222)
					(end 148.377656 -13.15339)
				)
				(xy 148.361908 -13.110718) (xy 148.081492 -13.633704) (xy 148.081746 -13.633958)
				(arc
					(start 148.083778 -13.634974)
					(mid 148.339454 -14.480875)
					(end 149.185376 -14.225016)
				)
				(xy 149.187408 -14.226286) (xy 149.93747 -12.826238)
				(arc
					(start 149.935438 -12.824968)
					(mid 149.679406 -11.979148)
					(end 148.833586 -12.23518)
				)
				(xy 148.831554 -12.23391)
				(arc
					(start 148.650198 -12.572492)
					(mid 148.753204 -12.766795)
					(end 148.837904 -12.969748)
				)
				(xy 148.84908 -12.98067)
				(arc
					(start 148.84908 -12.999974)
					(mid 148.991066 -13.151254)
					(end 149.197822 -13.168884)
				)
				(xy 149.207982 -13.158724)
				(arc
					(start 149.227286 -13.158724)
					(mid 149.352498 -13.060169)
					(end 149.40661 -12.910312)
				)
				(arc
					(start 149.40661 -12.910312)
					(mid 149.278119 -12.164016)
					(end 149.57171 -12.862052)
				)
				(arc
					(start 149.57171 -12.862052)
					(mid 149.502724 -13.132803)
					(end 149.2885 -13.31214)
				)
				(xy 149.276816 -13.323824)
				(arc
					(start 149.255734 -13.323824)
					(mid 148.924177 -13.302367)
					(end 148.695664 -13.061188)
				)
				(xy 148.68398 -13.049504)
				(arc
					(start 148.68398 -13.029438)
					(mid 148.625828 -12.885119)
					(end 148.557742 -12.745212)
				)
				(arc
					(start 148.461984 -12.923774)
					(mid 148.49954 -13.010081)
					(end 148.533104 -13.098018)
				)
				(arc
					(start 148.533104 -13.098018)
					(mid 148.604316 -13.321783)
					(end 148.660104 -13.549884)
				)
				(arc
					(start 148.660104 -13.549884)
					(mid 148.692481 -14.306802)
					(end 148.496528 -13.57503)
				)
			)
		)
	)
	(zone
		(layer "In2.Cu")
		(hatch none 0.5)
		(connect_pads
			(clearance 0)
		)
		(min_thickness 0.25)
		(keepout
			(tracks not_allowed)
			(vias allowed)
			(pads allowed)
			(copperpour not_allowed)
			(footprints allowed)
		)
		(placement
			(enabled no)
			(sheetname "")
		)
		(fill
			(thermal_gap 0.5)
			(thermal_bridge_width 0.5)
			(island_removal_mode 0)
		)
		(polygon
			(pts
				(arc
					(start 168.093644 -221.784164)
					(mid 167.583104 -222.294704)
					(end 168.093644 -222.805244)
				)
				(arc
					(start 168.90619 -222.805244)
					(mid 169.416984 -222.294831)
					(end 168.906444 -221.784164)
				)
				(arc
					(start 168.75125 -221.784164)
					(mid 168.776311 -221.915887)
					(end 168.824656 -222.040958)
				)
				(arc
					(start 168.824656 -222.040958)
					(mid 169.063224 -222.510053)
					(end 168.689528 -222.13951)
				)
				(arc
					(start 168.689528 -222.13951)
					(mid 168.61913 -221.967209)
					(end 168.585388 -221.784164)
				)
				(arc
					(start 168.4147 -221.784164)
					(mid 168.380973 -221.967213)
					(end 168.31056 -222.13951)
				)
				(arc
					(start 168.31056 -222.13951)
					(mid 167.936872 -222.510042)
					(end 168.175432 -222.040958)
				)
				(arc
					(start 168.175432 -222.040958)
					(mid 168.223811 -221.915897)
					(end 168.248838 -221.784164)
				)
			)
		)
	)
	(zone
		(layer "In2.Cu")
		(hatch none 0.5)
		(connect_pads
			(clearance 0)
		)
		(min_thickness 0.25)
		(keepout
			(tracks not_allowed)
			(vias allowed)
			(pads allowed)
			(copperpour not_allowed)
			(footprints allowed)
		)
		(placement
			(enabled no)
			(sheetname "")
		)
		(fill
			(thermal_gap 0.5)
			(thermal_bridge_width 0.5)
			(island_removal_mode 0)
		)
		(polygon
			(pts
				(arc
					(start 337.293712 -221.784164)
					(mid 336.783172 -222.294704)
					(end 337.293712 -222.805244)
				)
				(arc
					(start 338.106258 -222.805244)
					(mid 338.617052 -222.294831)
					(end 338.106512 -221.784164)
				)
				(xy 337.947762 -221.784164)
				(arc
					(start 337.947762 -221.793308)
					(mid 337.963602 -221.923436)
					(end 338.009992 -222.046038)
				)
				(arc
					(start 338.009992 -222.046038)
					(mid 338.276492 -222.500271)
					(end 337.880452 -222.153226)
				)
				(arc
					(start 337.880452 -222.153226)
					(mid 337.812265 -221.996407)
					(end 337.783424 -221.827852)
				)
				(xy 337.782662 -221.82709) (xy 337.782662 -221.784164) (xy 337.617562 -221.784164) (xy 337.617562 -221.82709)
				(arc
					(start 337.6168 -221.827852)
					(mid 337.587983 -221.996414)
					(end 337.519772 -222.153226)
				)
				(arc
					(start 337.519772 -222.153226)
					(mid 337.12377 -222.500225)
					(end 337.390232 -222.046038)
				)
				(arc
					(start 337.390232 -222.046038)
					(mid 337.436596 -221.92343)
					(end 337.452462 -221.793308)
				)
				(xy 337.452462 -221.784164)
			)
		)
	)
	(zone
		(layer "In2.Cu")
		(hatch none 0.5)
		(connect_pads
			(clearance 0)
		)
		(min_thickness 0.25)
		(keepout
			(tracks not_allowed)
			(vias allowed)
			(pads allowed)
			(copperpour not_allowed)
			(footprints allowed)
		)
		(placement
			(enabled no)
			(sheetname "")
		)
		(fill
			(thermal_gap 0.5)
			(thermal_bridge_width 0.5)
			(island_removal_mode 0)
		)
		(polygon
			(pts
				(arc
					(start 152.893776 -221.784164)
					(mid 152.383236 -222.294704)
					(end 152.893776 -222.805244)
				)
				(arc
					(start 153.706322 -222.805244)
					(mid 154.217116 -222.294831)
					(end 153.706576 -221.784164)
				)
				(arc
					(start 153.551382 -221.784164)
					(mid 153.576443 -221.915887)
					(end 153.624788 -222.040958)
				)
				(arc
					(start 153.624788 -222.040958)
					(mid 153.863356 -222.510053)
					(end 153.48966 -222.13951)
				)
				(arc
					(start 153.48966 -222.13951)
					(mid 153.419262 -221.967209)
					(end 153.38552 -221.784164)
				)
				(arc
					(start 153.214832 -221.784164)
					(mid 153.181105 -221.967213)
					(end 153.110692 -222.13951)
				)
				(arc
					(start 153.110692 -222.13951)
					(mid 152.737004 -222.510042)
					(end 152.975564 -222.040958)
				)
				(arc
					(start 152.975564 -222.040958)
					(mid 153.023943 -221.915897)
					(end 153.04897 -221.784164)
				)
			)
		)
	)
	(zone
		(layer "In2.Cu")
		(hatch none 0.5)
		(connect_pads
			(clearance 0)
		)
		(min_thickness 0.25)
		(keepout
			(tracks not_allowed)
			(vias allowed)
			(pads allowed)
			(copperpour not_allowed)
			(footprints allowed)
		)
		(placement
			(enabled no)
			(sheetname "")
		)
		(fill
			(thermal_gap 0.5)
			(thermal_bridge_width 0.5)
			(island_removal_mode 0)
		)
		(polygon
			(pts
				(arc
					(start 18.6944 -57.627266)
					(mid 18.08226 -58.239406)
					(end 18.6944 -58.851546)
				)
				(arc
					(start 19.812 -58.851546)
					(mid 20.42414 -58.239406)
					(end 19.812 -57.627266)
				)
				(xy 19.4691 -57.627266) (xy 19.4691 -57.80659)
				(arc
					(start 19.673824 -58.011314)
					(mid 20.000572 -58.427978)
					(end 19.583908 -58.10123)
				)
				(xy 19.379184 -57.896506) (xy 19.3421 -57.859422) (xy 19.3421 -57.80659) (xy 19.3421 -57.627266)
				(xy 19.1643 -57.627266) (xy 19.1643 -57.80659) (xy 19.1643 -57.859422) (xy 19.127216 -57.896506)
				(arc
					(start 18.922492 -58.10123)
					(mid 18.505828 -58.427978)
					(end 18.832576 -58.011314)
				)
				(xy 19.0373 -57.80659) (xy 19.0373 -57.627266)
			)
		)
	)
	(zone
		(layer "In2.Cu")
		(hatch none 0.5)
		(connect_pads
			(clearance 0)
		)
		(min_thickness 0.25)
		(keepout
			(tracks not_allowed)
			(vias allowed)
			(pads allowed)
			(copperpour not_allowed)
			(footprints allowed)
		)
		(placement
			(enabled no)
			(sheetname "")
		)
		(fill
			(thermal_gap 0.5)
			(thermal_bridge_width 0.5)
			(island_removal_mode 0)
		)
		(polygon
			(pts
				(arc
					(start 56.86298 -85.210904)
					(mid 56.250967 -84.59851)
					(end 55.6387 -85.21065)
				)
				(xy 55.6387 -85.5218)
				(arc
					(start 55.799228 -85.5218)
					(mid 55.9462 -85.491702)
					(end 56.069484 -85.40623)
				)
				(arc
					(start 56.069484 -85.40623)
					(mid 56.359502 -84.967064)
					(end 56.226456 -85.476334)
				)
				(arc
					(start 56.226456 -85.476334)
					(mid 56.053095 -85.623304)
					(end 55.834534 -85.68563)
				)
				(xy 55.833518 -85.6869) (xy 55.6387 -85.6869) (xy 55.6387 -85.852) (xy 55.833518 -85.852)
				(arc
					(start 55.834534 -85.85327)
					(mid 56.05309 -85.915605)
					(end 56.226456 -86.062566)
				)
				(arc
					(start 56.226456 -86.062566)
					(mid 56.359534 -86.571906)
					(end 56.069484 -86.13267)
				)
				(arc
					(start 56.069484 -86.13267)
					(mid 55.946186 -86.04723)
					(end 55.799228 -86.0171)
				)
				(xy 55.6387 -86.0171)
				(arc
					(start 55.6387 -86.32825)
					(mid 56.25084 -86.94039)
					(end 56.86298 -86.32825)
				)
			)
		)
	)
	(zone
		(layer "In2.Cu")
		(hatch none 0.5)
		(connect_pads
			(clearance 0)
		)
		(min_thickness 0.25)
		(keepout
			(tracks not_allowed)
			(vias allowed)
			(pads allowed)
			(copperpour not_allowed)
			(footprints allowed)
		)
		(placement
			(enabled no)
			(sheetname "")
		)
		(fill
			(thermal_gap 0.5)
			(thermal_bridge_width 0.5)
			(island_removal_mode 0)
		)
		(polygon
			(pts
				(arc
					(start 171.516548 -17.411954)
					(mid 171.355657 -17.069106)
					(end 171.282868 -16.697452)
				)
				(arc
					(start 171.282868 -16.697452)
					(mid 171.402824 -15.949613)
					(end 171.449238 -16.70558)
				)
				(arc
					(start 171.449238 -16.70558)
					(mid 171.501289 -16.98152)
					(end 171.607988 -17.241266)
				)
				(xy 171.937426 -16.626586)
				(arc
					(start 171.93514 -16.625316)
					(mid 171.679616 -15.779496)
					(end 170.833796 -16.03502)
				)
				(xy 170.83151 -16.03375) (xy 170.081448 -17.433544) (xy 170.081702 -17.433798)
				(arc
					(start 170.083734 -17.434814)
					(mid 170.339258 -18.280634)
					(end 171.185078 -18.02511)
				)
				(xy 171.187364 -18.02638)
				(arc
					(start 171.341796 -17.73809)
					(mid 171.30544 -17.689517)
					(end 171.270676 -17.639792)
				)
				(arc
					(start 171.270676 -17.639792)
					(mid 171.128617 -17.525995)
					(end 170.94708 -17.512284)
				)
				(arc
					(start 170.94708 -17.512284)
					(mid 170.384603 -18.017671)
					(end 170.80484 -17.389094)
				)
				(arc
					(start 170.80484 -17.389094)
					(mid 171.135803 -17.355007)
					(end 171.407328 -17.547336)
				)
				(xy 171.428156 -17.577308)
			)
		)
	)
	(zone
		(layer "In2.Cu")
		(hatch none 0.5)
		(connect_pads
			(clearance 0)
		)
		(min_thickness 0.25)
		(keepout
			(tracks not_allowed)
			(vias allowed)
			(pads allowed)
			(copperpour not_allowed)
			(footprints allowed)
		)
		(placement
			(enabled no)
			(sheetname "")
		)
		(fill
			(thermal_gap 0.5)
			(thermal_bridge_width 0.5)
			(island_removal_mode 0)
		)
		(polygon
			(pts
				(arc
					(start 195.293742 -221.784164)
					(mid 194.783202 -222.294704)
					(end 195.293742 -222.805244)
				)
				(arc
					(start 196.106288 -222.805244)
					(mid 196.617082 -222.294831)
					(end 196.106542 -221.784164)
				)
				(arc
					(start 195.951348 -221.784164)
					(mid 195.976409 -221.915887)
					(end 196.024754 -222.040958)
				)
				(arc
					(start 196.024754 -222.040958)
					(mid 196.263322 -222.510053)
					(end 195.889626 -222.13951)
				)
				(arc
					(start 195.889626 -222.13951)
					(mid 195.819228 -221.967209)
					(end 195.785486 -221.784164)
				)
				(arc
					(start 195.614798 -221.784164)
					(mid 195.581071 -221.967213)
					(end 195.510658 -222.13951)
				)
				(arc
					(start 195.510658 -222.13951)
					(mid 195.13697 -222.510042)
					(end 195.37553 -222.040958)
				)
				(arc
					(start 195.37553 -222.040958)
					(mid 195.423909 -221.915897)
					(end 195.448936 -221.784164)
				)
			)
		)
	)
	(zone
		(layer "In2.Cu")
		(hatch none 0.5)
		(connect_pads
			(clearance 0)
		)
		(min_thickness 0.25)
		(keepout
			(tracks not_allowed)
			(vias allowed)
			(pads allowed)
			(copperpour not_allowed)
			(footprints allowed)
		)
		(placement
			(enabled no)
			(sheetname "")
		)
		(fill
			(thermal_gap 0.5)
			(thermal_bridge_width 0.5)
			(island_removal_mode 0)
		)
		(polygon
			(pts
				(arc
					(start 20.447 -83.058)
					(mid 20.375158 -83.087758)
					(end 20.3454 -83.1596)
				)
				(arc
					(start 20.3454 -84.4804)
					(mid 20.375158 -84.552242)
					(end 20.447 -84.582)
				)
				(arc
					(start 21.717 -84.582)
					(mid 21.788842 -84.552242)
					(end 21.8186 -84.4804)
				)
				(arc
					(start 21.8186 -83.1596)
					(mid 21.788842 -83.087758)
					(end 21.717 -83.058)
				)
			)
		)
	)
	(zone
		(layer "In2.Cu")
		(hatch none 0.5)
		(connect_pads
			(clearance 0)
		)
		(min_thickness 0.25)
		(keepout
			(tracks not_allowed)
			(vias allowed)
			(pads allowed)
			(copperpour not_allowed)
			(footprints allowed)
		)
		(placement
			(enabled no)
			(sheetname "")
		)
		(fill
			(thermal_gap 0.5)
			(thermal_bridge_width 0.5)
			(island_removal_mode 0)
		)
		(polygon
			(pts
				(xy 160.51911 -17.407382) (xy 160.49498 -17.383506) (xy 160.49498 -17.38249) (xy 160.47974 -17.365726)
				(arc
					(start 160.476438 -17.361662)
					(mid 160.286599 -17.042606)
					(end 160.22574 -16.67637)
				)
				(arc
					(start 160.22574 -16.67637)
					(mid 160.463782 -15.957325)
					(end 160.390586 -16.711168)
				)
				(arc
					(start 160.390586 -16.711168)
					(mid 160.447456 -17.001293)
					(end 160.601406 -17.253712)
				)
				(xy 160.937448 -16.626586)
				(arc
					(start 160.935162 -16.625316)
					(mid 160.679638 -15.779496)
					(end 159.833818 -16.03502)
				)
				(xy 159.831532 -16.03375) (xy 159.08147 -17.433544) (xy 159.081724 -17.433798)
				(arc
					(start 159.083756 -17.434814)
					(mid 159.33928 -18.280634)
					(end 160.1851 -18.02511)
				)
				(xy 160.187386 -18.02638) (xy 160.356042 -17.711674) (xy 160.285684 -17.641316) (xy 160.284414 -17.640046)
				(xy 160.261554 -17.617186) (xy 160.261554 -17.616424)
				(arc
					(start 160.233614 -17.586198)
					(mid 160.097183 -17.499252)
					(end 159.935418 -17.496282)
				)
				(arc
					(start 159.935418 -17.496282)
					(mid 159.401024 -18.031166)
					(end 159.785558 -17.380204)
				)
				(arc
					(start 159.785558 -17.380204)
					(mid 160.087816 -17.327979)
					(end 160.35655 -17.475962)
				)
				(xy 160.401254 -17.523206) (xy 160.402524 -17.524476) (xy 160.437576 -17.559528) (xy 160.456372 -17.524476)
			)
		)
	)
	(zone
		(layer "In2.Cu")
		(hatch none 0.5)
		(connect_pads
			(clearance 0)
		)
		(min_thickness 0.25)
		(keepout
			(tracks not_allowed)
			(vias allowed)
			(pads allowed)
			(copperpour not_allowed)
			(footprints allowed)
		)
		(placement
			(enabled no)
			(sheetname "")
		)
		(fill
			(thermal_gap 0.5)
			(thermal_bridge_width 0.5)
			(island_removal_mode 0)
		)
		(polygon
			(pts
				(arc
					(start 158.685484 -12.824968)
					(mid 158.429452 -11.979148)
					(end 157.583632 -12.23518)
				)
				(xy 157.5816 -12.23391) (xy 156.831538 -13.633704) (xy 156.831792 -13.633958)
				(arc
					(start 156.833824 -13.634974)
					(mid 157.0895 -14.480875)
					(end 157.935422 -14.225016)
				)
				(xy 157.937454 -14.226286)
				(arc
					(start 158.027116 -14.0589)
					(mid 158.016834 -13.938203)
					(end 158.019242 -13.817092)
				)
				(arc
					(start 158.019242 -13.817092)
					(mid 158.008891 -13.726302)
					(end 157.96641 -13.645388)
				)
				(arc
					(start 157.96641 -13.645388)
					(mid 157.896254 -13.548001)
					(end 157.835092 -13.444728)
				)
				(xy 157.834584 -13.444474)
				(arc
					(start 157.715712 -13.206984)
					(mid 157.589222 -13.094525)
					(end 157.420056 -13.099796)
				)
				(xy 157.405832 -13.11402)
				(arc
					(start 157.392624 -13.11402)
					(mid 157.291423 -13.245415)
					(end 157.305502 -13.410692)
				)
				(xy 157.319726 -13.439394) (xy 157.322012 -13.44422) (xy 157.334966 -13.470128) (xy 157.334458 -13.471906)
				(xy 157.335728 -13.475462) (xy 157.33776 -13.476732) (xy 157.347412 -13.509498)
				(arc
					(start 157.35935 -13.549884)
					(mid 157.491951 -14.295819)
					(end 157.200854 -13.596366)
				)
				(arc
					(start 157.188916 -13.55598)
					(mid 157.182222 -13.536116)
					(end 157.17393 -13.516864)
				)
				(xy 157.158436 -13.485876) (xy 157.15742 -13.483844) (xy 157.143196 -13.455142)
				(arc
					(start 157.143958 -13.45311)
					(mid 157.14077 -13.17505)
					(end 157.322012 -12.96416)
				)
				(xy 157.337506 -12.948666)
				(arc
					(start 157.353508 -12.948666)
					(mid 157.628273 -12.933492)
					(end 157.846014 -13.101828)
				)
				(xy 157.848046 -13.10259)
				(arc
					(start 157.966918 -13.34008)
					(mid 158.02624 -13.444732)
					(end 158.09595 -13.542772)
				)
				(arc
					(start 158.09595 -13.543026)
					(mid 158.156383 -13.648404)
					(end 158.18358 -13.7668)
				)
				(arc
					(start 158.29661 -13.55598)
					(mid 158.264443 -13.496229)
					(end 158.22549 -13.440664)
				)
				(arc
					(start 158.22549 -13.44041)
					(mid 158.175057 -13.370676)
					(end 158.130748 -13.2969)
				)
				(xy 158.129732 -13.296646) (xy 158.02737 -13.091414)
				(arc
					(start 158.027878 -13.090144)
					(mid 157.992255 -12.985183)
					(end 157.974538 -12.875768)
				)
				(arc
					(start 157.974538 -12.875768)
					(mid 158.211267 -12.156943)
					(end 158.145226 -12.91082)
				)
				(arc
					(start 158.145226 -12.91082)
					(mid 158.162846 -12.981168)
					(end 158.190438 -13.048234)
				)
				(arc
					(start 158.26232 -13.192252)
					(mid 158.304919 -13.267662)
					(end 158.35503 -13.338302)
				)
				(arc
					(start 158.35503 -13.338302)
					(mid 158.372235 -13.360967)
					(end 158.388558 -13.384276)
				)
				(xy 158.687516 -12.826238)
			)
		)
	)
	(zone
		(layer "In2.Cu")
		(hatch none 0.5)
		(connect_pads
			(clearance 0)
		)
		(min_thickness 0.25)
		(keepout
			(tracks not_allowed)
			(vias allowed)
			(pads allowed)
			(copperpour not_allowed)
			(footprints allowed)
		)
		(placement
			(enabled no)
			(sheetname "")
		)
		(fill
			(thermal_gap 0.5)
			(thermal_bridge_width 0.5)
			(island_removal_mode 0)
		)
		(polygon
			(pts
				(arc
					(start 136.893554 -221.784164)
					(mid 136.383014 -222.294704)
					(end 136.893554 -222.805244)
				)
				(arc
					(start 137.7061 -222.805244)
					(mid 138.216894 -222.294831)
					(end 137.706354 -221.784164)
				)
				(arc
					(start 137.55116 -221.784164)
					(mid 137.576221 -221.915887)
					(end 137.624566 -222.040958)
				)
				(arc
					(start 137.624566 -222.040958)
					(mid 137.863134 -222.510053)
					(end 137.489438 -222.13951)
				)
				(arc
					(start 137.489438 -222.13951)
					(mid 137.41904 -221.967209)
					(end 137.385298 -221.784164)
				)
				(arc
					(start 137.21461 -221.784164)
					(mid 137.180883 -221.967213)
					(end 137.11047 -222.13951)
				)
				(arc
					(start 137.11047 -222.13951)
					(mid 136.736782 -222.510042)
					(end 136.975342 -222.040958)
				)
				(arc
					(start 136.975342 -222.040958)
					(mid 137.023721 -221.915897)
					(end 137.048748 -221.784164)
				)
			)
		)
	)
	(zone
		(layer "In2.Cu")
		(hatch none 0.5)
		(connect_pads
			(clearance 0)
		)
		(min_thickness 0.25)
		(keepout
			(tracks not_allowed)
			(vias allowed)
			(pads allowed)
			(copperpour not_allowed)
			(footprints allowed)
		)
		(placement
			(enabled no)
			(sheetname "")
		)
		(fill
			(thermal_gap 0.5)
			(thermal_bridge_width 0.5)
			(island_removal_mode 0)
		)
		(polygon
			(pts
				(arc
					(start 87.6935 -221.784164)
					(mid 87.18296 -222.294704)
					(end 87.6935 -222.805244)
				)
				(arc
					(start 88.506046 -222.805244)
					(mid 89.01684 -222.294831)
					(end 88.5063 -221.784164)
				)
				(arc
					(start 88.351106 -221.784164)
					(mid 88.376167 -221.915887)
					(end 88.424512 -222.040958)
				)
				(arc
					(start 88.424512 -222.040958)
					(mid 88.66308 -222.510053)
					(end 88.289384 -222.13951)
				)
				(arc
					(start 88.289384 -222.13951)
					(mid 88.218986 -221.967209)
					(end 88.185244 -221.784164)
				)
				(arc
					(start 88.014556 -221.784164)
					(mid 87.980829 -221.967213)
					(end 87.910416 -222.13951)
				)
				(arc
					(start 87.910416 -222.13951)
					(mid 87.536728 -222.510042)
					(end 87.775288 -222.040958)
				)
				(arc
					(start 87.775288 -222.040958)
					(mid 87.823667 -221.915897)
					(end 87.848694 -221.784164)
				)
			)
		)
	)
	(zone
		(layer "In2.Cu")
		(hatch none 0.5)
		(connect_pads
			(clearance 0)
		)
		(min_thickness 0.25)
		(keepout
			(tracks not_allowed)
			(vias allowed)
			(pads allowed)
			(copperpour not_allowed)
			(footprints allowed)
		)
		(placement
			(enabled no)
			(sheetname "")
		)
		(fill
			(thermal_gap 0.5)
			(thermal_bridge_width 0.5)
			(island_removal_mode 0)
		)
		(polygon
			(pts
				(arc
					(start 133.0071 -32.75584)
					(mid 132.917297 -32.793037)
					(end 132.8801 -32.88284)
				)
				(arc
					(start 132.8801 -34.20364)
					(mid 132.917297 -34.293443)
					(end 133.0071 -34.33064)
				)
				(arc
					(start 134.3025 -34.33064)
					(mid 134.392303 -34.293443)
					(end 134.4295 -34.20364)
				)
				(arc
					(start 134.4295 -32.88284)
					(mid 134.392303 -32.793037)
					(end 134.3025 -32.75584)
				)
			)
		)
	)
	(zone
		(layer "In2.Cu")
		(hatch none 0.5)
		(connect_pads
			(clearance 0)
		)
		(min_thickness 0.25)
		(keepout
			(tracks not_allowed)
			(vias allowed)
			(pads allowed)
			(copperpour not_allowed)
			(footprints allowed)
		)
		(placement
			(enabled no)
			(sheetname "")
		)
		(fill
			(thermal_gap 0.5)
			(thermal_bridge_width 0.5)
			(island_removal_mode 0)
		)
		(polygon
			(pts
				(xy 200.53935 -50.343562) (xy 200.70445 -50.342546) (xy 200.70445 -50.15611)
				(arc
					(start 200.70572 -50.15484)
					(mid 200.760819 -49.966082)
					(end 200.887838 -49.816004)
				)
				(xy 200.888092 -49.814226)
				(arc
					(start 200.910952 -49.798986)
					(mid 201.39029 -49.580115)
					(end 201.002392 -49.936654)
				)
				(arc
					(start 201.002392 -49.936654)
					(mid 200.904858 -50.047089)
					(end 200.86955 -50.190146)
				)
				(xy 200.86955 -50.34153)
				(arc
					(start 201.171302 -50.339752)
					(mid 201.780139 -49.724183)
					(end 201.164444 -49.115472)
				)
				(arc
					(start 200.046844 -49.122076)
					(mid 199.43826 -49.737772)
					(end 200.053956 -50.346356)
				)
				(xy 200.37425 -50.344578)
				(arc
					(start 200.37425 -50.243994)
					(mid 200.330895 -50.074502)
					(end 200.229978 -49.931574)
				)
				(arc
					(start 200.229978 -49.931574)
					(mid 199.817479 -49.604677)
					(end 200.312528 -49.783492)
				)
				(arc
					(start 200.312528 -49.783492)
					(mid 200.464497 -49.972477)
					(end 200.536302 -50.204116)
				)
				(xy 200.53935 -50.20691)
			)
		)
	)
	(zone
		(layer "In2.Cu")
		(hatch none 0.5)
		(connect_pads
			(clearance 0)
		)
		(min_thickness 0.25)
		(keepout
			(tracks not_allowed)
			(vias allowed)
			(pads allowed)
			(copperpour not_allowed)
			(footprints allowed)
		)
		(placement
			(enabled no)
			(sheetname "")
		)
		(fill
			(thermal_gap 0.5)
			(thermal_bridge_width 0.5)
			(island_removal_mode 0)
		)
		(polygon
			(pts
				(arc
					(start 204.893672 -221.784164)
					(mid 204.383132 -222.294704)
					(end 204.893672 -222.805244)
				)
				(arc
					(start 205.706218 -222.805244)
					(mid 206.217012 -222.294831)
					(end 205.706472 -221.784164)
				)
				(arc
					(start 205.551278 -221.784164)
					(mid 205.576339 -221.915887)
					(end 205.624684 -222.040958)
				)
				(arc
					(start 205.624684 -222.040958)
					(mid 205.863252 -222.510053)
					(end 205.489556 -222.13951)
				)
				(arc
					(start 205.489556 -222.13951)
					(mid 205.419158 -221.967209)
					(end 205.385416 -221.784164)
				)
				(arc
					(start 205.214728 -221.784164)
					(mid 205.181001 -221.967213)
					(end 205.110588 -222.13951)
				)
				(arc
					(start 205.110588 -222.13951)
					(mid 204.7369 -222.510042)
					(end 204.97546 -222.040958)
				)
				(arc
					(start 204.97546 -222.040958)
					(mid 205.023839 -221.915897)
					(end 205.048866 -221.784164)
				)
			)
		)
	)
	(zone
		(layer "In2.Cu")
		(hatch none 0.5)
		(connect_pads
			(clearance 0)
		)
		(min_thickness 0.25)
		(keepout
			(tracks not_allowed)
			(vias allowed)
			(pads allowed)
			(copperpour not_allowed)
			(footprints allowed)
		)
		(placement
			(enabled no)
			(sheetname "")
		)
		(fill
			(thermal_gap 0.5)
			(thermal_bridge_width 0.5)
			(island_removal_mode 0)
		)
		(polygon
			(pts
				(arc
					(start 26.74112 -142.580614)
					(mid 26.129107 -141.96822)
					(end 25.51684 -142.58036)
				)
				(xy 25.51684 -142.91945) (xy 25.67305 -142.91945)
				(arc
					(start 25.891236 -142.701264)
					(mid 26.31758 -142.39176)
					(end 26.008076 -142.818104)
				)
				(xy 25.78989 -143.03629) (xy 25.74163 -143.08455) (xy 25.67305 -143.08455) (xy 25.51684 -143.08455)
				(xy 25.51684 -143.24965) (xy 25.72893 -143.24965) (xy 25.79751 -143.24965) (xy 25.84577 -143.29791)
				(arc
					(start 26.008076 -143.460216)
					(mid 26.31758 -143.88656)
					(end 25.891236 -143.577056)
				)
				(xy 25.72893 -143.41475) (xy 25.51684 -143.41475)
				(arc
					(start 25.51684 -143.69796)
					(mid 26.12898 -144.3101)
					(end 26.74112 -143.69796)
				)
			)
		)
	)
	(zone
		(layer "In2.Cu")
		(hatch none 0.5)
		(connect_pads
			(clearance 0)
		)
		(min_thickness 0.25)
		(keepout
			(tracks not_allowed)
			(vias allowed)
			(pads allowed)
			(copperpour not_allowed)
			(footprints allowed)
		)
		(placement
			(enabled no)
			(sheetname "")
		)
		(fill
			(thermal_gap 0.5)
			(thermal_bridge_width 0.5)
			(island_removal_mode 0)
		)
		(polygon
			(pts
				(arc
					(start 300.493684 -221.784164)
					(mid 299.983144 -222.294704)
					(end 300.493684 -222.805244)
				)
				(arc
					(start 301.30623 -222.805244)
					(mid 301.817024 -222.294831)
					(end 301.306484 -221.784164)
				)
				(xy 301.147734 -221.784164)
				(arc
					(start 301.147734 -221.793308)
					(mid 301.163574 -221.923436)
					(end 301.209964 -222.046038)
				)
				(arc
					(start 301.209964 -222.046038)
					(mid 301.476464 -222.500271)
					(end 301.080424 -222.153226)
				)
				(arc
					(start 301.080424 -222.153226)
					(mid 301.012237 -221.996407)
					(end 300.983396 -221.827852)
				)
				(xy 300.982634 -221.82709) (xy 300.982634 -221.784164) (xy 300.817534 -221.784164) (xy 300.817534 -221.82709)
				(arc
					(start 300.816772 -221.827852)
					(mid 300.787955 -221.996414)
					(end 300.719744 -222.153226)
				)
				(arc
					(start 300.719744 -222.153226)
					(mid 300.323742 -222.500225)
					(end 300.590204 -222.046038)
				)
				(arc
					(start 300.590204 -222.046038)
					(mid 300.636568 -221.92343)
					(end 300.652434 -221.793308)
				)
				(xy 300.652434 -221.784164)
			)
		)
	)
	(zone
		(layer "In2.Cu")
		(hatch none 0.5)
		(connect_pads
			(clearance 0)
		)
		(min_thickness 0.25)
		(keepout
			(tracks not_allowed)
			(vias allowed)
			(pads allowed)
			(copperpour not_allowed)
			(footprints allowed)
		)
		(placement
			(enabled no)
			(sheetname "")
		)
		(fill
			(thermal_gap 0.5)
			(thermal_bridge_width 0.5)
			(island_removal_mode 0)
		)
		(polygon
			(pts
				(arc
					(start 271.19834 -8.353806)
					(mid 270.687927 -7.843012)
					(end 270.17726 -8.353552)
				)
				(xy 270.17726 -8.506968) (xy 270.417544 -8.506968)
				(arc
					(start 270.450056 -8.474456)
					(mid 270.8764 -8.164952)
					(end 270.566896 -8.591296)
				)
				(xy 270.534384 -8.623808) (xy 270.486124 -8.672068) (xy 270.417544 -8.672068) (xy 270.17726 -8.672068)
				(xy 270.17726 -8.837168) (xy 270.406876 -8.837168) (xy 270.475456 -8.837168) (xy 270.523716 -8.885428)
				(arc
					(start 270.566896 -8.928608)
					(mid 270.8764 -9.354952)
					(end 270.450056 -9.045448)
				)
				(xy 270.406876 -9.002268) (xy 270.17726 -9.002268)
				(arc
					(start 270.17726 -9.166352)
					(mid 270.6878 -9.676892)
					(end 271.19834 -9.166352)
				)
			)
		)
	)
	(zone
		(layer "In2.Cu")
		(hatch none 0.5)
		(connect_pads
			(clearance 0)
		)
		(min_thickness 0.25)
		(keepout
			(tracks not_allowed)
			(vias allowed)
			(pads allowed)
			(copperpour not_allowed)
			(footprints allowed)
		)
		(placement
			(enabled no)
			(sheetname "")
		)
		(fill
			(thermal_gap 0.5)
			(thermal_bridge_width 0.5)
			(island_removal_mode 0)
		)
		(polygon
			(pts
				(arc
					(start 68.493386 -221.784164)
					(mid 67.982846 -222.294704)
					(end 68.493386 -222.805244)
				)
				(arc
					(start 69.305932 -222.805244)
					(mid 69.816726 -222.294831)
					(end 69.306186 -221.784164)
				)
				(arc
					(start 69.150992 -221.784164)
					(mid 69.176053 -221.915887)
					(end 69.224398 -222.040958)
				)
				(arc
					(start 69.224398 -222.040958)
					(mid 69.462966 -222.510053)
					(end 69.08927 -222.13951)
				)
				(arc
					(start 69.08927 -222.13951)
					(mid 69.018872 -221.967209)
					(end 68.98513 -221.784164)
				)
				(arc
					(start 68.814442 -221.784164)
					(mid 68.780715 -221.967213)
					(end 68.710302 -222.13951)
				)
				(arc
					(start 68.710302 -222.13951)
					(mid 68.336614 -222.510042)
					(end 68.575174 -222.040958)
				)
				(arc
					(start 68.575174 -222.040958)
					(mid 68.623553 -221.915897)
					(end 68.64858 -221.784164)
				)
			)
		)
	)
	(zone
		(net "P3V3_STBY")
		(layer "In2.Cu")
		(hatch none 0.5)
		(connect_pads
			(clearance 0.5)
		)
		(min_thickness 0.25)
		(fill yes
			(thermal_gap 0.5)
			(thermal_bridge_width 0.5)
			(island_removal_mode 0)
		)
		(polygon
			(pts
				(xy 121.031 -208.915) (xy 135.255 -208.915) (xy 135.89 -208.28) (xy 135.89 -196.088) (xy 135.128 -195.326)
				(xy 134.366 -195.326) (xy 133.477 -196.215) (xy 133.35 -196.342) (xy 132.1562 -196.342) (xy 131.3688 -195.5546)
				(xy 131.3688 -194.9704) (xy 131.2672 -194.8688) (xy 130.6322 -194.8688) (xy 130.4798 -195.0212)
				(xy 130.4798 -195.8848) (xy 130.0226 -196.342) (xy 122.682 -196.342) (xy 121.666 -196.342) (xy 120.777 -197.231)
				(xy 120.777 -198.247) (xy 120.777 -208.661)
			)
		)
	)
	(zone
		(layer "In2.Cu")
		(hatch none 0.5)
		(connect_pads
			(clearance 0)
		)
		(min_thickness 0.25)
		(keepout
			(tracks not_allowed)
			(vias allowed)
			(pads allowed)
			(copperpour not_allowed)
			(footprints allowed)
		)
		(placement
			(enabled no)
			(sheetname "")
		)
		(fill
			(thermal_gap 0.5)
			(thermal_bridge_width 0.5)
			(island_removal_mode 0)
		)
		(polygon
			(pts
				(arc
					(start 71.7042 -219.50426)
					(mid 71.19366 -220.0148)
					(end 71.7042 -220.52534)
				)
				(arc
					(start 72.516746 -220.52534)
					(mid 73.02754 -220.014927)
					(end 72.517 -219.50426)
				)
				(arc
					(start 72.361806 -219.50426)
					(mid 72.386867 -219.635983)
					(end 72.435212 -219.761054)
				)
				(arc
					(start 72.435212 -219.761054)
					(mid 72.67378 -220.230149)
					(end 72.300084 -219.859606)
				)
				(arc
					(start 72.300084 -219.859606)
					(mid 72.229686 -219.687305)
					(end 72.195944 -219.50426)
				)
				(arc
					(start 72.025256 -219.50426)
					(mid 71.991529 -219.687309)
					(end 71.921116 -219.859606)
				)
				(arc
					(start 71.921116 -219.859606)
					(mid 71.547428 -220.230138)
					(end 71.785988 -219.761054)
				)
				(arc
					(start 71.785988 -219.761054)
					(mid 71.834367 -219.635993)
					(end 71.859394 -219.50426)
				)
			)
		)
	)
	(zone
		(layer "In2.Cu")
		(hatch none 0.5)
		(connect_pads
			(clearance 0)
		)
		(min_thickness 0.25)
		(keepout
			(tracks not_allowed)
			(vias allowed)
			(pads allowed)
			(copperpour not_allowed)
			(footprints allowed)
		)
		(placement
			(enabled no)
			(sheetname "")
		)
		(fill
			(thermal_gap 0.5)
			(thermal_bridge_width 0.5)
			(island_removal_mode 0)
		)
		(polygon
			(pts
				(xy 184.16778 -8.56488)
				(arc
					(start 184.205626 -8.527034)
					(mid 184.63197 -8.21753)
					(end 184.322466 -8.643874)
				)
				(xy 184.28462 -8.68172) (xy 184.28462 -8.91667)
				(arc
					(start 184.443116 -8.91667)
					(mid 184.95391 -8.406257)
					(end 184.44337 -7.89559)
				)
				(arc
					(start 183.63057 -7.89559)
					(mid 183.12003 -8.40613)
					(end 183.63057 -8.91667)
				)
				(xy 183.78932 -8.91667) (xy 183.78932 -8.68172)
				(arc
					(start 183.751474 -8.643874)
					(mid 183.44197 -8.21753)
					(end 183.868314 -8.527034)
				)
				(xy 183.90616 -8.56488) (xy 183.95442 -8.61314) (xy 183.95442 -8.68172) (xy 183.95442 -8.91667)
				(xy 184.11952 -8.91667) (xy 184.11952 -8.68172) (xy 184.11952 -8.61314)
			)
		)
	)
	(zone
		(layer "In2.Cu")
		(hatch none 0.5)
		(connect_pads
			(clearance 0)
		)
		(min_thickness 0.25)
		(keepout
			(tracks not_allowed)
			(vias allowed)
			(pads allowed)
			(copperpour not_allowed)
			(footprints allowed)
		)
		(placement
			(enabled no)
			(sheetname "")
		)
		(fill
			(thermal_gap 0.5)
			(thermal_bridge_width 0.5)
			(island_removal_mode 0)
		)
		(polygon
			(pts
				(arc
					(start 158.26359 -17.417796)
					(mid 158.056522 -17.07525)
					(end 157.986222 -16.681196)
				)
				(arc
					(start 157.986222 -16.681196)
					(mid 158.200845 -15.955185)
					(end 158.151576 -16.71066)
				)
				(arc
					(start 158.151576 -16.71066)
					(mid 158.205331 -17.001532)
					(end 158.347664 -17.260824)
				)
				(xy 158.687516 -16.626586)
				(arc
					(start 158.68523 -16.625316)
					(mid 158.429706 -15.779496)
					(end 157.583886 -16.03502)
				)
				(xy 157.5816 -16.03375) (xy 156.831538 -17.433544) (xy 156.831792 -17.433798)
				(arc
					(start 156.833824 -17.434814)
					(mid 157.089348 -18.280634)
					(end 157.935168 -18.02511)
				)
				(xy 157.937454 -18.02638) (xy 158.099506 -17.723866)
				(arc
					(start 157.964632 -17.588992)
					(mid 157.839913 -17.514775)
					(end 157.694884 -17.508982)
				)
				(arc
					(start 157.694884 -17.508982)
					(mid 157.139623 -18.021386)
					(end 157.549342 -17.386554)
				)
				(arc
					(start 157.549342 -17.386554)
					(mid 157.811608 -17.340837)
					(end 158.05531 -17.448022)
				)
				(xy 158.057342 -17.448022) (xy 158.18104 -17.57172)
			)
		)
	)
	(zone
		(layer "In2.Cu")
		(hatch none 0.5)
		(connect_pads
			(clearance 0)
		)
		(min_thickness 0.25)
		(keepout
			(tracks not_allowed)
			(vias allowed)
			(pads allowed)
			(copperpour not_allowed)
			(footprints allowed)
		)
		(placement
			(enabled no)
			(sheetname "")
		)
		(fill
			(thermal_gap 0.5)
			(thermal_bridge_width 0.5)
			(island_removal_mode 0)
		)
		(polygon
			(pts
				(xy 149.48154 -17.477486) (xy 149.299676 -17.29613) (xy 149.275546 -17.272)
				(arc
					(start 149.275546 -17.270222)
					(mid 149.179326 -17.115892)
					(end 149.138132 -16.938752)
				)
				(xy 149.137116 -16.937736) (xy 149.137116 -16.693896)
				(arc
					(start 149.138132 -16.693134)
					(mid 149.14083 -16.659768)
					(end 149.145244 -16.626586)
				)
				(arc
					(start 149.145244 -16.626586)
					(mid 149.549317 -15.986726)
					(end 149.302978 -16.702278)
				)
				(xy 149.302216 -16.728186)
				(arc
					(start 149.302216 -16.903446)
					(mid 149.331914 -17.052748)
					(end 149.416516 -17.17929)
				)
				(xy 149.533356 -17.29613) (xy 149.56282 -17.325594) (xy 149.93747 -16.626586)
				(arc
					(start 149.935184 -16.625316)
					(mid 149.67966 -15.779496)
					(end 148.83384 -16.03502)
				)
				(xy 148.831554 -16.03375) (xy 148.081492 -17.433544) (xy 148.081746 -17.433798)
				(arc
					(start 148.083778 -17.434814)
					(mid 148.339302 -18.280634)
					(end 149.185122 -18.02511)
				)
				(xy 149.187408 -18.02638)
				(arc
					(start 149.321012 -17.777206)
					(mid 149.263668 -17.765035)
					(end 149.205188 -17.76095)
				)
				(arc
					(start 149.01418 -17.76095)
					(mid 148.25714 -17.782803)
					(end 148.991066 -17.59585)
				)
				(xy 149.239478 -17.59585)
				(arc
					(start 149.240494 -17.596866)
					(mid 149.321517 -17.607523)
					(end 149.40026 -17.629378)
				)
			)
		)
	)
	(zone
		(layer "In2.Cu")
		(hatch none 0.5)
		(connect_pads
			(clearance 0)
		)
		(min_thickness 0.25)
		(keepout
			(tracks not_allowed)
			(vias allowed)
			(pads allowed)
			(copperpour not_allowed)
			(footprints allowed)
		)
		(placement
			(enabled no)
			(sheetname "")
		)
		(fill
			(thermal_gap 0.5)
			(thermal_bridge_width 0.5)
			(island_removal_mode 0)
		)
		(polygon
			(pts
				(arc
					(start 185.693812 -221.784164)
					(mid 185.183018 -222.294577)
					(end 185.693558 -222.805244)
				)
				(arc
					(start 186.506358 -222.805244)
					(mid 187.016898 -222.294704)
					(end 186.506358 -221.784164)
				)
				(arc
					(start 186.351164 -221.784164)
					(mid 186.376225 -221.915887)
					(end 186.42457 -222.040958)
				)
				(arc
					(start 186.42457 -222.040958)
					(mid 186.663138 -222.510053)
					(end 186.289442 -222.13951)
				)
				(arc
					(start 186.289442 -222.13951)
					(mid 186.219044 -221.967209)
					(end 186.185302 -221.784164)
				)
				(arc
					(start 186.014614 -221.784164)
					(mid 185.980887 -221.967213)
					(end 185.910474 -222.13951)
				)
				(arc
					(start 185.910474 -222.13951)
					(mid 185.536786 -222.510042)
					(end 185.775346 -222.040958)
				)
				(arc
					(start 185.775346 -222.040958)
					(mid 185.823725 -221.915897)
					(end 185.848752 -221.784164)
				)
			)
		)
	)
	(zone
		(layer "In2.Cu")
		(hatch none 0.5)
		(connect_pads
			(clearance 0)
		)
		(min_thickness 0.25)
		(keepout
			(tracks not_allowed)
			(vias allowed)
			(pads allowed)
			(copperpour not_allowed)
			(footprints allowed)
		)
		(placement
			(enabled no)
			(sheetname "")
		)
		(fill
			(thermal_gap 0.5)
			(thermal_bridge_width 0.5)
			(island_removal_mode 0)
		)
		(polygon
			(pts
				(xy 289.148266 -13.827506) (xy 288.502598 -13.181838)
				(arc
					(start 288.502598 -13.18006)
					(mid 288.409725 -12.689431)
					(end 288.79038 -12.366244)
				)
				(arc
					(start 288.79038 -12.366244)
					(mid 289.507702 -12.605482)
					(end 288.753804 -12.5476)
				)
				(arc
					(start 288.753804 -12.5476)
					(mid 288.553035 -12.78877)
					(end 288.643568 -13.089128)
				)
				(xy 289.2298 -13.67536)
				(arc
					(start 289.681158 -12.832588)
					(mid 289.433024 -11.981135)
					(end 288.58337 -12.23518)
				)
				(arc
					(start 287.833562 -13.635228)
					(mid 288.089594 -14.481048)
					(end 288.935414 -14.225016)
				)
				(arc
					(start 288.983928 -14.134592)
					(mid 288.877919 -14.067316)
					(end 288.759392 -14.02588)
				)
				(arc
					(start 288.75355 -14.02461)
					(mid 288.003632 -13.918408)
					(end 288.75863 -13.857478)
				)
				(arc
					(start 288.79546 -13.864844)
					(mid 288.935552 -13.912003)
					(end 289.062922 -13.987018)
				)
			)
		)
	)
	(zone
		(layer "In2.Cu")
		(hatch none 0.5)
		(connect_pads
			(clearance 0)
		)
		(min_thickness 0.25)
		(keepout
			(tracks not_allowed)
			(vias allowed)
			(pads allowed)
			(copperpour not_allowed)
			(footprints allowed)
		)
		(placement
			(enabled no)
			(sheetname "")
		)
		(fill
			(thermal_gap 0.5)
			(thermal_bridge_width 0.5)
			(island_removal_mode 0)
		)
		(polygon
			(pts
				(xy 147.271486 -17.402556) (xy 146.887438 -17.018762)
				(arc
					(start 146.887438 -17.01673)
					(mid 146.778383 -16.782733)
					(end 146.807682 -16.526256)
				)
				(arc
					(start 146.807682 -16.526256)
					(mid 147.40311 -16.060043)
					(end 146.941032 -16.65859)
				)
				(arc
					(start 146.941032 -16.65859)
					(mid 146.952694 -16.802782)
					(end 147.028408 -16.926052)
				)
				(xy 147.352766 -17.250664) (xy 147.687284 -16.626332)
				(arc
					(start 147.685252 -16.625062)
					(mid 147.42922 -15.779242)
					(end 146.5834 -16.035274)
				)
				(xy 146.581368 -16.034004) (xy 145.83156 -17.433544) (xy 145.831814 -17.433798)
				(arc
					(start 145.833846 -17.434814)
					(mid 146.089522 -18.280715)
					(end 146.935444 -18.024856)
				)
				(xy 146.937476 -18.026126)
				(arc
					(start 147.101052 -17.720564)
					(mid 146.934824 -17.65289)
					(end 146.755612 -17.643094)
				)
				(arc
					(start 146.755612 -17.643094)
					(mid 146.043377 -17.899219)
					(end 146.678904 -17.488154)
				)
				(arc
					(start 146.678904 -17.488154)
					(mid 146.937119 -17.485072)
					(end 147.179284 -17.574768)
				)
			)
		)
	)
	(zone
		(layer "In2.Cu")
		(hatch none 0.5)
		(connect_pads
			(clearance 0)
		)
		(min_thickness 0.25)
		(keepout
			(tracks not_allowed)
			(vias allowed)
			(pads allowed)
			(copperpour not_allowed)
			(footprints allowed)
		)
		(placement
			(enabled no)
			(sheetname "")
		)
		(fill
			(thermal_gap 0.5)
			(thermal_bridge_width 0.5)
			(island_removal_mode 0)
		)
		(polygon
			(pts
				(arc
					(start 275.693632 -221.784164)
					(mid 275.183092 -222.294704)
					(end 275.693632 -222.805244)
				)
				(arc
					(start 276.506178 -222.805244)
					(mid 277.016972 -222.294831)
					(end 276.506432 -221.784164)
				)
				(xy 276.347682 -221.784164)
				(arc
					(start 276.347682 -221.793308)
					(mid 276.363522 -221.923436)
					(end 276.409912 -222.046038)
				)
				(arc
					(start 276.409912 -222.046038)
					(mid 276.676412 -222.500271)
					(end 276.280372 -222.153226)
				)
				(arc
					(start 276.280372 -222.153226)
					(mid 276.212185 -221.996407)
					(end 276.183344 -221.827852)
				)
				(xy 276.182582 -221.82709) (xy 276.182582 -221.784164) (xy 276.017482 -221.784164) (xy 276.017482 -221.82709)
				(arc
					(start 276.01672 -221.827852)
					(mid 275.987903 -221.996414)
					(end 275.919692 -222.153226)
				)
				(arc
					(start 275.919692 -222.153226)
					(mid 275.52369 -222.500225)
					(end 275.790152 -222.046038)
				)
				(arc
					(start 275.790152 -222.046038)
					(mid 275.836516 -221.92343)
					(end 275.852382 -221.793308)
				)
				(xy 275.852382 -221.784164)
			)
		)
	)
	(zone
		(layer "In2.Cu")
		(hatch none 0.5)
		(connect_pads
			(clearance 0)
		)
		(min_thickness 0.25)
		(keepout
			(tracks not_allowed)
			(vias allowed)
			(pads allowed)
			(copperpour not_allowed)
			(footprints allowed)
		)
		(placement
			(enabled no)
			(sheetname "")
		)
		(fill
			(thermal_gap 0.5)
			(thermal_bridge_width 0.5)
			(island_removal_mode 0)
		)
		(polygon
			(pts
				(arc
					(start 288.884868 -16.618204)
					(mid 288.615577 -16.625298)
					(end 288.375598 -16.502888)
				)
				(xy 288.37382 -16.502888) (xy 288.34969 -16.478758) (xy 288.345372 -16.47444) (xy 288.263838 -16.626586)
				(xy 288.585402 -16.94815) (xy 288.609532 -16.97228)
				(arc
					(start 288.609532 -16.974058)
					(mid 288.732277 -17.233162)
					(end 288.700972 -17.518126)
				)
				(arc
					(start 288.700972 -17.518126)
					(mid 288.126721 -18.0109)
					(end 288.566606 -17.39519)
				)
				(arc
					(start 288.566606 -17.39519)
					(mid 288.559458 -17.217656)
					(end 288.468562 -17.06499)
				)
				(xy 288.182304 -16.778732) (xy 287.83153 -17.433544) (xy 287.831784 -17.433798)
				(arc
					(start 287.833816 -17.434814)
					(mid 288.089492 -18.280715)
					(end 288.935414 -18.024856)
				)
				(xy 288.937446 -18.026126) (xy 289.514788 -16.94815) (xy 289.687254 -16.626332)
				(arc
					(start 289.685222 -16.625062)
					(mid 289.42919 -15.779242)
					(end 288.58337 -16.035274)
				)
				(xy 288.581338 -16.034004) (xy 288.426906 -16.322294)
				(arc
					(start 288.46653 -16.361918)
					(mid 288.610854 -16.452507)
					(end 288.78022 -16.471138)
				)
				(arc
					(start 288.78022 -16.471138)
					(mid 289.444872 -16.108879)
					(end 288.884868 -16.618204)
				)
			)
		)
	)
	(zone
		(layer "In2.Cu")
		(hatch none 0.5)
		(connect_pads
			(clearance 0)
		)
		(min_thickness 0.25)
		(keepout
			(tracks not_allowed)
			(vias allowed)
			(pads allowed)
			(copperpour not_allowed)
			(footprints allowed)
		)
		(placement
			(enabled no)
			(sheetname "")
		)
		(fill
			(thermal_gap 0.5)
			(thermal_bridge_width 0.5)
			(island_removal_mode 0)
		)
		(polygon
			(pts
				(arc
					(start 299.35678 -16.639794)
					(mid 299.330918 -16.590765)
					(end 299.310552 -16.53921)
				)
				(xy 299.213016 -16.721328)
				(arc
					(start 299.215302 -16.725138)
					(mid 299.360727 -17.028582)
					(end 299.446188 -17.354042)
				)
				(arc
					(start 299.446188 -17.354042)
					(mid 299.406065 -18.110303)
					(end 299.28058 -17.36344)
				)
				(arc
					(start 299.28058 -17.36344)
					(mid 299.218957 -17.122281)
					(end 299.120814 -16.89354)
				)
				(xy 298.831508 -17.433544) (xy 298.831762 -17.433798)
				(arc
					(start 298.833794 -17.434814)
					(mid 299.08947 -18.280715)
					(end 299.935392 -18.024856)
				)
				(xy 299.937424 -18.026126) (xy 300.687232 -16.626332)
				(arc
					(start 300.6852 -16.625062)
					(mid 300.429168 -15.779242)
					(end 299.583348 -16.035274)
				)
				(xy 299.581316 -16.034004)
				(arc
					(start 299.423836 -16.328136)
					(mid 299.43882 -16.379233)
					(end 299.452284 -16.430752)
				)
				(xy 299.460158 -16.438626)
				(arc
					(start 299.460158 -16.46301)
					(mid 299.475974 -16.510386)
					(end 299.498512 -16.554958)
				)
				(arc
					(start 299.498512 -16.554958)
					(mid 299.57038 -16.651818)
					(end 299.659802 -16.732758)
				)
				(arc
					(start 299.659802 -16.732758)
					(mid 299.851218 -16.785411)
					(end 300.02861 -16.696182)
				)
				(arc
					(start 300.02861 -16.696182)
					(mid 300.142953 -15.949382)
					(end 300.222158 -16.700754)
				)
				(arc
					(start 300.222158 -16.700754)
					(mid 299.930713 -16.938763)
					(end 299.561758 -16.865346)
				)
				(arc
					(start 299.561758 -16.865346)
					(mid 299.448111 -16.762709)
					(end 299.35678 -16.639794)
				)
			)
		)
	)
	(zone
		(layer "In2.Cu")
		(hatch none 0.5)
		(connect_pads
			(clearance 0)
		)
		(min_thickness 0.25)
		(keepout
			(tracks allowed)
			(vias allowed)
			(pads allowed)
			(copperpour allowed)
			(footprints allowed)
		)
		(placement
			(enabled no)
			(sheetname "")
		)
		(fill
			(thermal_gap 0.5)
			(thermal_bridge_width 0.5)
			(island_removal_mode 0)
		)
		(polygon
			(pts
				(xy 27.686 -158.9786) (xy 27.686 -147.6756) (xy 43.5356 -147.6756) (xy 43.5356 -158.9786)
			)
		)
	)
	(zone
		(layer "In2.Cu")
		(hatch none 0.5)
		(connect_pads
			(clearance 0)
		)
		(min_thickness 0.25)
		(keepout
			(tracks not_allowed)
			(vias allowed)
			(pads allowed)
			(copperpour not_allowed)
			(footprints allowed)
		)
		(placement
			(enabled no)
			(sheetname "")
		)
		(fill
			(thermal_gap 0.5)
			(thermal_bridge_width 0.5)
			(island_removal_mode 0)
		)
		(polygon
			(pts
				(arc
					(start 318.093598 -221.784164)
					(mid 317.583058 -222.294704)
					(end 318.093598 -222.805244)
				)
				(arc
					(start 318.906144 -222.805244)
					(mid 319.416938 -222.294831)
					(end 318.906398 -221.784164)
				)
				(xy 318.747648 -221.784164)
				(arc
					(start 318.747648 -221.793308)
					(mid 318.763488 -221.923436)
					(end 318.809878 -222.046038)
				)
				(arc
					(start 318.809878 -222.046038)
					(mid 319.076378 -222.500271)
					(end 318.680338 -222.153226)
				)
				(arc
					(start 318.680338 -222.153226)
					(mid 318.612151 -221.996407)
					(end 318.58331 -221.827852)
				)
				(xy 318.582548 -221.82709) (xy 318.582548 -221.784164) (xy 318.417448 -221.784164) (xy 318.417448 -221.82709)
				(arc
					(start 318.416686 -221.827852)
					(mid 318.387869 -221.996414)
					(end 318.319658 -222.153226)
				)
				(arc
					(start 318.319658 -222.153226)
					(mid 317.923656 -222.500225)
					(end 318.190118 -222.046038)
				)
				(arc
					(start 318.190118 -222.046038)
					(mid 318.236482 -221.92343)
					(end 318.252348 -221.793308)
				)
				(xy 318.252348 -221.784164)
			)
		)
	)
	(zone
		(layer "In2.Cu")
		(hatch none 0.5)
		(connect_pads
			(clearance 0)
		)
		(min_thickness 0.25)
		(keepout
			(tracks not_allowed)
			(vias allowed)
			(pads allowed)
			(copperpour not_allowed)
			(footprints allowed)
		)
		(placement
			(enabled no)
			(sheetname "")
		)
		(fill
			(thermal_gap 0.5)
			(thermal_bridge_width 0.5)
			(island_removal_mode 0)
		)
		(polygon
			(pts
				(arc
					(start 311.271666 -13.602462)
					(mid 311.247992 -13.539072)
					(end 311.218326 -13.478256)
				)
				(arc
					(start 311.218326 -13.478256)
					(mid 311.188669 -13.428955)
					(end 311.15508 -13.382244)
				)
				(arc
					(start 311.15508 -13.382244)
					(mid 311.10724 -13.308363)
					(end 311.073546 -13.22705)
				)
				(xy 311.07126 -13.21943) (xy 311.070244 -13.216382)
				(arc
					(start 311.068974 -13.211048)
					(mid 311.058881 -13.165326)
					(end 311.053226 -13.118846)
				)
				(xy 311.051956 -13.117576) (xy 311.051956 -13.084556) (xy 311.051956 -13.083286)
				(arc
					(start 311.051956 -12.90193)
					(mid 311.134506 -12.149165)
					(end 311.217056 -12.90193)
				)
				(arc
					(start 311.217056 -13.084556)
					(mid 311.220016 -13.126715)
					(end 311.228486 -13.168122)
				)
				(xy 311.22874 -13.169392) (xy 311.229248 -13.171678) (xy 311.230518 -13.175996)
				(arc
					(start 311.23128 -13.17752)
					(mid 311.253506 -13.231413)
					(end 311.285128 -13.28039)
				)
				(arc
					(start 311.285128 -13.280644)
					(mid 311.326542 -13.338229)
					(end 311.363106 -13.399008)
				)
				(xy 311.371742 -13.415264) (xy 311.687464 -12.826238)
				(arc
					(start 311.685432 -12.824968)
					(mid 311.4294 -11.979148)
					(end 310.58358 -12.23518)
				)
				(xy 310.581548 -12.23391) (xy 309.831486 -13.633704) (xy 309.83174 -13.633958)
				(arc
					(start 309.833772 -13.634974)
					(mid 310.089448 -14.480875)
					(end 310.93537 -14.225016)
				)
				(xy 310.937402 -14.226286) (xy 310.97474 -14.15669)
				(arc
					(start 310.97474 -13.81633)
					(mid 310.947212 -13.678026)
					(end 310.868822 -13.560806)
				)
				(arc
					(start 310.829452 -13.521182)
					(mid 310.742603 -13.463308)
					(end 310.640222 -13.44295)
				)
				(arc
					(start 310.526938 -13.44295)
					(mid 310.442453 -13.472907)
					(end 310.39562 -13.549376)
				)
				(arc
					(start 310.39562 -13.549376)
					(mid 310.45874 -14.303673)
					(end 310.227472 -13.582904)
				)
				(xy 310.227472 -13.543026)
				(arc
					(start 310.229758 -13.540994)
					(mid 310.315236 -13.365614)
					(end 310.490616 -13.280136)
				)
				(xy 310.492648 -13.27785) (xy 310.674512 -13.27785)
				(arc
					(start 310.675782 -13.279374)
					(mid 310.805745 -13.310817)
					(end 310.919876 -13.380466)
				)
				(xy 310.922162 -13.380466) (xy 310.946038 -13.404596) (xy 310.946292 -13.404596) (xy 310.985662 -13.443966)
				(xy 311.009792 -13.468096)
				(arc
					(start 311.009792 -13.469874)
					(mid 311.099767 -13.614867)
					(end 311.13857 -13.781024)
				)
				(xy 311.13984 -13.78204) (xy 311.13984 -13.848334)
			)
		)
	)
	(zone
		(layer "In2.Cu")
		(hatch none 0.5)
		(connect_pads
			(clearance 0)
		)
		(min_thickness 0.25)
		(keepout
			(tracks not_allowed)
			(vias allowed)
			(pads allowed)
			(copperpour not_allowed)
			(footprints allowed)
		)
		(placement
			(enabled no)
			(sheetname "")
		)
		(fill
			(thermal_gap 0.5)
			(thermal_bridge_width 0.5)
			(island_removal_mode 0)
		)
		(polygon
			(pts
				(arc
					(start 282.09367 -221.784164)
					(mid 281.58313 -222.294704)
					(end 282.09367 -222.805244)
				)
				(arc
					(start 282.906216 -222.805244)
					(mid 283.41701 -222.294831)
					(end 282.90647 -221.784164)
				)
				(xy 282.74772 -221.784164)
				(arc
					(start 282.74772 -221.793308)
					(mid 282.76356 -221.923436)
					(end 282.80995 -222.046038)
				)
				(arc
					(start 282.80995 -222.046038)
					(mid 283.07645 -222.500271)
					(end 282.68041 -222.153226)
				)
				(arc
					(start 282.68041 -222.153226)
					(mid 282.612223 -221.996407)
					(end 282.583382 -221.827852)
				)
				(xy 282.58262 -221.82709) (xy 282.58262 -221.784164) (xy 282.41752 -221.784164) (xy 282.41752 -221.82709)
				(arc
					(start 282.416758 -221.827852)
					(mid 282.387941 -221.996414)
					(end 282.31973 -222.153226)
				)
				(arc
					(start 282.31973 -222.153226)
					(mid 281.923728 -222.500225)
					(end 282.19019 -222.046038)
				)
				(arc
					(start 282.19019 -222.046038)
					(mid 282.236554 -221.92343)
					(end 282.25242 -221.793308)
				)
				(xy 282.25242 -221.784164)
			)
		)
	)
	(zone
		(layer "In2.Cu")
		(hatch none 0.5)
		(connect_pads
			(clearance 0)
		)
		(min_thickness 0.25)
		(keepout
			(tracks not_allowed)
			(vias allowed)
			(pads allowed)
			(copperpour not_allowed)
			(footprints allowed)
		)
		(placement
			(enabled no)
			(sheetname "")
		)
		(fill
			(thermal_gap 0.5)
			(thermal_bridge_width 0.5)
			(island_removal_mode 0)
		)
		(polygon
			(pts
				(arc
					(start 56.49341 -221.784164)
					(mid 55.98287 -222.294704)
					(end 56.49341 -222.805244)
				)
				(arc
					(start 57.305956 -222.805244)
					(mid 57.81675 -222.294831)
					(end 57.30621 -221.784164)
				)
				(arc
					(start 57.151016 -221.784164)
					(mid 57.176077 -221.915887)
					(end 57.224422 -222.040958)
				)
				(arc
					(start 57.224422 -222.040958)
					(mid 57.46299 -222.510053)
					(end 57.089294 -222.13951)
				)
				(arc
					(start 57.089294 -222.13951)
					(mid 57.018896 -221.967209)
					(end 56.985154 -221.784164)
				)
				(arc
					(start 56.814466 -221.784164)
					(mid 56.780739 -221.967213)
					(end 56.710326 -222.13951)
				)
				(arc
					(start 56.710326 -222.13951)
					(mid 56.336638 -222.510042)
					(end 56.575198 -222.040958)
				)
				(arc
					(start 56.575198 -222.040958)
					(mid 56.623577 -221.915897)
					(end 56.648604 -221.784164)
				)
			)
		)
	)
	(zone
		(layer "In2.Cu")
		(hatch none 0.5)
		(connect_pads
			(clearance 0)
		)
		(min_thickness 0.25)
		(keepout
			(tracks not_allowed)
			(vias allowed)
			(pads allowed)
			(copperpour not_allowed)
			(footprints allowed)
		)
		(placement
			(enabled no)
			(sheetname "")
		)
		(fill
			(thermal_gap 0.5)
			(thermal_bridge_width 0.5)
			(island_removal_mode 0)
		)
		(polygon
			(pts
				(arc
					(start 81.293462 -221.784164)
					(mid 80.782922 -222.294704)
					(end 81.293462 -222.805244)
				)
				(arc
					(start 82.106008 -222.805244)
					(mid 82.616802 -222.294831)
					(end 82.106262 -221.784164)
				)
				(arc
					(start 81.951068 -221.784164)
					(mid 81.976129 -221.915887)
					(end 82.024474 -222.040958)
				)
				(arc
					(start 82.024474 -222.040958)
					(mid 82.263042 -222.510053)
					(end 81.889346 -222.13951)
				)
				(arc
					(start 81.889346 -222.13951)
					(mid 81.818948 -221.967209)
					(end 81.785206 -221.784164)
				)
				(arc
					(start 81.614518 -221.784164)
					(mid 81.580791 -221.967213)
					(end 81.510378 -222.13951)
				)
				(arc
					(start 81.510378 -222.13951)
					(mid 81.13669 -222.510042)
					(end 81.37525 -222.040958)
				)
				(arc
					(start 81.37525 -222.040958)
					(mid 81.423629 -221.915897)
					(end 81.448656 -221.784164)
				)
			)
		)
	)
	(zone
		(layer "In2.Cu")
		(hatch none 0.5)
		(connect_pads
			(clearance 0)
		)
		(min_thickness 0.25)
		(keepout
			(tracks not_allowed)
			(vias allowed)
			(pads allowed)
			(copperpour not_allowed)
			(footprints allowed)
		)
		(placement
			(enabled no)
			(sheetname "")
		)
		(fill
			(thermal_gap 0.5)
			(thermal_bridge_width 0.5)
			(island_removal_mode 0)
		)
		(polygon
			(pts
				(arc
					(start 106.093514 -221.784164)
					(mid 105.582974 -222.294704)
					(end 106.093514 -222.805244)
				)
				(arc
					(start 106.90606 -222.805244)
					(mid 107.416854 -222.294831)
					(end 106.906314 -221.784164)
				)
				(arc
					(start 106.75112 -221.784164)
					(mid 106.776181 -221.915887)
					(end 106.824526 -222.040958)
				)
				(arc
					(start 106.824526 -222.040958)
					(mid 107.063094 -222.510053)
					(end 106.689398 -222.13951)
				)
				(arc
					(start 106.689398 -222.13951)
					(mid 106.619 -221.967209)
					(end 106.585258 -221.784164)
				)
				(arc
					(start 106.41457 -221.784164)
					(mid 106.380843 -221.967213)
					(end 106.31043 -222.13951)
				)
				(arc
					(start 106.31043 -222.13951)
					(mid 105.936742 -222.510042)
					(end 106.175302 -222.040958)
				)
				(arc
					(start 106.175302 -222.040958)
					(mid 106.223681 -221.915897)
					(end 106.248708 -221.784164)
				)
			)
		)
	)
	(zone
		(layer "In2.Cu")
		(hatch none 0.5)
		(connect_pads
			(clearance 0)
		)
		(min_thickness 0.25)
		(keepout
			(tracks not_allowed)
			(vias allowed)
			(pads allowed)
			(copperpour not_allowed)
			(footprints allowed)
		)
		(placement
			(enabled no)
			(sheetname "")
		)
		(fill
			(thermal_gap 0.5)
			(thermal_bridge_width 0.5)
			(island_removal_mode 0)
		)
		(polygon
			(pts
				(arc
					(start 272.49374 -221.784164)
					(mid 271.9832 -222.294704)
					(end 272.49374 -222.805244)
				)
				(arc
					(start 273.306286 -222.805244)
					(mid 273.81708 -222.294831)
					(end 273.30654 -221.784164)
				)
				(xy 273.14779 -221.784164)
				(arc
					(start 273.14779 -221.9198)
					(mid 273.15575 -221.99178)
					(end 273.179286 -222.060262)
				)
				(arc
					(start 273.179286 -222.060262)
					(mid 273.503177 -222.474955)
					(end 273.061938 -222.188278)
				)
				(arc
					(start 273.061938 -222.188278)
					(mid 273.008274 -222.076734)
					(end 272.98396 -221.95536)
				)
				(xy 272.98269 -221.95409) (xy 272.98269 -221.784164) (xy 272.81759 -221.784164) (xy 272.81759 -221.82709)
				(arc
					(start 272.816828 -221.827852)
					(mid 272.788011 -221.996414)
					(end 272.7198 -222.153226)
				)
				(arc
					(start 272.7198 -222.153226)
					(mid 272.323798 -222.500225)
					(end 272.59026 -222.046038)
				)
				(arc
					(start 272.59026 -222.046038)
					(mid 272.636624 -221.92343)
					(end 272.65249 -221.793308)
				)
				(xy 272.65249 -221.784164)
			)
		)
	)
	(zone
		(layer "In2.Cu")
		(hatch none 0.5)
		(connect_pads
			(clearance 0)
		)
		(min_thickness 0.25)
		(keepout
			(tracks not_allowed)
			(vias allowed)
			(pads allowed)
			(copperpour not_allowed)
			(footprints allowed)
		)
		(placement
			(enabled no)
			(sheetname "")
		)
		(fill
			(thermal_gap 0.5)
			(thermal_bridge_width 0.5)
			(island_removal_mode 0)
		)
		(polygon
			(pts
				(arc
					(start 135.753348 -12.52601)
					(mid 136.506012 -12.445907)
					(end 135.791956 -12.696952)
				)
				(xy 135.766302 -12.693904) (xy 135.737092 -12.693904) (xy 135.733282 -12.68984) (xy 135.628634 -12.67714)
				(xy 135.608568 -12.681458) (xy 135.595868 -12.67333) (xy 135.580882 -12.671298) (xy 135.570722 -12.658344)
				(xy 135.529066 -12.64031) (xy 135.527796 -12.640818) (xy 135.497824 -12.626848) (xy 135.467344 -12.61364)
				(xy 135.466836 -12.612624) (xy 135.446008 -12.602972) (xy 135.421878 -12.59205) (xy 135.42137 -12.591796)
				(xy 135.420862 -12.591288) (xy 135.41883 -12.591796) (xy 135.399272 -12.578842) (xy 135.321294 -12.724384)
				(arc
					(start 135.35406 -12.74445)
					(mid 135.43029 -12.772254)
					(end 135.502396 -12.809474)
				)
				(xy 135.502904 -12.809728) (xy 135.536432 -12.831572) (xy 135.562848 -12.85113) (xy 135.567928 -12.85113)
				(xy 135.607806 -12.891008) (xy 135.742172 -13.025374) (xy 135.766302 -13.049504)
				(arc
					(start 135.766302 -13.051282)
					(mid 135.856277 -13.196275)
					(end 135.89508 -13.362432)
				)
				(xy 135.89635 -13.363448) (xy 135.89635 -13.489686)
				(arc
					(start 135.895334 -13.490702)
					(mid 135.853351 -13.676364)
					(end 135.754364 -13.838936)
				)
				(arc
					(start 135.754364 -13.838936)
					(mid 135.046959 -14.107172)
					(end 135.66902 -13.67663)
				)
				(arc
					(start 135.66902 -13.67663)
					(mid 135.715362 -13.570299)
					(end 135.73125 -13.455396)
				)
				(arc
					(start 135.73125 -13.397738)
					(mid 135.703737 -13.25942)
					(end 135.625332 -13.142214)
				)
				(arc
					(start 135.477504 -12.994386)
					(mid 135.460173 -12.980379)
					(end 135.442198 -12.967208)
				)
				(xy 135.441944 -12.967208)
				(arc
					(start 135.417306 -12.950952)
					(mid 135.369077 -12.925604)
					(end 135.318246 -12.905994)
				)
				(xy 135.306562 -12.909042) (xy 135.277606 -12.891008) (xy 135.243316 -12.87018)
				(arc
					(start 134.833614 -13.635228)
					(mid 135.089646 -14.481048)
					(end 135.935466 -14.225016)
				)
				(arc
					(start 136.68121 -12.832588)
					(mid 136.433076 -11.981135)
					(end 135.583422 -12.23518)
				)
				(xy 135.477758 -12.432538) (xy 135.479536 -12.434062) (xy 135.485886 -12.437872) (xy 135.51535 -12.453112)
				(xy 135.56488 -12.475972) (xy 135.62457 -12.501626) (xy 135.632444 -12.500102) (xy 135.65378 -12.513818)
			)
		)
	)
	(zone
		(net "GND")
		(layer "In2.Cu")
		(hatch none 0.5)
		(connect_pads
			(clearance 0.5)
		)
		(min_thickness 0.25)
		(fill yes
			(thermal_gap 0.5)
			(thermal_bridge_width 0.5)
			(island_removal_mode 0)
		)
		(polygon
			(pts
				(xy 258.93522 2.96799) (xy 329.717908 2.96799) (xy 329.717908 2.063242) (xy 330.986892 2.063242)
				(arc
					(start 330.986892 3.999992)
					(mid 330.917482 4.167564)
					(end 330.74991 4.236974)
				)
				(xy 258.976114 4.236974) (xy 258.93522 4.19608)
			)
		)
	)
	(zone
		(layer "In2.Cu")
		(hatch none 0.5)
		(connect_pads
			(clearance 0)
		)
		(min_thickness 0.25)
		(keepout
			(tracks not_allowed)
			(vias allowed)
			(pads allowed)
			(copperpour not_allowed)
			(footprints allowed)
		)
		(placement
			(enabled no)
			(sheetname "")
		)
		(fill
			(thermal_gap 0.5)
			(thermal_bridge_width 0.5)
			(island_removal_mode 0)
		)
		(polygon
			(pts
				(arc
					(start 23.77694 -113.995454)
					(mid 23.164927 -113.38306)
					(end 22.55266 -113.9952)
				)
				(arc
					(start 22.55266 -115.1128)
					(mid 23.1648 -115.72494)
					(end 23.77694 -115.1128)
				)
				(xy 23.77694 -114.80165)
				(arc
					(start 23.616412 -114.80165)
					(mid 23.594542 -114.806)
					(end 23.576026 -114.818414)
				)
				(arc
					(start 23.402544 -114.991896)
					(mid 22.9762 -115.3014)
					(end 23.285704 -114.875056)
				)
				(xy 23.483316 -114.677444)
				(arc
					(start 23.487888 -114.677444)
					(mid 23.531351 -114.653385)
					(end 23.579074 -114.639598)
				)
				(xy 23.582122 -114.63655) (xy 23.77694 -114.63655) (xy 23.77694 -114.47145) (xy 23.582122 -114.47145)
				(arc
					(start 23.579074 -114.468402)
					(mid 23.531361 -114.454591)
					(end 23.487888 -114.430556)
				)
				(xy 23.483316 -114.430556)
				(arc
					(start 23.285704 -114.232944)
					(mid 22.9762 -113.8066)
					(end 23.402544 -114.116104)
				)
				(arc
					(start 23.576026 -114.289586)
					(mid 23.594555 -114.301967)
					(end 23.616412 -114.30635)
				)
				(xy 23.77694 -114.30635)
			)
		)
	)
	(zone
		(layers "In2.Cu" "In3.Cu" "In4.Cu" "In5.Cu")
		(hatch none 0.5)
		(connect_pads
			(clearance 0)
		)
		(min_thickness 0.25)
		(keepout
			(tracks not_allowed)
			(vias allowed)
			(pads allowed)
			(copperpour not_allowed)
			(footprints allowed)
		)
		(placement
			(enabled no)
			(sheetname "")
		)
		(fill yes
			(thermal_gap 0.5)
			(thermal_bridge_width 0.5)
			(island_removal_mode 0)
		)
		(polygon
			(pts
				(arc
					(start 349.58782 -203.499974)
					(mid 341.61222 -203.499974)
					(end 349.58782 -203.499974)
				)
			)
		)
	)
	(zone
		(layers "In2.Cu" "In3.Cu" "In4.Cu" "In5.Cu")
		(hatch none 0.5)
		(connect_pads
			(clearance 0)
		)
		(min_thickness 0.25)
		(keepout
			(tracks not_allowed)
			(vias allowed)
			(pads allowed)
			(copperpour not_allowed)
			(footprints allowed)
		)
		(placement
			(enabled no)
			(sheetname "")
		)
		(fill yes
			(thermal_gap 0.5)
			(thermal_bridge_width 0.5)
			(island_removal_mode 0)
		)
		(polygon
			(pts
				(arc
					(start 349.58782 -34.499804)
					(mid 341.61222 -34.499804)
					(end 349.58782 -34.499804)
				)
			)
		)
	)
	(zone
		(layers "In2.Cu" "In3.Cu" "In4.Cu" "In5.Cu")
		(hatch none 0.5)
		(connect_pads
			(clearance 0)
		)
		(min_thickness 0.25)
		(keepout
			(tracks not_allowed)
			(vias allowed)
			(pads allowed)
			(copperpour not_allowed)
			(footprints allowed)
		)
		(placement
			(enabled no)
			(sheetname "")
		)
		(fill yes
			(thermal_gap 0.5)
			(thermal_bridge_width 0.5)
			(island_removal_mode 0)
		)
		(polygon
			(pts
				(arc
					(start 13.98778 -203.499974)
					(mid 6.01218 -203.499974)
					(end 13.98778 -203.499974)
				)
			)
		)
	)
	(zone
		(layers "In2.Cu" "In5.Cu")
		(hatch none 0.5)
		(connect_pads
			(clearance 0)
		)
		(min_thickness 0.25)
		(keepout
			(tracks not_allowed)
			(vias allowed)
			(pads allowed)
			(copperpour not_allowed)
			(footprints allowed)
		)
		(placement
			(enabled no)
			(sheetname "")
		)
		(fill yes
			(thermal_gap 0.5)
			(thermal_bridge_width 0.5)
			(island_removal_mode 0)
		)
		(polygon
			(pts
				(arc
					(start 52.399692 -47.366428)
					(mid 51.888898 -47.876841)
					(end 52.399438 -48.387508)
				)
				(arc
					(start 53.305964 -48.387508)
					(mid 53.666071 -48.238871)
					(end 53.816504 -47.879508)
				)
				(arc
					(start 53.572664 -47.879508)
					(mid 53.305964 -48.14368)
					(end 53.039264 -47.879508)
				)
				(arc
					(start 52.666138 -47.879508)
					(mid 52.399438 -48.14368)
					(end 52.132738 -47.879508)
				)
				(arc
					(start 52.132738 -47.876968)
					(mid 52.399438 -47.610268)
					(end 52.666138 -47.876968)
				)
				(arc
					(start 53.039264 -47.876968)
					(mid 53.305964 -47.610268)
					(end 53.572664 -47.876968)
				)
				(arc
					(start 53.816504 -47.876968)
					(mid 53.66697 -47.515962)
					(end 53.305964 -47.366428)
				)
			)
		)
	)
	(zone
		(layers "In2.Cu" "In5.Cu")
		(hatch none 0.5)
		(connect_pads
			(clearance 0)
		)
		(min_thickness 0.25)
		(keepout
			(tracks not_allowed)
			(vias allowed)
			(pads allowed)
			(copperpour not_allowed)
			(footprints allowed)
		)
		(placement
			(enabled no)
			(sheetname "")
		)
		(fill yes
			(thermal_gap 0.5)
			(thermal_bridge_width 0.5)
			(island_removal_mode 0)
		)
		(polygon
			(pts
				(arc
					(start 65.330832 -127.168656)
					(mid 64.820038 -127.679069)
					(end 65.330578 -128.189736)
				)
				(arc
					(start 66.143378 -128.189736)
					(mid 66.503485 -128.041099)
					(end 66.653918 -127.681736)
				)
				(arc
					(start 66.410078 -127.681736)
					(mid 66.143378 -127.945908)
					(end 65.876678 -127.681736)
				)
				(arc
					(start 65.597278 -127.681736)
					(mid 65.330578 -127.945908)
					(end 65.063878 -127.681736)
				)
				(arc
					(start 65.063878 -127.679196)
					(mid 65.330578 -127.412496)
					(end 65.597278 -127.679196)
				)
				(arc
					(start 65.876678 -127.679196)
					(mid 66.143378 -127.412496)
					(end 66.410078 -127.679196)
				)
				(arc
					(start 66.653918 -127.679196)
					(mid 66.504384 -127.31819)
					(end 66.143378 -127.168656)
				)
			)
		)
	)
	(zone
		(net "P0V9_E")
		(layer "In3.Cu")
		(hatch none 0.5)
		(connect_pads
			(clearance 0.5)
		)
		(min_thickness 0.25)
		(fill yes
			(thermal_gap 0.5)
			(thermal_bridge_width 0.5)
			(island_removal_mode 0)
		)
		(polygon
			(pts
				(xy 310.754776 -55.1815) (xy 310.3245 -55.611776) (xy 310.3245 -67.884294) (xy 310.702706 -68.2625)
				(xy 325.168006 -68.2625) (xy 325.5645 -67.866006) (xy 325.5645 -55.958994) (xy 324.787006 -55.1815)
			)
		)
	)
	(zone
		(net "P12V")
		(layer "In3.Cu")
		(hatch none 0.5)
		(connect_pads
			(clearance 0.5)
		)
		(min_thickness 0.25)
		(fill yes
			(thermal_gap 0.5)
			(thermal_bridge_width 0.5)
			(island_removal_mode 0)
		)
		(polygon
			(pts
				(xy 54.180994 -46.2915) (xy 53.106066 -47.366428)
				(arc
					(start 53.305964 -47.366428)
					(mid 53.816504 -47.876968)
					(end 53.305964 -48.387508)
				)
				(arc
					(start 52.399438 -48.387508)
					(mid 52.270562 -48.370974)
					(end 52.15001 -48.322484)
				)
				(xy 30.2895 -70.182994) (xy 30.2895 -75.740006) (xy 32.717994 -78.1685) (xy 76.024994 -78.1685)
				(xy 86.1695 -88.313006) (xy 86.1695 -155.145994) (xy 73.484994 -167.8305) (xy 52.148994 -167.8305)
				(xy 29.923994 -190.0555) (xy 25.886918 -190.0555) (xy 25.7175 -190.224918) (xy 25.7175 -199.946006)
				(xy 26.113994 -200.3425) (xy 55.674006 -200.3425) (xy 67.104006 -188.9125) (xy 86.408006 -188.9125)
				(xy 132.255006 -143.0655) (xy 335.836006 -143.0655) (xy 353.1235 -125.778006) (xy 353.1235 -48.084994)
				(xy 352.219006 -47.1805) (xy 346.153994 -47.1805) (xy 345.2495 -48.084994) (xy 345.2495 -120.093994)
				(xy 330.786994 -134.5565) (xy 142.161006 -134.5565) (xy 141.2875 -133.682994) (xy 141.2875 -84.909406)
				(xy 143.2941 -82.902806) (xy 143.2941 -78.488794) (xy 141.830806 -77.0255) (xy 112.316006 -77.0255)
				(xy 96.060006 -60.7695) (xy 87.805006 -60.7695) (xy 73.327006 -46.2915)
			)
		)
		(polygon
			(pts
				(arc
					(start 58.8645 -196.77634)
					(mid 59.37504 -196.2658)
					(end 58.8645 -195.75526)
				)
				(arc
					(start 58.051446 -195.75526)
					(mid 57.54116 -196.265927)
					(end 58.0517 -196.77634)
				)
			)
		)
		(polygon
			(pts
				(arc
					(start 103.2383 -81.000346)
					(mid 102.626033 -80.38846)
					(end 102.01402 -81.0006)
				)
				(arc
					(start 102.01402 -82.1182)
					(mid 102.62616 -82.73034)
					(end 103.2383 -82.1182)
				)
			)
		)
		(polygon
			(pts
				(arc
					(start 87.290148 -76.589636)
					(mid 86.779608 -76.079096)
					(end 86.269068 -76.589636)
				)
				(arc
					(start 86.269068 -77.47889)
					(mid 86.779735 -77.989176)
					(end 87.290148 -77.478636)
				)
			)
		)
	)
	(zone
		(net "P12V_PCIE")
		(layer "In3.Cu")
		(hatch none 0.5)
		(connect_pads
			(clearance 0.5)
		)
		(min_thickness 0.25)
		(fill yes
			(thermal_gap 0.5)
			(thermal_bridge_width 0.5)
			(island_removal_mode 0)
		)
		(polygon
			(pts
				(xy 25.864312 -209.296) (xy 25.781 -209.379312)
				(arc
					(start 25.781 -212.772498)
					(mid 26.987702 -213.482798)
					(end 27.462988 -214.799926)
				)
				(xy 27.462988 -221.136972)
				(arc
					(start 28.000198 -221.136972)
					(mid 28.89312 -221.506938)
					(end 29.263086 -222.39986)
				)
				(xy 29.263086 -225.460052) (xy 33.655 -225.460052) (xy 33.655 -213.951312) (xy 32.639 -212.935312)
				(xy 32.639 -210.268312) (xy 31.666688 -209.296)
			)
		)
	)
	(zone
		(net "DUT_VDD")
		(layer "In3.Cu")
		(hatch none 0.5)
		(connect_pads
			(clearance 0.5)
		)
		(min_thickness 0.25)
		(fill yes
			(thermal_gap 0.5)
			(thermal_bridge_width 0.5)
			(island_removal_mode 0)
		)
		(polygon
			(pts
				(xy 232.869994 -25.2095) (xy 232.0925 -25.986994) (xy 232.0925 -31.925006) (xy 233.9975 -33.830006)
				(xy 233.9975 -39.956994) (xy 232.7275 -41.226994) (xy 232.7275 -52.880006) (xy 234.647994 -54.8005)
				(xy 255.145794 -54.8005) (xy 255.7145 -55.369206) (xy 255.7145 -73.095104) (xy 256.088896 -73.4695)
				(xy 309.166006 -73.4695) (xy 309.9435 -72.692006) (xy 309.9435 -50.878994) (xy 299.0215 -39.956994)
				(xy 294.755316 -35.69081)
				(arc
					(start 294.159178 -35.69081)
					(mid 293.743579 -35.476797)
					(end 293.676324 -35.014154)
				)
				(arc
					(start 293.676324 -35.014154)
					(mid 293.74293 -34.8845)
					(end 293.843456 -34.77895)
				)
				(xy 284.274006 -25.2095)
			)
		)
		(polygon
			(pts
				(arc
					(start 290.042854 -35.524694)
					(mid 290.55314 -35.014027)
					(end 290.0426 -34.503614)
				)
				(arc
					(start 289.2298 -34.503614)
					(mid 288.71926 -35.014154)
					(end 289.2298 -35.524694)
				)
			)
		)
		(polygon
			(pts
				(arc
					(start 285.498794 -33.051496)
					(mid 284.988254 -32.540956)
					(end 284.477714 -33.051496)
				)
				(arc
					(start 284.477714 -33.86455)
					(mid 284.988381 -34.374836)
					(end 285.498794 -33.864296)
				)
			)
		)
	)
	(zone
		(layer "In3.Cu")
		(hatch none 0.5)
		(connect_pads
			(clearance 0)
		)
		(min_thickness 0.25)
		(keepout
			(tracks allowed)
			(vias allowed)
			(pads allowed)
			(copperpour allowed)
			(footprints allowed)
		)
		(placement
			(enabled no)
			(sheetname "")
		)
		(fill
			(thermal_gap 0.5)
			(thermal_bridge_width 0.5)
			(island_removal_mode 0)
		)
		(polygon
			(pts
				(arc
					(start 22.276816 -54.175406)
					(mid 21.63065 -53.565175)
					(end 22.258782 -52.936394)
				)
				(xy 23.366984 -52.936394) (xy 23.37689 -52.93614)
				(arc
					(start 23.420324 -52.936902)
					(mid 24.007694 -53.572034)
					(end 23.388066 -54.17566)
				)
				(xy 22.27707 -54.17566)
			)
		)
	)
	(zone
		(net "GND")
		(layer "In3.Cu")
		(hatch none 0.5)
		(connect_pads
			(clearance 0.5)
		)
		(min_thickness 0.25)
		(fill yes
			(thermal_gap 0.5)
			(thermal_bridge_width 0.5)
			(island_removal_mode 0)
		)
		(polygon
			(pts
				(arc
					(start 123.637548 4.236974)
					(mid 122.762871 3.874671)
					(end 122.400568 2.999994)
				)
				(arc
					(start 122.400568 1.999996)
					(mid 121.591301 0.046251)
					(end 119.637556 -0.763016)
				)
				(arc
					(start 53.950108 -0.763016)
					(mid 53.075431 -1.125319)
					(end 52.713128 -1.999996)
				)
				(arc
					(start 52.713128 -24.010112)
					(mid 51.903861 -25.963857)
					(end 49.950116 -26.773124)
				)
				(arc
					(start 1.999996 -26.773124)
					(mid 1.125319 -27.135427)
					(end 0.763016 -28.010104)
				)
				(arc
					(start 0.763016 -212.499956)
					(mid 0.832426 -212.667528)
					(end 0.999998 -212.736938)
				)
				(xy 24.765 -212.736938) (xy 24.765 -208.958688) (xy 25.443688 -208.28) (xy 32.087312 -208.28) (xy 33.655 -209.847688)
				(xy 33.655 -212.514688) (xy 34.671 -213.530688) (xy 34.671 -224.492312) (xy 34.373312 -224.79) (xy 34.163 -224.79)
				(xy 34.163 -225.460052) (xy 73.337928 -225.460052)
				(arc
					(start 73.337928 -222.600012)
					(mid 73.343892 -222.44689)
					(end 73.361804 -222.294704)
				)
				(arc
					(start 73.361804 -222.294704)
					(mid 73.927667 -221.197654)
					(end 75.03668 -220.655642)
				)
				(arc
					(start 75.03668 -220.655642)
					(mid 75.299952 -220.636928)
					(end 75.563222 -220.655642)
				)
				(arc
					(start 75.563222 -220.655642)
					(mid 76.777453 -221.309057)
					(end 77.261974 -222.600012)
				)
				(xy 77.261974 -225.460052) (xy 111.736886 -225.460052)
				(arc
					(start 111.736886 -222.39986)
					(mid 112.106852 -221.506938)
					(end 112.999774 -221.136972)
				)
				(xy 113.536984 -221.136972)
				(arc
					(start 113.536984 -214.799926)
					(mid 114.141219 -213.341173)
					(end 115.599972 -212.736938)
				)
				(arc
					(start 131.400042 -212.736938)
					(mid 132.858795 -213.341173)
					(end 133.46303 -214.799926)
				)
				(xy 133.46303 -221.136972)
				(arc
					(start 134.00024 -221.136972)
					(mid 134.893162 -221.506938)
					(end 135.263128 -222.39986)
				)
				(xy 135.263128 -225.460052) (xy 179.33797 -225.460052)
				(arc
					(start 179.33797 -222.600012)
					(mid 179.343934 -222.44689)
					(end 179.361846 -222.294704)
				)
				(arc
					(start 179.361846 -222.294704)
					(mid 179.927709 -221.197654)
					(end 181.036722 -220.655642)
				)
				(arc
					(start 181.036722 -220.655642)
					(mid 181.299994 -220.636928)
					(end 181.563264 -220.655642)
				)
				(arc
					(start 181.563264 -220.655642)
					(mid 182.777495 -221.309057)
					(end 183.262016 -222.600012)
				)
				(xy 183.262016 -225.460052) (xy 217.736928 -225.460052)
				(arc
					(start 217.736928 -222.39986)
					(mid 218.106894 -221.506938)
					(end 218.999816 -221.136972)
				)
				(xy 219.537026 -221.136972)
				(arc
					(start 219.537026 -214.799926)
					(mid 220.141261 -213.341173)
					(end 221.600014 -212.736938)
				)
				(arc
					(start 229.142036 -212.736938)
					(mid 232.138029 -211.495957)
					(end 233.37901 -208.499964)
				)
				(arc
					(start 233.37901 -165.269926)
					(mid 233.974467 -163.832367)
					(end 235.412026 -163.23691)
				)
				(arc
					(start 249.871992 -163.23691)
					(mid 251.309551 -163.832367)
					(end 251.905008 -165.269926)
				)
				(arc
					(start 251.905008 -208.499964)
					(mid 253.145989 -211.495957)
					(end 256.141982 -212.736938)
				)
				(arc
					(start 257.400044 -212.736938)
					(mid 258.858797 -213.341173)
					(end 259.463032 -214.799926)
				)
				(xy 259.463032 -221.136972)
				(arc
					(start 260.000242 -221.136972)
					(mid 260.893164 -221.506938)
					(end 261.26313 -222.39986)
				)
				(xy 261.26313 -225.460052) (xy 305.337972 -225.460052)
				(arc
					(start 305.337972 -222.600012)
					(mid 305.343936 -222.44689)
					(end 305.361848 -222.294704)
				)
				(arc
					(start 305.361848 -222.294704)
					(mid 305.927711 -221.197654)
					(end 307.036724 -220.655642)
				)
				(arc
					(start 307.036724 -220.655642)
					(mid 307.299996 -220.636928)
					(end 307.563266 -220.655642)
				)
				(arc
					(start 307.563266 -220.655642)
					(mid 308.777497 -221.309057)
					(end 309.262018 -222.600012)
				)
				(xy 309.262018 -225.460052) (xy 343.73693 -225.460052)
				(arc
					(start 343.73693 -222.39986)
					(mid 344.106896 -221.506938)
					(end 344.999818 -221.136972)
				)
				(xy 345.537028 -221.136972)
				(arc
					(start 345.537028 -214.799926)
					(mid 346.141263 -213.341173)
					(end 347.600016 -212.736938)
				)
				(arc
					(start 354.600002 -212.736938)
					(mid 354.767574 -212.667528)
					(end 354.836984 -212.499956)
				)
				(xy 354.836984 -19.463004)
				(arc
					(start 354.749862 -19.463004)
					(mid 353.856865 -19.093113)
					(end 353.486974 -18.200116)
				)
				(arc
					(start 353.486974 -10.199878)
					(mid 353.856865 -9.306881)
					(end 354.749862 -8.93699)
				)
				(xy 354.836984 -8.93699)
				(arc
					(start 354.836984 -0.999998)
					(mid 354.767574 -0.832426)
					(end 354.600002 -0.763016)
				)
				(arc
					(start 332.749906 -0.763016)
					(mid 331.503267 -0.246641)
					(end 330.986892 0.999998)
				)
				(arc
					(start 330.986892 3.999992)
					(mid 330.917482 4.167564)
					(end 330.74991 4.236974)
				)
			)
		)
		(polygon
			(pts
				(arc
					(start 341.306404 -222.805244)
					(mid 341.816944 -222.294704)
					(end 341.306404 -221.784164)
				)
				(arc
					(start 340.49335 -221.784164)
					(mid 339.983064 -222.294831)
					(end 340.493604 -222.805244)
				)
			)
		)
		(polygon
			(pts
				(arc
					(start 338.106766 -222.805244)
					(mid 338.617052 -222.294577)
					(end 338.106512 -221.784164)
				)
				(arc
					(start 337.293712 -221.784164)
					(mid 336.783172 -222.294704)
					(end 337.293712 -222.805244)
				)
			)
		)
		(polygon
			(pts
				(arc
					(start 334.90662 -222.805244)
					(mid 335.416906 -222.294577)
					(end 334.906366 -221.784164)
				)
				(arc
					(start 334.093566 -221.784164)
					(mid 333.583026 -222.294704)
					(end 334.093566 -222.805244)
				)
			)
		)
		(polygon
			(pts
				(arc
					(start 331.706728 -222.805244)
					(mid 332.217014 -222.294577)
					(end 331.706474 -221.784164)
				)
				(arc
					(start 330.893674 -221.784164)
					(mid 330.383134 -222.294704)
					(end 330.893674 -222.805244)
				)
			)
		)
		(polygon
			(pts
				(arc
					(start 328.506836 -222.805244)
					(mid 329.017122 -222.294577)
					(end 328.506582 -221.784164)
				)
				(arc
					(start 327.693782 -221.784164)
					(mid 327.183242 -222.294704)
					(end 327.693782 -222.805244)
				)
			)
		)
		(polygon
			(pts
				(arc
					(start 325.30669 -222.805244)
					(mid 325.816976 -222.294577)
					(end 325.306436 -221.784164)
				)
				(arc
					(start 324.493636 -221.784164)
					(mid 323.983096 -222.294704)
					(end 324.493636 -222.805244)
				)
			)
		)
		(polygon
			(pts
				(arc
					(start 322.106798 -222.805244)
					(mid 322.617084 -222.294577)
					(end 322.106544 -221.784164)
				)
				(arc
					(start 321.293744 -221.784164)
					(mid 320.783204 -222.294704)
					(end 321.293744 -222.805244)
				)
			)
		)
		(polygon
			(pts
				(arc
					(start 318.906652 -222.805244)
					(mid 319.416938 -222.294577)
					(end 318.906398 -221.784164)
				)
				(arc
					(start 318.093598 -221.784164)
					(mid 317.583058 -222.294704)
					(end 318.093598 -222.805244)
				)
			)
		)
		(polygon
			(pts
				(arc
					(start 315.70676 -222.805244)
					(mid 316.217046 -222.294577)
					(end 315.706506 -221.784164)
				)
				(arc
					(start 314.893706 -221.784164)
					(mid 314.383166 -222.294704)
					(end 314.893706 -222.805244)
				)
			)
		)
		(polygon
			(pts
				(arc
					(start 312.506614 -222.805244)
					(mid 313.0169 -222.294577)
					(end 312.50636 -221.784164)
				)
				(arc
					(start 311.69356 -221.784164)
					(mid 311.18302 -222.294704)
					(end 311.69356 -222.805244)
				)
			)
		)
		(polygon
			(pts
				(arc
					(start 301.306738 -222.805244)
					(mid 301.817024 -222.294577)
					(end 301.306484 -221.784164)
				)
				(arc
					(start 300.493684 -221.784164)
					(mid 299.983144 -222.294704)
					(end 300.493684 -222.805244)
				)
			)
		)
		(polygon
			(pts
				(arc
					(start 295.7068 -222.805244)
					(mid 296.217086 -222.294577)
					(end 295.706546 -221.784164)
				)
				(arc
					(start 294.893746 -221.784164)
					(mid 294.383206 -222.294704)
					(end 294.893746 -222.805244)
				)
			)
		)
		(polygon
			(pts
				(arc
					(start 292.506654 -222.805244)
					(mid 293.01694 -222.294577)
					(end 292.5064 -221.784164)
				)
				(arc
					(start 291.6936 -221.784164)
					(mid 291.18306 -222.294704)
					(end 291.6936 -222.805244)
				)
			)
		)
		(polygon
			(pts
				(arc
					(start 289.306762 -222.805244)
					(mid 289.817048 -222.294577)
					(end 289.306508 -221.784164)
				)
				(arc
					(start 288.493708 -221.784164)
					(mid 287.983168 -222.294704)
					(end 288.493708 -222.805244)
				)
			)
		)
		(polygon
			(pts
				(arc
					(start 286.106616 -222.805244)
					(mid 286.616902 -222.294577)
					(end 286.106362 -221.784164)
				)
				(arc
					(start 285.293562 -221.784164)
					(mid 284.783022 -222.294704)
					(end 285.293562 -222.805244)
				)
			)
		)
		(polygon
			(pts
				(arc
					(start 282.906724 -222.805244)
					(mid 283.41701 -222.294577)
					(end 282.90647 -221.784164)
				)
				(arc
					(start 282.09367 -221.784164)
					(mid 281.58313 -222.294704)
					(end 282.09367 -222.805244)
				)
			)
		)
		(polygon
			(pts
				(arc
					(start 279.706832 -222.805244)
					(mid 280.217118 -222.294577)
					(end 279.706578 -221.784164)
				)
				(arc
					(start 278.893778 -221.784164)
					(mid 278.383238 -222.294704)
					(end 278.893778 -222.805244)
				)
			)
		)
		(polygon
			(pts
				(arc
					(start 276.506686 -222.805244)
					(mid 277.016972 -222.294577)
					(end 276.506432 -221.784164)
				)
				(arc
					(start 275.693632 -221.784164)
					(mid 275.183092 -222.294704)
					(end 275.693632 -222.805244)
				)
			)
		)
		(polygon
			(pts
				(arc
					(start 273.306794 -222.805244)
					(mid 273.81708 -222.294577)
					(end 273.30654 -221.784164)
				)
				(arc
					(start 272.49374 -221.784164)
					(mid 271.9832 -222.294704)
					(end 272.49374 -222.805244)
				)
			)
		)
		(polygon
			(pts
				(arc
					(start 266.906756 -222.805244)
					(mid 267.417042 -222.294577)
					(end 266.906502 -221.784164)
				)
				(arc
					(start 266.093702 -221.784164)
					(mid 265.583162 -222.294704)
					(end 266.093702 -222.805244)
				)
			)
		)
		(polygon
			(pts
				(arc
					(start 263.70661 -222.805244)
					(mid 264.216896 -222.294577)
					(end 263.706356 -221.784164)
				)
				(arc
					(start 262.893556 -221.784164)
					(mid 262.383016 -222.294704)
					(end 262.893556 -222.805244)
				)
			)
		)
		(polygon
			(pts
				(arc
					(start 215.306656 -222.805244)
					(mid 215.816942 -222.294577)
					(end 215.306402 -221.784164)
				)
				(arc
					(start 214.493602 -221.784164)
					(mid 213.983062 -222.294704)
					(end 214.493602 -222.805244)
				)
			)
		)
		(polygon
			(pts
				(arc
					(start 212.106764 -222.805244)
					(mid 212.61705 -222.294577)
					(end 212.10651 -221.784164)
				)
				(arc
					(start 211.29371 -221.784164)
					(mid 210.78317 -222.294704)
					(end 211.29371 -222.805244)
				)
			)
		)
		(polygon
			(pts
				(arc
					(start 205.706726 -222.805244)
					(mid 206.217012 -222.294577)
					(end 205.706472 -221.784164)
				)
				(arc
					(start 204.893672 -221.784164)
					(mid 204.383132 -222.294704)
					(end 204.893672 -222.805244)
				)
			)
		)
		(polygon
			(pts
				(arc
					(start 202.506834 -222.805244)
					(mid 203.01712 -222.294577)
					(end 202.50658 -221.784164)
				)
				(arc
					(start 201.69378 -221.784164)
					(mid 201.18324 -222.294704)
					(end 201.69378 -222.805244)
				)
			)
		)
		(polygon
			(pts
				(arc
					(start 199.306688 -222.805244)
					(mid 199.816974 -222.294577)
					(end 199.306434 -221.784164)
				)
				(arc
					(start 198.493634 -221.784164)
					(mid 197.983094 -222.294704)
					(end 198.493634 -222.805244)
				)
			)
		)
		(polygon
			(pts
				(arc
					(start 196.106796 -222.805244)
					(mid 196.617082 -222.294577)
					(end 196.106542 -221.784164)
				)
				(arc
					(start 195.293742 -221.784164)
					(mid 194.783202 -222.294704)
					(end 195.293742 -222.805244)
				)
			)
		)
		(polygon
			(pts
				(arc
					(start 192.90665 -222.805244)
					(mid 193.416936 -222.294577)
					(end 192.906396 -221.784164)
				)
				(arc
					(start 192.093596 -221.784164)
					(mid 191.583056 -222.294704)
					(end 192.093596 -222.805244)
				)
			)
		)
		(polygon
			(pts
				(arc
					(start 189.706758 -222.805244)
					(mid 190.217044 -222.294577)
					(end 189.706504 -221.784164)
				)
				(arc
					(start 188.893704 -221.784164)
					(mid 188.383164 -222.294704)
					(end 188.893704 -222.805244)
				)
			)
		)
		(polygon
			(pts
				(arc
					(start 186.506358 -222.805244)
					(mid 187.016898 -222.294704)
					(end 186.506358 -221.784164)
				)
				(arc
					(start 185.693304 -221.784164)
					(mid 185.183018 -222.294831)
					(end 185.693558 -222.805244)
				)
			)
		)
		(polygon
			(pts
				(arc
					(start 175.306736 -222.805244)
					(mid 175.817022 -222.294577)
					(end 175.306482 -221.784164)
				)
				(arc
					(start 174.493682 -221.784164)
					(mid 173.983142 -222.294704)
					(end 174.493682 -222.805244)
				)
			)
		)
		(polygon
			(pts
				(arc
					(start 172.106844 -222.805244)
					(mid 172.61713 -222.294577)
					(end 172.10659 -221.784164)
				)
				(arc
					(start 171.29379 -221.784164)
					(mid 170.78325 -222.294704)
					(end 171.29379 -222.805244)
				)
			)
		)
		(polygon
			(pts
				(arc
					(start 168.906698 -222.805244)
					(mid 169.416984 -222.294577)
					(end 168.906444 -221.784164)
				)
				(arc
					(start 168.093644 -221.784164)
					(mid 167.583104 -222.294704)
					(end 168.093644 -222.805244)
				)
			)
		)
		(polygon
			(pts
				(arc
					(start 165.706806 -222.805244)
					(mid 166.217092 -222.294577)
					(end 165.706552 -221.784164)
				)
				(arc
					(start 164.893752 -221.784164)
					(mid 164.383212 -222.294704)
					(end 164.893752 -222.805244)
				)
			)
		)
		(polygon
			(pts
				(arc
					(start 160.106614 -222.805244)
					(mid 160.6169 -222.294577)
					(end 160.10636 -221.784164)
				)
				(arc
					(start 159.29356 -221.784164)
					(mid 158.78302 -222.294704)
					(end 159.29356 -222.805244)
				)
			)
		)
		(polygon
			(pts
				(arc
					(start 156.906722 -222.805244)
					(mid 157.417008 -222.294577)
					(end 156.906468 -221.784164)
				)
				(arc
					(start 156.093668 -221.784164)
					(mid 155.583128 -222.294704)
					(end 156.093668 -222.805244)
				)
			)
		)
		(polygon
			(pts
				(arc
					(start 153.70683 -222.805244)
					(mid 154.217116 -222.294577)
					(end 153.706576 -221.784164)
				)
				(arc
					(start 152.893776 -221.784164)
					(mid 152.383236 -222.294704)
					(end 152.893776 -222.805244)
				)
			)
		)
		(polygon
			(pts
				(arc
					(start 150.506684 -222.805244)
					(mid 151.01697 -222.294577)
					(end 150.50643 -221.784164)
				)
				(arc
					(start 149.69363 -221.784164)
					(mid 149.18309 -222.294704)
					(end 149.69363 -222.805244)
				)
			)
		)
		(polygon
			(pts
				(arc
					(start 147.306792 -222.805244)
					(mid 147.817078 -222.294577)
					(end 147.306538 -221.784164)
				)
				(arc
					(start 146.493738 -221.784164)
					(mid 145.983198 -222.294704)
					(end 146.493738 -222.805244)
				)
			)
		)
		(polygon
			(pts
				(arc
					(start 144.106646 -222.805244)
					(mid 144.616932 -222.294577)
					(end 144.106392 -221.784164)
				)
				(arc
					(start 143.293592 -221.784164)
					(mid 142.783052 -222.294704)
					(end 143.293592 -222.805244)
				)
			)
		)
		(polygon
			(pts
				(arc
					(start 140.906754 -222.805244)
					(mid 141.41704 -222.294577)
					(end 140.9065 -221.784164)
				)
				(arc
					(start 140.0937 -221.784164)
					(mid 139.58316 -222.294704)
					(end 140.0937 -222.805244)
				)
			)
		)
		(polygon
			(pts
				(arc
					(start 137.706608 -222.805244)
					(mid 138.216894 -222.294577)
					(end 137.706354 -221.784164)
				)
				(arc
					(start 136.893554 -221.784164)
					(mid 136.383014 -222.294704)
					(end 136.893554 -222.805244)
				)
			)
		)
		(polygon
			(pts
				(arc
					(start 106.906568 -222.805244)
					(mid 107.416854 -222.294577)
					(end 106.906314 -221.784164)
				)
				(arc
					(start 106.093514 -221.784164)
					(mid 105.582974 -222.294704)
					(end 106.093514 -222.805244)
				)
			)
		)
		(polygon
			(pts
				(arc
					(start 103.706422 -222.805244)
					(mid 104.216708 -222.294577)
					(end 103.706168 -221.784164)
				)
				(arc
					(start 102.893368 -221.784164)
					(mid 102.382828 -222.294704)
					(end 102.893368 -222.805244)
				)
			)
		)
		(polygon
			(pts
				(arc
					(start 100.50653 -222.805244)
					(mid 101.016816 -222.294577)
					(end 100.506276 -221.784164)
				)
				(arc
					(start 99.693476 -221.784164)
					(mid 99.182936 -222.294704)
					(end 99.693476 -222.805244)
				)
			)
		)
		(polygon
			(pts
				(arc
					(start 97.306638 -222.805244)
					(mid 97.816924 -222.294577)
					(end 97.306384 -221.784164)
				)
				(arc
					(start 96.493584 -221.784164)
					(mid 95.983044 -222.294704)
					(end 96.493584 -222.805244)
				)
			)
		)
		(polygon
			(pts
				(arc
					(start 91.706446 -222.805244)
					(mid 92.216732 -222.294577)
					(end 91.706192 -221.784164)
				)
				(arc
					(start 90.893392 -221.784164)
					(mid 90.382852 -222.294704)
					(end 90.893392 -222.805244)
				)
			)
		)
		(polygon
			(pts
				(arc
					(start 88.506554 -222.805244)
					(mid 89.01684 -222.294577)
					(end 88.5063 -221.784164)
				)
				(arc
					(start 87.6935 -221.784164)
					(mid 87.18296 -222.294704)
					(end 87.6935 -222.805244)
				)
			)
		)
		(polygon
			(pts
				(arc
					(start 85.306408 -222.805244)
					(mid 85.816694 -222.294577)
					(end 85.306154 -221.784164)
				)
				(arc
					(start 84.493354 -221.784164)
					(mid 83.982814 -222.294704)
					(end 84.493354 -222.805244)
				)
			)
		)
		(polygon
			(pts
				(arc
					(start 82.106516 -222.805244)
					(mid 82.616802 -222.294577)
					(end 82.106262 -221.784164)
				)
				(arc
					(start 81.293462 -221.784164)
					(mid 80.782922 -222.294704)
					(end 81.293462 -222.805244)
				)
			)
		)
		(polygon
			(pts
				(arc
					(start 69.30644 -222.805244)
					(mid 69.816726 -222.294577)
					(end 69.306186 -221.784164)
				)
				(arc
					(start 68.493386 -221.784164)
					(mid 67.982846 -222.294704)
					(end 68.493386 -222.805244)
				)
			)
		)
		(polygon
			(pts
				(arc
					(start 66.106548 -222.805244)
					(mid 66.616834 -222.294577)
					(end 66.106294 -221.784164)
				)
				(arc
					(start 65.293494 -221.784164)
					(mid 64.782954 -222.294704)
					(end 65.293494 -222.805244)
				)
			)
		)
		(polygon
			(pts
				(arc
					(start 60.506356 -222.805244)
					(mid 61.016642 -222.294577)
					(end 60.506102 -221.784164)
				)
				(arc
					(start 59.693302 -221.784164)
					(mid 59.182762 -222.294704)
					(end 59.693302 -222.805244)
				)
			)
		)
		(polygon
			(pts
				(arc
					(start 57.306464 -222.805244)
					(mid 57.81675 -222.294577)
					(end 57.30621 -221.784164)
				)
				(arc
					(start 56.49341 -221.784164)
					(mid 55.98287 -222.294704)
					(end 56.49341 -222.805244)
				)
			)
		)
		(polygon
			(pts
				(arc
					(start 54.106572 -222.805244)
					(mid 54.616858 -222.294577)
					(end 54.106318 -221.784164)
				)
				(arc
					(start 53.293518 -221.784164)
					(mid 52.782978 -222.294704)
					(end 53.293518 -222.805244)
				)
			)
		)
		(polygon
			(pts
				(arc
					(start 50.906426 -221.916244)
					(mid 51.416712 -221.405577)
					(end 50.906172 -220.895164)
				)
				(arc
					(start 50.093372 -220.895164)
					(mid 49.582832 -221.405704)
					(end 50.093372 -221.916244)
				)
			)
		)
		(polygon
			(pts
				(arc
					(start 178.409854 -221.18574)
					(mid 178.92014 -220.675073)
					(end 178.4096 -220.16466)
				)
				(arc
					(start 177.5968 -220.16466)
					(mid 177.08626 -220.6752)
					(end 177.5968 -221.18574)
				)
			)
		)
		(polygon
			(pts
				(arc
					(start 304.562002 -220.779086)
					(mid 305.056286 -220.252798)
					(end 304.529998 -219.758514)
				)
				(xy 304.529998 -219.755974) (xy 303.717198 -219.781374)
				(arc
					(start 303.717198 -219.783914)
					(mid 303.222914 -220.310202)
					(end 303.749202 -220.804486)
				)
				(xy 303.749202 -220.807026) (xy 304.561748 -220.781626) (xy 304.562002 -220.781372)
			)
		)
		(polygon
			(pts
				(arc
					(start 72.517254 -220.52534)
					(mid 73.02754 -220.014673)
					(end 72.517 -219.50426)
				)
				(arc
					(start 71.7042 -219.50426)
					(mid 71.19366 -220.0148)
					(end 71.7042 -220.52534)
				)
			)
		)
		(polygon
			(pts
				(arc
					(start 78.982824 -220.392244)
					(mid 79.49311 -219.881577)
					(end 78.98257 -219.371164)
				)
				(arc
					(start 78.16977 -219.371164)
					(mid 77.65923 -219.881704)
					(end 78.16977 -220.392244)
				)
			)
		)
		(polygon
			(pts
				(arc
					(start 342.906604 -211.406994)
					(mid 343.41689 -210.896327)
					(end 342.90635 -210.385914)
				)
				(arc
					(start 342.09355 -210.385914)
					(mid 341.58301 -210.896454)
					(end 342.09355 -211.406994)
				)
			)
		)
		(polygon
			(pts
				(arc
					(start 339.706712 -211.406994)
					(mid 340.216998 -210.896327)
					(end 339.706458 -210.385914)
				)
				(arc
					(start 338.893658 -210.385914)
					(mid 338.383118 -210.896454)
					(end 338.893658 -211.406994)
				)
			)
		)
		(polygon
			(pts
				(arc
					(start 336.506566 -211.406994)
					(mid 337.017106 -210.896454)
					(end 336.506566 -210.385914)
				)
				(arc
					(start 335.693512 -210.385914)
					(mid 335.183226 -210.896581)
					(end 335.693766 -211.406994)
				)
			)
		)
		(polygon
			(pts
				(arc
					(start 333.306674 -211.406994)
					(mid 333.817214 -210.896454)
					(end 333.306674 -210.385914)
				)
				(arc
					(start 332.49362 -210.385914)
					(mid 331.983334 -210.896581)
					(end 332.493874 -211.406994)
				)
			)
		)
		(polygon
			(pts
				(arc
					(start 326.906382 -211.406994)
					(mid 327.416922 -210.896454)
					(end 326.906382 -210.385914)
				)
				(arc
					(start 326.093328 -210.385914)
					(mid 325.583042 -210.896581)
					(end 326.093582 -211.406994)
				)
			)
		)
		(polygon
			(pts
				(arc
					(start 323.70649 -211.406994)
					(mid 324.21703 -210.896454)
					(end 323.70649 -210.385914)
				)
				(arc
					(start 322.893436 -210.385914)
					(mid 322.38315 -210.896581)
					(end 322.89369 -211.406994)
				)
			)
		)
		(polygon
			(pts
				(arc
					(start 320.506598 -211.406994)
					(mid 321.017138 -210.896454)
					(end 320.506598 -210.385914)
				)
				(arc
					(start 319.693544 -210.385914)
					(mid 319.183258 -210.896581)
					(end 319.693798 -211.406994)
				)
			)
		)
		(polygon
			(pts
				(arc
					(start 317.306706 -211.406994)
					(mid 317.817246 -210.896454)
					(end 317.306706 -210.385914)
				)
				(arc
					(start 316.493652 -210.385914)
					(mid 315.983366 -210.896581)
					(end 316.493906 -211.406994)
				)
			)
		)
		(polygon
			(pts
				(arc
					(start 314.10656 -211.406994)
					(mid 314.6171 -210.896454)
					(end 314.10656 -210.385914)
				)
				(arc
					(start 313.293506 -210.385914)
					(mid 312.78322 -210.896581)
					(end 313.29376 -211.406994)
				)
			)
		)
		(polygon
			(pts
				(arc
					(start 310.906922 -211.406994)
					(mid 311.417208 -210.896327)
					(end 310.906668 -210.385914)
				)
				(arc
					(start 310.093868 -210.385914)
					(mid 309.583328 -210.896454)
					(end 310.093868 -211.406994)
				)
			)
		)
		(polygon
			(pts
				(arc
					(start 302.90643 -211.406994)
					(mid 303.41697 -210.896454)
					(end 302.90643 -210.385914)
				)
				(arc
					(start 302.093376 -210.385914)
					(mid 301.58309 -210.896581)
					(end 302.09363 -211.406994)
				)
			)
		)
		(polygon
			(pts
				(arc
					(start 299.706538 -211.406994)
					(mid 300.217078 -210.896454)
					(end 299.706538 -210.385914)
				)
				(arc
					(start 298.893484 -210.385914)
					(mid 298.383198 -210.896581)
					(end 298.893738 -211.406994)
				)
			)
		)
		(polygon
			(pts
				(arc
					(start 294.106346 -211.406994)
					(mid 294.616886 -210.896454)
					(end 294.106346 -210.385914)
				)
				(arc
					(start 293.293292 -210.385914)
					(mid 292.783006 -210.896581)
					(end 293.293546 -211.406994)
				)
			)
		)
		(polygon
			(pts
				(arc
					(start 290.906454 -211.406994)
					(mid 291.416994 -210.896454)
					(end 290.906454 -210.385914)
				)
				(arc
					(start 290.0934 -210.385914)
					(mid 289.583114 -210.896581)
					(end 290.093654 -211.406994)
				)
			)
		)
		(polygon
			(pts
				(arc
					(start 287.706816 -211.406994)
					(mid 288.217102 -210.896327)
					(end 287.706562 -210.385914)
				)
				(arc
					(start 286.893762 -210.385914)
					(mid 286.383222 -210.896454)
					(end 286.893762 -211.406994)
				)
			)
		)
		(polygon
			(pts
				(arc
					(start 284.506416 -211.406994)
					(mid 285.016956 -210.896454)
					(end 284.506416 -210.385914)
				)
				(arc
					(start 283.693362 -210.385914)
					(mid 283.183076 -210.896581)
					(end 283.693616 -211.406994)
				)
			)
		)
		(polygon
			(pts
				(arc
					(start 281.306524 -211.406994)
					(mid 281.817064 -210.896454)
					(end 281.306524 -210.385914)
				)
				(arc
					(start 280.49347 -210.385914)
					(mid 279.983184 -210.896581)
					(end 280.493724 -211.406994)
				)
			)
		)
		(polygon
			(pts
				(arc
					(start 278.106378 -211.406994)
					(mid 278.616918 -210.896454)
					(end 278.106378 -210.385914)
				)
				(arc
					(start 277.293324 -210.385914)
					(mid 276.783038 -210.896581)
					(end 277.293578 -211.406994)
				)
			)
		)
		(polygon
			(pts
				(arc
					(start 274.906486 -211.406994)
					(mid 275.417026 -210.896454)
					(end 274.906486 -210.385914)
				)
				(arc
					(start 274.093432 -210.385914)
					(mid 273.583146 -210.896581)
					(end 274.093686 -211.406994)
				)
			)
		)
		(polygon
			(pts
				(arc
					(start 271.706594 -211.406994)
					(mid 272.217134 -210.896454)
					(end 271.706594 -210.385914)
				)
				(arc
					(start 270.89354 -210.385914)
					(mid 270.383254 -210.896581)
					(end 270.893794 -211.406994)
				)
			)
		)
		(polygon
			(pts
				(arc
					(start 268.506448 -211.406994)
					(mid 269.016988 -210.896454)
					(end 268.506448 -210.385914)
				)
				(arc
					(start 267.693394 -210.385914)
					(mid 267.183108 -210.896581)
					(end 267.693648 -211.406994)
				)
			)
		)
		(polygon
			(pts
				(arc
					(start 265.306556 -211.406994)
					(mid 265.817096 -210.896454)
					(end 265.306556 -210.385914)
				)
				(arc
					(start 264.493502 -210.385914)
					(mid 263.983216 -210.896581)
					(end 264.493756 -211.406994)
				)
			)
		)
		(polygon
			(pts
				(arc
					(start 216.906348 -211.406994)
					(mid 217.416888 -210.896454)
					(end 216.906348 -210.385914)
				)
				(arc
					(start 216.093294 -210.385914)
					(mid 215.583008 -210.896581)
					(end 216.093548 -211.406994)
				)
			)
		)
		(polygon
			(pts
				(arc
					(start 213.706456 -211.406994)
					(mid 214.216996 -210.896454)
					(end 213.706456 -210.385914)
				)
				(arc
					(start 212.893402 -210.385914)
					(mid 212.383116 -210.896581)
					(end 212.893656 -211.406994)
				)
			)
		)
		(polygon
			(pts
				(arc
					(start 207.306418 -211.406994)
					(mid 207.816958 -210.896454)
					(end 207.306418 -210.385914)
				)
				(arc
					(start 206.493364 -210.385914)
					(mid 205.983078 -210.896581)
					(end 206.493618 -211.406994)
				)
			)
		)
		(polygon
			(pts
				(arc
					(start 204.106526 -211.406994)
					(mid 204.617066 -210.896454)
					(end 204.106526 -210.385914)
				)
				(arc
					(start 203.293472 -210.385914)
					(mid 202.783186 -210.896581)
					(end 203.293726 -211.406994)
				)
			)
		)
		(polygon
			(pts
				(arc
					(start 200.90638 -211.406994)
					(mid 201.41692 -210.896454)
					(end 200.90638 -210.385914)
				)
				(arc
					(start 200.093326 -210.385914)
					(mid 199.58304 -210.896581)
					(end 200.09358 -211.406994)
				)
			)
		)
		(polygon
			(pts
				(arc
					(start 197.706488 -211.406994)
					(mid 198.217028 -210.896454)
					(end 197.706488 -210.385914)
				)
				(arc
					(start 196.893434 -210.385914)
					(mid 196.383148 -210.896581)
					(end 196.893688 -211.406994)
				)
			)
		)
		(polygon
			(pts
				(arc
					(start 194.506596 -211.406994)
					(mid 195.017136 -210.896454)
					(end 194.506596 -210.385914)
				)
				(arc
					(start 193.693542 -210.385914)
					(mid 193.183256 -210.896581)
					(end 193.693796 -211.406994)
				)
			)
		)
		(polygon
			(pts
				(arc
					(start 191.30645 -211.406994)
					(mid 191.81699 -210.896454)
					(end 191.30645 -210.385914)
				)
				(arc
					(start 190.493396 -210.385914)
					(mid 189.98311 -210.896581)
					(end 190.49365 -211.406994)
				)
			)
		)
		(polygon
			(pts
				(arc
					(start 188.106558 -211.406994)
					(mid 188.617098 -210.896454)
					(end 188.106558 -210.385914)
				)
				(arc
					(start 187.293504 -210.385914)
					(mid 186.783218 -210.896581)
					(end 187.293758 -211.406994)
				)
			)
		)
		(polygon
			(pts
				(arc
					(start 184.906412 -211.406994)
					(mid 185.416952 -210.896454)
					(end 184.906412 -210.385914)
				)
				(arc
					(start 184.093358 -210.385914)
					(mid 183.583072 -210.896581)
					(end 184.093612 -211.406994)
				)
			)
		)
		(polygon
			(pts
				(arc
					(start 176.906428 -211.406994)
					(mid 177.416968 -210.896454)
					(end 176.906428 -210.385914)
				)
				(arc
					(start 176.093374 -210.385914)
					(mid 175.583088 -210.896581)
					(end 176.093628 -211.406994)
				)
			)
		)
		(polygon
			(pts
				(arc
					(start 173.706536 -211.406994)
					(mid 174.217076 -210.896454)
					(end 173.706536 -210.385914)
				)
				(arc
					(start 172.893482 -210.385914)
					(mid 172.383196 -210.896581)
					(end 172.893736 -211.406994)
				)
			)
		)
		(polygon
			(pts
				(arc
					(start 170.50639 -211.406994)
					(mid 171.01693 -210.896454)
					(end 170.50639 -210.385914)
				)
				(arc
					(start 169.693336 -210.385914)
					(mid 169.18305 -210.896581)
					(end 169.69359 -211.406994)
				)
			)
		)
		(polygon
			(pts
				(arc
					(start 167.306498 -211.406994)
					(mid 167.817038 -210.896454)
					(end 167.306498 -210.385914)
				)
				(arc
					(start 166.493444 -210.385914)
					(mid 165.983158 -210.896581)
					(end 166.493698 -211.406994)
				)
			)
		)
		(polygon
			(pts
				(arc
					(start 161.70656 -211.406994)
					(mid 162.2171 -210.896454)
					(end 161.70656 -210.385914)
				)
				(arc
					(start 160.893506 -210.385914)
					(mid 160.38322 -210.896581)
					(end 160.89376 -211.406994)
				)
			)
		)
		(polygon
			(pts
				(arc
					(start 158.506668 -211.406994)
					(mid 159.017208 -210.896454)
					(end 158.506668 -210.385914)
				)
				(arc
					(start 157.693614 -210.385914)
					(mid 157.183328 -210.896581)
					(end 157.693868 -211.406994)
				)
			)
		)
		(polygon
			(pts
				(arc
					(start 155.306522 -211.406994)
					(mid 155.817062 -210.896454)
					(end 155.306522 -210.385914)
				)
				(arc
					(start 154.493468 -210.385914)
					(mid 153.983182 -210.896581)
					(end 154.493722 -211.406994)
				)
			)
		)
		(polygon
			(pts
				(arc
					(start 152.10663 -211.406994)
					(mid 152.61717 -210.896454)
					(end 152.10663 -210.385914)
				)
				(arc
					(start 151.293576 -210.385914)
					(mid 150.78329 -210.896581)
					(end 151.29383 -211.406994)
				)
			)
		)
		(polygon
			(pts
				(arc
					(start 148.906484 -211.406994)
					(mid 149.417024 -210.896454)
					(end 148.906484 -210.385914)
				)
				(arc
					(start 148.09343 -210.385914)
					(mid 147.583144 -210.896581)
					(end 148.093684 -211.406994)
				)
			)
		)
		(polygon
			(pts
				(arc
					(start 145.706592 -211.406994)
					(mid 146.217132 -210.896454)
					(end 145.706592 -210.385914)
				)
				(arc
					(start 144.893538 -210.385914)
					(mid 144.383252 -210.896581)
					(end 144.893792 -211.406994)
				)
			)
		)
		(polygon
			(pts
				(arc
					(start 142.5067 -211.406994)
					(mid 143.01724 -210.896454)
					(end 142.5067 -210.385914)
				)
				(arc
					(start 141.693646 -210.385914)
					(mid 141.18336 -210.896581)
					(end 141.6939 -211.406994)
				)
			)
		)
		(polygon
			(pts
				(arc
					(start 139.306554 -211.406994)
					(mid 139.817094 -210.896454)
					(end 139.306554 -210.385914)
				)
				(arc
					(start 138.4935 -210.385914)
					(mid 137.983214 -210.896581)
					(end 138.493754 -211.406994)
				)
			)
		)
		(polygon
			(pts
				(arc
					(start 108.506514 -211.406994)
					(mid 109.017054 -210.896454)
					(end 108.506514 -210.385914)
				)
				(arc
					(start 107.69346 -210.385914)
					(mid 107.183174 -210.896581)
					(end 107.693714 -211.406994)
				)
			)
		)
		(polygon
			(pts
				(arc
					(start 105.306622 -211.406994)
					(mid 105.817162 -210.896454)
					(end 105.306622 -210.385914)
				)
				(arc
					(start 104.493568 -210.385914)
					(mid 103.983282 -210.896581)
					(end 104.493822 -211.406994)
				)
			)
		)
		(polygon
			(pts
				(arc
					(start 102.10673 -211.406994)
					(mid 102.617016 -210.896327)
					(end 102.106476 -210.385914)
				)
				(arc
					(start 101.293676 -210.385914)
					(mid 100.783136 -210.896454)
					(end 101.293676 -211.406994)
				)
			)
		)
		(polygon
			(pts
				(arc
					(start 98.906584 -211.406994)
					(mid 99.417124 -210.896454)
					(end 98.906584 -210.385914)
				)
				(arc
					(start 98.09353 -210.385914)
					(mid 97.583244 -210.896581)
					(end 98.093784 -211.406994)
				)
			)
		)
		(polygon
			(pts
				(arc
					(start 93.306392 -211.406994)
					(mid 93.816932 -210.896454)
					(end 93.306392 -210.385914)
				)
				(arc
					(start 92.493338 -210.385914)
					(mid 91.983052 -210.896581)
					(end 92.493592 -211.406994)
				)
			)
		)
		(polygon
			(pts
				(arc
					(start 90.1065 -211.406994)
					(mid 90.61704 -210.896454)
					(end 90.1065 -210.385914)
				)
				(arc
					(start 89.293446 -210.385914)
					(mid 88.78316 -210.896581)
					(end 89.2937 -211.406994)
				)
			)
		)
		(polygon
			(pts
				(arc
					(start 86.906354 -211.406994)
					(mid 87.416894 -210.896454)
					(end 86.906354 -210.385914)
				)
				(arc
					(start 86.0933 -210.385914)
					(mid 85.583014 -210.896581)
					(end 86.093554 -211.406994)
				)
			)
		)
		(polygon
			(pts
				(arc
					(start 83.706462 -211.406994)
					(mid 84.217002 -210.896454)
					(end 83.706462 -210.385914)
				)
				(arc
					(start 82.893408 -210.385914)
					(mid 82.383122 -210.896581)
					(end 82.893662 -211.406994)
				)
			)
		)
		(polygon
			(pts
				(arc
					(start 80.506316 -211.406994)
					(mid 81.016856 -210.896454)
					(end 80.506316 -210.385914)
				)
				(arc
					(start 79.693262 -210.385914)
					(mid 79.182976 -210.896581)
					(end 79.693516 -211.406994)
				)
			)
		)
		(polygon
			(pts
				(arc
					(start 70.906386 -211.406994)
					(mid 71.416926 -210.896454)
					(end 70.906386 -210.385914)
				)
				(arc
					(start 70.093332 -210.385914)
					(mid 69.583046 -210.896581)
					(end 70.093586 -211.406994)
				)
			)
		)
		(polygon
			(pts
				(arc
					(start 67.706494 -211.406994)
					(mid 68.217034 -210.896454)
					(end 67.706494 -210.385914)
				)
				(arc
					(start 66.89344 -210.385914)
					(mid 66.383154 -210.896581)
					(end 66.893694 -211.406994)
				)
			)
		)
		(polygon
			(pts
				(arc
					(start 64.506348 -211.406994)
					(mid 65.016888 -210.896454)
					(end 64.506348 -210.385914)
				)
				(arc
					(start 63.693294 -210.385914)
					(mid 63.183008 -210.896581)
					(end 63.693548 -211.406994)
				)
			)
		)
		(polygon
			(pts
				(arc
					(start 58.90641 -211.406994)
					(mid 59.41695 -210.896454)
					(end 58.90641 -210.385914)
				)
				(arc
					(start 58.093356 -210.385914)
					(mid 57.58307 -210.896581)
					(end 58.09361 -211.406994)
				)
			)
		)
		(polygon
			(pts
				(arc
					(start 55.706772 -211.406994)
					(mid 56.217058 -210.896327)
					(end 55.706518 -210.385914)
				)
				(arc
					(start 54.893718 -210.385914)
					(mid 54.383178 -210.896454)
					(end 54.893718 -211.406994)
				)
			)
		)
		(polygon
			(pts
				(arc
					(start 52.506372 -211.406994)
					(mid 53.016912 -210.896454)
					(end 52.506372 -210.385914)
				)
				(arc
					(start 51.693318 -210.385914)
					(mid 51.183032 -210.896581)
					(end 51.693572 -211.406994)
				)
			)
		)
		(polygon
			(pts
				(arc
					(start 49.30648 -211.406994)
					(mid 49.81702 -210.896454)
					(end 49.30648 -210.385914)
				)
				(arc
					(start 48.493426 -210.385914)
					(mid 47.98314 -210.896581)
					(end 48.49368 -211.406994)
				)
			)
		)
		(polygon
			(pts
				(arc
					(start 50.95748 -209.222594)
					(mid 51.46802 -208.712054)
					(end 50.95748 -208.201514)
				)
				(arc
					(start 50.144426 -208.201514)
					(mid 49.63414 -208.712181)
					(end 50.14468 -209.222594)
				)
			)
		)
		(polygon
			(pts
				(arc
					(start 92.332048 -184.941718)
					(mid 91.61018 -184.941718)
					(end 91.61018 -185.663586)
				)
				(xy 91.608402 -185.665364) (xy 92.18295 -186.240166) (xy 92.183204 -186.240166)
				(arc
					(start 92.184982 -186.238388)
					(mid 92.90685 -186.238388)
					(end 92.90685 -185.51652)
				)
				(xy 92.908628 -185.514742) (xy 92.333826 -184.93994)
			)
		)
		(polygon
			(pts
				(arc
					(start 94.202504 -184.15254)
					(mid 94.71279 -183.641873)
					(end 94.20225 -183.13146)
				)
				(arc
					(start 93.38945 -183.13146)
					(mid 92.87891 -183.642)
					(end 93.38945 -184.15254)
				)
			)
		)
		(polygon
			(pts
				(arc
					(start 173.6344 -96.704912)
					(mid 174.14494 -96.194372)
					(end 173.6344 -95.683832)
				)
				(arc
					(start 172.745146 -95.683832)
					(mid 172.23486 -96.194499)
					(end 172.7454 -96.704912)
				)
			)
		)
		(polygon
			(pts
				(arc
					(start 168.212516 -88.645746)
					(mid 167.701849 -88.13546)
					(end 167.191436 -88.646)
				)
				(arc
					(start 167.191436 -89.4588)
					(mid 167.701976 -89.96934)
					(end 168.212516 -89.4588)
				)
			)
		)
		(polygon
			(pts
				(arc
					(start 163.512754 -82.17154)
					(mid 164.02304 -81.660873)
					(end 163.5125 -81.15046)
				)
				(arc
					(start 162.6997 -81.15046)
					(mid 162.18916 -81.661)
					(end 162.6997 -82.17154)
				)
			)
		)
		(polygon
			(pts
				(arc
					(start 123.80087 -63.78702)
					(mid 123.80087 -65.8749)
					(end 123.80087 -63.78702)
				)
			)
		)
		(polygon
			(pts
				(arc
					(start 132.358384 -41.604946)
					(mid 131.746117 -40.99306)
					(end 131.134104 -41.6052)
				)
				(arc
					(start 131.134104 -42.7228)
					(mid 131.746244 -43.33494)
					(end 132.358384 -42.7228)
				)
			)
		)
		(polygon
			(pts
				(arc
					(start 306.575968 -40.31996)
					(mid 307.086254 -39.809293)
					(end 306.575714 -39.29888)
				)
				(arc
					(start 305.762914 -39.29888)
					(mid 305.252374 -39.80942)
					(end 305.762914 -40.31996)
				)
			)
		)
		(polygon
			(pts
				(arc
					(start 139.3698 -39.16934)
					(mid 139.88034 -38.6588)
					(end 139.3698 -38.14826)
				)
				(arc
					(start 138.556746 -38.14826)
					(mid 138.04646 -38.658927)
					(end 138.557 -39.16934)
				)
			)
		)
		(polygon
			(pts
				(arc
					(start 151.727154 -38.59784)
					(mid 152.23744 -38.087173)
					(end 151.7269 -37.57676)
				)
				(arc
					(start 150.9141 -37.57676)
					(mid 150.40356 -38.0873)
					(end 150.9141 -38.59784)
				)
			)
		)
		(polygon
			(pts
				(arc
					(start 162.598354 -38.52164)
					(mid 163.10864 -38.010973)
					(end 162.5981 -37.50056)
				)
				(arc
					(start 161.7853 -37.50056)
					(mid 161.27476 -38.0111)
					(end 161.7853 -38.52164)
				)
			)
		)
		(polygon
			(pts
				(arc
					(start 24.432006 -37.212016)
					(mid 24.432006 -39.807896)
					(end 24.432006 -37.212016)
				)
			)
		)
		(polygon
			(pts
				(arc
					(start 6.852158 -37.212016)
					(mid 6.852158 -39.807896)
					(end 6.852158 -37.212016)
				)
			)
		)
		(polygon
			(pts
				(arc
					(start 320.53403 -37.53612)
					(mid 321.044316 -37.025453)
					(end 320.533776 -36.51504)
				)
				(arc
					(start 319.720722 -36.51504)
					(mid 319.210436 -37.025707)
					(end 319.720976 -37.53612)
				)
			)
		)
		(polygon
			(pts
				(arc
					(start 304.647854 -36.794694)
					(mid 305.15814 -36.284027)
					(end 304.6476 -35.773614)
				)
				(arc
					(start 303.8348 -35.773614)
					(mid 303.32426 -36.284154)
					(end 303.8348 -36.794694)
				)
			)
		)
		(polygon
			(pts
				(arc
					(start 300.243494 -36.699952)
					(mid 300.754034 -36.189412)
					(end 300.243494 -35.678872)
				)
				(arc
					(start 299.43044 -35.678872)
					(mid 298.920154 -36.189539)
					(end 299.430694 -36.699952)
				)
			)
		)
		(polygon
			(pts
				(arc
					(start 313.489086 -36.696142)
					(mid 313.999626 -36.185602)
					(end 313.489086 -35.675062)
				)
				(arc
					(start 312.676032 -35.675062)
					(mid 312.165746 -36.185729)
					(end 312.676286 -36.696142)
				)
			)
		)
		(polygon
			(pts
				(arc
					(start 326.782176 -36.472114)
					(mid 327.292462 -35.961447)
					(end 326.781922 -35.451034)
				)
				(arc
					(start 325.969122 -35.451034)
					(mid 325.458582 -35.961574)
					(end 325.969122 -36.472114)
				)
			)
		)
		(polygon
			(pts
				(arc
					(start 134.665212 -36.250372)
					(mid 135.175498 -35.739705)
					(end 134.664958 -35.229292)
				)
				(arc
					(start 133.852158 -35.229292)
					(mid 133.341618 -35.739832)
					(end 133.852158 -36.250372)
				)
			)
		)
		(polygon
			(pts
				(arc
					(start 131.9022 -35.783774)
					(mid 132.41274 -35.273234)
					(end 131.9022 -34.762694)
				)
				(arc
					(start 131.089146 -34.762694)
					(mid 130.57886 -35.273361)
					(end 131.0894 -35.783774)
				)
			)
		)
		(polygon
			(pts
				(arc
					(start 311.238646 -35.55238)
					(mid 311.748932 -35.041713)
					(end 311.238392 -34.5313)
				)
				(arc
					(start 310.425592 -34.5313)
					(mid 309.915052 -35.04184)
					(end 310.425592 -35.55238)
				)
			)
		)
		(polygon
			(pts
				(arc
					(start 302.472344 -35.536886)
					(mid 302.98263 -35.026219)
					(end 302.47209 -34.515806)
				)
				(arc
					(start 301.65929 -34.515806)
					(mid 301.14875 -35.026346)
					(end 301.65929 -35.536886)
				)
			)
		)
		(polygon
			(pts
				(arc
					(start 162.0901 -35.53206)
					(mid 162.60064 -35.02152)
					(end 162.0901 -34.51098)
				)
				(arc
					(start 161.277046 -34.51098)
					(mid 160.76676 -35.021647)
					(end 161.2773 -35.53206)
				)
			)
		)
		(polygon
			(pts
				(arc
					(start 159.467804 -35.53206)
					(mid 159.978344 -35.02152)
					(end 159.467804 -34.51098)
				)
				(arc
					(start 158.65475 -34.51098)
					(mid 158.144464 -35.021647)
					(end 158.655004 -35.53206)
				)
			)
		)
		(polygon
			(pts
				(arc
					(start 315.696854 -35.524694)
					(mid 316.20714 -35.014027)
					(end 315.6966 -34.503614)
				)
				(arc
					(start 314.8838 -34.503614)
					(mid 314.37326 -35.014154)
					(end 314.8838 -35.524694)
				)
			)
		)
		(polygon
			(pts
				(arc
					(start 149.314154 -35.51174)
					(mid 149.82444 -35.001073)
					(end 149.3139 -34.49066)
				)
				(arc
					(start 148.5011 -34.49066)
					(mid 147.99056 -35.0012)
					(end 148.5011 -35.51174)
				)
			)
		)
		(polygon
			(pts
				(arc
					(start 153.530554 -35.50666)
					(mid 154.04084 -34.995993)
					(end 153.5303 -34.48558)
				)
				(arc
					(start 152.7175 -34.48558)
					(mid 152.20696 -34.99612)
					(end 152.7175 -35.50666)
				)
			)
		)
		(polygon
			(pts
				(arc
					(start 146.7231 -35.50666)
					(mid 147.23364 -34.99612)
					(end 146.7231 -34.48558)
				)
				(arc
					(start 145.910046 -34.48558)
					(mid 145.39976 -34.996247)
					(end 145.9103 -35.50666)
				)
			)
		)
		(polygon
			(pts
				(arc
					(start 138.379454 -35.503866)
					(mid 138.88974 -34.993199)
					(end 138.3792 -34.482786)
				)
				(arc
					(start 137.5664 -34.482786)
					(mid 137.05586 -34.993326)
					(end 137.5664 -35.503866)
				)
			)
		)
		(polygon
			(pts
				(arc
					(start 324.425564 -35.479482)
					(mid 324.93585 -34.968815)
					(end 324.42531 -34.458402)
				)
				(arc
					(start 323.612256 -34.458402)
					(mid 323.10197 -34.969069)
					(end 323.61251 -35.479482)
				)
			)
		)
		(polygon
			(pts
				(arc
					(start 329.188572 -35.429952)
					(mid 329.698858 -34.919285)
					(end 329.188318 -34.408872)
				)
				(arc
					(start 328.375518 -34.408872)
					(mid 327.864978 -34.919412)
					(end 328.375518 -35.429952)
				)
			)
		)
		(polygon
			(pts
				(arc
					(start 183.59374 -28.993846)
					(mid 183.083073 -28.48356)
					(end 182.57266 -28.9941)
				)
				(arc
					(start 182.57266 -29.8069)
					(mid 183.0832 -30.31744)
					(end 183.59374 -29.8069)
				)
			)
		)
		(polygon
			(pts
				(arc
					(start 183.59374 -25.945846)
					(mid 183.083073 -25.43556)
					(end 182.57266 -25.9461)
				)
				(arc
					(start 182.57266 -26.7589)
					(mid 183.0832 -27.26944)
					(end 183.59374 -26.7589)
				)
			)
		)
		(polygon
			(pts
				(xy 284.431994 -24.8285) (xy 232.712006 -24.8285) (xy 231.7115 -25.829006) (xy 231.7115 -31.8135)
				(xy 215.313006 -31.8135) (xy 212.4075 -34.719006) (xy 212.4075 -41.196006) (xy 210.995006 -42.6085)
				(xy 181.785006 -42.6085) (xy 177.9905 -46.403006) (xy 177.9905 -61.240924) (xy 177.699924 -61.5315)
				(xy 163.878006 -61.5315) (xy 162.7505 -62.659006) (xy 162.7505 -70.690994) (xy 163.243006 -71.1835)
				(xy 177.613564 -71.1835) (xy 177.9905 -71.560436) (xy 177.9905 -72.722994) (xy 179.753006 -74.4855)
				(xy 248.744994 -74.4855) (xy 249.379994 -73.8505) (xy 309.323994 -73.8505) (xy 310.3245 -72.849994)
				(xy 310.3245 -69.029326) (xy 310.710326 -68.6435) (xy 325.325994 -68.6435) (xy 325.9455 -68.023994)
				(xy 325.9455 -55.801006) (xy 324.944994 -54.8005) (xy 310.670956 -54.8005) (xy 310.3245 -54.454044)
				(xy 310.3245 -50.721006)
				(arc
					(start 295.226232 -35.622992)
					(mid 295.46527 -35.048699)
					(end 294.971978 -34.66973)
				)
				(xy 294.273224 -34.66973)
			)
		)
		(polygon
			(pts
				(arc
					(start 186.56554 -24.99868)
					(mid 186.054873 -24.488394)
					(end 185.54446 -24.998934)
				)
				(arc
					(start 185.54446 -25.811734)
					(mid 186.055 -26.322274)
					(end 186.56554 -25.811734)
				)
			)
		)
		(polygon
			(pts
				(arc
					(start 145.435066 -24.22525)
					(mid 145.17939 -23.379349)
					(end 144.333468 -23.635208)
				)
				(xy 144.331436 -23.633938) (xy 143.581374 -25.033986)
				(arc
					(start 143.583406 -25.035256)
					(mid 143.839438 -25.881076)
					(end 144.685258 -25.625044)
				)
				(xy 144.68729 -25.626314) (xy 145.437352 -24.22652) (xy 145.437098 -24.226266)
			)
		)
		(polygon
			(pts
				(arc
					(start 298.435014 -24.22525)
					(mid 298.179338 -23.379349)
					(end 297.333416 -23.635208)
				)
				(xy 297.331384 -23.633938) (xy 296.581322 -25.033986)
				(arc
					(start 296.583354 -25.035256)
					(mid 296.839386 -25.881076)
					(end 297.685206 -25.625044)
				)
				(xy 297.687238 -25.626314) (xy 298.4373 -24.22652) (xy 298.437046 -24.226266)
			)
		)
		(polygon
			(pts
				(arc
					(start 324.935342 -24.224996)
					(mid 324.67931 -23.379176)
					(end 323.83349 -23.635208)
				)
				(xy 323.831458 -23.633938) (xy 323.081396 -25.033732) (xy 323.08165 -25.033986)
				(arc
					(start 323.083682 -25.035002)
					(mid 323.339358 -25.880903)
					(end 324.18528 -25.625044)
				)
				(xy 324.187312 -25.626314) (xy 324.937374 -24.226266)
			)
		)
		(polygon
			(pts
				(arc
					(start 322.68541 -24.224996)
					(mid 322.429378 -23.379176)
					(end 321.583558 -23.635208)
				)
				(xy 321.581526 -23.633938) (xy 320.831464 -25.033732) (xy 320.831718 -25.033986)
				(arc
					(start 320.83375 -25.035002)
					(mid 321.089426 -25.880903)
					(end 321.935348 -25.625044)
				)
				(xy 321.93738 -25.626314) (xy 322.687442 -24.226266)
			)
		)
		(polygon
			(pts
				(arc
					(start 313.935364 -24.224996)
					(mid 313.679332 -23.379176)
					(end 312.833512 -23.635208)
				)
				(xy 312.83148 -23.633938) (xy 312.081418 -25.033732) (xy 312.081672 -25.033986)
				(arc
					(start 312.083704 -25.035002)
					(mid 312.33938 -25.880903)
					(end 313.185302 -25.625044)
				)
				(xy 313.187334 -25.626314) (xy 313.937396 -24.226266)
			)
		)
		(polygon
			(pts
				(arc
					(start 311.685432 -24.224996)
					(mid 311.4294 -23.379176)
					(end 310.58358 -23.635208)
				)
				(xy 310.581548 -23.633938) (xy 309.831486 -25.033732) (xy 309.83174 -25.033986)
				(arc
					(start 309.833772 -25.035002)
					(mid 310.089448 -25.880903)
					(end 310.93537 -25.625044)
				)
				(xy 310.937402 -25.626314) (xy 311.687464 -24.226266)
			)
		)
		(polygon
			(pts
				(arc
					(start 302.935386 -24.224996)
					(mid 302.679354 -23.379176)
					(end 301.833534 -23.635208)
				)
				(xy 301.831502 -23.633938) (xy 301.08144 -25.033732) (xy 301.081694 -25.033986)
				(arc
					(start 301.083726 -25.035002)
					(mid 301.339402 -25.880903)
					(end 302.185324 -25.625044)
				)
				(xy 302.187356 -25.626314) (xy 302.937418 -24.226266)
			)
		)
		(polygon
			(pts
				(arc
					(start 300.6852 -24.224996)
					(mid 300.429168 -23.379176)
					(end 299.583348 -23.635208)
				)
				(arc
					(start 298.837604 -25.027636)
					(mid 299.085738 -25.879089)
					(end 299.935392 -25.625044)
				)
			)
		)
		(polygon
			(pts
				(arc
					(start 291.935408 -24.224996)
					(mid 291.679376 -23.379176)
					(end 290.833556 -23.635208)
				)
				(xy 290.831524 -23.633938) (xy 290.081462 -25.033732) (xy 290.081716 -25.033986)
				(arc
					(start 290.083748 -25.035002)
					(mid 290.339424 -25.880903)
					(end 291.185346 -25.625044)
				)
				(xy 291.187378 -25.626314) (xy 291.93744 -24.226266)
			)
		)
		(polygon
			(pts
				(arc
					(start 289.685222 -24.224996)
					(mid 289.42919 -23.379176)
					(end 288.58337 -23.635208)
				)
				(arc
					(start 287.837626 -25.027636)
					(mid 288.08576 -25.879089)
					(end 288.935414 -25.625044)
				)
			)
		)
		(polygon
			(pts
				(arc
					(start 287.43529 -24.224996)
					(mid 287.179258 -23.379176)
					(end 286.333438 -23.635208)
				)
				(xy 286.331406 -23.633938) (xy 285.581344 -25.033732) (xy 285.581598 -25.033986)
				(arc
					(start 285.58363 -25.035002)
					(mid 285.839306 -25.880903)
					(end 286.685228 -25.625044)
				)
				(xy 286.68726 -25.626314) (xy 287.437322 -24.226266)
			)
		)
		(polygon
			(pts
				(arc
					(start 171.935394 -24.224996)
					(mid 171.679362 -23.379176)
					(end 170.833542 -23.635208)
				)
				(xy 170.83151 -23.633938) (xy 170.081448 -25.033732) (xy 170.081702 -25.033986)
				(arc
					(start 170.083734 -25.035002)
					(mid 170.33941 -25.880903)
					(end 171.185332 -25.625044)
				)
				(xy 171.187364 -25.626314) (xy 171.937426 -24.226266)
			)
		)
		(polygon
			(pts
				(arc
					(start 169.685462 -24.224996)
					(mid 169.42943 -23.379176)
					(end 168.58361 -23.635208)
				)
				(xy 168.581578 -23.633938) (xy 167.831516 -25.033732) (xy 167.83177 -25.033986)
				(arc
					(start 167.833802 -25.035002)
					(mid 168.089478 -25.880903)
					(end 168.9354 -25.625044)
				)
				(xy 168.937432 -25.626314) (xy 169.687494 -24.226266)
			)
		)
		(polygon
			(pts
				(arc
					(start 160.935416 -24.224996)
					(mid 160.679384 -23.379176)
					(end 159.833564 -23.635208)
				)
				(xy 159.831532 -23.633938) (xy 159.08147 -25.033732) (xy 159.081724 -25.033986)
				(arc
					(start 159.083756 -25.035002)
					(mid 159.339432 -25.880903)
					(end 160.185354 -25.625044)
				)
				(xy 160.187386 -25.626314) (xy 160.937448 -24.226266)
			)
		)
		(polygon
			(pts
				(arc
					(start 158.685484 -24.224996)
					(mid 158.429452 -23.379176)
					(end 157.583632 -23.635208)
				)
				(xy 157.5816 -23.633938) (xy 156.831538 -25.033732) (xy 156.831792 -25.033986)
				(arc
					(start 156.833824 -25.035002)
					(mid 157.0895 -25.880903)
					(end 157.935422 -25.625044)
				)
				(xy 157.937454 -25.626314) (xy 158.687516 -24.226266)
			)
		)
		(polygon
			(pts
				(arc
					(start 149.935438 -24.224996)
					(mid 149.679406 -23.379176)
					(end 148.833586 -23.635208)
				)
				(xy 148.831554 -23.633938) (xy 148.081492 -25.033732) (xy 148.081746 -25.033986)
				(arc
					(start 148.083778 -25.035002)
					(mid 148.339454 -25.880903)
					(end 149.185376 -25.625044)
				)
				(xy 149.187408 -25.626314) (xy 149.93747 -24.226266)
			)
		)
		(polygon
			(pts
				(arc
					(start 147.685252 -24.224996)
					(mid 147.42922 -23.379176)
					(end 146.5834 -23.635208)
				)
				(arc
					(start 145.837656 -25.027636)
					(mid 146.08579 -25.879089)
					(end 146.935444 -25.625044)
				)
			)
		)
		(polygon
			(pts
				(arc
					(start 138.93546 -24.224996)
					(mid 138.679428 -23.379176)
					(end 137.833608 -23.635208)
				)
				(xy 137.831576 -23.633938) (xy 137.081514 -25.033732) (xy 137.081768 -25.033986)
				(arc
					(start 137.0838 -25.035002)
					(mid 137.339476 -25.880903)
					(end 138.185398 -25.625044)
				)
				(xy 138.18743 -25.626314) (xy 138.937492 -24.226266)
			)
		)
		(polygon
			(pts
				(arc
					(start 136.685274 -24.224996)
					(mid 136.429242 -23.379176)
					(end 135.583422 -23.635208)
				)
				(arc
					(start 134.837678 -25.027636)
					(mid 135.085812 -25.879089)
					(end 135.935466 -25.625044)
				)
			)
		)
		(polygon
			(pts
				(arc
					(start 134.435342 -24.224996)
					(mid 134.17931 -23.379176)
					(end 133.33349 -23.635208)
				)
				(xy 133.331458 -23.633938) (xy 132.581396 -25.033732) (xy 132.58165 -25.033986)
				(arc
					(start 132.583682 -25.035002)
					(mid 132.839358 -25.880903)
					(end 133.68528 -25.625044)
				)
				(xy 133.687312 -25.626314) (xy 134.437374 -24.226266)
			)
		)
		(polygon
			(pts
				(arc
					(start 320.43116 -24.232616)
					(mid 320.183026 -23.381163)
					(end 319.333372 -23.635208)
				)
				(arc
					(start 318.583564 -25.035256)
					(mid 318.596918 -25.648738)
					(end 319.128648 -25.95499)
				)
				(arc
					(start 319.128648 -25.95499)
					(mid 319.453069 -25.867706)
					(end 319.685416 -25.625044)
				)
			)
		)
		(polygon
			(pts
				(arc
					(start 309.431182 -24.232616)
					(mid 309.183048 -23.381163)
					(end 308.333394 -23.635208)
				)
				(arc
					(start 307.583586 -25.035256)
					(mid 307.839618 -25.881076)
					(end 308.685438 -25.625044)
				)
			)
		)
		(polygon
			(pts
				(arc
					(start 167.431212 -24.232616)
					(mid 167.183078 -23.381163)
					(end 166.333424 -23.635208)
				)
				(arc
					(start 165.583616 -25.035256)
					(mid 165.839648 -25.881076)
					(end 166.685468 -25.625044)
				)
			)
		)
		(polygon
			(pts
				(arc
					(start 156.431234 -24.232616)
					(mid 156.1831 -23.381163)
					(end 155.333446 -23.635208)
				)
				(arc
					(start 154.583638 -25.035256)
					(mid 154.83967 -25.881076)
					(end 155.68549 -25.625044)
				)
			)
		)
		(polygon
			(pts
				(arc
					(start 183.59374 -23.6601)
					(mid 183.0832 -23.14956)
					(end 182.57266 -23.6601)
				)
				(arc
					(start 182.57266 -24.473154)
					(mid 183.083327 -24.98344)
					(end 183.59374 -24.4729)
				)
			)
		)
		(polygon
			(pts
				(arc
					(start 273.100038 -22.381464)
					(mid 273.100038 -24.418544)
					(end 273.100038 -22.381464)
				)
			)
		)
		(polygon
			(pts
				(arc
					(start 283.005276 -20.15617)
					(mid 282.284107 -20.118381)
					(end 282.246578 -20.83943)
				)
				(xy 282.244546 -20.841208) (xy 282.788614 -21.44522)
				(arc
					(start 282.790646 -21.443442)
					(mid 283.511498 -21.481034)
					(end 283.54909 -20.760182)
				)
				(xy 283.551122 -20.758404) (xy 283.007308 -20.154646) (xy 283.0068 -20.154646)
			)
		)
		(polygon
			(pts
				(arc
					(start 160.935162 -20.425156)
					(mid 160.679486 -19.579255)
					(end 159.833564 -19.835114)
				)
				(xy 159.831532 -19.833844) (xy 159.08147 -21.233892)
				(arc
					(start 159.083502 -21.235162)
					(mid 159.339534 -22.080982)
					(end 160.185354 -21.82495)
				)
				(xy 160.187386 -21.82622) (xy 160.937448 -20.426426) (xy 160.937194 -20.426172)
			)
		)
		(polygon
			(pts
				(arc
					(start 158.68523 -20.425156)
					(mid 158.429554 -19.579255)
					(end 157.583632 -19.835114)
				)
				(xy 157.5816 -19.833844) (xy 156.831538 -21.233892)
				(arc
					(start 156.83357 -21.235162)
					(mid 157.089602 -22.080982)
					(end 157.935422 -21.82495)
				)
				(xy 157.937454 -21.82622) (xy 158.687516 -20.426426) (xy 158.687262 -20.426172)
			)
		)
		(polygon
			(pts
				(arc
					(start 324.935088 -20.425156)
					(mid 324.679412 -19.579255)
					(end 323.83349 -19.835114)
				)
				(xy 323.831458 -19.833844) (xy 323.081396 -21.233892)
				(arc
					(start 323.083428 -21.235162)
					(mid 323.33946 -22.080982)
					(end 324.18528 -21.82495)
				)
				(xy 324.187312 -21.82622) (xy 324.937374 -20.426426) (xy 324.93712 -20.426172)
			)
		)
		(polygon
			(pts
				(arc
					(start 322.685156 -20.425156)
					(mid 322.42948 -19.579255)
					(end 321.583558 -19.835114)
				)
				(xy 321.581526 -19.833844) (xy 320.831464 -21.233892)
				(arc
					(start 320.833496 -21.235162)
					(mid 321.089528 -22.080982)
					(end 321.935348 -21.82495)
				)
				(xy 321.93738 -21.82622) (xy 322.687442 -20.426426) (xy 322.687188 -20.426172)
			)
		)
		(polygon
			(pts
				(arc
					(start 313.93511 -20.425156)
					(mid 313.679434 -19.579255)
					(end 312.833512 -19.835114)
				)
				(xy 312.83148 -19.833844) (xy 312.081418 -21.233892)
				(arc
					(start 312.08345 -21.235162)
					(mid 312.339482 -22.080982)
					(end 313.185302 -21.82495)
				)
				(xy 313.187334 -21.82622) (xy 313.937396 -20.426426) (xy 313.937142 -20.426172)
			)
		)
		(polygon
			(pts
				(arc
					(start 311.685178 -20.425156)
					(mid 311.429502 -19.579255)
					(end 310.58358 -19.835114)
				)
				(xy 310.581548 -19.833844) (xy 309.831486 -21.233892)
				(arc
					(start 309.833518 -21.235162)
					(mid 310.08955 -22.080982)
					(end 310.93537 -21.82495)
				)
				(xy 310.937402 -21.82622) (xy 311.687464 -20.426426) (xy 311.68721 -20.426172)
			)
		)
		(polygon
			(pts
				(arc
					(start 171.93514 -20.425156)
					(mid 171.679464 -19.579255)
					(end 170.833542 -19.835114)
				)
				(xy 170.83151 -19.833844) (xy 170.081448 -21.233892)
				(arc
					(start 170.08348 -21.235162)
					(mid 170.339512 -22.080982)
					(end 171.185332 -21.82495)
				)
				(xy 171.187364 -21.82622) (xy 171.937426 -20.426426) (xy 171.937172 -20.426172)
			)
		)
		(polygon
			(pts
				(arc
					(start 169.685208 -20.425156)
					(mid 169.429532 -19.579255)
					(end 168.58361 -19.835114)
				)
				(xy 168.581578 -19.833844) (xy 167.831516 -21.233892)
				(arc
					(start 167.833548 -21.235162)
					(mid 168.08958 -22.080982)
					(end 168.9354 -21.82495)
				)
				(xy 168.937432 -21.82622) (xy 169.687494 -20.426426) (xy 169.68724 -20.426172)
			)
		)
		(polygon
			(pts
				(arc
					(start 149.935184 -20.425156)
					(mid 149.679508 -19.579255)
					(end 148.833586 -19.835114)
				)
				(xy 148.831554 -19.833844) (xy 148.081492 -21.233892)
				(arc
					(start 148.083524 -21.235162)
					(mid 148.339556 -22.080982)
					(end 149.185376 -21.82495)
				)
				(xy 149.187408 -21.82622) (xy 149.93747 -20.426426) (xy 149.937216 -20.426172)
			)
		)
		(polygon
			(pts
				(arc
					(start 302.935132 -20.425156)
					(mid 302.679456 -19.579255)
					(end 301.833534 -19.835114)
				)
				(xy 301.831502 -19.833844) (xy 301.08144 -21.233892)
				(arc
					(start 301.083472 -21.235162)
					(mid 301.339504 -22.080982)
					(end 302.185324 -21.82495)
				)
				(xy 302.187356 -21.82622) (xy 302.937418 -20.426426) (xy 302.937164 -20.426172)
			)
		)
		(polygon
			(pts
				(arc
					(start 291.935408 -20.424902)
					(mid 291.679376 -19.579082)
					(end 290.833556 -19.835114)
				)
				(xy 290.831524 -19.833844) (xy 290.081462 -21.233638) (xy 290.081716 -21.233892)
				(arc
					(start 290.083748 -21.234908)
					(mid 290.339424 -22.080809)
					(end 291.185346 -21.82495)
				)
				(xy 291.187378 -21.82622) (xy 291.93744 -20.426172)
			)
		)
		(polygon
			(pts
				(arc
					(start 289.685222 -20.424902)
					(mid 289.42919 -19.579082)
					(end 288.58337 -19.835114)
				)
				(arc
					(start 287.837626 -21.227542)
					(mid 288.08576 -22.078995)
					(end 288.935414 -21.82495)
				)
			)
		)
		(polygon
			(pts
				(arc
					(start 138.93546 -20.424902)
					(mid 138.679428 -19.579082)
					(end 137.833608 -19.835114)
				)
				(xy 137.831576 -19.833844) (xy 137.081514 -21.233638) (xy 137.081768 -21.233892)
				(arc
					(start 137.0838 -21.234908)
					(mid 137.339476 -22.080809)
					(end 138.185398 -21.82495)
				)
				(xy 138.18743 -21.82622) (xy 138.937492 -20.426172)
			)
		)
		(polygon
			(pts
				(arc
					(start 136.685274 -20.424902)
					(mid 136.429242 -19.579082)
					(end 135.583422 -19.835114)
				)
				(arc
					(start 134.837678 -21.227542)
					(mid 135.085812 -22.078995)
					(end 135.935466 -21.82495)
				)
			)
		)
		(polygon
			(pts
				(arc
					(start 147.681188 -20.432522)
					(mid 147.433054 -19.581069)
					(end 146.5834 -19.835114)
				)
				(arc
					(start 145.833592 -21.235162)
					(mid 146.089624 -22.080982)
					(end 146.935444 -21.82495)
				)
			)
		)
		(polygon
			(pts
				(arc
					(start 300.681136 -20.432522)
					(mid 300.433002 -19.581069)
					(end 299.583348 -19.835114)
				)
				(arc
					(start 298.83354 -21.235162)
					(mid 299.089572 -22.080982)
					(end 299.935392 -21.82495)
				)
			)
		)
		(polygon
			(pts
				(arc
					(start 183.59374 -19.849846)
					(mid 183.083073 -19.33956)
					(end 182.57266 -19.8501)
				)
				(arc
					(start 182.57266 -20.6629)
					(mid 183.0832 -21.17344)
					(end 183.59374 -20.6629)
				)
			)
		)
		(polygon
			(pts
				(arc
					(start 280.761186 -17.965928)
					(mid 280.258647 -17.447516)
					(end 279.740106 -17.949926)
				)
				(arc
					(start 279.72766 -18.762726)
					(mid 280.230326 -19.28114)
					(end 280.74874 -18.778474)
				)
			)
		)
		(polygon
			(pts
				(arc
					(start 324.935088 -16.625316)
					(mid 324.679564 -15.779496)
					(end 323.833744 -16.03502)
				)
				(xy 323.831458 -16.03375) (xy 323.081396 -17.433544) (xy 323.08165 -17.433798)
				(arc
					(start 323.083682 -17.434814)
					(mid 323.339206 -18.280634)
					(end 324.185026 -18.02511)
				)
				(xy 324.187312 -18.02638) (xy 324.937374 -16.626586)
			)
		)
		(polygon
			(pts
				(arc
					(start 322.685156 -16.625316)
					(mid 322.429632 -15.779496)
					(end 321.583812 -16.03502)
				)
				(xy 321.581526 -16.03375) (xy 320.831464 -17.433544) (xy 320.831718 -17.433798)
				(arc
					(start 320.83375 -17.434814)
					(mid 321.089274 -18.280634)
					(end 321.935094 -18.02511)
				)
				(xy 321.93738 -18.02638) (xy 322.687442 -16.626586)
			)
		)
		(polygon
			(pts
				(arc
					(start 313.93511 -16.625316)
					(mid 313.679586 -15.779496)
					(end 312.833766 -16.03502)
				)
				(xy 312.83148 -16.03375) (xy 312.081418 -17.433544) (xy 312.081672 -17.433798)
				(arc
					(start 312.083704 -17.434814)
					(mid 312.339228 -18.280634)
					(end 313.185048 -18.02511)
				)
				(xy 313.187334 -18.02638) (xy 313.937396 -16.626586)
			)
		)
		(polygon
			(pts
				(arc
					(start 311.685178 -16.625316)
					(mid 311.429654 -15.779496)
					(end 310.583834 -16.03502)
				)
				(xy 310.581548 -16.03375) (xy 309.831486 -17.433544) (xy 309.83174 -17.433798)
				(arc
					(start 309.833772 -17.434814)
					(mid 310.089296 -18.280634)
					(end 310.935116 -18.02511)
				)
				(xy 310.937402 -18.02638) (xy 311.687464 -16.626586)
			)
		)
		(polygon
			(pts
				(arc
					(start 302.935132 -16.625316)
					(mid 302.679608 -15.779496)
					(end 301.833788 -16.03502)
				)
				(xy 301.831502 -16.03375) (xy 301.08144 -17.433544) (xy 301.081694 -17.433798)
				(arc
					(start 301.083726 -17.434814)
					(mid 301.33925 -18.280634)
					(end 302.18507 -18.02511)
				)
				(xy 302.187356 -18.02638) (xy 302.937418 -16.626586)
			)
		)
		(polygon
			(pts
				(arc
					(start 291.935154 -16.625316)
					(mid 291.67963 -15.779496)
					(end 290.83381 -16.03502)
				)
				(xy 290.831524 -16.03375) (xy 290.081462 -17.433544) (xy 290.081716 -17.433798)
				(arc
					(start 290.083748 -17.434814)
					(mid 290.339272 -18.280634)
					(end 291.185092 -18.02511)
				)
				(xy 291.187378 -18.02638) (xy 291.93744 -16.626586)
			)
		)
		(polygon
			(pts
				(arc
					(start 171.93514 -16.625316)
					(mid 171.679616 -15.779496)
					(end 170.833796 -16.03502)
				)
				(xy 170.83151 -16.03375) (xy 170.081448 -17.433544) (xy 170.081702 -17.433798)
				(arc
					(start 170.083734 -17.434814)
					(mid 170.339258 -18.280634)
					(end 171.185078 -18.02511)
				)
				(xy 171.187364 -18.02638) (xy 171.937426 -16.626586)
			)
		)
		(polygon
			(pts
				(arc
					(start 169.685208 -16.625316)
					(mid 169.429684 -15.779496)
					(end 168.583864 -16.03502)
				)
				(xy 168.581578 -16.03375) (xy 167.831516 -17.433544) (xy 167.83177 -17.433798)
				(arc
					(start 167.833802 -17.434814)
					(mid 168.089326 -18.280634)
					(end 168.935146 -18.02511)
				)
				(xy 168.937432 -18.02638) (xy 169.687494 -16.626586)
			)
		)
		(polygon
			(pts
				(arc
					(start 160.935162 -16.625316)
					(mid 160.679638 -15.779496)
					(end 159.833818 -16.03502)
				)
				(xy 159.831532 -16.03375) (xy 159.08147 -17.433544) (xy 159.081724 -17.433798)
				(arc
					(start 159.083756 -17.434814)
					(mid 159.33928 -18.280634)
					(end 160.1851 -18.02511)
				)
				(xy 160.187386 -18.02638) (xy 160.937448 -16.626586)
			)
		)
		(polygon
			(pts
				(arc
					(start 158.68523 -16.625316)
					(mid 158.429706 -15.779496)
					(end 157.583886 -16.03502)
				)
				(xy 157.5816 -16.03375) (xy 156.831538 -17.433544) (xy 156.831792 -17.433798)
				(arc
					(start 156.833824 -17.434814)
					(mid 157.089348 -18.280634)
					(end 157.935168 -18.02511)
				)
				(xy 157.937454 -18.02638) (xy 158.687516 -16.626586)
			)
		)
		(polygon
			(pts
				(arc
					(start 149.935184 -16.625316)
					(mid 149.67966 -15.779496)
					(end 148.83384 -16.03502)
				)
				(xy 148.831554 -16.03375) (xy 148.081492 -17.433544) (xy 148.081746 -17.433798)
				(arc
					(start 148.083778 -17.434814)
					(mid 148.339302 -18.280634)
					(end 149.185122 -18.02511)
				)
				(xy 149.187408 -18.02638) (xy 149.93747 -16.626586)
			)
		)
		(polygon
			(pts
				(arc
					(start 138.935206 -16.625316)
					(mid 138.679682 -15.779496)
					(end 137.833862 -16.03502)
				)
				(xy 137.831576 -16.03375) (xy 137.081514 -17.433544) (xy 137.081768 -17.433798)
				(arc
					(start 137.0838 -17.434814)
					(mid 137.339324 -18.280634)
					(end 138.185144 -18.02511)
				)
				(xy 138.18743 -18.02638) (xy 138.937492 -16.626586)
			)
		)
		(polygon
			(pts
				(arc
					(start 300.6852 -16.625062)
					(mid 300.429168 -15.779242)
					(end 299.583348 -16.035274)
				)
				(xy 299.581316 -16.034004) (xy 298.831508 -17.433544) (xy 298.831762 -17.433798)
				(arc
					(start 298.833794 -17.434814)
					(mid 299.08947 -18.280715)
					(end 299.935392 -18.024856)
				)
				(xy 299.937424 -18.026126) (xy 300.687232 -16.626332)
			)
		)
		(polygon
			(pts
				(arc
					(start 289.685222 -16.625062)
					(mid 289.42919 -15.779242)
					(end 288.58337 -16.035274)
				)
				(xy 288.581338 -16.034004) (xy 287.83153 -17.433544) (xy 287.831784 -17.433798)
				(arc
					(start 287.833816 -17.434814)
					(mid 288.089492 -18.280715)
					(end 288.935414 -18.024856)
				)
				(xy 288.937446 -18.026126) (xy 289.687254 -16.626332)
			)
		)
		(polygon
			(pts
				(arc
					(start 147.685252 -16.625062)
					(mid 147.42922 -15.779242)
					(end 146.5834 -16.035274)
				)
				(xy 146.581368 -16.034004) (xy 145.83156 -17.433544) (xy 145.831814 -17.433798)
				(arc
					(start 145.833846 -17.434814)
					(mid 146.089522 -18.280715)
					(end 146.935444 -18.024856)
				)
				(xy 146.937476 -18.026126) (xy 147.687284 -16.626332)
			)
		)
		(polygon
			(pts
				(arc
					(start 136.685274 -16.625062)
					(mid 136.429242 -15.779242)
					(end 135.583422 -16.035274)
				)
				(xy 135.58139 -16.034004) (xy 134.831582 -17.433544) (xy 134.831836 -17.433798)
				(arc
					(start 134.833868 -17.434814)
					(mid 135.089544 -18.280715)
					(end 135.935466 -18.024856)
				)
				(xy 135.937498 -18.026126) (xy 136.687306 -16.626332)
			)
		)
		(polygon
			(pts
				(arc
					(start 291.935154 -12.825222)
					(mid 291.679478 -11.979321)
					(end 290.833556 -12.23518)
				)
				(xy 290.831524 -12.23391) (xy 290.081462 -13.633958)
				(arc
					(start 290.083494 -13.635228)
					(mid 290.339526 -14.481048)
					(end 291.185346 -14.225016)
				)
				(xy 291.187378 -14.226286) (xy 291.93744 -12.826492) (xy 291.937186 -12.826238)
			)
		)
		(polygon
			(pts
				(arc
					(start 287.435036 -12.825222)
					(mid 287.17936 -11.979321)
					(end 286.333438 -12.23518)
				)
				(xy 286.331406 -12.23391) (xy 285.581344 -13.633958)
				(arc
					(start 285.583376 -13.635228)
					(mid 285.839408 -14.481048)
					(end 286.685228 -14.225016)
				)
				(xy 286.68726 -14.226286) (xy 287.437322 -12.826492) (xy 287.437068 -12.826238)
			)
		)
		(polygon
			(pts
				(arc
					(start 138.935206 -12.825222)
					(mid 138.67953 -11.979321)
					(end 137.833608 -12.23518)
				)
				(xy 137.831576 -12.23391) (xy 137.081514 -13.633958)
				(arc
					(start 137.083546 -13.635228)
					(mid 137.339578 -14.481048)
					(end 138.185398 -14.225016)
				)
				(xy 138.18743 -14.226286) (xy 138.937492 -12.826492) (xy 138.937238 -12.826238)
			)
		)
		(polygon
			(pts
				(arc
					(start 134.435088 -12.825222)
					(mid 134.179412 -11.979321)
					(end 133.33349 -12.23518)
				)
				(xy 133.331458 -12.23391) (xy 132.581396 -13.633958)
				(arc
					(start 132.583428 -13.635228)
					(mid 132.83946 -14.481048)
					(end 133.68528 -14.225016)
				)
				(xy 133.687312 -14.226286) (xy 134.437374 -12.826492) (xy 134.43712 -12.826238)
			)
		)
		(polygon
			(pts
				(arc
					(start 324.935342 -12.824968)
					(mid 324.67931 -11.979148)
					(end 323.83349 -12.23518)
				)
				(xy 323.831458 -12.23391) (xy 323.081396 -13.633704) (xy 323.08165 -13.633958)
				(arc
					(start 323.083682 -13.634974)
					(mid 323.339358 -14.480875)
					(end 324.18528 -14.225016)
				)
				(xy 324.187312 -14.226286) (xy 324.937374 -12.826238)
			)
		)
		(polygon
			(pts
				(arc
					(start 322.68541 -12.824968)
					(mid 322.429378 -11.979148)
					(end 321.583558 -12.23518)
				)
				(xy 321.581526 -12.23391) (xy 320.831464 -13.633704) (xy 320.831718 -13.633958)
				(arc
					(start 320.83375 -13.634974)
					(mid 321.089426 -14.480875)
					(end 321.935348 -14.225016)
				)
				(xy 321.93738 -14.226286) (xy 322.687442 -12.826238)
			)
		)
		(polygon
			(pts
				(arc
					(start 320.435224 -12.824968)
					(mid 320.179192 -11.979148)
					(end 319.333372 -12.23518)
				)
				(arc
					(start 318.587628 -13.627608)
					(mid 318.835762 -14.479061)
					(end 319.685416 -14.225016)
				)
			)
		)
		(polygon
			(pts
				(arc
					(start 313.935364 -12.824968)
					(mid 313.679332 -11.979148)
					(end 312.833512 -12.23518)
				)
				(xy 312.83148 -12.23391) (xy 312.081418 -13.633704) (xy 312.081672 -13.633958)
				(arc
					(start 312.083704 -13.634974)
					(mid 312.33938 -14.480875)
					(end 313.185302 -14.225016)
				)
				(xy 313.187334 -14.226286) (xy 313.937396 -12.826238)
			)
		)
		(polygon
			(pts
				(arc
					(start 311.685432 -12.824968)
					(mid 311.4294 -11.979148)
					(end 310.58358 -12.23518)
				)
				(xy 310.581548 -12.23391) (xy 309.831486 -13.633704) (xy 309.83174 -13.633958)
				(arc
					(start 309.833772 -13.634974)
					(mid 310.089448 -14.480875)
					(end 310.93537 -14.225016)
				)
				(xy 310.937402 -14.226286) (xy 311.687464 -12.826238)
			)
		)
		(polygon
			(pts
				(arc
					(start 309.435246 -12.824968)
					(mid 309.179214 -11.979148)
					(end 308.333394 -12.23518)
				)
				(arc
					(start 307.58765 -13.627608)
					(mid 307.835784 -14.479061)
					(end 308.685438 -14.225016)
				)
			)
		)
		(polygon
			(pts
				(arc
					(start 302.935386 -12.824968)
					(mid 302.679354 -11.979148)
					(end 301.833534 -12.23518)
				)
				(xy 301.831502 -12.23391) (xy 301.08144 -13.633704) (xy 301.081694 -13.633958)
				(arc
					(start 301.083726 -13.634974)
					(mid 301.339402 -14.480875)
					(end 302.185324 -14.225016)
				)
				(xy 302.187356 -14.226286) (xy 302.937418 -12.826238)
			)
		)
		(polygon
			(pts
				(arc
					(start 300.6852 -12.824968)
					(mid 300.429168 -11.979148)
					(end 299.583348 -12.23518)
				)
				(arc
					(start 298.837604 -13.627608)
					(mid 299.085738 -14.479061)
					(end 299.935392 -14.225016)
				)
			)
		)
		(polygon
			(pts
				(arc
					(start 298.435268 -12.824968)
					(mid 298.179236 -11.979148)
					(end 297.333416 -12.23518)
				)
				(xy 297.331384 -12.23391) (xy 296.581322 -13.633704) (xy 296.581576 -13.633958)
				(arc
					(start 296.583608 -13.634974)
					(mid 296.839284 -14.480875)
					(end 297.685206 -14.225016)
				)
				(xy 297.687238 -14.226286) (xy 298.4373 -12.826238)
			)
		)
		(polygon
			(pts
				(arc
					(start 171.935394 -12.824968)
					(mid 171.679362 -11.979148)
					(end 170.833542 -12.23518)
				)
				(xy 170.83151 -12.23391) (xy 170.081448 -13.633704) (xy 170.081702 -13.633958)
				(arc
					(start 170.083734 -13.634974)
					(mid 170.33941 -14.480875)
					(end 171.185332 -14.225016)
				)
				(xy 171.187364 -14.226286) (xy 171.937426 -12.826238)
			)
		)
		(polygon
			(pts
				(arc
					(start 169.685462 -12.824968)
					(mid 169.42943 -11.979148)
					(end 168.58361 -12.23518)
				)
				(xy 168.581578 -12.23391) (xy 167.831516 -13.633704) (xy 167.83177 -13.633958)
				(arc
					(start 167.833802 -13.634974)
					(mid 168.089478 -14.480875)
					(end 168.9354 -14.225016)
				)
				(xy 168.937432 -14.226286) (xy 169.687494 -12.826238)
			)
		)
		(polygon
			(pts
				(arc
					(start 167.435276 -12.824968)
					(mid 167.179244 -11.979148)
					(end 166.333424 -12.23518)
				)
				(arc
					(start 165.58768 -13.627608)
					(mid 165.835814 -14.479061)
					(end 166.685468 -14.225016)
				)
			)
		)
		(polygon
			(pts
				(arc
					(start 160.935416 -12.824968)
					(mid 160.679384 -11.979148)
					(end 159.833564 -12.23518)
				)
				(xy 159.831532 -12.23391) (xy 159.08147 -13.633704) (xy 159.081724 -13.633958)
				(arc
					(start 159.083756 -13.634974)
					(mid 159.339432 -14.480875)
					(end 160.185354 -14.225016)
				)
				(xy 160.187386 -14.226286) (xy 160.937448 -12.826238)
			)
		)
		(polygon
			(pts
				(arc
					(start 158.685484 -12.824968)
					(mid 158.429452 -11.979148)
					(end 157.583632 -12.23518)
				)
				(xy 157.5816 -12.23391) (xy 156.831538 -13.633704) (xy 156.831792 -13.633958)
				(arc
					(start 156.833824 -13.634974)
					(mid 157.0895 -14.480875)
					(end 157.935422 -14.225016)
				)
				(xy 157.937454 -14.226286) (xy 158.687516 -12.826238)
			)
		)
		(polygon
			(pts
				(arc
					(start 156.435298 -12.824968)
					(mid 156.179266 -11.979148)
					(end 155.333446 -12.23518)
				)
				(arc
					(start 154.587702 -13.627608)
					(mid 154.835836 -14.479061)
					(end 155.68549 -14.225016)
				)
			)
		)
		(polygon
			(pts
				(arc
					(start 149.935438 -12.824968)
					(mid 149.679406 -11.979148)
					(end 148.833586 -12.23518)
				)
				(xy 148.831554 -12.23391) (xy 148.081492 -13.633704) (xy 148.081746 -13.633958)
				(arc
					(start 148.083778 -13.634974)
					(mid 148.339454 -14.480875)
					(end 149.185376 -14.225016)
				)
				(xy 149.187408 -14.226286) (xy 149.93747 -12.826238)
			)
		)
		(polygon
			(pts
				(arc
					(start 147.685252 -12.824968)
					(mid 147.42922 -11.979148)
					(end 146.5834 -12.23518)
				)
				(arc
					(start 145.837656 -13.627608)
					(mid 146.08579 -14.479061)
					(end 146.935444 -14.225016)
				)
			)
		)
		(polygon
			(pts
				(arc
					(start 145.43532 -12.824968)
					(mid 145.179288 -11.979148)
					(end 144.333468 -12.23518)
				)
				(xy 144.331436 -12.23391) (xy 143.581374 -13.633704) (xy 143.581628 -13.633958)
				(arc
					(start 143.58366 -13.634974)
					(mid 143.839336 -14.480875)
					(end 144.685258 -14.225016)
				)
				(xy 144.68729 -14.226286) (xy 145.437352 -12.826238)
			)
		)
		(polygon
			(pts
				(arc
					(start 289.681158 -12.832588)
					(mid 289.433024 -11.981135)
					(end 288.58337 -12.23518)
				)
				(arc
					(start 287.833562 -13.635228)
					(mid 288.089594 -14.481048)
					(end 288.935414 -14.225016)
				)
			)
		)
		(polygon
			(pts
				(arc
					(start 136.68121 -12.832588)
					(mid 136.433076 -11.981135)
					(end 135.583422 -12.23518)
				)
				(arc
					(start 134.833614 -13.635228)
					(mid 135.089646 -14.481048)
					(end 135.935466 -14.225016)
				)
			)
		)
		(polygon
			(pts
				(xy 246.255794 3.2385) (xy 129.842006 3.2385) (xy 104.696006 -21.9075) (xy 96.949006 -21.9075) (xy 89.920826 -28.93568)
				(xy 54.868826 -28.93568) (xy 45.304456 -38.50005) (xy 43.68419 -38.50005) (xy 30.890972 -51.293268)
				(xy 30.890972 -52.913534) (xy 29.639006 -54.1655) (xy 23.827994 -54.1655)
				(arc
					(start 23.646384 -53.984144)
					(mid 23.857484 -53.410968)
					(end 23.368 -53.045614)
				)
				(arc
					(start 22.554946 -53.045614)
					(mid 22.203291 -53.186274)
					(end 22.045422 -53.5305)
				)
				(arc
					(start 14.790166 -53.5305)
					(mid 14.608698 -53.375082)
					(end 14.3764 -53.319172)
				)
				(arc
					(start 13.563346 -53.319172)
					(mid 13.3312 -53.375134)
					(end 13.149834 -53.5305)
				)
				(xy 6.144006 -53.5305) (xy 2.0955 -57.579006) (xy 2.0955 -169.750994) (xy 22.400006 -190.0555) (xy 25.126442 -190.0555)
				(xy 25.3365 -190.265558) (xy 25.3365 -200.103994) (xy 25.956006 -200.7235) (xy 55.831994 -200.7235)
				(xy 67.261994 -189.2935) (xy 86.565994 -189.2935) (xy 132.412994 -143.4465) (xy 335.993994 -143.4465)
				(xy 353.5045 -125.935994) (xy 353.5045 -47.927006) (xy 352.376994 -46.7995) (xy 345.996006 -46.7995)
				(xy 344.8685 -47.927006) (xy 344.8685 -119.936006) (xy 330.629006 -134.1755) (xy 142.318994 -134.1755)
				(xy 141.6685 -133.525006) (xy 141.6685 -85.067394) (xy 143.6751 -83.060794) (xy 143.6751 -78.330806)
				(xy 141.988794 -76.6445) (xy 112.473994 -76.6445) (xy 96.217994 -60.3885) (xy 87.962994 -60.3885)
				(xy 76.05522 -48.480726) (xy 76.05522 -48.067214) (xy 76.306934 -47.8155) (xy 108.292138 -47.8155)
				(xy 121.41708 -34.690558) (xy 121.41708 -20.711414) (xy 136.095994 -6.0325) (xy 174.444406 -6.0325)
				(xy 186.786266 -18.37436) (xy 201.782934 -18.37436) (xy 205.082394 -15.0749) (xy 222.786194 -15.0749)
				(xy 222.963994 -14.8971) (xy 235.480606 -14.8971) (xy 238.554006 -17.9705) (xy 264.512806 -17.9705)
				(xy 266.798806 -20.2565) (xy 272.824194 -20.2565) (xy 274.5613 -18.519394) (xy 274.5613 -12.113006)
				(xy 273.2151 -10.766806) (xy 273.2151 -7.089394) (xy 274.0025 -6.301994) (xy 274.0025 2.669794)
				(xy 273.433794 3.2385) (xy 256.207006 3.2385) (xy 255.191006 2.2225) (xy 247.271794 2.2225)
			)
		)
	)
	(zone
		(net "DUT_AVD_PCIE")
		(layer "In3.Cu")
		(hatch none 0.5)
		(connect_pads
			(clearance 0.5)
		)
		(min_thickness 0.25)
		(fill yes
			(thermal_gap 0.5)
			(thermal_bridge_width 0.5)
			(island_removal_mode 0)
		)
		(polygon
			(pts
				(xy 215.470994 -32.1945) (xy 212.7885 -34.876994) (xy 212.7885 -41.353994) (xy 211.152994 -42.9895)
				(xy 181.942994 -42.9895) (xy 178.3715 -46.560994) (xy 178.3715 -72.565006) (xy 179.910994 -74.1045)
				(xy 248.587006 -74.1045) (xy 249.222006 -73.4695) (xy 254.961644 -73.4695) (xy 255.3335 -73.097644)
				(xy 255.3335 -55.527194) (xy 254.987806 -55.1815) (xy 234.490006 -55.1815) (xy 232.3465 -53.037994)
				(xy 232.3465 -41.069006) (xy 233.6165 -39.799006) (xy 233.6165 -33.987994) (xy 231.823006 -32.1945)
			)
		)
		(polygon
			(pts
				(arc
					(start 203.7588 -50.29454)
					(mid 204.26934 -49.784)
					(end 203.7588 -49.27346)
				)
				(arc
					(start 202.945746 -49.27346)
					(mid 202.43546 -49.784127)
					(end 202.946 -50.29454)
				)
			)
		)
		(polygon
			(pts
				(arc
					(start 201.171302 -50.339752)
					(mid 201.780139 -49.724183)
					(end 201.164444 -49.115472)
				)
				(arc
					(start 200.046844 -49.122076)
					(mid 199.43826 -49.737772)
					(end 200.053956 -50.346356)
				)
			)
		)
		(polygon
			(pts
				(arc
					(start 198.429118 -45.590206)
					(mid 197.816851 -44.97832)
					(end 197.204838 -45.59046)
				)
				(arc
					(start 197.204838 -46.70806)
					(mid 197.816978 -47.3202)
					(end 198.429118 -46.70806)
				)
			)
		)
		(polygon
			(pts
				(arc
					(start 201.97318 -44.714922)
					(mid 201.36104 -44.102782)
					(end 200.7489 -44.714922)
				)
				(arc
					(start 200.7489 -45.832776)
					(mid 201.361167 -46.444662)
					(end 201.97318 -45.832522)
				)
			)
		)
	)
	(zone
		(net "P0V9")
		(layer "In3.Cu")
		(hatch none 0.5)
		(connect_pads
			(clearance 0.5)
		)
		(min_thickness 0.25)
		(fill yes
			(thermal_gap 0.5)
			(thermal_bridge_width 0.5)
			(island_removal_mode 0)
		)
		(polygon
			(pts
				(xy 164.035994 -61.9125) (xy 163.1315 -62.816994) (xy 163.1315 -70.533006) (xy 163.400994 -70.8025)
				(xy 177.656744 -70.8025) (xy 177.9905 -70.468744) (xy 177.9905 -62.297056) (xy 177.605944 -61.9125)
			)
		)
	)
	(zone
		(layer "In3.Cu")
		(hatch none 0.5)
		(connect_pads
			(clearance 0)
		)
		(min_thickness 0.25)
		(keepout
			(tracks allowed)
			(vias allowed)
			(pads allowed)
			(copperpour allowed)
			(footprints allowed)
		)
		(placement
			(enabled no)
			(sheetname "")
		)
		(fill
			(thermal_gap 0.5)
			(thermal_bridge_width 0.5)
			(island_removal_mode 0)
		)
		(polygon
			(pts
				(arc
					(start 22.452076 -57.302654)
					(mid 21.80591 -56.692423)
					(end 22.434042 -56.063642)
				)
				(xy 23.542244 -56.063642) (xy 23.55215 -56.063388)
				(arc
					(start 23.595584 -56.06415)
					(mid 24.182954 -56.699282)
					(end 23.563326 -57.302908)
				)
				(xy 22.45233 -57.302908)
			)
		)
	)
	(zone
		(net "P3V3_STBY")
		(layer "In3.Cu")
		(hatch none 0.5)
		(connect_pads
			(clearance 0.5)
		)
		(min_thickness 0.25)
		(fill yes
			(thermal_gap 0.5)
			(thermal_bridge_width 0.5)
			(island_removal_mode 0)
		)
		(polygon
			(pts
				(xy 129.999994 2.8575) (xy 104.853994 -22.2885) (xy 97.106994 -22.2885) (xy 90.078814 -29.31668)
				(xy 55.026814 -29.31668) (xy 45.462444 -38.88105) (xy 43.842178 -38.88105) (xy 31.271972 -51.451256)
				(xy 31.271972 -53.071522) (xy 29.796994 -54.5465) (xy 23.670006 -54.5465) (xy 23.1902 -54.066694)
				(arc
					(start 22.5552 -54.066694)
					(mid 22.356195 -54.02629)
					(end 22.188678 -53.9115)
				)
				(arc
					(start 14.880336 -53.9115)
					(mid 14.707221 -54.218554)
					(end 14.3764 -54.340252)
				)
				(arc
					(start 13.5636 -54.340252)
					(mid 13.232772 -54.218562)
					(end 13.059664 -53.9115)
				)
				(xy 6.301994 -53.9115) (xy 2.4765 -57.736994) (xy 2.4765 -169.593006) (xy 22.557994 -189.6745) (xy 29.766006 -189.6745)
				(xy 51.991006 -167.4495) (xy 73.327006 -167.4495) (xy 85.7885 -154.988006) (xy 85.7885 -88.470994)
				(xy 75.867006 -78.5495) (xy 32.560006 -78.5495) (xy 29.9085 -75.897994) (xy 29.9085 -70.025006)
				(arc
					(start 51.910234 -48.023272)
					(mid 51.989832 -47.572094)
					(end 52.399184 -47.366428)
				)
				(xy 52.567078 -47.366428) (xy 54.023006 -45.9105) (xy 73.484994 -45.9105) (xy 75.372214 -47.79772)
				(xy 75.785726 -47.79772) (xy 76.148946 -47.4345) (xy 108.13415 -47.4345) (xy 121.03608 -34.53257)
				(xy 121.03608 -20.553426) (xy 135.938006 -5.6515) (xy 174.602394 -5.6515) (xy 186.944254 -17.99336)
				(xy 201.624946 -17.99336) (xy 204.924406 -14.6939) (xy 222.628206 -14.6939) (xy 222.806006 -14.5161)
				(xy 235.638594 -14.5161) (xy 238.711994 -17.5895) (xy 264.670794 -17.5895) (xy 266.956794 -19.8755)
				(xy 272.666206 -19.8755) (xy 274.1803 -18.361406) (xy 274.1803 -12.270994) (xy 272.8341 -10.924794)
				(xy 272.8341 -6.931406) (xy 273.6215 -6.144006) (xy 273.6215 2.511806) (xy 273.275806 2.8575) (xy 256.364994 2.8575)
				(xy 255.348994 1.8415) (xy 247.113806 1.8415) (xy 246.097806 2.8575)
			)
		)
		(polygon
			(pts
				(arc
					(start 26.74112 -142.580106)
					(mid 26.128853 -141.96822)
					(end 25.51684 -142.58036)
				)
				(arc
					(start 25.51684 -143.69796)
					(mid 26.12898 -144.3101)
					(end 26.74112 -143.69796)
				)
			)
		)
		(polygon
			(pts
				(arc
					(start 66.143378 -128.189736)
					(mid 66.653918 -127.679196)
					(end 66.143378 -127.168656)
				)
				(arc
					(start 65.330324 -127.168656)
					(mid 64.820038 -127.679323)
					(end 65.330578 -128.189736)
				)
			)
		)
		(polygon
			(pts
				(arc
					(start 23.77694 -113.994946)
					(mid 23.164673 -113.38306)
					(end 22.55266 -113.9952)
				)
				(arc
					(start 22.55266 -115.1128)
					(mid 23.1648 -115.72494)
					(end 23.77694 -115.1128)
				)
			)
		)
		(polygon
			(pts
				(arc
					(start 25.085294 -111.4044)
					(mid 24.473154 -110.79226)
					(end 23.861014 -111.4044)
				)
				(arc
					(start 23.861014 -112.522254)
					(mid 24.473281 -113.13414)
					(end 25.085294 -112.522)
				)
			)
		)
		(polygon
			(pts
				(arc
					(start 28.47594 -105.502202)
					(mid 27.610308 -105.502202)
					(end 27.610308 -106.367834)
				)
				(xy 27.60853 -106.369612) (xy 28.398978 -107.16006)
				(arc
					(start 28.400756 -107.158282)
					(mid 29.266388 -107.158282)
					(end 29.266388 -106.29265)
				)
				(xy 29.268166 -106.290872) (xy 28.477972 -105.500678) (xy 28.477464 -105.500678)
			)
		)
		(polygon
			(pts
				(arc
					(start 21.209 -87.93734)
					(mid 21.71954 -87.4268)
					(end 21.209 -86.91626)
				)
				(arc
					(start 20.395946 -86.91626)
					(mid 19.88566 -87.426927)
					(end 20.3962 -87.93734)
				)
			)
		)
		(polygon
			(pts
				(arc
					(start 16.9672 -87.65794)
					(mid 17.57934 -87.0458)
					(end 16.9672 -86.43366)
				)
				(arc
					(start 15.8496 -86.43366)
					(mid 15.23746 -87.0458)
					(end 15.8496 -87.65794)
				)
			)
		)
		(polygon
			(pts
				(arc
					(start 56.86298 -85.210396)
					(mid 56.250713 -84.59851)
					(end 55.6387 -85.21065)
				)
				(arc
					(start 55.6387 -86.32825)
					(mid 56.25084 -86.94039)
					(end 56.86298 -86.32825)
				)
			)
		)
		(polygon
			(pts
				(arc
					(start 19.664934 -82.41792)
					(mid 20.175474 -81.90738)
					(end 19.664934 -81.39684)
				)
				(arc
					(start 18.85188 -81.39684)
					(mid 18.341594 -81.907507)
					(end 18.852134 -82.41792)
				)
			)
		)
		(polygon
			(pts
				(arc
					(start 16.6116 -73.727564)
					(mid 17.12214 -73.217024)
					(end 16.6116 -72.706484)
				)
				(arc
					(start 15.798546 -72.706484)
					(mid 15.28826 -73.217151)
					(end 15.7988 -73.727564)
				)
			)
		)
		(polygon
			(pts
				(arc
					(start 19.38655 -73.721214)
					(mid 19.89709 -73.210674)
					(end 19.38655 -72.700134)
				)
				(arc
					(start 18.573496 -72.700134)
					(mid 18.06321 -73.210801)
					(end 18.57375 -73.721214)
				)
			)
		)
		(polygon
			(pts
				(arc
					(start 14.68374 -67.638168)
					(mid 14.173073 -67.127882)
					(end 13.66266 -67.638422)
				)
				(arc
					(start 13.66266 -68.451222)
					(mid 14.1732 -68.961762)
					(end 14.68374 -68.451222)
				)
			)
		)
		(polygon
			(pts
				(arc
					(start 16.69034 -66.223896)
					(mid 16.179673 -65.71361)
					(end 15.66926 -66.22415)
				)
				(arc
					(start 15.66926 -67.03695)
					(mid 16.1798 -67.54749)
					(end 16.69034 -67.03695)
				)
			)
		)
		(polygon
			(pts
				(arc
					(start 19.812 -58.851546)
					(mid 20.42414 -58.239406)
					(end 19.812 -57.627266)
				)
				(arc
					(start 18.6944 -57.627266)
					(mid 18.08226 -58.239406)
					(end 18.6944 -58.851546)
				)
			)
		)
		(polygon
			(pts
				(arc
					(start 23.535386 -57.300876)
					(mid 24.147526 -56.688736)
					(end 23.535386 -56.076596)
				)
				(arc
					(start 22.417786 -56.076596)
					(mid 21.805646 -56.688736)
					(end 22.417786 -57.300876)
				)
			)
		)
		(polygon
			(pts
				(arc
					(start 10.477754 -55.559452)
					(mid 10.98804 -55.048785)
					(end 10.4775 -54.538372)
				)
				(arc
					(start 9.6647 -54.538372)
					(mid 9.15416 -55.048912)
					(end 9.6647 -55.559452)
				)
			)
		)
		(polygon
			(pts
				(arc
					(start 19.659854 -55.508652)
					(mid 20.17014 -54.997985)
					(end 19.6596 -54.487572)
				)
				(arc
					(start 18.8468 -54.487572)
					(mid 18.33626 -54.998112)
					(end 18.8468 -55.508652)
				)
			)
		)
		(polygon
			(pts
				(arc
					(start 102.44074 -38.916356)
					(mid 101.930073 -38.40607)
					(end 101.41966 -38.91661)
				)
				(arc
					(start 101.41966 -39.80561)
					(mid 101.9302 -40.31615)
					(end 102.44074 -39.80561)
				)
			)
		)
		(polygon
			(pts
				(arc
					(start 103.02494 -36.205668)
					(mid 102.5144 -35.695128)
					(end 102.00386 -36.205668)
				)
				(arc
					(start 102.00386 -37.094922)
					(mid 102.514527 -37.605208)
					(end 103.02494 -37.094668)
				)
			)
		)
		(polygon
			(pts
				(arc
					(start 272.57883 -14.52245)
					(mid 272.06829 -14.01191)
					(end 271.55775 -14.52245)
				)
				(arc
					(start 271.55775 -15.335504)
					(mid 272.068417 -15.84579)
					(end 272.57883 -15.33525)
				)
			)
		)
		(polygon
			(pts
				(arc
					(start 268.98854 -13.842746)
					(mid 268.477873 -13.33246)
					(end 267.96746 -13.843)
				)
				(arc
					(start 267.96746 -14.6558)
					(mid 268.478 -15.16634)
					(end 268.98854 -14.6558)
				)
			)
		)
		(polygon
			(pts
				(arc
					(start 185.069226 -11.6967)
					(mid 184.558559 -11.186414)
					(end 184.048146 -11.696954)
				)
				(arc
					(start 184.048146 -12.509754)
					(mid 184.558686 -13.020294)
					(end 185.069226 -12.509754)
				)
			)
		)
		(polygon
			(pts
				(arc
					(start 184.443624 -8.91667)
					(mid 184.95391 -8.406003)
					(end 184.44337 -7.89559)
				)
				(arc
					(start 183.63057 -7.89559)
					(mid 183.12003 -8.40613)
					(end 183.63057 -8.91667)
				)
			)
		)
		(polygon
			(pts
				(arc
					(start 271.19834 -8.353298)
					(mid 270.687673 -7.843012)
					(end 270.17726 -8.353552)
				)
				(arc
					(start 270.17726 -9.166352)
					(mid 270.6878 -9.676892)
					(end 271.19834 -9.166352)
				)
			)
		)
		(polygon
			(pts
				(arc
					(start 270.05534 -5.305298)
					(mid 269.544673 -4.795012)
					(end 269.03426 -5.305552)
				)
				(arc
					(start 269.03426 -6.118352)
					(mid 269.5448 -6.628892)
					(end 270.05534 -6.118352)
				)
			)
		)
	)
	(zone
		(layers "In3.Cu" "In4.Cu")
		(hatch none 0.5)
		(connect_pads
			(clearance 0)
		)
		(min_thickness 0.25)
		(keepout
			(tracks not_allowed)
			(vias allowed)
			(pads allowed)
			(copperpour not_allowed)
			(footprints allowed)
		)
		(placement
			(enabled no)
			(sheetname "")
		)
		(fill yes
			(thermal_gap 0.5)
			(thermal_bridge_width 0.5)
			(island_removal_mode 0)
		)
		(polygon
			(pts
				(arc
					(start 25.729946 -38.509956)
					(mid 23.134066 -38.509956)
					(end 25.729946 -38.509956)
				)
			)
		)
	)
	(zone
		(layers "In3.Cu" "In4.Cu")
		(hatch none 0.5)
		(connect_pads
			(clearance 0)
		)
		(min_thickness 0.25)
		(keepout
			(tracks not_allowed)
			(vias allowed)
			(pads allowed)
			(copperpour not_allowed)
			(footprints allowed)
		)
		(placement
			(enabled no)
			(sheetname "")
		)
		(fill yes
			(thermal_gap 0.5)
			(thermal_bridge_width 0.5)
			(island_removal_mode 0)
		)
		(polygon
			(pts
				(arc
					(start 124.84481 -64.83096)
					(mid 122.75693 -64.83096)
					(end 124.84481 -64.83096)
				)
			)
		)
	)
	(zone
		(layers "In3.Cu" "In4.Cu")
		(hatch none 0.5)
		(connect_pads
			(clearance 0)
		)
		(min_thickness 0.25)
		(keepout
			(tracks not_allowed)
			(vias allowed)
			(pads allowed)
			(copperpour not_allowed)
			(footprints allowed)
		)
		(placement
			(enabled no)
			(sheetname "")
		)
		(fill yes
			(thermal_gap 0.5)
			(thermal_bridge_width 0.5)
			(island_removal_mode 0)
		)
		(polygon
			(pts
				(arc
					(start 258.48056 -1.011936)
					(mid 256.44348 -1.011936)
					(end 258.48056 -1.011936)
				)
			)
		)
	)
	(zone
		(layers "In3.Cu" "In4.Cu")
		(hatch none 0.5)
		(connect_pads
			(clearance 0)
		)
		(min_thickness 0.25)
		(keepout
			(tracks not_allowed)
			(vias allowed)
			(pads allowed)
			(copperpour not_allowed)
			(footprints allowed)
		)
		(placement
			(enabled no)
			(sheetname "")
		)
		(fill yes
			(thermal_gap 0.5)
			(thermal_bridge_width 0.5)
			(island_removal_mode 0)
		)
		(polygon
			(pts
				(arc
					(start 274.118578 -23.400004)
					(mid 272.081498 -23.400004)
					(end 274.118578 -23.400004)
				)
			)
		)
	)
	(zone
		(layers "In3.Cu" "In4.Cu")
		(hatch none 0.5)
		(connect_pads
			(clearance 0)
		)
		(min_thickness 0.25)
		(keepout
			(tracks not_allowed)
			(vias allowed)
			(pads allowed)
			(copperpour not_allowed)
			(footprints allowed)
		)
		(placement
			(enabled no)
			(sheetname "")
		)
		(fill yes
			(thermal_gap 0.5)
			(thermal_bridge_width 0.5)
			(island_removal_mode 0)
		)
		(polygon
			(pts
				(arc
					(start 17.81175 -60.300108)
					(mid 9.812274 -60.300108)
					(end 17.81175 -60.300108)
				)
			)
		)
	)
	(zone
		(layers "In3.Cu" "In4.Cu")
		(hatch none 0.5)
		(connect_pads
			(clearance 0)
		)
		(min_thickness 0.25)
		(keepout
			(tracks not_allowed)
			(vias allowed)
			(pads allowed)
			(copperpour not_allowed)
			(footprints allowed)
		)
		(placement
			(enabled no)
			(sheetname "")
		)
		(fill yes
			(thermal_gap 0.5)
			(thermal_bridge_width 0.5)
			(island_removal_mode 0)
		)
		(polygon
			(pts
				(arc
					(start 8.150098 -38.509956)
					(mid 5.554218 -38.509956)
					(end 8.150098 -38.509956)
				)
			)
		)
	)
	(zone
		(layers "In3.Cu" "In4.Cu")
		(hatch none 0.5)
		(connect_pads
			(clearance 0)
		)
		(min_thickness 0.25)
		(keepout
			(tracks not_allowed)
			(vias allowed)
			(pads allowed)
			(copperpour not_allowed)
			(footprints allowed)
		)
		(placement
			(enabled no)
			(sheetname "")
		)
		(fill yes
			(thermal_gap 0.5)
			(thermal_bridge_width 0.5)
			(island_removal_mode 0)
		)
		(polygon
			(pts
				(arc
					(start 251.9807 -1.011936)
					(mid 249.94362 -1.011936)
					(end 251.9807 -1.011936)
				)
			)
		)
	)
	(zone
		(net "DUT_AVD_PCIE")
		(layer "In4.Cu")
		(hatch none 0.5)
		(connect_pads
			(clearance 0.5)
		)
		(min_thickness 0.25)
		(fill yes
			(thermal_gap 0.5)
			(thermal_bridge_width 0.5)
			(island_removal_mode 0)
		)
		(polygon
			(pts
				(xy 201.97318 -45.1485)
				(arc
					(start 201.97318 -45.832522)
					(mid 201.361167 -46.444662)
					(end 200.7489 -45.832776)
				)
				(xy 200.7489 -45.773594) (xy 190.31966 -56.202834) (xy 190.31966 -56.210454) (xy 190.208154 -56.32196)
				(xy 190.200534 -56.32196) (xy 187.403994 -59.1185) (xy 179.402994 -59.1185) (xy 178.3715 -60.149994)
				(xy 178.3715 -70.533006) (xy 178.767994 -70.9295) (xy 189.689994 -70.9295) (xy 195.023994 -76.2635)
				(xy 225.219006 -76.2635) (xy 234.3785 -67.104006) (xy 234.3785 -55.425594) (xy 234.134406 -55.1815)
				(xy 229.029006 -55.1815) (xy 228.5365 -54.688994) (xy 228.5365 -45.392594) (xy 228.292406 -45.1485)
			)
		)
		(polygon
			(pts
				(arc
					(start 203.7588 -50.29454)
					(mid 204.26934 -49.784)
					(end 203.7588 -49.27346)
				)
				(arc
					(start 202.945746 -49.27346)
					(mid 202.43546 -49.784127)
					(end 202.946 -50.29454)
				)
			)
		)
		(polygon
			(pts
				(arc
					(start 201.171302 -50.339752)
					(mid 201.780139 -49.724183)
					(end 201.164444 -49.115472)
				)
				(arc
					(start 200.046844 -49.122076)
					(mid 199.43826 -49.737772)
					(end 200.053956 -50.346356)
				)
			)
		)
	)
	(zone
		(net "DUT_AVD_TX")
		(layer "In4.Cu")
		(hatch none 0.5)
		(connect_pads
			(clearance 0.5)
		)
		(min_thickness 0.25)
		(fill yes
			(thermal_gap 0.5)
			(thermal_bridge_width 0.5)
			(island_removal_mode 0)
		)
		(polygon
			(pts
				(xy 235.079794 -55.1815) (xy 234.7595 -55.501794) (xy 234.7595 -67.261994) (xy 225.376994 -76.6445)
				(xy 194.866006 -76.6445) (xy 189.532006 -71.3105) (xy 178.610006 -71.3105) (xy 178.054 -70.754494)
				(xy 177.624994 -71.1835) (xy 172.544232 -71.1835) (xy 172.0215 -71.706232) (xy 172.0215 -79.296006)
				(xy 178.894994 -86.1695) (xy 236.395006 -86.1695) (xy 246.5705 -75.994006) (xy 246.5705 -55.527194)
				(xy 246.224806 -55.1815)
			)
		)
	)
	(zone
		(net "P0V9")
		(layer "In4.Cu")
		(hatch none 0.5)
		(connect_pads
			(clearance 0.5)
		)
		(min_thickness 0.25)
		(fill yes
			(thermal_gap 0.5)
			(thermal_bridge_width 0.5)
			(island_removal_mode 0)
		)
		(polygon
			(pts
				(xy 164.035994 -61.9125) (xy 163.1315 -62.816994) (xy 163.1315 -70.533006) (xy 163.400994 -70.8025)
				(xy 177.467006 -70.8025) (xy 177.9905 -70.279006) (xy 177.9905 -62.446408) (xy 177.456592 -61.9125)
			)
		)
	)
	(zone
		(net "P0V9_E")
		(layer "In4.Cu")
		(hatch none 0.5)
		(connect_pads
			(clearance 0.5)
		)
		(min_thickness 0.25)
		(fill yes
			(thermal_gap 0.5)
			(thermal_bridge_width 0.5)
			(island_removal_mode 0)
		)
		(polygon
			(pts
				(xy 310.850788 -55.1815) (xy 310.3245 -55.707788) (xy 310.3245 -67.739768) (xy 310.847232 -68.2625)
				(xy 325.168006 -68.2625) (xy 325.5645 -67.866006) (xy 325.5645 -55.958994) (xy 324.787006 -55.1815)
			)
		)
	)
	(zone
		(net "GND")
		(layer "In4.Cu")
		(hatch none 0.5)
		(connect_pads
			(clearance 0.5)
		)
		(min_thickness 0.25)
		(fill yes
			(thermal_gap 0.5)
			(thermal_bridge_width 0.5)
			(island_removal_mode 0)
		)
		(polygon
			(pts
				(arc
					(start 123.637548 4.236974)
					(mid 122.762871 3.874671)
					(end 122.400568 2.999994)
				)
				(arc
					(start 122.400568 1.999996)
					(mid 121.591301 0.046251)
					(end 119.637556 -0.763016)
				)
				(arc
					(start 53.950108 -0.763016)
					(mid 53.075431 -1.125319)
					(end 52.713128 -1.999996)
				)
				(arc
					(start 52.713128 -24.010112)
					(mid 51.903861 -25.963857)
					(end 49.950116 -26.773124)
				)
				(arc
					(start 1.999996 -26.773124)
					(mid 1.125319 -27.135427)
					(end 0.763016 -28.010104)
				)
				(arc
					(start 0.763016 -212.499956)
					(mid 0.832426 -212.667528)
					(end 0.999998 -212.736938)
				)
				(arc
					(start 25.4 -212.736938)
					(mid 26.858753 -213.341173)
					(end 27.462988 -214.799926)
				)
				(xy 27.462988 -221.136972)
				(arc
					(start 28.000198 -221.136972)
					(mid 28.89312 -221.506938)
					(end 29.263086 -222.39986)
				)
				(xy 29.263086 -225.460052) (xy 73.337928 -225.460052)
				(arc
					(start 73.337928 -222.600012)
					(mid 73.343892 -222.44689)
					(end 73.361804 -222.294704)
				)
				(arc
					(start 73.361804 -222.294704)
					(mid 73.927667 -221.197654)
					(end 75.03668 -220.655642)
				)
				(arc
					(start 75.03668 -220.655642)
					(mid 75.299952 -220.636928)
					(end 75.563222 -220.655642)
				)
				(arc
					(start 75.563222 -220.655642)
					(mid 76.777453 -221.309057)
					(end 77.261974 -222.600012)
				)
				(xy 77.261974 -225.460052) (xy 111.736886 -225.460052)
				(arc
					(start 111.736886 -222.39986)
					(mid 112.106852 -221.506938)
					(end 112.999774 -221.136972)
				)
				(xy 113.536984 -221.136972)
				(arc
					(start 113.536984 -214.799926)
					(mid 114.141219 -213.341173)
					(end 115.599972 -212.736938)
				)
				(arc
					(start 131.400042 -212.736938)
					(mid 132.858795 -213.341173)
					(end 133.46303 -214.799926)
				)
				(xy 133.46303 -221.136972)
				(arc
					(start 134.00024 -221.136972)
					(mid 134.893162 -221.506938)
					(end 135.263128 -222.39986)
				)
				(xy 135.263128 -225.460052) (xy 179.33797 -225.460052)
				(arc
					(start 179.33797 -222.600012)
					(mid 179.343934 -222.44689)
					(end 179.361846 -222.294704)
				)
				(arc
					(start 179.361846 -222.294704)
					(mid 179.927709 -221.197654)
					(end 181.036722 -220.655642)
				)
				(arc
					(start 181.036722 -220.655642)
					(mid 181.299994 -220.636928)
					(end 181.563264 -220.655642)
				)
				(arc
					(start 181.563264 -220.655642)
					(mid 182.777495 -221.309057)
					(end 183.262016 -222.600012)
				)
				(xy 183.262016 -225.460052) (xy 217.736928 -225.460052)
				(arc
					(start 217.736928 -222.39986)
					(mid 218.106894 -221.506938)
					(end 218.999816 -221.136972)
				)
				(xy 219.537026 -221.136972)
				(arc
					(start 219.537026 -214.799926)
					(mid 220.141261 -213.341173)
					(end 221.600014 -212.736938)
				)
				(arc
					(start 229.142036 -212.736938)
					(mid 232.138029 -211.495957)
					(end 233.37901 -208.499964)
				)
				(arc
					(start 233.37901 -165.269926)
					(mid 233.974467 -163.832367)
					(end 235.412026 -163.23691)
				)
				(arc
					(start 249.871992 -163.23691)
					(mid 251.309551 -163.832367)
					(end 251.905008 -165.269926)
				)
				(arc
					(start 251.905008 -208.499964)
					(mid 253.145989 -211.495957)
					(end 256.141982 -212.736938)
				)
				(arc
					(start 257.400044 -212.736938)
					(mid 258.858797 -213.341173)
					(end 259.463032 -214.799926)
				)
				(xy 259.463032 -221.136972)
				(arc
					(start 260.000242 -221.136972)
					(mid 260.893164 -221.506938)
					(end 261.26313 -222.39986)
				)
				(xy 261.26313 -225.460052) (xy 305.337972 -225.460052)
				(arc
					(start 305.337972 -222.600012)
					(mid 305.343936 -222.44689)
					(end 305.361848 -222.294704)
				)
				(arc
					(start 305.361848 -222.294704)
					(mid 305.927711 -221.197654)
					(end 307.036724 -220.655642)
				)
				(arc
					(start 307.036724 -220.655642)
					(mid 307.299996 -220.636928)
					(end 307.563266 -220.655642)
				)
				(arc
					(start 307.563266 -220.655642)
					(mid 308.777497 -221.309057)
					(end 309.262018 -222.600012)
				)
				(xy 309.262018 -225.460052) (xy 343.73693 -225.460052)
				(arc
					(start 343.73693 -222.39986)
					(mid 344.106896 -221.506938)
					(end 344.999818 -221.136972)
				)
				(xy 345.537028 -221.136972)
				(arc
					(start 345.537028 -214.799926)
					(mid 346.141263 -213.341173)
					(end 347.600016 -212.736938)
				)
				(arc
					(start 354.600002 -212.736938)
					(mid 354.767574 -212.667528)
					(end 354.836984 -212.499956)
				)
				(xy 354.836984 -19.463004)
				(arc
					(start 354.749862 -19.463004)
					(mid 353.856865 -19.093113)
					(end 353.486974 -18.200116)
				)
				(arc
					(start 353.486974 -10.199878)
					(mid 353.856865 -9.306881)
					(end 354.749862 -8.93699)
				)
				(xy 354.836984 -8.93699)
				(arc
					(start 354.836984 -0.999998)
					(mid 354.767574 -0.832426)
					(end 354.600002 -0.763016)
				)
				(arc
					(start 332.749906 -0.763016)
					(mid 331.503267 -0.246641)
					(end 330.986892 0.999998)
				)
				(arc
					(start 330.986892 3.999992)
					(mid 330.917482 4.167564)
					(end 330.74991 4.236974)
				)
			)
		)
		(polygon
			(pts
				(arc
					(start 341.306404 -222.805244)
					(mid 341.816944 -222.294704)
					(end 341.306404 -221.784164)
				)
				(arc
					(start 340.49335 -221.784164)
					(mid 339.983064 -222.294831)
					(end 340.493604 -222.805244)
				)
			)
		)
		(polygon
			(pts
				(arc
					(start 338.106766 -222.805244)
					(mid 338.617052 -222.294577)
					(end 338.106512 -221.784164)
				)
				(arc
					(start 337.293712 -221.784164)
					(mid 336.783172 -222.294704)
					(end 337.293712 -222.805244)
				)
			)
		)
		(polygon
			(pts
				(arc
					(start 334.90662 -222.805244)
					(mid 335.416906 -222.294577)
					(end 334.906366 -221.784164)
				)
				(arc
					(start 334.093566 -221.784164)
					(mid 333.583026 -222.294704)
					(end 334.093566 -222.805244)
				)
			)
		)
		(polygon
			(pts
				(arc
					(start 331.706728 -222.805244)
					(mid 332.217014 -222.294577)
					(end 331.706474 -221.784164)
				)
				(arc
					(start 330.893674 -221.784164)
					(mid 330.383134 -222.294704)
					(end 330.893674 -222.805244)
				)
			)
		)
		(polygon
			(pts
				(arc
					(start 328.506836 -222.805244)
					(mid 329.017122 -222.294577)
					(end 328.506582 -221.784164)
				)
				(arc
					(start 327.693782 -221.784164)
					(mid 327.183242 -222.294704)
					(end 327.693782 -222.805244)
				)
			)
		)
		(polygon
			(pts
				(arc
					(start 325.30669 -222.805244)
					(mid 325.816976 -222.294577)
					(end 325.306436 -221.784164)
				)
				(arc
					(start 324.493636 -221.784164)
					(mid 323.983096 -222.294704)
					(end 324.493636 -222.805244)
				)
			)
		)
		(polygon
			(pts
				(arc
					(start 322.106798 -222.805244)
					(mid 322.617084 -222.294577)
					(end 322.106544 -221.784164)
				)
				(arc
					(start 321.293744 -221.784164)
					(mid 320.783204 -222.294704)
					(end 321.293744 -222.805244)
				)
			)
		)
		(polygon
			(pts
				(arc
					(start 318.906652 -222.805244)
					(mid 319.416938 -222.294577)
					(end 318.906398 -221.784164)
				)
				(arc
					(start 318.093598 -221.784164)
					(mid 317.583058 -222.294704)
					(end 318.093598 -222.805244)
				)
			)
		)
		(polygon
			(pts
				(arc
					(start 315.70676 -222.805244)
					(mid 316.217046 -222.294577)
					(end 315.706506 -221.784164)
				)
				(arc
					(start 314.893706 -221.784164)
					(mid 314.383166 -222.294704)
					(end 314.893706 -222.805244)
				)
			)
		)
		(polygon
			(pts
				(arc
					(start 312.506614 -222.805244)
					(mid 313.0169 -222.294577)
					(end 312.50636 -221.784164)
				)
				(arc
					(start 311.69356 -221.784164)
					(mid 311.18302 -222.294704)
					(end 311.69356 -222.805244)
				)
			)
		)
		(polygon
			(pts
				(arc
					(start 301.306738 -222.805244)
					(mid 301.817024 -222.294577)
					(end 301.306484 -221.784164)
				)
				(arc
					(start 300.493684 -221.784164)
					(mid 299.983144 -222.294704)
					(end 300.493684 -222.805244)
				)
			)
		)
		(polygon
			(pts
				(arc
					(start 295.7068 -222.805244)
					(mid 296.217086 -222.294577)
					(end 295.706546 -221.784164)
				)
				(arc
					(start 294.893746 -221.784164)
					(mid 294.383206 -222.294704)
					(end 294.893746 -222.805244)
				)
			)
		)
		(polygon
			(pts
				(arc
					(start 292.506654 -222.805244)
					(mid 293.01694 -222.294577)
					(end 292.5064 -221.784164)
				)
				(arc
					(start 291.6936 -221.784164)
					(mid 291.18306 -222.294704)
					(end 291.6936 -222.805244)
				)
			)
		)
		(polygon
			(pts
				(arc
					(start 289.306762 -222.805244)
					(mid 289.817048 -222.294577)
					(end 289.306508 -221.784164)
				)
				(arc
					(start 288.493708 -221.784164)
					(mid 287.983168 -222.294704)
					(end 288.493708 -222.805244)
				)
			)
		)
		(polygon
			(pts
				(arc
					(start 286.106616 -222.805244)
					(mid 286.616902 -222.294577)
					(end 286.106362 -221.784164)
				)
				(arc
					(start 285.293562 -221.784164)
					(mid 284.783022 -222.294704)
					(end 285.293562 -222.805244)
				)
			)
		)
		(polygon
			(pts
				(arc
					(start 282.906724 -222.805244)
					(mid 283.41701 -222.294577)
					(end 282.90647 -221.784164)
				)
				(arc
					(start 282.09367 -221.784164)
					(mid 281.58313 -222.294704)
					(end 282.09367 -222.805244)
				)
			)
		)
		(polygon
			(pts
				(arc
					(start 279.706832 -222.805244)
					(mid 280.217118 -222.294577)
					(end 279.706578 -221.784164)
				)
				(arc
					(start 278.893778 -221.784164)
					(mid 278.383238 -222.294704)
					(end 278.893778 -222.805244)
				)
			)
		)
		(polygon
			(pts
				(arc
					(start 276.506686 -222.805244)
					(mid 277.016972 -222.294577)
					(end 276.506432 -221.784164)
				)
				(arc
					(start 275.693632 -221.784164)
					(mid 275.183092 -222.294704)
					(end 275.693632 -222.805244)
				)
			)
		)
		(polygon
			(pts
				(arc
					(start 273.306794 -222.805244)
					(mid 273.81708 -222.294577)
					(end 273.30654 -221.784164)
				)
				(arc
					(start 272.49374 -221.784164)
					(mid 271.9832 -222.294704)
					(end 272.49374 -222.805244)
				)
			)
		)
		(polygon
			(pts
				(arc
					(start 266.906756 -222.805244)
					(mid 267.417042 -222.294577)
					(end 266.906502 -221.784164)
				)
				(arc
					(start 266.093702 -221.784164)
					(mid 265.583162 -222.294704)
					(end 266.093702 -222.805244)
				)
			)
		)
		(polygon
			(pts
				(arc
					(start 263.70661 -222.805244)
					(mid 264.216896 -222.294577)
					(end 263.706356 -221.784164)
				)
				(arc
					(start 262.893556 -221.784164)
					(mid 262.383016 -222.294704)
					(end 262.893556 -222.805244)
				)
			)
		)
		(polygon
			(pts
				(arc
					(start 215.306656 -222.805244)
					(mid 215.816942 -222.294577)
					(end 215.306402 -221.784164)
				)
				(arc
					(start 214.493602 -221.784164)
					(mid 213.983062 -222.294704)
					(end 214.493602 -222.805244)
				)
			)
		)
		(polygon
			(pts
				(arc
					(start 212.106764 -222.805244)
					(mid 212.61705 -222.294577)
					(end 212.10651 -221.784164)
				)
				(arc
					(start 211.29371 -221.784164)
					(mid 210.78317 -222.294704)
					(end 211.29371 -222.805244)
				)
			)
		)
		(polygon
			(pts
				(arc
					(start 205.706726 -222.805244)
					(mid 206.217012 -222.294577)
					(end 205.706472 -221.784164)
				)
				(arc
					(start 204.893672 -221.784164)
					(mid 204.383132 -222.294704)
					(end 204.893672 -222.805244)
				)
			)
		)
		(polygon
			(pts
				(arc
					(start 202.506834 -222.805244)
					(mid 203.01712 -222.294577)
					(end 202.50658 -221.784164)
				)
				(arc
					(start 201.69378 -221.784164)
					(mid 201.18324 -222.294704)
					(end 201.69378 -222.805244)
				)
			)
		)
		(polygon
			(pts
				(arc
					(start 199.306688 -222.805244)
					(mid 199.816974 -222.294577)
					(end 199.306434 -221.784164)
				)
				(arc
					(start 198.493634 -221.784164)
					(mid 197.983094 -222.294704)
					(end 198.493634 -222.805244)
				)
			)
		)
		(polygon
			(pts
				(arc
					(start 196.106796 -222.805244)
					(mid 196.617082 -222.294577)
					(end 196.106542 -221.784164)
				)
				(arc
					(start 195.293742 -221.784164)
					(mid 194.783202 -222.294704)
					(end 195.293742 -222.805244)
				)
			)
		)
		(polygon
			(pts
				(arc
					(start 192.90665 -222.805244)
					(mid 193.416936 -222.294577)
					(end 192.906396 -221.784164)
				)
				(arc
					(start 192.093596 -221.784164)
					(mid 191.583056 -222.294704)
					(end 192.093596 -222.805244)
				)
			)
		)
		(polygon
			(pts
				(arc
					(start 189.706758 -222.805244)
					(mid 190.217044 -222.294577)
					(end 189.706504 -221.784164)
				)
				(arc
					(start 188.893704 -221.784164)
					(mid 188.383164 -222.294704)
					(end 188.893704 -222.805244)
				)
			)
		)
		(polygon
			(pts
				(arc
					(start 186.506358 -222.805244)
					(mid 187.016898 -222.294704)
					(end 186.506358 -221.784164)
				)
				(arc
					(start 185.693304 -221.784164)
					(mid 185.183018 -222.294831)
					(end 185.693558 -222.805244)
				)
			)
		)
		(polygon
			(pts
				(arc
					(start 175.306736 -222.805244)
					(mid 175.817022 -222.294577)
					(end 175.306482 -221.784164)
				)
				(arc
					(start 174.493682 -221.784164)
					(mid 173.983142 -222.294704)
					(end 174.493682 -222.805244)
				)
			)
		)
		(polygon
			(pts
				(arc
					(start 172.106844 -222.805244)
					(mid 172.61713 -222.294577)
					(end 172.10659 -221.784164)
				)
				(arc
					(start 171.29379 -221.784164)
					(mid 170.78325 -222.294704)
					(end 171.29379 -222.805244)
				)
			)
		)
		(polygon
			(pts
				(arc
					(start 168.906698 -222.805244)
					(mid 169.416984 -222.294577)
					(end 168.906444 -221.784164)
				)
				(arc
					(start 168.093644 -221.784164)
					(mid 167.583104 -222.294704)
					(end 168.093644 -222.805244)
				)
			)
		)
		(polygon
			(pts
				(arc
					(start 165.706806 -222.805244)
					(mid 166.217092 -222.294577)
					(end 165.706552 -221.784164)
				)
				(arc
					(start 164.893752 -221.784164)
					(mid 164.383212 -222.294704)
					(end 164.893752 -222.805244)
				)
			)
		)
		(polygon
			(pts
				(arc
					(start 160.106614 -222.805244)
					(mid 160.6169 -222.294577)
					(end 160.10636 -221.784164)
				)
				(arc
					(start 159.29356 -221.784164)
					(mid 158.78302 -222.294704)
					(end 159.29356 -222.805244)
				)
			)
		)
		(polygon
			(pts
				(arc
					(start 156.906722 -222.805244)
					(mid 157.417008 -222.294577)
					(end 156.906468 -221.784164)
				)
				(arc
					(start 156.093668 -221.784164)
					(mid 155.583128 -222.294704)
					(end 156.093668 -222.805244)
				)
			)
		)
		(polygon
			(pts
				(arc
					(start 153.70683 -222.805244)
					(mid 154.217116 -222.294577)
					(end 153.706576 -221.784164)
				)
				(arc
					(start 152.893776 -221.784164)
					(mid 152.383236 -222.294704)
					(end 152.893776 -222.805244)
				)
			)
		)
		(polygon
			(pts
				(arc
					(start 150.506684 -222.805244)
					(mid 151.01697 -222.294577)
					(end 150.50643 -221.784164)
				)
				(arc
					(start 149.69363 -221.784164)
					(mid 149.18309 -222.294704)
					(end 149.69363 -222.805244)
				)
			)
		)
		(polygon
			(pts
				(arc
					(start 147.306792 -222.805244)
					(mid 147.817078 -222.294577)
					(end 147.306538 -221.784164)
				)
				(arc
					(start 146.493738 -221.784164)
					(mid 145.983198 -222.294704)
					(end 146.493738 -222.805244)
				)
			)
		)
		(polygon
			(pts
				(arc
					(start 144.106646 -222.805244)
					(mid 144.616932 -222.294577)
					(end 144.106392 -221.784164)
				)
				(arc
					(start 143.293592 -221.784164)
					(mid 142.783052 -222.294704)
					(end 143.293592 -222.805244)
				)
			)
		)
		(polygon
			(pts
				(arc
					(start 140.906754 -222.805244)
					(mid 141.41704 -222.294577)
					(end 140.9065 -221.784164)
				)
				(arc
					(start 140.0937 -221.784164)
					(mid 139.58316 -222.294704)
					(end 140.0937 -222.805244)
				)
			)
		)
		(polygon
			(pts
				(arc
					(start 137.706608 -222.805244)
					(mid 138.216894 -222.294577)
					(end 137.706354 -221.784164)
				)
				(arc
					(start 136.893554 -221.784164)
					(mid 136.383014 -222.294704)
					(end 136.893554 -222.805244)
				)
			)
		)
		(polygon
			(pts
				(arc
					(start 106.906568 -222.805244)
					(mid 107.416854 -222.294577)
					(end 106.906314 -221.784164)
				)
				(arc
					(start 106.093514 -221.784164)
					(mid 105.582974 -222.294704)
					(end 106.093514 -222.805244)
				)
			)
		)
		(polygon
			(pts
				(arc
					(start 103.706422 -222.805244)
					(mid 104.216708 -222.294577)
					(end 103.706168 -221.784164)
				)
				(arc
					(start 102.893368 -221.784164)
					(mid 102.382828 -222.294704)
					(end 102.893368 -222.805244)
				)
			)
		)
		(polygon
			(pts
				(arc
					(start 100.50653 -222.805244)
					(mid 101.016816 -222.294577)
					(end 100.506276 -221.784164)
				)
				(arc
					(start 99.693476 -221.784164)
					(mid 99.182936 -222.294704)
					(end 99.693476 -222.805244)
				)
			)
		)
		(polygon
			(pts
				(arc
					(start 97.306638 -222.805244)
					(mid 97.816924 -222.294577)
					(end 97.306384 -221.784164)
				)
				(arc
					(start 96.493584 -221.784164)
					(mid 95.983044 -222.294704)
					(end 96.493584 -222.805244)
				)
			)
		)
		(polygon
			(pts
				(arc
					(start 91.706446 -222.805244)
					(mid 92.216732 -222.294577)
					(end 91.706192 -221.784164)
				)
				(arc
					(start 90.893392 -221.784164)
					(mid 90.382852 -222.294704)
					(end 90.893392 -222.805244)
				)
			)
		)
		(polygon
			(pts
				(arc
					(start 88.506554 -222.805244)
					(mid 89.01684 -222.294577)
					(end 88.5063 -221.784164)
				)
				(arc
					(start 87.6935 -221.784164)
					(mid 87.18296 -222.294704)
					(end 87.6935 -222.805244)
				)
			)
		)
		(polygon
			(pts
				(arc
					(start 85.306408 -222.805244)
					(mid 85.816694 -222.294577)
					(end 85.306154 -221.784164)
				)
				(arc
					(start 84.493354 -221.784164)
					(mid 83.982814 -222.294704)
					(end 84.493354 -222.805244)
				)
			)
		)
		(polygon
			(pts
				(arc
					(start 82.106516 -222.805244)
					(mid 82.616802 -222.294577)
					(end 82.106262 -221.784164)
				)
				(arc
					(start 81.293462 -221.784164)
					(mid 80.782922 -222.294704)
					(end 81.293462 -222.805244)
				)
			)
		)
		(polygon
			(pts
				(arc
					(start 69.30644 -222.805244)
					(mid 69.816726 -222.294577)
					(end 69.306186 -221.784164)
				)
				(arc
					(start 68.493386 -221.784164)
					(mid 67.982846 -222.294704)
					(end 68.493386 -222.805244)
				)
			)
		)
		(polygon
			(pts
				(arc
					(start 66.106548 -222.805244)
					(mid 66.616834 -222.294577)
					(end 66.106294 -221.784164)
				)
				(arc
					(start 65.293494 -221.784164)
					(mid 64.782954 -222.294704)
					(end 65.293494 -222.805244)
				)
			)
		)
		(polygon
			(pts
				(arc
					(start 60.506356 -222.805244)
					(mid 61.016642 -222.294577)
					(end 60.506102 -221.784164)
				)
				(arc
					(start 59.693302 -221.784164)
					(mid 59.182762 -222.294704)
					(end 59.693302 -222.805244)
				)
			)
		)
		(polygon
			(pts
				(arc
					(start 57.306464 -222.805244)
					(mid 57.81675 -222.294577)
					(end 57.30621 -221.784164)
				)
				(arc
					(start 56.49341 -221.784164)
					(mid 55.98287 -222.294704)
					(end 56.49341 -222.805244)
				)
			)
		)
		(polygon
			(pts
				(arc
					(start 54.106572 -222.805244)
					(mid 54.616858 -222.294577)
					(end 54.106318 -221.784164)
				)
				(arc
					(start 53.293518 -221.784164)
					(mid 52.782978 -222.294704)
					(end 53.293518 -222.805244)
				)
			)
		)
		(polygon
			(pts
				(arc
					(start 50.906426 -221.916244)
					(mid 51.416712 -221.405577)
					(end 50.906172 -220.895164)
				)
				(arc
					(start 50.093372 -220.895164)
					(mid 49.582832 -221.405704)
					(end 50.093372 -221.916244)
				)
			)
		)
		(polygon
			(pts
				(arc
					(start 178.409854 -221.18574)
					(mid 178.92014 -220.675073)
					(end 178.4096 -220.16466)
				)
				(arc
					(start 177.5968 -220.16466)
					(mid 177.08626 -220.6752)
					(end 177.5968 -221.18574)
				)
			)
		)
		(polygon
			(pts
				(arc
					(start 304.562002 -220.779086)
					(mid 305.056286 -220.252798)
					(end 304.529998 -219.758514)
				)
				(xy 304.529998 -219.755974) (xy 303.717198 -219.781374)
				(arc
					(start 303.717198 -219.783914)
					(mid 303.222914 -220.310202)
					(end 303.749202 -220.804486)
				)
				(xy 303.749202 -220.807026) (xy 304.561748 -220.781626) (xy 304.562002 -220.781372)
			)
		)
		(polygon
			(pts
				(arc
					(start 72.517254 -220.52534)
					(mid 73.02754 -220.014673)
					(end 72.517 -219.50426)
				)
				(arc
					(start 71.7042 -219.50426)
					(mid 71.19366 -220.0148)
					(end 71.7042 -220.52534)
				)
			)
		)
		(polygon
			(pts
				(arc
					(start 78.982824 -220.392244)
					(mid 79.49311 -219.881577)
					(end 78.98257 -219.371164)
				)
				(arc
					(start 78.16977 -219.371164)
					(mid 77.65923 -219.881704)
					(end 78.16977 -220.392244)
				)
			)
		)
		(polygon
			(pts
				(arc
					(start 342.906604 -211.406994)
					(mid 343.41689 -210.896327)
					(end 342.90635 -210.385914)
				)
				(arc
					(start 342.09355 -210.385914)
					(mid 341.58301 -210.896454)
					(end 342.09355 -211.406994)
				)
			)
		)
		(polygon
			(pts
				(arc
					(start 339.706712 -211.406994)
					(mid 340.216998 -210.896327)
					(end 339.706458 -210.385914)
				)
				(arc
					(start 338.893658 -210.385914)
					(mid 338.383118 -210.896454)
					(end 338.893658 -211.406994)
				)
			)
		)
		(polygon
			(pts
				(arc
					(start 336.506566 -211.406994)
					(mid 337.017106 -210.896454)
					(end 336.506566 -210.385914)
				)
				(arc
					(start 335.693512 -210.385914)
					(mid 335.183226 -210.896581)
					(end 335.693766 -211.406994)
				)
			)
		)
		(polygon
			(pts
				(arc
					(start 333.306674 -211.406994)
					(mid 333.817214 -210.896454)
					(end 333.306674 -210.385914)
				)
				(arc
					(start 332.49362 -210.385914)
					(mid 331.983334 -210.896581)
					(end 332.493874 -211.406994)
				)
			)
		)
		(polygon
			(pts
				(arc
					(start 326.906382 -211.406994)
					(mid 327.416922 -210.896454)
					(end 326.906382 -210.385914)
				)
				(arc
					(start 326.093328 -210.385914)
					(mid 325.583042 -210.896581)
					(end 326.093582 -211.406994)
				)
			)
		)
		(polygon
			(pts
				(arc
					(start 323.70649 -211.406994)
					(mid 324.21703 -210.896454)
					(end 323.70649 -210.385914)
				)
				(arc
					(start 322.893436 -210.385914)
					(mid 322.38315 -210.896581)
					(end 322.89369 -211.406994)
				)
			)
		)
		(polygon
			(pts
				(arc
					(start 320.506598 -211.406994)
					(mid 321.017138 -210.896454)
					(end 320.506598 -210.385914)
				)
				(arc
					(start 319.693544 -210.385914)
					(mid 319.183258 -210.896581)
					(end 319.693798 -211.406994)
				)
			)
		)
		(polygon
			(pts
				(arc
					(start 317.306706 -211.406994)
					(mid 317.817246 -210.896454)
					(end 317.306706 -210.385914)
				)
				(arc
					(start 316.493652 -210.385914)
					(mid 315.983366 -210.896581)
					(end 316.493906 -211.406994)
				)
			)
		)
		(polygon
			(pts
				(arc
					(start 314.10656 -211.406994)
					(mid 314.6171 -210.896454)
					(end 314.10656 -210.385914)
				)
				(arc
					(start 313.293506 -210.385914)
					(mid 312.78322 -210.896581)
					(end 313.29376 -211.406994)
				)
			)
		)
		(polygon
			(pts
				(arc
					(start 310.906922 -211.406994)
					(mid 311.417208 -210.896327)
					(end 310.906668 -210.385914)
				)
				(arc
					(start 310.093868 -210.385914)
					(mid 309.583328 -210.896454)
					(end 310.093868 -211.406994)
				)
			)
		)
		(polygon
			(pts
				(arc
					(start 302.90643 -211.406994)
					(mid 303.41697 -210.896454)
					(end 302.90643 -210.385914)
				)
				(arc
					(start 302.093376 -210.385914)
					(mid 301.58309 -210.896581)
					(end 302.09363 -211.406994)
				)
			)
		)
		(polygon
			(pts
				(arc
					(start 299.706538 -211.406994)
					(mid 300.217078 -210.896454)
					(end 299.706538 -210.385914)
				)
				(arc
					(start 298.893484 -210.385914)
					(mid 298.383198 -210.896581)
					(end 298.893738 -211.406994)
				)
			)
		)
		(polygon
			(pts
				(arc
					(start 294.106346 -211.406994)
					(mid 294.616886 -210.896454)
					(end 294.106346 -210.385914)
				)
				(arc
					(start 293.293292 -210.385914)
					(mid 292.783006 -210.896581)
					(end 293.293546 -211.406994)
				)
			)
		)
		(polygon
			(pts
				(arc
					(start 290.906454 -211.406994)
					(mid 291.416994 -210.896454)
					(end 290.906454 -210.385914)
				)
				(arc
					(start 290.0934 -210.385914)
					(mid 289.583114 -210.896581)
					(end 290.093654 -211.406994)
				)
			)
		)
		(polygon
			(pts
				(arc
					(start 287.706816 -211.406994)
					(mid 288.217102 -210.896327)
					(end 287.706562 -210.385914)
				)
				(arc
					(start 286.893762 -210.385914)
					(mid 286.383222 -210.896454)
					(end 286.893762 -211.406994)
				)
			)
		)
		(polygon
			(pts
				(arc
					(start 284.506416 -211.406994)
					(mid 285.016956 -210.896454)
					(end 284.506416 -210.385914)
				)
				(arc
					(start 283.693362 -210.385914)
					(mid 283.183076 -210.896581)
					(end 283.693616 -211.406994)
				)
			)
		)
		(polygon
			(pts
				(arc
					(start 281.306524 -211.406994)
					(mid 281.817064 -210.896454)
					(end 281.306524 -210.385914)
				)
				(arc
					(start 280.49347 -210.385914)
					(mid 279.983184 -210.896581)
					(end 280.493724 -211.406994)
				)
			)
		)
		(polygon
			(pts
				(arc
					(start 278.106378 -211.406994)
					(mid 278.616918 -210.896454)
					(end 278.106378 -210.385914)
				)
				(arc
					(start 277.293324 -210.385914)
					(mid 276.783038 -210.896581)
					(end 277.293578 -211.406994)
				)
			)
		)
		(polygon
			(pts
				(arc
					(start 274.906486 -211.406994)
					(mid 275.417026 -210.896454)
					(end 274.906486 -210.385914)
				)
				(arc
					(start 274.093432 -210.385914)
					(mid 273.583146 -210.896581)
					(end 274.093686 -211.406994)
				)
			)
		)
		(polygon
			(pts
				(arc
					(start 271.706594 -211.406994)
					(mid 272.217134 -210.896454)
					(end 271.706594 -210.385914)
				)
				(arc
					(start 270.89354 -210.385914)
					(mid 270.383254 -210.896581)
					(end 270.893794 -211.406994)
				)
			)
		)
		(polygon
			(pts
				(arc
					(start 268.506448 -211.406994)
					(mid 269.016988 -210.896454)
					(end 268.506448 -210.385914)
				)
				(arc
					(start 267.693394 -210.385914)
					(mid 267.183108 -210.896581)
					(end 267.693648 -211.406994)
				)
			)
		)
		(polygon
			(pts
				(arc
					(start 265.306556 -211.406994)
					(mid 265.817096 -210.896454)
					(end 265.306556 -210.385914)
				)
				(arc
					(start 264.493502 -210.385914)
					(mid 263.983216 -210.896581)
					(end 264.493756 -211.406994)
				)
			)
		)
		(polygon
			(pts
				(arc
					(start 216.906348 -211.406994)
					(mid 217.416888 -210.896454)
					(end 216.906348 -210.385914)
				)
				(arc
					(start 216.093294 -210.385914)
					(mid 215.583008 -210.896581)
					(end 216.093548 -211.406994)
				)
			)
		)
		(polygon
			(pts
				(arc
					(start 213.706456 -211.406994)
					(mid 214.216996 -210.896454)
					(end 213.706456 -210.385914)
				)
				(arc
					(start 212.893402 -210.385914)
					(mid 212.383116 -210.896581)
					(end 212.893656 -211.406994)
				)
			)
		)
		(polygon
			(pts
				(arc
					(start 207.306418 -211.406994)
					(mid 207.816958 -210.896454)
					(end 207.306418 -210.385914)
				)
				(arc
					(start 206.493364 -210.385914)
					(mid 205.983078 -210.896581)
					(end 206.493618 -211.406994)
				)
			)
		)
		(polygon
			(pts
				(arc
					(start 204.106526 -211.406994)
					(mid 204.617066 -210.896454)
					(end 204.106526 -210.385914)
				)
				(arc
					(start 203.293472 -210.385914)
					(mid 202.783186 -210.896581)
					(end 203.293726 -211.406994)
				)
			)
		)
		(polygon
			(pts
				(arc
					(start 200.90638 -211.406994)
					(mid 201.41692 -210.896454)
					(end 200.90638 -210.385914)
				)
				(arc
					(start 200.093326 -210.385914)
					(mid 199.58304 -210.896581)
					(end 200.09358 -211.406994)
				)
			)
		)
		(polygon
			(pts
				(arc
					(start 197.706488 -211.406994)
					(mid 198.217028 -210.896454)
					(end 197.706488 -210.385914)
				)
				(arc
					(start 196.893434 -210.385914)
					(mid 196.383148 -210.896581)
					(end 196.893688 -211.406994)
				)
			)
		)
		(polygon
			(pts
				(arc
					(start 194.506596 -211.406994)
					(mid 195.017136 -210.896454)
					(end 194.506596 -210.385914)
				)
				(arc
					(start 193.693542 -210.385914)
					(mid 193.183256 -210.896581)
					(end 193.693796 -211.406994)
				)
			)
		)
		(polygon
			(pts
				(arc
					(start 191.30645 -211.406994)
					(mid 191.81699 -210.896454)
					(end 191.30645 -210.385914)
				)
				(arc
					(start 190.493396 -210.385914)
					(mid 189.98311 -210.896581)
					(end 190.49365 -211.406994)
				)
			)
		)
		(polygon
			(pts
				(arc
					(start 188.106558 -211.406994)
					(mid 188.617098 -210.896454)
					(end 188.106558 -210.385914)
				)
				(arc
					(start 187.293504 -210.385914)
					(mid 186.783218 -210.896581)
					(end 187.293758 -211.406994)
				)
			)
		)
		(polygon
			(pts
				(arc
					(start 184.906412 -211.406994)
					(mid 185.416952 -210.896454)
					(end 184.906412 -210.385914)
				)
				(arc
					(start 184.093358 -210.385914)
					(mid 183.583072 -210.896581)
					(end 184.093612 -211.406994)
				)
			)
		)
		(polygon
			(pts
				(arc
					(start 176.906428 -211.406994)
					(mid 177.416968 -210.896454)
					(end 176.906428 -210.385914)
				)
				(arc
					(start 176.093374 -210.385914)
					(mid 175.583088 -210.896581)
					(end 176.093628 -211.406994)
				)
			)
		)
		(polygon
			(pts
				(arc
					(start 173.706536 -211.406994)
					(mid 174.217076 -210.896454)
					(end 173.706536 -210.385914)
				)
				(arc
					(start 172.893482 -210.385914)
					(mid 172.383196 -210.896581)
					(end 172.893736 -211.406994)
				)
			)
		)
		(polygon
			(pts
				(arc
					(start 170.50639 -211.406994)
					(mid 171.01693 -210.896454)
					(end 170.50639 -210.385914)
				)
				(arc
					(start 169.693336 -210.385914)
					(mid 169.18305 -210.896581)
					(end 169.69359 -211.406994)
				)
			)
		)
		(polygon
			(pts
				(arc
					(start 167.306498 -211.406994)
					(mid 167.817038 -210.896454)
					(end 167.306498 -210.385914)
				)
				(arc
					(start 166.493444 -210.385914)
					(mid 165.983158 -210.896581)
					(end 166.493698 -211.406994)
				)
			)
		)
		(polygon
			(pts
				(arc
					(start 161.70656 -211.406994)
					(mid 162.2171 -210.896454)
					(end 161.70656 -210.385914)
				)
				(arc
					(start 160.893506 -210.385914)
					(mid 160.38322 -210.896581)
					(end 160.89376 -211.406994)
				)
			)
		)
		(polygon
			(pts
				(arc
					(start 158.506668 -211.406994)
					(mid 159.017208 -210.896454)
					(end 158.506668 -210.385914)
				)
				(arc
					(start 157.693614 -210.385914)
					(mid 157.183328 -210.896581)
					(end 157.693868 -211.406994)
				)
			)
		)
		(polygon
			(pts
				(arc
					(start 155.306522 -211.406994)
					(mid 155.817062 -210.896454)
					(end 155.306522 -210.385914)
				)
				(arc
					(start 154.493468 -210.385914)
					(mid 153.983182 -210.896581)
					(end 154.493722 -211.406994)
				)
			)
		)
		(polygon
			(pts
				(arc
					(start 152.10663 -211.406994)
					(mid 152.61717 -210.896454)
					(end 152.10663 -210.385914)
				)
				(arc
					(start 151.293576 -210.385914)
					(mid 150.78329 -210.896581)
					(end 151.29383 -211.406994)
				)
			)
		)
		(polygon
			(pts
				(arc
					(start 148.906484 -211.406994)
					(mid 149.417024 -210.896454)
					(end 148.906484 -210.385914)
				)
				(arc
					(start 148.09343 -210.385914)
					(mid 147.583144 -210.896581)
					(end 148.093684 -211.406994)
				)
			)
		)
		(polygon
			(pts
				(arc
					(start 145.706592 -211.406994)
					(mid 146.217132 -210.896454)
					(end 145.706592 -210.385914)
				)
				(arc
					(start 144.893538 -210.385914)
					(mid 144.383252 -210.896581)
					(end 144.893792 -211.406994)
				)
			)
		)
		(polygon
			(pts
				(arc
					(start 142.5067 -211.406994)
					(mid 143.01724 -210.896454)
					(end 142.5067 -210.385914)
				)
				(arc
					(start 141.693646 -210.385914)
					(mid 141.18336 -210.896581)
					(end 141.6939 -211.406994)
				)
			)
		)
		(polygon
			(pts
				(arc
					(start 139.306554 -211.406994)
					(mid 139.817094 -210.896454)
					(end 139.306554 -210.385914)
				)
				(arc
					(start 138.4935 -210.385914)
					(mid 137.983214 -210.896581)
					(end 138.493754 -211.406994)
				)
			)
		)
		(polygon
			(pts
				(arc
					(start 108.506514 -211.406994)
					(mid 109.017054 -210.896454)
					(end 108.506514 -210.385914)
				)
				(arc
					(start 107.69346 -210.385914)
					(mid 107.183174 -210.896581)
					(end 107.693714 -211.406994)
				)
			)
		)
		(polygon
			(pts
				(arc
					(start 105.306622 -211.406994)
					(mid 105.817162 -210.896454)
					(end 105.306622 -210.385914)
				)
				(arc
					(start 104.493568 -210.385914)
					(mid 103.983282 -210.896581)
					(end 104.493822 -211.406994)
				)
			)
		)
		(polygon
			(pts
				(arc
					(start 102.10673 -211.406994)
					(mid 102.617016 -210.896327)
					(end 102.106476 -210.385914)
				)
				(arc
					(start 101.293676 -210.385914)
					(mid 100.783136 -210.896454)
					(end 101.293676 -211.406994)
				)
			)
		)
		(polygon
			(pts
				(arc
					(start 98.906584 -211.406994)
					(mid 99.417124 -210.896454)
					(end 98.906584 -210.385914)
				)
				(arc
					(start 98.09353 -210.385914)
					(mid 97.583244 -210.896581)
					(end 98.093784 -211.406994)
				)
			)
		)
		(polygon
			(pts
				(arc
					(start 93.306392 -211.406994)
					(mid 93.816932 -210.896454)
					(end 93.306392 -210.385914)
				)
				(arc
					(start 92.493338 -210.385914)
					(mid 91.983052 -210.896581)
					(end 92.493592 -211.406994)
				)
			)
		)
		(polygon
			(pts
				(arc
					(start 90.1065 -211.406994)
					(mid 90.61704 -210.896454)
					(end 90.1065 -210.385914)
				)
				(arc
					(start 89.293446 -210.385914)
					(mid 88.78316 -210.896581)
					(end 89.2937 -211.406994)
				)
			)
		)
		(polygon
			(pts
				(arc
					(start 86.906354 -211.406994)
					(mid 87.416894 -210.896454)
					(end 86.906354 -210.385914)
				)
				(arc
					(start 86.0933 -210.385914)
					(mid 85.583014 -210.896581)
					(end 86.093554 -211.406994)
				)
			)
		)
		(polygon
			(pts
				(arc
					(start 83.706462 -211.406994)
					(mid 84.217002 -210.896454)
					(end 83.706462 -210.385914)
				)
				(arc
					(start 82.893408 -210.385914)
					(mid 82.383122 -210.896581)
					(end 82.893662 -211.406994)
				)
			)
		)
		(polygon
			(pts
				(arc
					(start 80.506316 -211.406994)
					(mid 81.016856 -210.896454)
					(end 80.506316 -210.385914)
				)
				(arc
					(start 79.693262 -210.385914)
					(mid 79.182976 -210.896581)
					(end 79.693516 -211.406994)
				)
			)
		)
		(polygon
			(pts
				(arc
					(start 70.906386 -211.406994)
					(mid 71.416926 -210.896454)
					(end 70.906386 -210.385914)
				)
				(arc
					(start 70.093332 -210.385914)
					(mid 69.583046 -210.896581)
					(end 70.093586 -211.406994)
				)
			)
		)
		(polygon
			(pts
				(arc
					(start 67.706494 -211.406994)
					(mid 68.217034 -210.896454)
					(end 67.706494 -210.385914)
				)
				(arc
					(start 66.89344 -210.385914)
					(mid 66.383154 -210.896581)
					(end 66.893694 -211.406994)
				)
			)
		)
		(polygon
			(pts
				(arc
					(start 64.506348 -211.406994)
					(mid 65.016888 -210.896454)
					(end 64.506348 -210.385914)
				)
				(arc
					(start 63.693294 -210.385914)
					(mid 63.183008 -210.896581)
					(end 63.693548 -211.406994)
				)
			)
		)
		(polygon
			(pts
				(arc
					(start 58.90641 -211.406994)
					(mid 59.41695 -210.896454)
					(end 58.90641 -210.385914)
				)
				(arc
					(start 58.093356 -210.385914)
					(mid 57.58307 -210.896581)
					(end 58.09361 -211.406994)
				)
			)
		)
		(polygon
			(pts
				(arc
					(start 55.706772 -211.406994)
					(mid 56.217058 -210.896327)
					(end 55.706518 -210.385914)
				)
				(arc
					(start 54.893718 -210.385914)
					(mid 54.383178 -210.896454)
					(end 54.893718 -211.406994)
				)
			)
		)
		(polygon
			(pts
				(arc
					(start 52.506372 -211.406994)
					(mid 53.016912 -210.896454)
					(end 52.506372 -210.385914)
				)
				(arc
					(start 51.693318 -210.385914)
					(mid 51.183032 -210.896581)
					(end 51.693572 -211.406994)
				)
			)
		)
		(polygon
			(pts
				(arc
					(start 49.30648 -211.406994)
					(mid 49.81702 -210.896454)
					(end 49.30648 -210.385914)
				)
				(arc
					(start 48.493426 -210.385914)
					(mid 47.98314 -210.896581)
					(end 48.49368 -211.406994)
				)
			)
		)
		(polygon
			(pts
				(arc
					(start 50.95748 -209.222594)
					(mid 51.46802 -208.712054)
					(end 50.95748 -208.201514)
				)
				(arc
					(start 50.144426 -208.201514)
					(mid 49.63414 -208.712181)
					(end 50.14468 -209.222594)
				)
			)
		)
		(polygon
			(pts
				(arc
					(start 58.8645 -196.77634)
					(mid 59.37504 -196.2658)
					(end 58.8645 -195.75526)
				)
				(arc
					(start 58.051446 -195.75526)
					(mid 57.54116 -196.265927)
					(end 58.0517 -196.77634)
				)
			)
		)
		(polygon
			(pts
				(arc
					(start 92.332048 -184.941718)
					(mid 91.61018 -184.941718)
					(end 91.61018 -185.663586)
				)
				(xy 91.608402 -185.665364) (xy 92.18295 -186.240166) (xy 92.183204 -186.240166)
				(arc
					(start 92.184982 -186.238388)
					(mid 92.90685 -186.238388)
					(end 92.90685 -185.51652)
				)
				(xy 92.908628 -185.514742) (xy 92.333826 -184.93994)
			)
		)
		(polygon
			(pts
				(arc
					(start 94.202504 -184.15254)
					(mid 94.71279 -183.641873)
					(end 94.20225 -183.13146)
				)
				(arc
					(start 93.38945 -183.13146)
					(mid 92.87891 -183.642)
					(end 93.38945 -184.15254)
				)
			)
		)
		(polygon
			(pts
				(arc
					(start 26.74112 -142.580106)
					(mid 26.128853 -141.96822)
					(end 25.51684 -142.58036)
				)
				(arc
					(start 25.51684 -143.69796)
					(mid 26.12898 -144.3101)
					(end 26.74112 -143.69796)
				)
			)
		)
		(polygon
			(pts
				(arc
					(start 66.143378 -128.189736)
					(mid 66.653918 -127.679196)
					(end 66.143378 -127.168656)
				)
				(arc
					(start 65.330324 -127.168656)
					(mid 64.820038 -127.679323)
					(end 65.330578 -128.189736)
				)
			)
		)
		(polygon
			(pts
				(arc
					(start 23.77694 -113.994946)
					(mid 23.164673 -113.38306)
					(end 22.55266 -113.9952)
				)
				(arc
					(start 22.55266 -115.1128)
					(mid 23.1648 -115.72494)
					(end 23.77694 -115.1128)
				)
			)
		)
		(polygon
			(pts
				(arc
					(start 25.085294 -111.4044)
					(mid 24.473154 -110.79226)
					(end 23.861014 -111.4044)
				)
				(arc
					(start 23.861014 -112.522254)
					(mid 24.473281 -113.13414)
					(end 25.085294 -112.522)
				)
			)
		)
		(polygon
			(pts
				(arc
					(start 28.47594 -105.502202)
					(mid 27.610308 -105.502202)
					(end 27.610308 -106.367834)
				)
				(xy 27.60853 -106.369612) (xy 28.398978 -107.16006)
				(arc
					(start 28.400756 -107.158282)
					(mid 29.266388 -107.158282)
					(end 29.266388 -106.29265)
				)
				(xy 29.268166 -106.290872) (xy 28.477972 -105.500678) (xy 28.477464 -105.500678)
			)
		)
		(polygon
			(pts
				(arc
					(start 173.6344 -96.704912)
					(mid 174.14494 -96.194372)
					(end 173.6344 -95.683832)
				)
				(arc
					(start 172.745146 -95.683832)
					(mid 172.23486 -96.194499)
					(end 172.7454 -96.704912)
				)
			)
		)
		(polygon
			(pts
				(arc
					(start 168.212516 -88.645746)
					(mid 167.701849 -88.13546)
					(end 167.191436 -88.646)
				)
				(arc
					(start 167.191436 -89.4588)
					(mid 167.701976 -89.96934)
					(end 168.212516 -89.4588)
				)
			)
		)
		(polygon
			(pts
				(arc
					(start 21.209 -87.93734)
					(mid 21.71954 -87.4268)
					(end 21.209 -86.91626)
				)
				(arc
					(start 20.395946 -86.91626)
					(mid 19.88566 -87.426927)
					(end 20.3962 -87.93734)
				)
			)
		)
		(polygon
			(pts
				(arc
					(start 16.9672 -87.65794)
					(mid 17.57934 -87.0458)
					(end 16.9672 -86.43366)
				)
				(arc
					(start 15.8496 -86.43366)
					(mid 15.23746 -87.0458)
					(end 15.8496 -87.65794)
				)
			)
		)
		(polygon
			(pts
				(arc
					(start 56.86298 -85.210396)
					(mid 56.250713 -84.59851)
					(end 55.6387 -85.21065)
				)
				(arc
					(start 55.6387 -86.32825)
					(mid 56.25084 -86.94039)
					(end 56.86298 -86.32825)
				)
			)
		)
		(polygon
			(pts
				(arc
					(start 19.664934 -82.41792)
					(mid 20.175474 -81.90738)
					(end 19.664934 -81.39684)
				)
				(arc
					(start 18.85188 -81.39684)
					(mid 18.341594 -81.907507)
					(end 18.852134 -82.41792)
				)
			)
		)
		(polygon
			(pts
				(arc
					(start 163.512754 -82.17154)
					(mid 164.02304 -81.660873)
					(end 163.5125 -81.15046)
				)
				(arc
					(start 162.6997 -81.15046)
					(mid 162.18916 -81.661)
					(end 162.6997 -82.17154)
				)
			)
		)
		(polygon
			(pts
				(arc
					(start 103.2383 -81.000346)
					(mid 102.626033 -80.38846)
					(end 102.01402 -81.0006)
				)
				(arc
					(start 102.01402 -82.1182)
					(mid 102.62616 -82.73034)
					(end 103.2383 -82.1182)
				)
			)
		)
		(polygon
			(pts
				(arc
					(start 87.290148 -76.589636)
					(mid 86.779608 -76.079096)
					(end 86.269068 -76.589636)
				)
				(arc
					(start 86.269068 -77.47889)
					(mid 86.779735 -77.989176)
					(end 87.290148 -77.478636)
				)
			)
		)
		(polygon
			(pts
				(arc
					(start 16.6116 -73.727564)
					(mid 17.12214 -73.217024)
					(end 16.6116 -72.706484)
				)
				(arc
					(start 15.798546 -72.706484)
					(mid 15.28826 -73.217151)
					(end 15.7988 -73.727564)
				)
			)
		)
		(polygon
			(pts
				(arc
					(start 19.38655 -73.721214)
					(mid 19.89709 -73.210674)
					(end 19.38655 -72.700134)
				)
				(arc
					(start 18.573496 -72.700134)
					(mid 18.06321 -73.210801)
					(end 18.57375 -73.721214)
				)
			)
		)
		(polygon
			(pts
				(arc
					(start 14.68374 -67.638168)
					(mid 14.173073 -67.127882)
					(end 13.66266 -67.638422)
				)
				(arc
					(start 13.66266 -68.451222)
					(mid 14.1732 -68.961762)
					(end 14.68374 -68.451222)
				)
			)
		)
		(polygon
			(pts
				(arc
					(start 16.69034 -66.223896)
					(mid 16.179673 -65.71361)
					(end 15.66926 -66.22415)
				)
				(arc
					(start 15.66926 -67.03695)
					(mid 16.1798 -67.54749)
					(end 16.69034 -67.03695)
				)
			)
		)
		(polygon
			(pts
				(arc
					(start 19.812 -58.851546)
					(mid 20.42414 -58.239406)
					(end 19.812 -57.627266)
				)
				(arc
					(start 18.6944 -57.627266)
					(mid 18.08226 -58.239406)
					(end 18.6944 -58.851546)
				)
			)
		)
		(polygon
			(pts
				(arc
					(start 23.535386 -57.300876)
					(mid 24.147526 -56.688736)
					(end 23.535386 -56.076596)
				)
				(arc
					(start 22.417786 -56.076596)
					(mid 21.805646 -56.688736)
					(end 22.417786 -57.300876)
				)
			)
		)
		(polygon
			(pts
				(arc
					(start 10.477754 -55.559452)
					(mid 10.98804 -55.048785)
					(end 10.4775 -54.538372)
				)
				(arc
					(start 9.6647 -54.538372)
					(mid 9.15416 -55.048912)
					(end 9.6647 -55.559452)
				)
			)
		)
		(polygon
			(pts
				(arc
					(start 19.659854 -55.508652)
					(mid 20.17014 -54.997985)
					(end 19.6596 -54.487572)
				)
				(arc
					(start 18.8468 -54.487572)
					(mid 18.33626 -54.998112)
					(end 18.8468 -55.508652)
				)
			)
		)
		(polygon
			(pts
				(arc
					(start 14.3764 -54.340252)
					(mid 14.88694 -53.829712)
					(end 14.3764 -53.319172)
				)
				(arc
					(start 13.563346 -53.319172)
					(mid 13.05306 -53.829839)
					(end 13.5636 -54.340252)
				)
			)
		)
		(polygon
			(pts
				(arc
					(start 23.368 -54.066694)
					(mid 23.87854 -53.556154)
					(end 23.368 -53.045614)
				)
				(arc
					(start 22.554946 -53.045614)
					(mid 22.04466 -53.556281)
					(end 22.5552 -54.066694)
				)
			)
		)
		(polygon
			(pts
				(arc
					(start 53.305964 -48.387508)
					(mid 53.816504 -47.876968)
					(end 53.305964 -47.366428)
				)
				(arc
					(start 52.399184 -47.366428)
					(mid 51.888898 -47.877095)
					(end 52.399438 -48.387508)
				)
			)
		)
		(polygon
			(pts
				(arc
					(start 132.358384 -41.604946)
					(mid 131.746117 -40.99306)
					(end 131.134104 -41.6052)
				)
				(arc
					(start 131.134104 -42.7228)
					(mid 131.746244 -43.33494)
					(end 132.358384 -42.7228)
				)
			)
		)
		(polygon
			(pts
				(arc
					(start 306.575968 -40.31996)
					(mid 307.086254 -39.809293)
					(end 306.575714 -39.29888)
				)
				(arc
					(start 305.762914 -39.29888)
					(mid 305.252374 -39.80942)
					(end 305.762914 -40.31996)
				)
			)
		)
		(polygon
			(pts
				(arc
					(start 102.44074 -38.916356)
					(mid 101.930073 -38.40607)
					(end 101.41966 -38.91661)
				)
				(arc
					(start 101.41966 -39.80561)
					(mid 101.9302 -40.31615)
					(end 102.44074 -39.80561)
				)
			)
		)
		(polygon
			(pts
				(arc
					(start 139.3698 -39.16934)
					(mid 139.88034 -38.6588)
					(end 139.3698 -38.14826)
				)
				(arc
					(start 138.556746 -38.14826)
					(mid 138.04646 -38.658927)
					(end 138.557 -39.16934)
				)
			)
		)
		(polygon
			(pts
				(arc
					(start 151.727154 -38.59784)
					(mid 152.23744 -38.087173)
					(end 151.7269 -37.57676)
				)
				(arc
					(start 150.9141 -37.57676)
					(mid 150.40356 -38.0873)
					(end 150.9141 -38.59784)
				)
			)
		)
		(polygon
			(pts
				(arc
					(start 162.598354 -38.52164)
					(mid 163.10864 -38.010973)
					(end 162.5981 -37.50056)
				)
				(arc
					(start 161.7853 -37.50056)
					(mid 161.27476 -38.0111)
					(end 161.7853 -38.52164)
				)
			)
		)
		(polygon
			(pts
				(arc
					(start 24.432006 -37.212016)
					(mid 24.432006 -39.807896)
					(end 24.432006 -37.212016)
				)
			)
		)
		(polygon
			(pts
				(arc
					(start 6.852158 -37.212016)
					(mid 6.852158 -39.807896)
					(end 6.852158 -37.212016)
				)
			)
		)
		(polygon
			(pts
				(arc
					(start 320.53403 -37.53612)
					(mid 321.044316 -37.025453)
					(end 320.533776 -36.51504)
				)
				(arc
					(start 319.720722 -36.51504)
					(mid 319.210436 -37.025707)
					(end 319.720976 -37.53612)
				)
			)
		)
		(polygon
			(pts
				(arc
					(start 304.647854 -36.794694)
					(mid 305.15814 -36.284027)
					(end 304.6476 -35.773614)
				)
				(arc
					(start 303.8348 -35.773614)
					(mid 303.32426 -36.284154)
					(end 303.8348 -36.794694)
				)
			)
		)
		(polygon
			(pts
				(arc
					(start 103.02494 -36.205668)
					(mid 102.5144 -35.695128)
					(end 102.00386 -36.205668)
				)
				(arc
					(start 102.00386 -37.094922)
					(mid 102.514527 -37.605208)
					(end 103.02494 -37.094668)
				)
			)
		)
		(polygon
			(pts
				(arc
					(start 300.243494 -36.699952)
					(mid 300.754034 -36.189412)
					(end 300.243494 -35.678872)
				)
				(arc
					(start 299.43044 -35.678872)
					(mid 298.920154 -36.189539)
					(end 299.430694 -36.699952)
				)
			)
		)
		(polygon
			(pts
				(arc
					(start 313.489086 -36.696142)
					(mid 313.999626 -36.185602)
					(end 313.489086 -35.675062)
				)
				(arc
					(start 312.676032 -35.675062)
					(mid 312.165746 -36.185729)
					(end 312.676286 -36.696142)
				)
			)
		)
		(polygon
			(pts
				(arc
					(start 326.782176 -36.472114)
					(mid 327.292462 -35.961447)
					(end 326.781922 -35.451034)
				)
				(arc
					(start 325.969122 -35.451034)
					(mid 325.458582 -35.961574)
					(end 325.969122 -36.472114)
				)
			)
		)
		(polygon
			(pts
				(arc
					(start 134.665212 -36.250372)
					(mid 135.175498 -35.739705)
					(end 134.664958 -35.229292)
				)
				(arc
					(start 133.852158 -35.229292)
					(mid 133.341618 -35.739832)
					(end 133.852158 -36.250372)
				)
			)
		)
		(polygon
			(pts
				(arc
					(start 131.9022 -35.783774)
					(mid 132.41274 -35.273234)
					(end 131.9022 -34.762694)
				)
				(arc
					(start 131.089146 -34.762694)
					(mid 130.57886 -35.273361)
					(end 131.0894 -35.783774)
				)
			)
		)
		(polygon
			(pts
				(arc
					(start 311.238646 -35.55238)
					(mid 311.748932 -35.041713)
					(end 311.238392 -34.5313)
				)
				(arc
					(start 310.425592 -34.5313)
					(mid 309.915052 -35.04184)
					(end 310.425592 -35.55238)
				)
			)
		)
		(polygon
			(pts
				(arc
					(start 302.472344 -35.536886)
					(mid 302.98263 -35.026219)
					(end 302.47209 -34.515806)
				)
				(arc
					(start 301.65929 -34.515806)
					(mid 301.14875 -35.026346)
					(end 301.65929 -35.536886)
				)
			)
		)
		(polygon
			(pts
				(arc
					(start 162.0901 -35.53206)
					(mid 162.60064 -35.02152)
					(end 162.0901 -34.51098)
				)
				(arc
					(start 161.277046 -34.51098)
					(mid 160.76676 -35.021647)
					(end 161.2773 -35.53206)
				)
			)
		)
		(polygon
			(pts
				(arc
					(start 159.467804 -35.53206)
					(mid 159.978344 -35.02152)
					(end 159.467804 -34.51098)
				)
				(arc
					(start 158.65475 -34.51098)
					(mid 158.144464 -35.021647)
					(end 158.655004 -35.53206)
				)
			)
		)
		(polygon
			(pts
				(arc
					(start 315.696854 -35.524694)
					(mid 316.20714 -35.014027)
					(end 315.6966 -34.503614)
				)
				(arc
					(start 314.8838 -34.503614)
					(mid 314.37326 -35.014154)
					(end 314.8838 -35.524694)
				)
			)
		)
		(polygon
			(pts
				(arc
					(start 149.314154 -35.51174)
					(mid 149.82444 -35.001073)
					(end 149.3139 -34.49066)
				)
				(arc
					(start 148.5011 -34.49066)
					(mid 147.99056 -35.0012)
					(end 148.5011 -35.51174)
				)
			)
		)
		(polygon
			(pts
				(arc
					(start 153.530554 -35.50666)
					(mid 154.04084 -34.995993)
					(end 153.5303 -34.48558)
				)
				(arc
					(start 152.7175 -34.48558)
					(mid 152.20696 -34.99612)
					(end 152.7175 -35.50666)
				)
			)
		)
		(polygon
			(pts
				(arc
					(start 146.7231 -35.50666)
					(mid 147.23364 -34.99612)
					(end 146.7231 -34.48558)
				)
				(arc
					(start 145.910046 -34.48558)
					(mid 145.39976 -34.996247)
					(end 145.9103 -35.50666)
				)
			)
		)
		(polygon
			(pts
				(arc
					(start 138.379454 -35.503866)
					(mid 138.88974 -34.993199)
					(end 138.3792 -34.482786)
				)
				(arc
					(start 137.5664 -34.482786)
					(mid 137.05586 -34.993326)
					(end 137.5664 -35.503866)
				)
			)
		)
		(polygon
			(pts
				(arc
					(start 324.425564 -35.479482)
					(mid 324.93585 -34.968815)
					(end 324.42531 -34.458402)
				)
				(arc
					(start 323.612256 -34.458402)
					(mid 323.10197 -34.969069)
					(end 323.61251 -35.479482)
				)
			)
		)
		(polygon
			(pts
				(arc
					(start 329.188572 -35.429952)
					(mid 329.698858 -34.919285)
					(end 329.188318 -34.408872)
				)
				(arc
					(start 328.375518 -34.408872)
					(mid 327.864978 -34.919412)
					(end 328.375518 -35.429952)
				)
			)
		)
		(polygon
			(pts
				(arc
					(start 183.59374 -28.993846)
					(mid 183.083073 -28.48356)
					(end 182.57266 -28.9941)
				)
				(arc
					(start 182.57266 -29.8069)
					(mid 183.0832 -30.31744)
					(end 183.59374 -29.8069)
				)
			)
		)
		(polygon
			(pts
				(arc
					(start 183.59374 -25.945846)
					(mid 183.083073 -25.43556)
					(end 182.57266 -25.9461)
				)
				(arc
					(start 182.57266 -26.7589)
					(mid 183.0832 -27.26944)
					(end 183.59374 -26.7589)
				)
			)
		)
		(polygon
			(pts
				(arc
					(start 186.56554 -24.99868)
					(mid 186.054873 -24.488394)
					(end 185.54446 -24.998934)
				)
				(arc
					(start 185.54446 -25.811734)
					(mid 186.055 -26.322274)
					(end 186.56554 -25.811734)
				)
			)
		)
		(polygon
			(pts
				(arc
					(start 145.435066 -24.22525)
					(mid 145.17939 -23.379349)
					(end 144.333468 -23.635208)
				)
				(xy 144.331436 -23.633938) (xy 143.581374 -25.033986)
				(arc
					(start 143.583406 -25.035256)
					(mid 143.839438 -25.881076)
					(end 144.685258 -25.625044)
				)
				(xy 144.68729 -25.626314) (xy 145.437352 -24.22652) (xy 145.437098 -24.226266)
			)
		)
		(polygon
			(pts
				(arc
					(start 298.435014 -24.22525)
					(mid 298.179338 -23.379349)
					(end 297.333416 -23.635208)
				)
				(xy 297.331384 -23.633938) (xy 296.581322 -25.033986)
				(arc
					(start 296.583354 -25.035256)
					(mid 296.839386 -25.881076)
					(end 297.685206 -25.625044)
				)
				(xy 297.687238 -25.626314) (xy 298.4373 -24.22652) (xy 298.437046 -24.226266)
			)
		)
		(polygon
			(pts
				(arc
					(start 324.935342 -24.224996)
					(mid 324.67931 -23.379176)
					(end 323.83349 -23.635208)
				)
				(xy 323.831458 -23.633938) (xy 323.081396 -25.033732) (xy 323.08165 -25.033986)
				(arc
					(start 323.083682 -25.035002)
					(mid 323.339358 -25.880903)
					(end 324.18528 -25.625044)
				)
				(xy 324.187312 -25.626314) (xy 324.937374 -24.226266)
			)
		)
		(polygon
			(pts
				(arc
					(start 322.68541 -24.224996)
					(mid 322.429378 -23.379176)
					(end 321.583558 -23.635208)
				)
				(xy 321.581526 -23.633938) (xy 320.831464 -25.033732) (xy 320.831718 -25.033986)
				(arc
					(start 320.83375 -25.035002)
					(mid 321.089426 -25.880903)
					(end 321.935348 -25.625044)
				)
				(xy 321.93738 -25.626314) (xy 322.687442 -24.226266)
			)
		)
		(polygon
			(pts
				(arc
					(start 313.935364 -24.224996)
					(mid 313.679332 -23.379176)
					(end 312.833512 -23.635208)
				)
				(xy 312.83148 -23.633938) (xy 312.081418 -25.033732) (xy 312.081672 -25.033986)
				(arc
					(start 312.083704 -25.035002)
					(mid 312.33938 -25.880903)
					(end 313.185302 -25.625044)
				)
				(xy 313.187334 -25.626314) (xy 313.937396 -24.226266)
			)
		)
		(polygon
			(pts
				(arc
					(start 311.685432 -24.224996)
					(mid 311.4294 -23.379176)
					(end 310.58358 -23.635208)
				)
				(xy 310.581548 -23.633938) (xy 309.831486 -25.033732) (xy 309.83174 -25.033986)
				(arc
					(start 309.833772 -25.035002)
					(mid 310.089448 -25.880903)
					(end 310.93537 -25.625044)
				)
				(xy 310.937402 -25.626314) (xy 311.687464 -24.226266)
			)
		)
		(polygon
			(pts
				(arc
					(start 302.935386 -24.224996)
					(mid 302.679354 -23.379176)
					(end 301.833534 -23.635208)
				)
				(xy 301.831502 -23.633938) (xy 301.08144 -25.033732) (xy 301.081694 -25.033986)
				(arc
					(start 301.083726 -25.035002)
					(mid 301.339402 -25.880903)
					(end 302.185324 -25.625044)
				)
				(xy 302.187356 -25.626314) (xy 302.937418 -24.226266)
			)
		)
		(polygon
			(pts
				(arc
					(start 300.6852 -24.224996)
					(mid 300.429168 -23.379176)
					(end 299.583348 -23.635208)
				)
				(arc
					(start 298.837604 -25.027636)
					(mid 299.085738 -25.879089)
					(end 299.935392 -25.625044)
				)
			)
		)
		(polygon
			(pts
				(arc
					(start 291.935408 -24.224996)
					(mid 291.679376 -23.379176)
					(end 290.833556 -23.635208)
				)
				(xy 290.831524 -23.633938) (xy 290.081462 -25.033732) (xy 290.081716 -25.033986)
				(arc
					(start 290.083748 -25.035002)
					(mid 290.339424 -25.880903)
					(end 291.185346 -25.625044)
				)
				(xy 291.187378 -25.626314) (xy 291.93744 -24.226266)
			)
		)
		(polygon
			(pts
				(arc
					(start 289.685222 -24.224996)
					(mid 289.42919 -23.379176)
					(end 288.58337 -23.635208)
				)
				(arc
					(start 287.837626 -25.027636)
					(mid 288.08576 -25.879089)
					(end 288.935414 -25.625044)
				)
			)
		)
		(polygon
			(pts
				(arc
					(start 287.43529 -24.224996)
					(mid 287.179258 -23.379176)
					(end 286.333438 -23.635208)
				)
				(xy 286.331406 -23.633938) (xy 285.581344 -25.033732) (xy 285.581598 -25.033986)
				(arc
					(start 285.58363 -25.035002)
					(mid 285.839306 -25.880903)
					(end 286.685228 -25.625044)
				)
				(xy 286.68726 -25.626314) (xy 287.437322 -24.226266)
			)
		)
		(polygon
			(pts
				(arc
					(start 171.935394 -24.224996)
					(mid 171.679362 -23.379176)
					(end 170.833542 -23.635208)
				)
				(xy 170.83151 -23.633938) (xy 170.081448 -25.033732) (xy 170.081702 -25.033986)
				(arc
					(start 170.083734 -25.035002)
					(mid 170.33941 -25.880903)
					(end 171.185332 -25.625044)
				)
				(xy 171.187364 -25.626314) (xy 171.937426 -24.226266)
			)
		)
		(polygon
			(pts
				(arc
					(start 169.685462 -24.224996)
					(mid 169.42943 -23.379176)
					(end 168.58361 -23.635208)
				)
				(xy 168.581578 -23.633938) (xy 167.831516 -25.033732) (xy 167.83177 -25.033986)
				(arc
					(start 167.833802 -25.035002)
					(mid 168.089478 -25.880903)
					(end 168.9354 -25.625044)
				)
				(xy 168.937432 -25.626314) (xy 169.687494 -24.226266)
			)
		)
		(polygon
			(pts
				(arc
					(start 160.935416 -24.224996)
					(mid 160.679384 -23.379176)
					(end 159.833564 -23.635208)
				)
				(xy 159.831532 -23.633938) (xy 159.08147 -25.033732) (xy 159.081724 -25.033986)
				(arc
					(start 159.083756 -25.035002)
					(mid 159.339432 -25.880903)
					(end 160.185354 -25.625044)
				)
				(xy 160.187386 -25.626314) (xy 160.937448 -24.226266)
			)
		)
		(polygon
			(pts
				(arc
					(start 158.685484 -24.224996)
					(mid 158.429452 -23.379176)
					(end 157.583632 -23.635208)
				)
				(xy 157.5816 -23.633938) (xy 156.831538 -25.033732) (xy 156.831792 -25.033986)
				(arc
					(start 156.833824 -25.035002)
					(mid 157.0895 -25.880903)
					(end 157.935422 -25.625044)
				)
				(xy 157.937454 -25.626314) (xy 158.687516 -24.226266)
			)
		)
		(polygon
			(pts
				(arc
					(start 149.935438 -24.224996)
					(mid 149.679406 -23.379176)
					(end 148.833586 -23.635208)
				)
				(xy 148.831554 -23.633938) (xy 148.081492 -25.033732) (xy 148.081746 -25.033986)
				(arc
					(start 148.083778 -25.035002)
					(mid 148.339454 -25.880903)
					(end 149.185376 -25.625044)
				)
				(xy 149.187408 -25.626314) (xy 149.93747 -24.226266)
			)
		)
		(polygon
			(pts
				(arc
					(start 147.685252 -24.224996)
					(mid 147.42922 -23.379176)
					(end 146.5834 -23.635208)
				)
				(arc
					(start 145.837656 -25.027636)
					(mid 146.08579 -25.879089)
					(end 146.935444 -25.625044)
				)
			)
		)
		(polygon
			(pts
				(arc
					(start 138.93546 -24.224996)
					(mid 138.679428 -23.379176)
					(end 137.833608 -23.635208)
				)
				(xy 137.831576 -23.633938) (xy 137.081514 -25.033732) (xy 137.081768 -25.033986)
				(arc
					(start 137.0838 -25.035002)
					(mid 137.339476 -25.880903)
					(end 138.185398 -25.625044)
				)
				(xy 138.18743 -25.626314) (xy 138.937492 -24.226266)
			)
		)
		(polygon
			(pts
				(arc
					(start 136.685274 -24.224996)
					(mid 136.429242 -23.379176)
					(end 135.583422 -23.635208)
				)
				(arc
					(start 134.837678 -25.027636)
					(mid 135.085812 -25.879089)
					(end 135.935466 -25.625044)
				)
			)
		)
		(polygon
			(pts
				(arc
					(start 134.435342 -24.224996)
					(mid 134.17931 -23.379176)
					(end 133.33349 -23.635208)
				)
				(xy 133.331458 -23.633938) (xy 132.581396 -25.033732) (xy 132.58165 -25.033986)
				(arc
					(start 132.583682 -25.035002)
					(mid 132.839358 -25.880903)
					(end 133.68528 -25.625044)
				)
				(xy 133.687312 -25.626314) (xy 134.437374 -24.226266)
			)
		)
		(polygon
			(pts
				(arc
					(start 320.43116 -24.232616)
					(mid 320.183026 -23.381163)
					(end 319.333372 -23.635208)
				)
				(arc
					(start 318.583564 -25.035256)
					(mid 318.596918 -25.648738)
					(end 319.128648 -25.95499)
				)
				(arc
					(start 319.128648 -25.95499)
					(mid 319.453069 -25.867706)
					(end 319.685416 -25.625044)
				)
			)
		)
		(polygon
			(pts
				(arc
					(start 309.431182 -24.232616)
					(mid 309.183048 -23.381163)
					(end 308.333394 -23.635208)
				)
				(arc
					(start 307.583586 -25.035256)
					(mid 307.839618 -25.881076)
					(end 308.685438 -25.625044)
				)
			)
		)
		(polygon
			(pts
				(arc
					(start 167.431212 -24.232616)
					(mid 167.183078 -23.381163)
					(end 166.333424 -23.635208)
				)
				(arc
					(start 165.583616 -25.035256)
					(mid 165.839648 -25.881076)
					(end 166.685468 -25.625044)
				)
			)
		)
		(polygon
			(pts
				(arc
					(start 156.431234 -24.232616)
					(mid 156.1831 -23.381163)
					(end 155.333446 -23.635208)
				)
				(arc
					(start 154.583638 -25.035256)
					(mid 154.83967 -25.881076)
					(end 155.68549 -25.625044)
				)
			)
		)
		(polygon
			(pts
				(arc
					(start 183.59374 -23.6601)
					(mid 183.0832 -23.14956)
					(end 182.57266 -23.6601)
				)
				(arc
					(start 182.57266 -24.473154)
					(mid 183.083327 -24.98344)
					(end 183.59374 -24.4729)
				)
			)
		)
		(polygon
			(pts
				(arc
					(start 273.100038 -22.381464)
					(mid 273.100038 -24.418544)
					(end 273.100038 -22.381464)
				)
			)
		)
		(polygon
			(pts
				(arc
					(start 283.005276 -20.15617)
					(mid 282.284107 -20.118381)
					(end 282.246578 -20.83943)
				)
				(xy 282.244546 -20.841208) (xy 282.788614 -21.44522)
				(arc
					(start 282.790646 -21.443442)
					(mid 283.511498 -21.481034)
					(end 283.54909 -20.760182)
				)
				(xy 283.551122 -20.758404) (xy 283.007308 -20.154646) (xy 283.0068 -20.154646)
			)
		)
		(polygon
			(pts
				(arc
					(start 160.935162 -20.425156)
					(mid 160.679486 -19.579255)
					(end 159.833564 -19.835114)
				)
				(xy 159.831532 -19.833844) (xy 159.08147 -21.233892)
				(arc
					(start 159.083502 -21.235162)
					(mid 159.339534 -22.080982)
					(end 160.185354 -21.82495)
				)
				(xy 160.187386 -21.82622) (xy 160.937448 -20.426426) (xy 160.937194 -20.426172)
			)
		)
		(polygon
			(pts
				(arc
					(start 158.68523 -20.425156)
					(mid 158.429554 -19.579255)
					(end 157.583632 -19.835114)
				)
				(xy 157.5816 -19.833844) (xy 156.831538 -21.233892)
				(arc
					(start 156.83357 -21.235162)
					(mid 157.089602 -22.080982)
					(end 157.935422 -21.82495)
				)
				(xy 157.937454 -21.82622) (xy 158.687516 -20.426426) (xy 158.687262 -20.426172)
			)
		)
		(polygon
			(pts
				(arc
					(start 324.935088 -20.425156)
					(mid 324.679412 -19.579255)
					(end 323.83349 -19.835114)
				)
				(xy 323.831458 -19.833844) (xy 323.081396 -21.233892)
				(arc
					(start 323.083428 -21.235162)
					(mid 323.33946 -22.080982)
					(end 324.18528 -21.82495)
				)
				(xy 324.187312 -21.82622) (xy 324.937374 -20.426426) (xy 324.93712 -20.426172)
			)
		)
		(polygon
			(pts
				(arc
					(start 322.685156 -20.425156)
					(mid 322.42948 -19.579255)
					(end 321.583558 -19.835114)
				)
				(xy 321.581526 -19.833844) (xy 320.831464 -21.233892)
				(arc
					(start 320.833496 -21.235162)
					(mid 321.089528 -22.080982)
					(end 321.935348 -21.82495)
				)
				(xy 321.93738 -21.82622) (xy 322.687442 -20.426426) (xy 322.687188 -20.426172)
			)
		)
		(polygon
			(pts
				(arc
					(start 313.93511 -20.425156)
					(mid 313.679434 -19.579255)
					(end 312.833512 -19.835114)
				)
				(xy 312.83148 -19.833844) (xy 312.081418 -21.233892)
				(arc
					(start 312.08345 -21.235162)
					(mid 312.339482 -22.080982)
					(end 313.185302 -21.82495)
				)
				(xy 313.187334 -21.82622) (xy 313.937396 -20.426426) (xy 313.937142 -20.426172)
			)
		)
		(polygon
			(pts
				(arc
					(start 311.685178 -20.425156)
					(mid 311.429502 -19.579255)
					(end 310.58358 -19.835114)
				)
				(xy 310.581548 -19.833844) (xy 309.831486 -21.233892)
				(arc
					(start 309.833518 -21.235162)
					(mid 310.08955 -22.080982)
					(end 310.93537 -21.82495)
				)
				(xy 310.937402 -21.82622) (xy 311.687464 -20.426426) (xy 311.68721 -20.426172)
			)
		)
		(polygon
			(pts
				(arc
					(start 171.93514 -20.425156)
					(mid 171.679464 -19.579255)
					(end 170.833542 -19.835114)
				)
				(xy 170.83151 -19.833844) (xy 170.081448 -21.233892)
				(arc
					(start 170.08348 -21.235162)
					(mid 170.339512 -22.080982)
					(end 171.185332 -21.82495)
				)
				(xy 171.187364 -21.82622) (xy 171.937426 -20.426426) (xy 171.937172 -20.426172)
			)
		)
		(polygon
			(pts
				(arc
					(start 169.685208 -20.425156)
					(mid 169.429532 -19.579255)
					(end 168.58361 -19.835114)
				)
				(xy 168.581578 -19.833844) (xy 167.831516 -21.233892)
				(arc
					(start 167.833548 -21.235162)
					(mid 168.08958 -22.080982)
					(end 168.9354 -21.82495)
				)
				(xy 168.937432 -21.82622) (xy 169.687494 -20.426426) (xy 169.68724 -20.426172)
			)
		)
		(polygon
			(pts
				(arc
					(start 149.935184 -20.425156)
					(mid 149.679508 -19.579255)
					(end 148.833586 -19.835114)
				)
				(xy 148.831554 -19.833844) (xy 148.081492 -21.233892)
				(arc
					(start 148.083524 -21.235162)
					(mid 148.339556 -22.080982)
					(end 149.185376 -21.82495)
				)
				(xy 149.187408 -21.82622) (xy 149.93747 -20.426426) (xy 149.937216 -20.426172)
			)
		)
		(polygon
			(pts
				(arc
					(start 302.935132 -20.425156)
					(mid 302.679456 -19.579255)
					(end 301.833534 -19.835114)
				)
				(xy 301.831502 -19.833844) (xy 301.08144 -21.233892)
				(arc
					(start 301.083472 -21.235162)
					(mid 301.339504 -22.080982)
					(end 302.185324 -21.82495)
				)
				(xy 302.187356 -21.82622) (xy 302.937418 -20.426426) (xy 302.937164 -20.426172)
			)
		)
		(polygon
			(pts
				(arc
					(start 291.935408 -20.424902)
					(mid 291.679376 -19.579082)
					(end 290.833556 -19.835114)
				)
				(xy 290.831524 -19.833844) (xy 290.081462 -21.233638) (xy 290.081716 -21.233892)
				(arc
					(start 290.083748 -21.234908)
					(mid 290.339424 -22.080809)
					(end 291.185346 -21.82495)
				)
				(xy 291.187378 -21.82622) (xy 291.93744 -20.426172)
			)
		)
		(polygon
			(pts
				(arc
					(start 289.685222 -20.424902)
					(mid 289.42919 -19.579082)
					(end 288.58337 -19.835114)
				)
				(arc
					(start 287.837626 -21.227542)
					(mid 288.08576 -22.078995)
					(end 288.935414 -21.82495)
				)
			)
		)
		(polygon
			(pts
				(arc
					(start 138.93546 -20.424902)
					(mid 138.679428 -19.579082)
					(end 137.833608 -19.835114)
				)
				(xy 137.831576 -19.833844) (xy 137.081514 -21.233638) (xy 137.081768 -21.233892)
				(arc
					(start 137.0838 -21.234908)
					(mid 137.339476 -22.080809)
					(end 138.185398 -21.82495)
				)
				(xy 138.18743 -21.82622) (xy 138.937492 -20.426172)
			)
		)
		(polygon
			(pts
				(arc
					(start 136.685274 -20.424902)
					(mid 136.429242 -19.579082)
					(end 135.583422 -19.835114)
				)
				(arc
					(start 134.837678 -21.227542)
					(mid 135.085812 -22.078995)
					(end 135.935466 -21.82495)
				)
			)
		)
		(polygon
			(pts
				(arc
					(start 147.681188 -20.432522)
					(mid 147.433054 -19.581069)
					(end 146.5834 -19.835114)
				)
				(arc
					(start 145.833592 -21.235162)
					(mid 146.089624 -22.080982)
					(end 146.935444 -21.82495)
				)
			)
		)
		(polygon
			(pts
				(arc
					(start 300.681136 -20.432522)
					(mid 300.433002 -19.581069)
					(end 299.583348 -19.835114)
				)
				(arc
					(start 298.83354 -21.235162)
					(mid 299.089572 -22.080982)
					(end 299.935392 -21.82495)
				)
			)
		)
		(polygon
			(pts
				(arc
					(start 183.59374 -19.849846)
					(mid 183.083073 -19.33956)
					(end 182.57266 -19.8501)
				)
				(arc
					(start 182.57266 -20.6629)
					(mid 183.0832 -21.17344)
					(end 183.59374 -20.6629)
				)
			)
		)
		(polygon
			(pts
				(arc
					(start 280.761186 -17.965928)
					(mid 280.258647 -17.447516)
					(end 279.740106 -17.949926)
				)
				(arc
					(start 279.72766 -18.762726)
					(mid 280.230326 -19.28114)
					(end 280.74874 -18.778474)
				)
			)
		)
		(polygon
			(pts
				(arc
					(start 324.935088 -16.625316)
					(mid 324.679564 -15.779496)
					(end 323.833744 -16.03502)
				)
				(xy 323.831458 -16.03375) (xy 323.081396 -17.433544) (xy 323.08165 -17.433798)
				(arc
					(start 323.083682 -17.434814)
					(mid 323.339206 -18.280634)
					(end 324.185026 -18.02511)
				)
				(xy 324.187312 -18.02638) (xy 324.937374 -16.626586)
			)
		)
		(polygon
			(pts
				(arc
					(start 322.685156 -16.625316)
					(mid 322.429632 -15.779496)
					(end 321.583812 -16.03502)
				)
				(xy 321.581526 -16.03375) (xy 320.831464 -17.433544) (xy 320.831718 -17.433798)
				(arc
					(start 320.83375 -17.434814)
					(mid 321.089274 -18.280634)
					(end 321.935094 -18.02511)
				)
				(xy 321.93738 -18.02638) (xy 322.687442 -16.626586)
			)
		)
		(polygon
			(pts
				(arc
					(start 313.93511 -16.625316)
					(mid 313.679586 -15.779496)
					(end 312.833766 -16.03502)
				)
				(xy 312.83148 -16.03375) (xy 312.081418 -17.433544) (xy 312.081672 -17.433798)
				(arc
					(start 312.083704 -17.434814)
					(mid 312.339228 -18.280634)
					(end 313.185048 -18.02511)
				)
				(xy 313.187334 -18.02638) (xy 313.937396 -16.626586)
			)
		)
		(polygon
			(pts
				(arc
					(start 311.685178 -16.625316)
					(mid 311.429654 -15.779496)
					(end 310.583834 -16.03502)
				)
				(xy 310.581548 -16.03375) (xy 309.831486 -17.433544) (xy 309.83174 -17.433798)
				(arc
					(start 309.833772 -17.434814)
					(mid 310.089296 -18.280634)
					(end 310.935116 -18.02511)
				)
				(xy 310.937402 -18.02638) (xy 311.687464 -16.626586)
			)
		)
		(polygon
			(pts
				(arc
					(start 302.935132 -16.625316)
					(mid 302.679608 -15.779496)
					(end 301.833788 -16.03502)
				)
				(xy 301.831502 -16.03375) (xy 301.08144 -17.433544) (xy 301.081694 -17.433798)
				(arc
					(start 301.083726 -17.434814)
					(mid 301.33925 -18.280634)
					(end 302.18507 -18.02511)
				)
				(xy 302.187356 -18.02638) (xy 302.937418 -16.626586)
			)
		)
		(polygon
			(pts
				(arc
					(start 291.935154 -16.625316)
					(mid 291.67963 -15.779496)
					(end 290.83381 -16.03502)
				)
				(xy 290.831524 -16.03375) (xy 290.081462 -17.433544) (xy 290.081716 -17.433798)
				(arc
					(start 290.083748 -17.434814)
					(mid 290.339272 -18.280634)
					(end 291.185092 -18.02511)
				)
				(xy 291.187378 -18.02638) (xy 291.93744 -16.626586)
			)
		)
		(polygon
			(pts
				(arc
					(start 171.93514 -16.625316)
					(mid 171.679616 -15.779496)
					(end 170.833796 -16.03502)
				)
				(xy 170.83151 -16.03375) (xy 170.081448 -17.433544) (xy 170.081702 -17.433798)
				(arc
					(start 170.083734 -17.434814)
					(mid 170.339258 -18.280634)
					(end 171.185078 -18.02511)
				)
				(xy 171.187364 -18.02638) (xy 171.937426 -16.626586)
			)
		)
		(polygon
			(pts
				(arc
					(start 169.685208 -16.625316)
					(mid 169.429684 -15.779496)
					(end 168.583864 -16.03502)
				)
				(xy 168.581578 -16.03375) (xy 167.831516 -17.433544) (xy 167.83177 -17.433798)
				(arc
					(start 167.833802 -17.434814)
					(mid 168.089326 -18.280634)
					(end 168.935146 -18.02511)
				)
				(xy 168.937432 -18.02638) (xy 169.687494 -16.626586)
			)
		)
		(polygon
			(pts
				(arc
					(start 160.935162 -16.625316)
					(mid 160.679638 -15.779496)
					(end 159.833818 -16.03502)
				)
				(xy 159.831532 -16.03375) (xy 159.08147 -17.433544) (xy 159.081724 -17.433798)
				(arc
					(start 159.083756 -17.434814)
					(mid 159.33928 -18.280634)
					(end 160.1851 -18.02511)
				)
				(xy 160.187386 -18.02638) (xy 160.937448 -16.626586)
			)
		)
		(polygon
			(pts
				(arc
					(start 158.68523 -16.625316)
					(mid 158.429706 -15.779496)
					(end 157.583886 -16.03502)
				)
				(xy 157.5816 -16.03375) (xy 156.831538 -17.433544) (xy 156.831792 -17.433798)
				(arc
					(start 156.833824 -17.434814)
					(mid 157.089348 -18.280634)
					(end 157.935168 -18.02511)
				)
				(xy 157.937454 -18.02638) (xy 158.687516 -16.626586)
			)
		)
		(polygon
			(pts
				(arc
					(start 149.935184 -16.625316)
					(mid 149.67966 -15.779496)
					(end 148.83384 -16.03502)
				)
				(xy 148.831554 -16.03375) (xy 148.081492 -17.433544) (xy 148.081746 -17.433798)
				(arc
					(start 148.083778 -17.434814)
					(mid 148.339302 -18.280634)
					(end 149.185122 -18.02511)
				)
				(xy 149.187408 -18.02638) (xy 149.93747 -16.626586)
			)
		)
		(polygon
			(pts
				(arc
					(start 138.935206 -16.625316)
					(mid 138.679682 -15.779496)
					(end 137.833862 -16.03502)
				)
				(xy 137.831576 -16.03375) (xy 137.081514 -17.433544) (xy 137.081768 -17.433798)
				(arc
					(start 137.0838 -17.434814)
					(mid 137.339324 -18.280634)
					(end 138.185144 -18.02511)
				)
				(xy 138.18743 -18.02638) (xy 138.937492 -16.626586)
			)
		)
		(polygon
			(pts
				(arc
					(start 300.6852 -16.625062)
					(mid 300.429168 -15.779242)
					(end 299.583348 -16.035274)
				)
				(xy 299.581316 -16.034004) (xy 298.831508 -17.433544) (xy 298.831762 -17.433798)
				(arc
					(start 298.833794 -17.434814)
					(mid 299.08947 -18.280715)
					(end 299.935392 -18.024856)
				)
				(xy 299.937424 -18.026126) (xy 300.687232 -16.626332)
			)
		)
		(polygon
			(pts
				(arc
					(start 289.685222 -16.625062)
					(mid 289.42919 -15.779242)
					(end 288.58337 -16.035274)
				)
				(xy 288.581338 -16.034004) (xy 287.83153 -17.433544) (xy 287.831784 -17.433798)
				(arc
					(start 287.833816 -17.434814)
					(mid 288.089492 -18.280715)
					(end 288.935414 -18.024856)
				)
				(xy 288.937446 -18.026126) (xy 289.687254 -16.626332)
			)
		)
		(polygon
			(pts
				(arc
					(start 147.685252 -16.625062)
					(mid 147.42922 -15.779242)
					(end 146.5834 -16.035274)
				)
				(xy 146.581368 -16.034004) (xy 145.83156 -17.433544) (xy 145.831814 -17.433798)
				(arc
					(start 145.833846 -17.434814)
					(mid 146.089522 -18.280715)
					(end 146.935444 -18.024856)
				)
				(xy 146.937476 -18.026126) (xy 147.687284 -16.626332)
			)
		)
		(polygon
			(pts
				(arc
					(start 136.685274 -16.625062)
					(mid 136.429242 -15.779242)
					(end 135.583422 -16.035274)
				)
				(xy 135.58139 -16.034004) (xy 134.831582 -17.433544) (xy 134.831836 -17.433798)
				(arc
					(start 134.833868 -17.434814)
					(mid 135.089544 -18.280715)
					(end 135.935466 -18.024856)
				)
				(xy 135.937498 -18.026126) (xy 136.687306 -16.626332)
			)
		)
		(polygon
			(pts
				(arc
					(start 272.57883 -14.52245)
					(mid 272.06829 -14.01191)
					(end 271.55775 -14.52245)
				)
				(arc
					(start 271.55775 -15.335504)
					(mid 272.068417 -15.84579)
					(end 272.57883 -15.33525)
				)
			)
		)
		(polygon
			(pts
				(arc
					(start 268.98854 -13.842746)
					(mid 268.477873 -13.33246)
					(end 267.96746 -13.843)
				)
				(arc
					(start 267.96746 -14.6558)
					(mid 268.478 -15.16634)
					(end 268.98854 -14.6558)
				)
			)
		)
		(polygon
			(pts
				(arc
					(start 291.935154 -12.825222)
					(mid 291.679478 -11.979321)
					(end 290.833556 -12.23518)
				)
				(xy 290.831524 -12.23391) (xy 290.081462 -13.633958)
				(arc
					(start 290.083494 -13.635228)
					(mid 290.339526 -14.481048)
					(end 291.185346 -14.225016)
				)
				(xy 291.187378 -14.226286) (xy 291.93744 -12.826492) (xy 291.937186 -12.826238)
			)
		)
		(polygon
			(pts
				(arc
					(start 287.435036 -12.825222)
					(mid 287.17936 -11.979321)
					(end 286.333438 -12.23518)
				)
				(xy 286.331406 -12.23391) (xy 285.581344 -13.633958)
				(arc
					(start 285.583376 -13.635228)
					(mid 285.839408 -14.481048)
					(end 286.685228 -14.225016)
				)
				(xy 286.68726 -14.226286) (xy 287.437322 -12.826492) (xy 287.437068 -12.826238)
			)
		)
		(polygon
			(pts
				(arc
					(start 138.935206 -12.825222)
					(mid 138.67953 -11.979321)
					(end 137.833608 -12.23518)
				)
				(xy 137.831576 -12.23391) (xy 137.081514 -13.633958)
				(arc
					(start 137.083546 -13.635228)
					(mid 137.339578 -14.481048)
					(end 138.185398 -14.225016)
				)
				(xy 138.18743 -14.226286) (xy 138.937492 -12.826492) (xy 138.937238 -12.826238)
			)
		)
		(polygon
			(pts
				(arc
					(start 134.435088 -12.825222)
					(mid 134.179412 -11.979321)
					(end 133.33349 -12.23518)
				)
				(xy 133.331458 -12.23391) (xy 132.581396 -13.633958)
				(arc
					(start 132.583428 -13.635228)
					(mid 132.83946 -14.481048)
					(end 133.68528 -14.225016)
				)
				(xy 133.687312 -14.226286) (xy 134.437374 -12.826492) (xy 134.43712 -12.826238)
			)
		)
		(polygon
			(pts
				(arc
					(start 324.935342 -12.824968)
					(mid 324.67931 -11.979148)
					(end 323.83349 -12.23518)
				)
				(xy 323.831458 -12.23391) (xy 323.081396 -13.633704) (xy 323.08165 -13.633958)
				(arc
					(start 323.083682 -13.634974)
					(mid 323.339358 -14.480875)
					(end 324.18528 -14.225016)
				)
				(xy 324.187312 -14.226286) (xy 324.937374 -12.826238)
			)
		)
		(polygon
			(pts
				(arc
					(start 322.68541 -12.824968)
					(mid 322.429378 -11.979148)
					(end 321.583558 -12.23518)
				)
				(xy 321.581526 -12.23391) (xy 320.831464 -13.633704) (xy 320.831718 -13.633958)
				(arc
					(start 320.83375 -13.634974)
					(mid 321.089426 -14.480875)
					(end 321.935348 -14.225016)
				)
				(xy 321.93738 -14.226286) (xy 322.687442 -12.826238)
			)
		)
		(polygon
			(pts
				(arc
					(start 320.435224 -12.824968)
					(mid 320.179192 -11.979148)
					(end 319.333372 -12.23518)
				)
				(arc
					(start 318.587628 -13.627608)
					(mid 318.835762 -14.479061)
					(end 319.685416 -14.225016)
				)
			)
		)
		(polygon
			(pts
				(arc
					(start 313.935364 -12.824968)
					(mid 313.679332 -11.979148)
					(end 312.833512 -12.23518)
				)
				(xy 312.83148 -12.23391) (xy 312.081418 -13.633704) (xy 312.081672 -13.633958)
				(arc
					(start 312.083704 -13.634974)
					(mid 312.33938 -14.480875)
					(end 313.185302 -14.225016)
				)
				(xy 313.187334 -14.226286) (xy 313.937396 -12.826238)
			)
		)
		(polygon
			(pts
				(arc
					(start 311.685432 -12.824968)
					(mid 311.4294 -11.979148)
					(end 310.58358 -12.23518)
				)
				(xy 310.581548 -12.23391) (xy 309.831486 -13.633704) (xy 309.83174 -13.633958)
				(arc
					(start 309.833772 -13.634974)
					(mid 310.089448 -14.480875)
					(end 310.93537 -14.225016)
				)
				(xy 310.937402 -14.226286) (xy 311.687464 -12.826238)
			)
		)
		(polygon
			(pts
				(arc
					(start 309.435246 -12.824968)
					(mid 309.179214 -11.979148)
					(end 308.333394 -12.23518)
				)
				(arc
					(start 307.58765 -13.627608)
					(mid 307.835784 -14.479061)
					(end 308.685438 -14.225016)
				)
			)
		)
		(polygon
			(pts
				(arc
					(start 302.935386 -12.824968)
					(mid 302.679354 -11.979148)
					(end 301.833534 -12.23518)
				)
				(xy 301.831502 -12.23391) (xy 301.08144 -13.633704) (xy 301.081694 -13.633958)
				(arc
					(start 301.083726 -13.634974)
					(mid 301.339402 -14.480875)
					(end 302.185324 -14.225016)
				)
				(xy 302.187356 -14.226286) (xy 302.937418 -12.826238)
			)
		)
		(polygon
			(pts
				(arc
					(start 300.6852 -12.824968)
					(mid 300.429168 -11.979148)
					(end 299.583348 -12.23518)
				)
				(arc
					(start 298.837604 -13.627608)
					(mid 299.085738 -14.479061)
					(end 299.935392 -14.225016)
				)
			)
		)
		(polygon
			(pts
				(arc
					(start 298.435268 -12.824968)
					(mid 298.179236 -11.979148)
					(end 297.333416 -12.23518)
				)
				(xy 297.331384 -12.23391) (xy 296.581322 -13.633704) (xy 296.581576 -13.633958)
				(arc
					(start 296.583608 -13.634974)
					(mid 296.839284 -14.480875)
					(end 297.685206 -14.225016)
				)
				(xy 297.687238 -14.226286) (xy 298.4373 -12.826238)
			)
		)
		(polygon
			(pts
				(arc
					(start 171.935394 -12.824968)
					(mid 171.679362 -11.979148)
					(end 170.833542 -12.23518)
				)
				(xy 170.83151 -12.23391) (xy 170.081448 -13.633704) (xy 170.081702 -13.633958)
				(arc
					(start 170.083734 -13.634974)
					(mid 170.33941 -14.480875)
					(end 171.185332 -14.225016)
				)
				(xy 171.187364 -14.226286) (xy 171.937426 -12.826238)
			)
		)
		(polygon
			(pts
				(arc
					(start 169.685462 -12.824968)
					(mid 169.42943 -11.979148)
					(end 168.58361 -12.23518)
				)
				(xy 168.581578 -12.23391) (xy 167.831516 -13.633704) (xy 167.83177 -13.633958)
				(arc
					(start 167.833802 -13.634974)
					(mid 168.089478 -14.480875)
					(end 168.9354 -14.225016)
				)
				(xy 168.937432 -14.226286) (xy 169.687494 -12.826238)
			)
		)
		(polygon
			(pts
				(arc
					(start 167.435276 -12.824968)
					(mid 167.179244 -11.979148)
					(end 166.333424 -12.23518)
				)
				(arc
					(start 165.58768 -13.627608)
					(mid 165.835814 -14.479061)
					(end 166.685468 -14.225016)
				)
			)
		)
		(polygon
			(pts
				(arc
					(start 160.935416 -12.824968)
					(mid 160.679384 -11.979148)
					(end 159.833564 -12.23518)
				)
				(xy 159.831532 -12.23391) (xy 159.08147 -13.633704) (xy 159.081724 -13.633958)
				(arc
					(start 159.083756 -13.634974)
					(mid 159.339432 -14.480875)
					(end 160.185354 -14.225016)
				)
				(xy 160.187386 -14.226286) (xy 160.937448 -12.826238)
			)
		)
		(polygon
			(pts
				(arc
					(start 158.685484 -12.824968)
					(mid 158.429452 -11.979148)
					(end 157.583632 -12.23518)
				)
				(xy 157.5816 -12.23391) (xy 156.831538 -13.633704) (xy 156.831792 -13.633958)
				(arc
					(start 156.833824 -13.634974)
					(mid 157.0895 -14.480875)
					(end 157.935422 -14.225016)
				)
				(xy 157.937454 -14.226286) (xy 158.687516 -12.826238)
			)
		)
		(polygon
			(pts
				(arc
					(start 156.435298 -12.824968)
					(mid 156.179266 -11.979148)
					(end 155.333446 -12.23518)
				)
				(arc
					(start 154.587702 -13.627608)
					(mid 154.835836 -14.479061)
					(end 155.68549 -14.225016)
				)
			)
		)
		(polygon
			(pts
				(arc
					(start 149.935438 -12.824968)
					(mid 149.679406 -11.979148)
					(end 148.833586 -12.23518)
				)
				(xy 148.831554 -12.23391) (xy 148.081492 -13.633704) (xy 148.081746 -13.633958)
				(arc
					(start 148.083778 -13.634974)
					(mid 148.339454 -14.480875)
					(end 149.185376 -14.225016)
				)
				(xy 149.187408 -14.226286) (xy 149.93747 -12.826238)
			)
		)
		(polygon
			(pts
				(arc
					(start 147.685252 -12.824968)
					(mid 147.42922 -11.979148)
					(end 146.5834 -12.23518)
				)
				(arc
					(start 145.837656 -13.627608)
					(mid 146.08579 -14.479061)
					(end 146.935444 -14.225016)
				)
			)
		)
		(polygon
			(pts
				(arc
					(start 145.43532 -12.824968)
					(mid 145.179288 -11.979148)
					(end 144.333468 -12.23518)
				)
				(xy 144.331436 -12.23391) (xy 143.581374 -13.633704) (xy 143.581628 -13.633958)
				(arc
					(start 143.58366 -13.634974)
					(mid 143.839336 -14.480875)
					(end 144.685258 -14.225016)
				)
				(xy 144.68729 -14.226286) (xy 145.437352 -12.826238)
			)
		)
		(polygon
			(pts
				(arc
					(start 289.681158 -12.832588)
					(mid 289.433024 -11.981135)
					(end 288.58337 -12.23518)
				)
				(arc
					(start 287.833562 -13.635228)
					(mid 288.089594 -14.481048)
					(end 288.935414 -14.225016)
				)
			)
		)
		(polygon
			(pts
				(arc
					(start 136.68121 -12.832588)
					(mid 136.433076 -11.981135)
					(end 135.583422 -12.23518)
				)
				(arc
					(start 134.833614 -13.635228)
					(mid 135.089646 -14.481048)
					(end 135.935466 -14.225016)
				)
			)
		)
		(polygon
			(pts
				(arc
					(start 185.069226 -11.6967)
					(mid 184.558559 -11.186414)
					(end 184.048146 -11.696954)
				)
				(arc
					(start 184.048146 -12.509754)
					(mid 184.558686 -13.020294)
					(end 185.069226 -12.509754)
				)
			)
		)
		(polygon
			(pts
				(xy 234.698794 -8.2169) (xy 221.739206 -8.2169) (xy 218.640406 -11.3157) (xy 217.675206 -11.3157)
				(xy 214.3379 -14.653006) (xy 214.3379 -20.424394) (xy 214.906606 -20.9931) (xy 228.619812 -20.987258)
				(xy 229.380288 -21.747734) (xy 229.380288 -32.56661) (xy 229.094538 -32.85236) (xy 226.740466 -32.85236)
				(xy 226.396296 -33.19653) (xy 226.396296 -39.48049) (xy 226.189286 -39.6875) (xy 196.136006 -39.6875)
				(xy 187.7695 -48.054006) (xy 187.7695 -54.942994) (xy 189.05474 -56.228234) (xy 189.05474 -56.928766)
				(xy 187.246006 -58.7375) (xy 179.245006 -58.7375) (xy 177.9905 -59.992006) (xy 177.9905 -61.009276)
				(xy 177.468276 -61.5315) (xy 163.878006 -61.5315) (xy 162.7505 -62.659006) (xy 162.7505 -70.690994)
				(xy 163.243006 -71.1835) (xy 171.104052 -71.1835) (xy 171.6405 -71.719948) (xy 171.6405 -79.453994)
				(xy 178.737006 -86.5505) (xy 236.552994 -86.5505) (xy 246.9515 -76.151994) (xy 246.9515 -74.374248)
				(xy 247.475248 -73.8505) (xy 309.323994 -73.8505) (xy 310.3245 -72.849994) (xy 310.3245 -69.179948)
				(xy 310.860948 -68.6435) (xy 325.325994 -68.6435) (xy 325.9455 -68.023994) (xy 325.9455 -55.801006)
				(xy 324.944994 -54.8005) (xy 310.826912 -54.8005) (xy 310.3245 -54.298088) (xy 310.3245 -50.721006)
				(arc
					(start 295.226232 -35.622992)
					(mid 295.46527 -35.048699)
					(end 294.971978 -34.66973)
				)
				(xy 294.273224 -34.66973) (xy 285.574994 -25.9715) (xy 241.124994 -25.9715) (xy 251.8029 -15.293594)
				(xy 251.8029 -9.852406) (xy 250.878594 -8.9281) (xy 235.409994 -8.9281)
			)
		)
		(polygon
			(pts
				(arc
					(start 184.443624 -8.91667)
					(mid 184.95391 -8.406003)
					(end 184.44337 -7.89559)
				)
				(arc
					(start 183.63057 -7.89559)
					(mid 183.12003 -8.40613)
					(end 183.63057 -8.91667)
				)
			)
		)
		(polygon
			(pts
				(arc
					(start 271.19834 -8.353298)
					(mid 270.687673 -7.843012)
					(end 270.17726 -8.353552)
				)
				(arc
					(start 270.17726 -9.166352)
					(mid 270.6878 -9.676892)
					(end 271.19834 -9.166352)
				)
			)
		)
		(polygon
			(pts
				(arc
					(start 270.05534 -5.305298)
					(mid 269.544673 -4.795012)
					(end 269.03426 -5.305552)
				)
				(arc
					(start 269.03426 -6.118352)
					(mid 269.5448 -6.628892)
					(end 270.05534 -6.118352)
				)
			)
		)
		(polygon
			(pts
				(arc
					(start 231.550464 -2.557272)
					(mid 231.550464 -4.441952)
					(end 231.550464 -2.557272)
				)
			)
		)
	)
	(zone
		(net "DUT_VDD")
		(layer "In4.Cu")
		(hatch none 0.5)
		(connect_pads
			(clearance 0.5)
		)
		(min_thickness 0.25)
		(fill yes
			(thermal_gap 0.5)
			(thermal_bridge_width 0.5)
			(island_removal_mode 0)
		)
		(polygon
			(pts
				(xy 240.743994 -26.3525) (xy 239.7125 -27.383994) (xy 239.7125 -39.677594) (xy 239.321594 -40.0685)
				(xy 233.250994 -40.0685) (xy 232.7275 -40.591994) (xy 232.7275 -53.540406) (xy 232.996994 -53.8099)
				(xy 233.352594 -53.8099) (xy 233.7435 -54.200806) (xy 233.7435 -54.505606) (xy 234.038394 -54.8005)
				(xy 246.382794 -54.8005) (xy 246.9515 -55.369206) (xy 246.9515 -72.949308) (xy 247.471692 -73.4695)
				(xy 309.166006 -73.4695) (xy 309.9435 -72.692006) (xy 309.9435 -50.878994) (xy 294.755316 -35.69081)
				(arc
					(start 294.159178 -35.69081)
					(mid 293.743579 -35.476797)
					(end 293.676324 -35.014154)
				)
				(arc
					(start 293.676324 -35.014154)
					(mid 293.74293 -34.8845)
					(end 293.843456 -34.77895)
				)
				(xy 285.417006 -26.3525)
			)
		)
		(polygon
			(pts
				(arc
					(start 290.042854 -35.524694)
					(mid 290.55314 -35.014027)
					(end 290.0426 -34.503614)
				)
				(arc
					(start 289.2298 -34.503614)
					(mid 288.71926 -35.014154)
					(end 289.2298 -35.524694)
				)
			)
		)
		(polygon
			(pts
				(arc
					(start 285.498794 -33.051496)
					(mid 284.988254 -32.540956)
					(end 284.477714 -33.051496)
				)
				(arc
					(start 284.477714 -33.86455)
					(mid 284.988381 -34.374836)
					(end 285.498794 -33.864296)
				)
			)
		)
	)
	(zone
		(net "DUT_VDDO")
		(layer "In4.Cu")
		(hatch none 0.5)
		(connect_pads
			(clearance 0.5)
		)
		(min_thickness 0.25)
		(fill yes
			(thermal_gap 0.5)
			(thermal_bridge_width 0.5)
			(island_removal_mode 0)
		)
		(polygon
			(pts
				(xy 221.897194 -8.5979) (xy 218.798394 -11.6967) (xy 217.833194 -11.6967) (xy 214.7189 -14.810994)
				(xy 214.7189 -20.266406) (xy 215.064594 -20.6121) (xy 228.7778 -20.606258) (xy 229.761288 -21.589746)
				(xy 229.761288 -32.724598) (xy 229.252526 -33.23336) (xy 226.898454 -33.23336) (xy 226.777296 -33.354518)
				(xy 226.777296 -39.561262) (xy 226.903534 -39.6875) (xy 239.163606 -39.6875) (xy 239.3315 -39.519606)
				(xy 239.3315 -27.226006) (xy 251.4219 -15.135606) (xy 251.4219 -10.010394) (xy 250.720606 -9.3091)
				(xy 235.252006 -9.3091) (xy 234.540806 -8.5979)
			)
		)
	)
	(zone
		(net "DUT_AVD_PCIE_Q")
		(layer "In4.Cu")
		(hatch none 0.5)
		(connect_pads
			(clearance 0.5)
		)
		(min_thickness 0.25)
		(fill yes
			(thermal_gap 0.5)
			(thermal_bridge_width 0.5)
			(island_removal_mode 0)
		)
		(polygon
			(pts
				(xy 196.293994 -40.0685) (xy 188.1505 -48.211994) (xy 188.1505 -54.785006) (xy 189.306454 -55.94096)
				(xy 190.042546 -55.94096) (xy 200.7489 -45.234606)
				(arc
					(start 200.7489 -44.714922)
					(mid 201.36104 -44.102782)
					(end 201.97318 -44.714922)
				)
				(xy 201.97318 -44.7675) (xy 228.450394 -44.7675) (xy 228.9175 -45.234606) (xy 228.9175 -54.531006)
				(xy 229.186994 -54.8005) (xy 233.118406 -54.8005) (xy 233.3625 -54.556406) (xy 233.3625 -54.358794)
				(xy 233.194606 -54.1909) (xy 232.839006 -54.1909) (xy 232.3465 -53.698394) (xy 232.3465 -40.464994)
				(xy 231.950006 -40.0685)
			)
		)
		(polygon
			(pts
				(arc
					(start 198.429118 -45.590206)
					(mid 197.816851 -44.97832)
					(end 197.204838 -45.59046)
				)
				(arc
					(start 197.204838 -46.70806)
					(mid 197.816978 -47.3202)
					(end 198.429118 -46.70806)
				)
			)
		)
	)
	(zone
		(layer "In4.Cu")
		(hatch none 0.5)
		(connect_pads
			(clearance 0)
		)
		(min_thickness 0.25)
		(keepout
			(tracks not_allowed)
			(vias allowed)
			(pads allowed)
			(copperpour not_allowed)
			(footprints allowed)
		)
		(placement
			(enabled no)
			(sheetname "")
		)
		(fill
			(thermal_gap 0.5)
			(thermal_bridge_width 0.5)
			(island_removal_mode 0)
		)
		(polygon
			(pts
				(arc
					(start 232.492804 -3.499612)
					(mid 230.608124 -3.499612)
					(end 232.492804 -3.499612)
				)
			)
		)
	)
	(zone
		(layer "In5.Cu")
		(hatch none 0.5)
		(connect_pads
			(clearance 0)
		)
		(min_thickness 0.25)
		(keepout
			(tracks not_allowed)
			(vias allowed)
			(pads allowed)
			(copperpour not_allowed)
			(footprints allowed)
		)
		(placement
			(enabled no)
			(sheetname "")
		)
		(fill
			(thermal_gap 0.5)
			(thermal_bridge_width 0.5)
			(island_removal_mode 0)
		)
		(polygon
			(pts
				(arc
					(start 79.69377 -210.385914)
					(mid 79.182976 -210.896327)
					(end 79.693516 -211.406994)
				)
				(arc
					(start 80.506316 -211.406994)
					(mid 81.016856 -210.896454)
					(end 80.506316 -210.385914)
				)
				(arc
					(start 80.36052 -210.385914)
					(mid 80.391023 -210.514869)
					(end 80.439006 -210.63839)
				)
				(arc
					(start 80.439006 -210.63839)
					(mid 80.651199 -211.120607)
					(end 80.299306 -210.72856)
				)
				(arc
					(start 80.299306 -210.72856)
					(mid 80.232599 -210.561486)
					(end 80.193388 -210.385914)
				)
				(arc
					(start 80.006444 -210.385914)
					(mid 79.967221 -210.561483)
					(end 79.900526 -210.72856)
				)
				(arc
					(start 79.900526 -210.72856)
					(mid 79.548649 -211.120583)
					(end 79.760826 -210.63839)
				)
				(arc
					(start 79.760826 -210.63839)
					(mid 79.808797 -210.514866)
					(end 79.839312 -210.385914)
				)
			)
		)
	)
	(zone
		(layer "In5.Cu")
		(hatch none 0.5)
		(connect_pads
			(clearance 0)
		)
		(min_thickness 0.25)
		(keepout
			(tracks not_allowed)
			(vias allowed)
			(pads allowed)
			(copperpour not_allowed)
			(footprints allowed)
		)
		(placement
			(enabled no)
			(sheetname "")
		)
		(fill
			(thermal_gap 0.5)
			(thermal_bridge_width 0.5)
			(island_removal_mode 0)
		)
		(polygon
			(pts
				(arc
					(start 48.493934 -210.385914)
					(mid 47.98314 -210.896327)
					(end 48.49368 -211.406994)
				)
				(arc
					(start 49.30648 -211.406994)
					(mid 49.81702 -210.896454)
					(end 49.30648 -210.385914)
				)
				(arc
					(start 49.160684 -210.385914)
					(mid 49.191187 -210.514869)
					(end 49.23917 -210.63839)
				)
				(arc
					(start 49.23917 -210.63839)
					(mid 49.451363 -211.120607)
					(end 49.09947 -210.72856)
				)
				(arc
					(start 49.09947 -210.72856)
					(mid 49.032763 -210.561486)
					(end 48.993552 -210.385914)
				)
				(xy 48.81753 -210.385914) (xy 48.81753 -210.47329)
				(arc
					(start 48.816514 -210.474306)
					(mid 48.788528 -210.623932)
					(end 48.724058 -210.761834)
				)
				(arc
					(start 48.724058 -210.761834)
					(mid 48.317439 -211.096793)
					(end 48.59782 -210.650836)
				)
				(arc
					(start 48.59782 -210.650836)
					(mid 48.638513 -210.548373)
					(end 48.65243 -210.439)
				)
				(xy 48.65243 -210.385914)
			)
		)
	)
	(zone
		(layer "In5.Cu")
		(hatch none 0.5)
		(connect_pads
			(clearance 0)
		)
		(min_thickness 0.25)
		(keepout
			(tracks not_allowed)
			(vias allowed)
			(pads allowed)
			(copperpour not_allowed)
			(footprints allowed)
		)
		(placement
			(enabled no)
			(sheetname "")
		)
		(fill
			(thermal_gap 0.5)
			(thermal_bridge_width 0.5)
			(island_removal_mode 0)
		)
		(polygon
			(pts
				(arc
					(start 70.09384 -210.385914)
					(mid 69.583046 -210.896327)
					(end 70.093586 -211.406994)
				)
				(arc
					(start 70.906386 -211.406994)
					(mid 71.416926 -210.896454)
					(end 70.906386 -210.385914)
				)
				(arc
					(start 70.776846 -210.385914)
					(mid 70.81057 -210.512221)
					(end 70.856602 -210.63458)
				)
				(arc
					(start 70.856602 -210.63458)
					(mid 71.03469 -211.129915)
					(end 70.711314 -210.71459)
				)
				(arc
					(start 70.711314 -210.71459)
					(mid 70.650346 -210.553236)
					(end 70.608444 -210.385914)
				)
				(arc
					(start 70.391528 -210.385914)
					(mid 70.349631 -210.553237)
					(end 70.288658 -210.71459)
				)
				(arc
					(start 70.288658 -210.71459)
					(mid 69.965284 -211.129911)
					(end 70.14337 -210.63458)
				)
				(arc
					(start 70.14337 -210.63458)
					(mid 70.189389 -210.512217)
					(end 70.223126 -210.385914)
				)
			)
		)
	)
	(zone
		(layer "In5.Cu")
		(hatch none 0.5)
		(connect_pads
			(clearance 0)
		)
		(min_thickness 0.25)
		(keepout
			(tracks not_allowed)
			(vias allowed)
			(pads allowed)
			(copperpour not_allowed)
			(footprints allowed)
		)
		(placement
			(enabled no)
			(sheetname "")
		)
		(fill
			(thermal_gap 0.5)
			(thermal_bridge_width 0.5)
			(island_removal_mode 0)
		)
		(polygon
			(pts
				(arc
					(start 285.498794 -33.051496)
					(mid 284.988254 -32.540956)
					(end 284.477714 -33.051496)
				)
				(xy 284.477714 -33.21685)
				(arc
					(start 284.60446 -33.21685)
					(mid 284.681951 -33.207796)
					(end 284.755336 -33.18129)
				)
				(arc
					(start 284.755336 -33.18129)
					(mid 285.166321 -32.853028)
					(end 284.884368 -33.297114)
				)
				(arc
					(start 284.884368 -33.297114)
					(mid 284.767639 -33.354812)
					(end 284.64002 -33.38068)
				)
				(xy 284.63875 -33.38195) (xy 284.477714 -33.38195) (xy 284.477714 -33.54705) (xy 284.533086 -33.54705)
				(arc
					(start 284.533848 -33.547812)
					(mid 284.694932 -33.575193)
					(end 284.845252 -33.639252)
				)
				(arc
					(start 284.845252 -33.639252)
					(mid 285.194829 -34.032881)
					(end 284.73908 -33.7693)
				)
				(arc
					(start 284.73908 -33.7693)
					(mid 284.622296 -33.726605)
					(end 284.498796 -33.71215)
				)
				(xy 284.477714 -33.71215)
				(arc
					(start 284.477714 -33.864042)
					(mid 284.988127 -34.374836)
					(end 285.498794 -33.864296)
				)
			)
		)
	)
	(zone
		(net "DUT_AVD_PCIE_Q")
		(layer "In5.Cu")
		(hatch none 0.5)
		(connect_pads
			(clearance 0.5)
		)
		(min_thickness 0.25)
		(fill yes
			(thermal_gap 0.5)
			(thermal_bridge_width 0.5)
			(island_removal_mode 0)
		)
		(polygon
			(pts
				(xy 232.41 -54.61) (xy 232.791 -54.229) (xy 248.412 -54.229) (xy 248.793 -54.61) (xy 249.682 -54.61)
				(xy 249.809 -54.483) (xy 249.809 -46.482) (xy 249.809 -41.91) (xy 249.555 -41.656) (xy 242.951 -41.656)
				(xy 242.57 -41.275) (xy 241.681 -41.275) (xy 241.427 -41.529) (xy 241.427 -43.053) (xy 241.3508 -43.1292)
				(xy 241.3508 -47.5742) (xy 240.1824 -48.7426) (xy 231.7496 -48.7426) (xy 231.4194 -49.0728) (xy 231.4194 -54.3814)
				(xy 231.521 -54.483) (xy 231.775 -54.737) (xy 232.283 -54.737)
			)
		)
	)
	(zone
		(layer "In5.Cu")
		(hatch none 0.5)
		(connect_pads
			(clearance 0)
		)
		(min_thickness 0.25)
		(keepout
			(tracks not_allowed)
			(vias allowed)
			(pads allowed)
			(copperpour not_allowed)
			(footprints allowed)
		)
		(placement
			(enabled no)
			(sheetname "")
		)
		(fill
			(thermal_gap 0.5)
			(thermal_bridge_width 0.5)
			(island_removal_mode 0)
		)
		(polygon
			(pts
				(arc
					(start 206.493872 -210.385914)
					(mid 205.983078 -210.896327)
					(end 206.493618 -211.406994)
				)
				(arc
					(start 207.306418 -211.406994)
					(mid 207.816958 -210.896454)
					(end 207.306418 -210.385914)
				)
				(arc
					(start 207.151224 -210.385914)
					(mid 207.176285 -210.517637)
					(end 207.22463 -210.642708)
				)
				(arc
					(start 207.22463 -210.642708)
					(mid 207.463198 -211.111803)
					(end 207.089502 -210.74126)
				)
				(arc
					(start 207.089502 -210.74126)
					(mid 207.019104 -210.568959)
					(end 206.985362 -210.385914)
				)
				(arc
					(start 206.814674 -210.385914)
					(mid 206.780947 -210.568963)
					(end 206.710534 -210.74126)
				)
				(arc
					(start 206.710534 -210.74126)
					(mid 206.336846 -211.111792)
					(end 206.575406 -210.642708)
				)
				(arc
					(start 206.575406 -210.642708)
					(mid 206.623785 -210.517647)
					(end 206.648812 -210.385914)
				)
			)
		)
	)
	(zone
		(layer "In5.Cu")
		(hatch none 0.5)
		(connect_pads
			(clearance 0)
		)
		(min_thickness 0.25)
		(keepout
			(tracks not_allowed)
			(vias allowed)
			(pads allowed)
			(copperpour not_allowed)
			(footprints allowed)
		)
		(placement
			(enabled no)
			(sheetname "")
		)
		(fill
			(thermal_gap 0.5)
			(thermal_bridge_width 0.5)
			(island_removal_mode 0)
		)
		(polygon
			(pts
				(arc
					(start 294.159432 -34.66973)
					(mid 293.648638 -35.180143)
					(end 294.159178 -35.69081)
				)
				(arc
					(start 294.299894 -35.69081)
					(mid 294.30368 -35.657759)
					(end 294.304974 -35.624516)
				)
				(arc
					(start 294.305228 -35.618674)
					(mid 294.292811 -35.520539)
					(end 294.258746 -35.427666)
				)
				(arc
					(start 294.258746 -35.427666)
					(mid 293.987024 -34.976939)
					(end 294.38727 -35.3187)
				)
				(arc
					(start 294.38727 -35.3187)
					(mid 294.449195 -35.465809)
					(end 294.470328 -35.624008)
				)
				(xy 294.470328 -35.624516)
				(arc
					(start 294.470074 -35.631374)
					(mid 294.469029 -35.661136)
					(end 294.466518 -35.69081)
				)
				(arc
					(start 294.632634 -35.69081)
					(mid 294.634744 -35.657693)
					(end 294.635428 -35.624516)
				)
				(arc
					(start 294.635428 -35.624516)
					(mid 294.661701 -35.458101)
					(end 294.73779 -35.307778)
				)
				(arc
					(start 294.73779 -35.307778)
					(mid 295.154407 -34.985791)
					(end 294.85971 -35.422078)
				)
				(arc
					(start 294.85971 -35.422078)
					(mid 294.815661 -35.51907)
					(end 294.800528 -35.624516)
				)
				(arc
					(start 294.800528 -35.624516)
					(mid 294.799976 -35.657683)
					(end 294.798242 -35.69081)
				)
				(arc
					(start 294.971978 -35.69081)
					(mid 295.482518 -35.18027)
					(end 294.971978 -34.66973)
				)
			)
		)
	)
	(zone
		(layer "In5.Cu")
		(hatch none 0.5)
		(connect_pads
			(clearance 0)
		)
		(min_thickness 0.25)
		(keepout
			(tracks not_allowed)
			(vias allowed)
			(pads allowed)
			(copperpour not_allowed)
			(footprints allowed)
		)
		(placement
			(enabled no)
			(sheetname "")
		)
		(fill
			(thermal_gap 0.5)
			(thermal_bridge_width 0.5)
			(island_removal_mode 0)
		)
		(polygon
			(pts
				(arc
					(start 18.574004 -72.700134)
					(mid 18.06321 -73.210547)
					(end 18.57375 -73.721214)
				)
				(xy 18.74647 -73.721214) (xy 18.76425 -73.703434) (xy 18.76425 -73.49109)
				(arc
					(start 18.711926 -73.438766)
					(mid 18.385178 -73.022102)
					(end 18.801842 -73.34885)
				)
				(xy 18.854166 -73.401174) (xy 18.89125 -73.438258) (xy 18.89125 -73.49109) (xy 18.89125 -73.703434)
				(xy 18.89125 -73.721214) (xy 19.06905 -73.721214) (xy 19.06905 -73.49109) (xy 19.06905 -73.438258)
				(xy 19.106134 -73.401174)
				(arc
					(start 19.158458 -73.34885)
					(mid 19.575122 -73.022102)
					(end 19.248374 -73.438766)
				)
				(xy 19.19605 -73.49109) (xy 19.19605 -73.721214)
				(arc
					(start 19.38655 -73.721214)
					(mid 19.89709 -73.210674)
					(end 19.38655 -72.700134)
				)
			)
		)
	)
	(zone
		(layer "In5.Cu")
		(hatch none 0.5)
		(connect_pads
			(clearance 0)
		)
		(min_thickness 0.25)
		(keepout
			(tracks not_allowed)
			(vias allowed)
			(pads allowed)
			(copperpour not_allowed)
			(footprints allowed)
		)
		(placement
			(enabled no)
			(sheetname "")
		)
		(fill
			(thermal_gap 0.5)
			(thermal_bridge_width 0.5)
			(island_removal_mode 0)
		)
		(polygon
			(pts
				(arc
					(start 102.44074 -38.916864)
					(mid 101.930327 -38.40607)
					(end 101.41966 -38.91661)
				)
				(xy 101.41966 -39.11346) (xy 101.61651 -39.11346)
				(arc
					(start 101.692456 -39.037514)
					(mid 102.1188 -38.72801)
					(end 101.809296 -39.154354)
				)
				(xy 101.73335 -39.2303) (xy 101.68509 -39.27856) (xy 101.61651 -39.27856) (xy 101.41966 -39.27856)
				(xy 101.41966 -39.44366) (xy 101.61651 -39.44366) (xy 101.68509 -39.44366) (xy 101.73335 -39.49192)
				(arc
					(start 101.809296 -39.567866)
					(mid 102.1188 -39.99421)
					(end 101.692456 -39.684706)
				)
				(xy 101.61651 -39.60876) (xy 101.41966 -39.60876)
				(arc
					(start 101.41966 -39.80561)
					(mid 101.9302 -40.31615)
					(end 102.44074 -39.80561)
				)
			)
		)
	)
	(zone
		(layer "In5.Cu")
		(hatch none 0.5)
		(connect_pads
			(clearance 0)
		)
		(min_thickness 0.25)
		(keepout
			(tracks not_allowed)
			(vias allowed)
			(pads allowed)
			(copperpour not_allowed)
			(footprints allowed)
		)
		(placement
			(enabled no)
			(sheetname "")
		)
		(fill
			(thermal_gap 0.5)
			(thermal_bridge_width 0.5)
			(island_removal_mode 0)
		)
		(polygon
			(pts
				(arc
					(start 148.5011 -34.49066)
					(mid 147.99056 -35.0012)
					(end 148.5011 -35.51174)
				)
				(xy 148.68525 -35.51174)
				(arc
					(start 148.68525 -35.4838)
					(mid 148.66869 -35.357573)
					(end 148.619972 -35.23996)
				)
				(arc
					(start 148.619972 -35.23996)
					(mid 148.31217 -34.812524)
					(end 148.739606 -35.120326)
				)
				(arc
					(start 148.739606 -35.120326)
					(mid 148.816636 -35.277128)
					(end 148.849334 -35.448748)
				)
				(xy 148.85035 -35.44951) (xy 148.85035 -35.51174) (xy 149.01545 -35.51174) (xy 149.01545 -35.44951)
				(arc
					(start 149.016212 -35.448748)
					(mid 149.039798 -35.296764)
					(end 149.094698 -35.153092)
				)
				(arc
					(start 149.094698 -35.153092)
					(mid 149.473962 -34.787891)
					(end 149.229318 -35.254184)
				)
				(arc
					(start 149.229318 -35.254184)
					(mid 149.192874 -35.366431)
					(end 149.18055 -35.4838)
				)
				(xy 149.18055 -35.51174)
				(arc
					(start 149.313646 -35.51174)
					(mid 149.82444 -35.001327)
					(end 149.3139 -34.49066)
				)
			)
		)
	)
	(zone
		(layer "In5.Cu")
		(hatch none 0.5)
		(connect_pads
			(clearance 0)
		)
		(min_thickness 0.25)
		(keepout
			(tracks not_allowed)
			(vias allowed)
			(pads allowed)
			(copperpour not_allowed)
			(footprints allowed)
		)
		(placement
			(enabled no)
			(sheetname "")
		)
		(fill
			(thermal_gap 0.5)
			(thermal_bridge_width 0.5)
			(island_removal_mode 0)
		)
		(polygon
			(pts
				(arc
					(start 169.693844 -210.385914)
					(mid 169.18305 -210.896327)
					(end 169.69359 -211.406994)
				)
				(arc
					(start 170.50639 -211.406994)
					(mid 171.01693 -210.896454)
					(end 170.50639 -210.385914)
				)
				(xy 170.34764 -210.385914)
				(arc
					(start 170.34764 -210.467702)
					(mid 170.348329 -210.488566)
					(end 170.35018 -210.509358)
				)
				(arc
					(start 170.35018 -210.509358)
					(mid 170.366807 -210.583525)
					(end 170.397932 -210.652868)
				)
				(arc
					(start 170.397932 -210.652868)
					(mid 170.685601 -211.094087)
					(end 170.273726 -210.765898)
				)
				(arc
					(start 170.273726 -210.765898)
					(mid 170.215925 -210.652577)
					(end 170.186096 -210.528916)
				)
				(xy 170.186096 -210.528408) (xy 170.183556 -210.499706) (xy 170.18254 -210.49869) (xy 170.18254 -210.467956)
				(xy 170.18254 -210.464146) (xy 170.18254 -210.385914) (xy 170.01744 -210.385914) (xy 170.01744 -210.49869)
				(arc
					(start 170.01617 -210.499706)
					(mid 170.012243 -210.538887)
					(end 170.005502 -210.577684)
				)
				(arc
					(start 170.005502 -210.577684)
					(mid 169.974667 -210.675555)
					(end 169.926 -210.765898)
				)
				(arc
					(start 169.926 -210.765898)
					(mid 169.514054 -211.093498)
					(end 169.802048 -210.652868)
				)
				(arc
					(start 169.802048 -210.652868)
					(mid 169.82727 -210.599636)
					(end 169.843958 -210.54314)
				)
				(arc
					(start 169.843958 -210.54314)
					(mid 169.850226 -210.503991)
					(end 169.85234 -210.4644)
				)
				(xy 169.85234 -210.385914)
			)
		)
	)
	(zone
		(layer "In5.Cu")
		(hatch none 0.5)
		(connect_pads
			(clearance 0)
		)
		(min_thickness 0.25)
		(keepout
			(tracks not_allowed)
			(vias allowed)
			(pads allowed)
			(copperpour not_allowed)
			(footprints allowed)
		)
		(placement
			(enabled no)
			(sheetname "")
		)
		(fill
			(thermal_gap 0.5)
			(thermal_bridge_width 0.5)
			(island_removal_mode 0)
		)
		(polygon
			(pts
				(arc
					(start 58.093864 -210.385914)
					(mid 57.58307 -210.896327)
					(end 58.09361 -211.406994)
				)
				(arc
					(start 58.90641 -211.406994)
					(mid 59.41695 -210.896454)
					(end 58.90641 -210.385914)
				)
				(arc
					(start 58.760614 -210.385914)
					(mid 58.791117 -210.514869)
					(end 58.8391 -210.63839)
				)
				(arc
					(start 58.8391 -210.63839)
					(mid 59.051293 -211.120607)
					(end 58.6994 -210.72856)
				)
				(arc
					(start 58.6994 -210.72856)
					(mid 58.632693 -210.561486)
					(end 58.593482 -210.385914)
				)
				(arc
					(start 58.406538 -210.385914)
					(mid 58.367315 -210.561483)
					(end 58.30062 -210.72856)
				)
				(arc
					(start 58.30062 -210.72856)
					(mid 57.948743 -211.120583)
					(end 58.16092 -210.63839)
				)
				(arc
					(start 58.16092 -210.63839)
					(mid 58.208891 -210.514866)
					(end 58.239406 -210.385914)
				)
			)
		)
	)
	(zone
		(layer "In5.Cu")
		(hatch none 0.5)
		(connect_pads
			(clearance 0)
		)
		(min_thickness 0.25)
		(keepout
			(tracks not_allowed)
			(vias allowed)
			(pads allowed)
			(copperpour not_allowed)
			(footprints allowed)
		)
		(placement
			(enabled no)
			(sheetname "")
		)
		(fill
			(thermal_gap 0.5)
			(thermal_bridge_width 0.5)
			(island_removal_mode 0)
		)
		(polygon
			(pts
				(arc
					(start 293.2938 -210.385914)
					(mid 292.783006 -210.896327)
					(end 293.293546 -211.406994)
				)
				(arc
					(start 294.106346 -211.406994)
					(mid 294.616886 -210.896454)
					(end 294.106346 -210.385914)
				)
				(arc
					(start 293.951152 -210.385914)
					(mid 293.976213 -210.517637)
					(end 294.024558 -210.642708)
				)
				(arc
					(start 294.024558 -210.642708)
					(mid 294.263126 -211.111803)
					(end 293.88943 -210.74126)
				)
				(arc
					(start 293.88943 -210.74126)
					(mid 293.819032 -210.568959)
					(end 293.78529 -210.385914)
				)
				(arc
					(start 293.614602 -210.385914)
					(mid 293.580875 -210.568963)
					(end 293.510462 -210.74126)
				)
				(arc
					(start 293.510462 -210.74126)
					(mid 293.136774 -211.111792)
					(end 293.375334 -210.642708)
				)
				(arc
					(start 293.375334 -210.642708)
					(mid 293.423713 -210.517647)
					(end 293.44874 -210.385914)
				)
			)
		)
	)
	(zone
		(layer "In5.Cu")
		(hatch none 0.5)
		(connect_pads
			(clearance 0)
		)
		(min_thickness 0.25)
		(keepout
			(tracks allowed)
			(vias allowed)
			(pads allowed)
			(copperpour allowed)
			(footprints allowed)
		)
		(placement
			(enabled no)
			(sheetname "")
		)
		(fill
			(thermal_gap 0.5)
			(thermal_bridge_width 0.5)
			(island_removal_mode 0)
		)
		(polygon
			(pts
				(xy 219.9894 -41.5544) (xy 219.9894 -43.6372) (xy 212.2678 -43.6372) (xy 212.2678 -41.5544)
			)
		)
	)
	(zone
		(layer "In5.Cu")
		(hatch none 0.5)
		(connect_pads
			(clearance 0)
		)
		(min_thickness 0.25)
		(keepout
			(tracks not_allowed)
			(vias allowed)
			(pads allowed)
			(copperpour not_allowed)
			(footprints allowed)
		)
		(placement
			(enabled no)
			(sheetname "")
		)
		(fill
			(thermal_gap 0.5)
			(thermal_bridge_width 0.5)
			(island_removal_mode 0)
		)
		(polygon
			(pts
				(arc
					(start 172.89399 -210.385914)
					(mid 172.383196 -210.896327)
					(end 172.893736 -211.406994)
				)
				(arc
					(start 173.706536 -211.406994)
					(mid 174.217076 -210.896454)
					(end 173.706536 -210.385914)
				)
				(arc
					(start 173.565312 -210.385914)
					(mid 173.584149 -210.516832)
					(end 173.627796 -210.641692)
				)
				(arc
					(start 173.627796 -210.641692)
					(mid 173.860786 -211.113692)
					(end 173.491398 -210.73872)
				)
				(arc
					(start 173.491398 -210.73872)
					(mid 173.426983 -210.568876)
					(end 173.400212 -210.389216)
				)
				(xy 173.39945 -210.388708) (xy 173.39945 -210.385914)
				(arc
					(start 173.227746 -210.385914)
					(mid 173.187517 -210.570277)
					(end 173.112176 -210.743292)
				)
				(arc
					(start 173.112176 -210.743292)
					(mid 172.734205 -211.110287)
					(end 172.978318 -210.64347)
				)
				(arc
					(start 172.978318 -210.64347)
					(mid 173.030828 -210.518234)
					(end 173.061376 -210.385914)
				)
			)
		)
	)
	(zone
		(layer "In5.Cu")
		(hatch none 0.5)
		(connect_pads
			(clearance 0)
		)
		(min_thickness 0.25)
		(keepout
			(tracks not_allowed)
			(vias allowed)
			(pads allowed)
			(copperpour not_allowed)
			(footprints allowed)
		)
		(placement
			(enabled no)
			(sheetname "")
		)
		(fill
			(thermal_gap 0.5)
			(thermal_bridge_width 0.5)
			(island_removal_mode 0)
		)
		(polygon
			(pts
				(arc
					(start 325.969122 -35.451034)
					(mid 325.458582 -35.961574)
					(end 325.969122 -36.472114)
				)
				(arc
					(start 326.101202 -36.472114)
					(mid 326.086449 -36.341797)
					(end 326.04583 -36.217098)
				)
				(arc
					(start 326.04583 -36.217098)
					(mid 325.815597 -35.743667)
					(end 326.18299 -36.120832)
				)
				(arc
					(start 326.18299 -36.120832)
					(mid 326.241058 -36.278479)
					(end 326.26554 -36.444682)
				)
				(xy 326.266302 -36.445444) (xy 326.266302 -36.472114)
				(arc
					(start 326.432418 -36.472114)
					(mid 326.468398 -36.277438)
					(end 326.553068 -36.09848)
				)
				(arc
					(start 326.553068 -36.09848)
					(mid 326.956871 -35.76022)
					(end 326.67956 -36.207954)
				)
				(arc
					(start 326.67956 -36.207954)
					(mid 326.62326 -36.335263)
					(end 326.597772 -36.472114)
				)
				(arc
					(start 326.781668 -36.472114)
					(mid 327.292462 -35.961701)
					(end 326.781922 -35.451034)
				)
			)
		)
	)
	(zone
		(layer "In5.Cu")
		(hatch none 0.5)
		(connect_pads
			(clearance 0)
		)
		(min_thickness 0.25)
		(keepout
			(tracks not_allowed)
			(vias allowed)
			(pads allowed)
			(copperpour not_allowed)
			(footprints allowed)
		)
		(placement
			(enabled no)
			(sheetname "")
		)
		(fill
			(thermal_gap 0.5)
			(thermal_bridge_width 0.5)
			(island_removal_mode 0)
		)
		(polygon
			(pts
				(arc
					(start 187.294012 -210.385914)
					(mid 186.783218 -210.896327)
					(end 187.293758 -211.406994)
				)
				(arc
					(start 188.106558 -211.406994)
					(mid 188.617098 -210.896454)
					(end 188.106558 -210.385914)
				)
				(arc
					(start 187.951364 -210.385914)
					(mid 187.976425 -210.517637)
					(end 188.02477 -210.642708)
				)
				(arc
					(start 188.02477 -210.642708)
					(mid 188.263338 -211.111803)
					(end 187.889642 -210.74126)
				)
				(arc
					(start 187.889642 -210.74126)
					(mid 187.819244 -210.568959)
					(end 187.785502 -210.385914)
				)
				(arc
					(start 187.614814 -210.385914)
					(mid 187.581087 -210.568963)
					(end 187.510674 -210.74126)
				)
				(arc
					(start 187.510674 -210.74126)
					(mid 187.136986 -211.111792)
					(end 187.375546 -210.642708)
				)
				(arc
					(start 187.375546 -210.642708)
					(mid 187.423925 -210.517647)
					(end 187.448952 -210.385914)
				)
			)
		)
	)
	(zone
		(net "GND")
		(layer "In5.Cu")
		(hatch none 0.5)
		(connect_pads
			(clearance 0.5)
		)
		(min_thickness 0.25)
		(fill yes
			(thermal_gap 0.5)
			(thermal_bridge_width 0.5)
			(island_removal_mode 0)
		)
		(polygon
			(pts
				(xy 83.474306 -100.253038) (xy 78.928468 -104.798876) (xy 76.71308 -107.014264) (xy 76.71308 -112.685068)
				(xy 75.735434 -113.662714) (xy 75.735434 -116.849144) (xy 75.735434 -128.023874) (xy 74.335894 -129.423414)
				(xy 74.335894 -137.252202) (xy 76.741528 -139.657836) (xy 76.741528 -144.73174) (xy 62.789308 -158.68396)
				(xy 62.789308 -158.75) (xy 62.5348 -159.004508) (xy 62.5348 -168.444926) (xy 65.369694 -171.27982)
				(xy 71.886826 -171.27982) (xy 95.155004 -171.148756) (xy 116.148866 -159.864552) (xy 123.321826 -149.45487)
				(xy 141.298168 -135.852916) (xy 156.256228 -118.270274) (xy 168.67759 -104.011984) (xy 168.983914 -103.70566)
				(xy 168.983914 -92.749624) (xy 162.226752 -85.992462) (xy 154.887422 -85.992462) (xy 154.269186 -85.374226)
				(xy 154.269186 -85.366098) (xy 153.764488 -84.8614) (xy 150.538942 -84.8614) (xy 150.034244 -85.366098)
				(xy 149.40788 -85.992462) (xy 139.470384 -85.992462) (xy 137.124948 -88.337898) (xy 132.05333 -88.337898)
				(xy 131.420108 -88.97112) (xy 131.420108 -96.113092) (xy 121.285 -106.2482) (xy 115.225068 -106.2482)
				(xy 111.02213 -110.451138) (xy 110.533688 -110.93958) (xy 109.4232 -110.93958) (xy 109.38002 -110.8964)
				(xy 109.38002 -109.81944) (xy 109.38002 -108.809028) (xy 108.006896 -107.435904) (xy 100.82403 -100.253038)
			)
		)
	)
	(zone
		(layer "In5.Cu")
		(hatch none 0.5)
		(connect_pads
			(clearance 0)
		)
		(min_thickness 0.25)
		(keepout
			(tracks not_allowed)
			(vias allowed)
			(pads allowed)
			(copperpour not_allowed)
			(footprints allowed)
		)
		(placement
			(enabled no)
			(sheetname "")
		)
		(fill
			(thermal_gap 0.5)
			(thermal_bridge_width 0.5)
			(island_removal_mode 0)
		)
		(polygon
			(pts
				(arc
					(start 92.493846 -210.385914)
					(mid 91.983052 -210.896327)
					(end 92.493592 -211.406994)
				)
				(arc
					(start 93.306392 -211.406994)
					(mid 93.816932 -210.896454)
					(end 93.306392 -210.385914)
				)
				(arc
					(start 93.176852 -210.385914)
					(mid 93.210576 -210.512221)
					(end 93.256608 -210.63458)
				)
				(arc
					(start 93.256608 -210.63458)
					(mid 93.434696 -211.129915)
					(end 93.11132 -210.71459)
				)
				(arc
					(start 93.11132 -210.71459)
					(mid 93.050352 -210.553236)
					(end 93.00845 -210.385914)
				)
				(arc
					(start 92.791534 -210.385914)
					(mid 92.749637 -210.553237)
					(end 92.688664 -210.71459)
				)
				(arc
					(start 92.688664 -210.71459)
					(mid 92.36529 -211.129911)
					(end 92.543376 -210.63458)
				)
				(arc
					(start 92.543376 -210.63458)
					(mid 92.589395 -210.512217)
					(end 92.623132 -210.385914)
				)
			)
		)
	)
	(zone
		(layer "In5.Cu")
		(hatch none 0.5)
		(connect_pads
			(clearance 0)
		)
		(min_thickness 0.25)
		(keepout
			(tracks not_allowed)
			(vias allowed)
			(pads allowed)
			(copperpour not_allowed)
			(footprints allowed)
		)
		(placement
			(enabled no)
			(sheetname "")
		)
		(fill
			(thermal_gap 0.5)
			(thermal_bridge_width 0.5)
			(island_removal_mode 0)
		)
		(polygon
			(pts
				(arc
					(start 181.53126 -6.19252)
					(mid 181.457622 -6.223022)
					(end 181.42712 -6.29666)
				)
				(xy 181.42712 -6.65226) (xy 181.428136 -6.667246) (xy 181.428136 -7.346442) (xy 181.42712 -7.36092)
				(arc
					(start 181.42712 -7.71652)
					(mid 181.457622 -7.790158)
					(end 181.53126 -7.82066)
				)
				(arc
					(start 182.357776 -7.82066)
					(mid 182.373581 -7.824433)
					(end 182.38978 -7.82574)
				)
				(arc
					(start 182.74538 -7.82574)
					(mid 182.819018 -7.795238)
					(end 182.84952 -7.7216)
				)
				(xy 182.84952 -7.366)
				(arc
					(start 182.84952 -6.684264)
					(mid 182.853293 -6.668459)
					(end 182.8546 -6.65226)
				)
				(arc
					(start 182.8546 -6.29666)
					(mid 182.824098 -6.223022)
					(end 182.75046 -6.19252)
				)
				(xy 182.39486 -6.19252) (xy 182.3847 -6.193028) (xy 181.896766 -6.193028) (xy 181.88686 -6.19252)
			)
		)
	)
	(zone
		(layer "In5.Cu")
		(hatch none 0.5)
		(connect_pads
			(clearance 0)
		)
		(min_thickness 0.25)
		(keepout
			(tracks not_allowed)
			(vias allowed)
			(pads allowed)
			(copperpour not_allowed)
			(footprints allowed)
		)
		(placement
			(enabled no)
			(sheetname "")
		)
		(fill
			(thermal_gap 0.5)
			(thermal_bridge_width 0.5)
			(island_removal_mode 0)
		)
		(polygon
			(pts
				(arc
					(start 183.59374 -23.6601)
					(mid 183.0832 -23.14956)
					(end 182.57266 -23.6601)
				)
				(arc
					(start 182.57266 -24.472646)
					(mid 183.083073 -24.98344)
					(end 183.59374 -24.4729)
				)
				(xy 183.59374 -24.31415)
				(arc
					(start 183.514746 -24.31415)
					(mid 183.417478 -24.326831)
					(end 183.326786 -24.364188)
				)
				(arc
					(start 183.326786 -24.364188)
					(mid 182.886147 -24.652685)
					(end 183.213756 -24.240236)
				)
				(arc
					(start 183.213756 -24.240236)
					(mid 183.340794 -24.177664)
					(end 183.479694 -24.150066)
				)
				(xy 183.48071 -24.14905) (xy 183.59374 -24.14905) (xy 183.59374 -23.98395) (xy 183.48071 -23.98395)
				(arc
					(start 183.479694 -23.982934)
					(mid 183.340786 -23.95536)
					(end 183.213756 -23.892764)
				)
				(arc
					(start 183.213756 -23.892764)
					(mid 182.886113 -23.480283)
					(end 183.326786 -23.768812)
				)
				(arc
					(start 183.326786 -23.768812)
					(mid 183.41749 -23.806124)
					(end 183.514746 -23.81885)
				)
				(xy 183.59374 -23.81885)
			)
		)
	)
	(zone
		(layer "In5.Cu")
		(hatch none 0.5)
		(connect_pads
			(clearance 0)
		)
		(min_thickness 0.25)
		(keepout
			(tracks not_allowed)
			(vias allowed)
			(pads allowed)
			(copperpour not_allowed)
			(footprints allowed)
		)
		(placement
			(enabled no)
			(sheetname "")
		)
		(fill
			(thermal_gap 0.5)
			(thermal_bridge_width 0.5)
			(island_removal_mode 0)
		)
		(polygon
			(pts
				(arc
					(start 151.294084 -210.385914)
					(mid 150.78329 -210.896327)
					(end 151.29383 -211.406994)
				)
				(arc
					(start 152.10663 -211.406994)
					(mid 152.61717 -210.896454)
					(end 152.10663 -210.385914)
				)
				(arc
					(start 151.951436 -210.385914)
					(mid 151.976497 -210.517637)
					(end 152.024842 -210.642708)
				)
				(arc
					(start 152.024842 -210.642708)
					(mid 152.26341 -211.111803)
					(end 151.889714 -210.74126)
				)
				(arc
					(start 151.889714 -210.74126)
					(mid 151.819316 -210.568959)
					(end 151.785574 -210.385914)
				)
				(arc
					(start 151.614886 -210.385914)
					(mid 151.581159 -210.568963)
					(end 151.510746 -210.74126)
				)
				(arc
					(start 151.510746 -210.74126)
					(mid 151.137058 -211.111792)
					(end 151.375618 -210.642708)
				)
				(arc
					(start 151.375618 -210.642708)
					(mid 151.423997 -210.517647)
					(end 151.449024 -210.385914)
				)
			)
		)
	)
	(zone
		(layer "In5.Cu")
		(hatch none 0.5)
		(connect_pads
			(clearance 0)
		)
		(min_thickness 0.25)
		(keepout
			(tracks not_allowed)
			(vias allowed)
			(pads allowed)
			(copperpour not_allowed)
			(footprints allowed)
		)
		(placement
			(enabled no)
			(sheetname "")
		)
		(fill
			(thermal_gap 0.5)
			(thermal_bridge_width 0.5)
			(island_removal_mode 0)
		)
		(polygon
			(pts
				(arc
					(start 133.852158 -35.229292)
					(mid 133.341618 -35.739832)
					(end 133.852158 -36.250372)
				)
				(xy 134.010908 -36.250372)
				(arc
					(start 134.010908 -35.954208)
					(mid 133.621506 -35.605823)
					(end 134.11708 -35.771582)
				)
				(arc
					(start 134.11708 -35.771582)
					(mid 134.154503 -35.837203)
					(end 134.173722 -35.910266)
				)
				(xy 134.176008 -35.912552) (xy 134.176008 -36.244276) (xy 134.176008 -36.250372) (xy 134.341108 -36.250372)
				(xy 134.341108 -35.912552)
				(arc
					(start 134.343394 -35.910266)
					(mid 134.36257 -35.837185)
					(end 134.400036 -35.771582)
				)
				(arc
					(start 134.400036 -35.771582)
					(mid 134.895663 -35.605792)
					(end 134.506208 -35.954208)
				)
				(xy 134.506208 -36.244276) (xy 134.506462 -36.250372)
				(arc
					(start 134.664704 -36.250372)
					(mid 135.175498 -35.739959)
					(end 134.664958 -35.229292)
				)
			)
		)
	)
	(zone
		(net "DUT_VDDO")
		(layer "In5.Cu")
		(hatch none 0.5)
		(connect_pads
			(clearance 0.5)
		)
		(min_thickness 0.25)
		(fill yes
			(thermal_gap 0.5)
			(thermal_bridge_width 0.5)
			(island_removal_mode 0)
		)
		(polygon
			(pts
				(xy 245.872 -40.386) (xy 245.872 -39.116) (xy 246.253 -38.735) (xy 246.253 -37.846) (xy 246.126 -37.719)
				(xy 244.221 -37.719) (xy 242.316 -39.624) (xy 242.316 -40.513) (xy 242.443 -40.64) (xy 245.618 -40.64)
			)
		)
	)
	(zone
		(layer "In5.Cu")
		(hatch none 0.5)
		(connect_pads
			(clearance 0)
		)
		(min_thickness 0.25)
		(keepout
			(tracks not_allowed)
			(vias allowed)
			(pads allowed)
			(copperpour not_allowed)
			(footprints allowed)
		)
		(placement
			(enabled no)
			(sheetname "")
		)
		(fill
			(thermal_gap 0.5)
			(thermal_bridge_width 0.5)
			(island_removal_mode 0)
		)
		(polygon
			(pts
				(arc
					(start 184.093866 -210.385914)
					(mid 183.583072 -210.896327)
					(end 184.093612 -211.406994)
				)
				(arc
					(start 184.906412 -211.406994)
					(mid 185.416952 -210.896454)
					(end 184.906412 -210.385914)
				)
				(arc
					(start 184.751218 -210.385914)
					(mid 184.776279 -210.517637)
					(end 184.824624 -210.642708)
				)
				(arc
					(start 184.824624 -210.642708)
					(mid 185.063192 -211.111803)
					(end 184.689496 -210.74126)
				)
				(arc
					(start 184.689496 -210.74126)
					(mid 184.619098 -210.568959)
					(end 184.585356 -210.385914)
				)
				(arc
					(start 184.414668 -210.385914)
					(mid 184.380941 -210.568963)
					(end 184.310528 -210.74126)
				)
				(arc
					(start 184.310528 -210.74126)
					(mid 183.93684 -211.111792)
					(end 184.1754 -210.642708)
				)
				(arc
					(start 184.1754 -210.642708)
					(mid 184.223779 -210.517647)
					(end 184.248806 -210.385914)
				)
			)
		)
	)
	(zone
		(layer "In5.Cu")
		(hatch none 0.5)
		(connect_pads
			(clearance 0)
		)
		(min_thickness 0.25)
		(keepout
			(tracks not_allowed)
			(vias allowed)
			(pads allowed)
			(copperpour not_allowed)
			(footprints allowed)
		)
		(placement
			(enabled no)
			(sheetname "")
		)
		(fill
			(thermal_gap 0.5)
			(thermal_bridge_width 0.5)
			(island_removal_mode 0)
		)
		(polygon
			(pts
				(arc
					(start 316.49416 -210.385914)
					(mid 315.983366 -210.896327)
					(end 316.493906 -211.406994)
				)
				(arc
					(start 317.306706 -211.406994)
					(mid 317.817246 -210.896454)
					(end 317.306706 -210.385914)
				)
				(arc
					(start 317.151258 -210.385914)
					(mid 317.176311 -210.517641)
					(end 317.224664 -210.642708)
				)
				(arc
					(start 317.224664 -210.642708)
					(mid 317.464087 -211.111743)
					(end 317.08979 -210.74126)
				)
				(arc
					(start 317.08979 -210.74126)
					(mid 317.019274 -210.568971)
					(end 316.985396 -210.385914)
				)
				(arc
					(start 316.814962 -210.385914)
					(mid 316.781235 -210.568963)
					(end 316.710822 -210.74126)
				)
				(arc
					(start 316.710822 -210.74126)
					(mid 316.337134 -211.111792)
					(end 316.575694 -210.642708)
				)
				(arc
					(start 316.575694 -210.642708)
					(mid 316.624073 -210.517647)
					(end 316.6491 -210.385914)
				)
			)
		)
	)
	(zone
		(layer "In5.Cu")
		(hatch none 0.5)
		(connect_pads
			(clearance 0)
		)
		(min_thickness 0.25)
		(keepout
			(tracks not_allowed)
			(vias allowed)
			(pads allowed)
			(copperpour not_allowed)
			(footprints allowed)
		)
		(placement
			(enabled no)
			(sheetname "")
		)
		(fill
			(thermal_gap 0.5)
			(thermal_bridge_width 0.5)
			(island_removal_mode 0)
		)
		(polygon
			(pts
				(arc
					(start 166.493952 -210.385914)
					(mid 165.983158 -210.896327)
					(end 166.493698 -211.406994)
				)
				(arc
					(start 167.306498 -211.406994)
					(mid 167.817038 -210.896454)
					(end 167.306498 -210.385914)
				)
				(arc
					(start 167.151304 -210.385914)
					(mid 167.176365 -210.517637)
					(end 167.22471 -210.642708)
				)
				(arc
					(start 167.22471 -210.642708)
					(mid 167.463278 -211.111803)
					(end 167.089582 -210.74126)
				)
				(arc
					(start 167.089582 -210.74126)
					(mid 167.019184 -210.568959)
					(end 166.985442 -210.385914)
				)
				(arc
					(start 166.814754 -210.385914)
					(mid 166.781027 -210.568963)
					(end 166.710614 -210.74126)
				)
				(arc
					(start 166.710614 -210.74126)
					(mid 166.336926 -211.111792)
					(end 166.575486 -210.642708)
				)
				(arc
					(start 166.575486 -210.642708)
					(mid 166.623865 -210.517647)
					(end 166.648892 -210.385914)
				)
			)
		)
	)
	(zone
		(net "P3V3_STBY")
		(layer "In5.Cu")
		(hatch none 0.5)
		(connect_pads
			(clearance 0.5)
		)
		(min_thickness 0.25)
		(fill yes
			(thermal_gap 0.5)
			(thermal_bridge_width 0.5)
			(island_removal_mode 0)
		)
		(polygon
			(pts
				(xy 322.58 -85.598) (xy 322.961 -85.598) (xy 323.469 -85.09) (xy 333.121 -85.09) (xy 333.756 -85.725)
				(xy 333.756 -97.536) (xy 332.232 -99.06) (xy 332.232 -100.33) (xy 332.486 -100.584) (xy 333.502 -100.584)
				(xy 336.169 -97.917) (xy 336.169 -85.725) (xy 353.314 -68.58) (xy 353.314 -44.704) (xy 350.139 -41.529)
				(xy 349.6818 -41.0718) (xy 335.9912 -41.0718) (xy 335.28 -41.783) (xy 335.28 -46.4566) (xy 335.7499 -46.9265)
				(xy 351.5995 -46.9265) (xy 351.917 -47.244) (xy 351.917 -65.913) (xy 334.391 -83.439) (xy 322.961 -83.439)
				(xy 322.326 -84.074) (xy 322.326 -85.344)
			)
		)
	)
	(zone
		(layer "In5.Cu")
		(hatch none 0.5)
		(connect_pads
			(clearance 0)
		)
		(min_thickness 0.25)
		(keepout
			(tracks not_allowed)
			(vias allowed)
			(pads allowed)
			(copperpour not_allowed)
			(footprints allowed)
		)
		(placement
			(enabled no)
			(sheetname "")
		)
		(fill
			(thermal_gap 0.5)
			(thermal_bridge_width 0.5)
			(island_removal_mode 0)
		)
		(polygon
			(pts
				(arc
					(start 158.655258 -34.51098)
					(mid 158.144464 -35.021393)
					(end 158.655004 -35.53206)
				)
				(xy 158.813754 -35.53206)
				(arc
					(start 158.813754 -35.387534)
					(mid 158.803344 -35.320864)
					(end 158.773114 -35.260534)
				)
				(arc
					(start 158.773114 -35.260534)
					(mid 158.468302 -34.831204)
					(end 158.891732 -35.144202)
				)
				(arc
					(start 158.891732 -35.144202)
					(mid 158.949916 -35.241582)
					(end 158.977076 -35.35172)
				)
				(xy 158.978854 -35.353244) (xy 158.978854 -35.53206) (xy 159.143954 -35.53206) (xy 159.143954 -35.353244)
				(arc
					(start 159.145732 -35.35172)
					(mid 159.172899 -35.241585)
					(end 159.231076 -35.144202)
				)
				(arc
					(start 159.231076 -35.144202)
					(mid 159.654523 -34.831186)
					(end 159.349694 -35.260534)
				)
				(arc
					(start 159.349694 -35.260534)
					(mid 159.319453 -35.32086)
					(end 159.309054 -35.387534)
				)
				(xy 159.309054 -35.53206)
				(arc
					(start 159.467804 -35.53206)
					(mid 159.978344 -35.02152)
					(end 159.467804 -34.51098)
				)
			)
		)
	)
	(zone
		(layer "In5.Cu")
		(hatch none 0.5)
		(connect_pads
			(clearance 0)
		)
		(min_thickness 0.25)
		(keepout
			(tracks allowed)
			(vias allowed)
			(pads allowed)
			(copperpour allowed)
			(footprints allowed)
		)
		(placement
			(enabled no)
			(sheetname "")
		)
		(fill
			(thermal_gap 0.5)
			(thermal_bridge_width 0.5)
			(island_removal_mode 0)
		)
		(polygon
			(pts
				(xy 219.342208 -68.9356) (xy 219.342208 -25.8064) (xy 262.420608 -25.8064) (xy 262.420608 -68.9356)
				(xy 241.046 -68.9356)
			)
		)
	)
	(zone
		(layer "In5.Cu")
		(hatch none 0.5)
		(connect_pads
			(clearance 0)
		)
		(min_thickness 0.25)
		(keepout
			(tracks not_allowed)
			(vias allowed)
			(pads allowed)
			(copperpour not_allowed)
			(footprints allowed)
		)
		(placement
			(enabled no)
			(sheetname "")
		)
		(fill
			(thermal_gap 0.5)
			(thermal_bridge_width 0.5)
			(island_removal_mode 0)
		)
		(polygon
			(pts
				(arc
					(start 161.7853 -37.50056)
					(mid 161.27476 -38.0111)
					(end 161.7853 -38.52164)
				)
				(xy 161.94405 -38.52164)
				(arc
					(start 161.94405 -38.395148)
					(mid 161.935498 -38.318957)
					(end 161.910268 -38.246558)
				)
				(arc
					(start 161.910268 -38.246558)
					(mid 161.591098 -37.828361)
					(end 162.028632 -38.12032)
				)
				(arc
					(start 162.028632 -38.12032)
					(mid 162.083317 -38.235096)
					(end 162.10788 -38.359842)
				)
				(xy 162.10915 -38.360858) (xy 162.10915 -38.52164) (xy 162.27425 -38.52164) (xy 162.27425 -38.360858)
				(arc
					(start 162.27552 -38.359842)
					(mid 162.300052 -38.235085)
					(end 162.354768 -38.12032)
				)
				(arc
					(start 162.354768 -38.12032)
					(mid 162.792244 -37.828415)
					(end 162.473132 -38.246558)
				)
				(arc
					(start 162.473132 -38.246558)
					(mid 162.447901 -38.318957)
					(end 162.43935 -38.395148)
				)
				(xy 162.43935 -38.52164)
				(arc
					(start 162.597846 -38.52164)
					(mid 163.10864 -38.011227)
					(end 162.5981 -37.50056)
				)
			)
		)
	)
	(zone
		(layer "In5.Cu")
		(hatch none 0.5)
		(connect_pads
			(clearance 0)
		)
		(min_thickness 0.25)
		(keepout
			(tracks not_allowed)
			(vias allowed)
			(pads allowed)
			(copperpour not_allowed)
			(footprints allowed)
		)
		(placement
			(enabled no)
			(sheetname "")
		)
		(fill
			(thermal_gap 0.5)
			(thermal_bridge_width 0.5)
			(island_removal_mode 0)
		)
		(polygon
			(pts
				(arc
					(start 314.8838 -34.503614)
					(mid 314.37326 -35.014154)
					(end 314.8838 -35.524694)
				)
				(arc
					(start 315.038994 -35.524694)
					(mid 315.013933 -35.392971)
					(end 314.965588 -35.2679)
				)
				(arc
					(start 314.965588 -35.2679)
					(mid 314.72702 -34.798805)
					(end 315.100716 -35.169348)
				)
				(arc
					(start 315.100716 -35.169348)
					(mid 315.171114 -35.341649)
					(end 315.204856 -35.524694)
				)
				(xy 315.37275 -35.524694) (xy 315.37275 -35.455352)
				(arc
					(start 315.373766 -35.45459)
					(mid 315.40205 -35.297223)
					(end 315.468 -35.151568)
				)
				(arc
					(start 315.468 -35.151568)
					(mid 315.870276 -34.811726)
					(end 315.595508 -35.261042)
				)
				(arc
					(start 315.595508 -35.261042)
					(mid 315.552504 -35.371768)
					(end 315.53785 -35.489642)
				)
				(xy 315.53785 -35.524694)
				(arc
					(start 315.696346 -35.524694)
					(mid 316.20714 -35.014281)
					(end 315.6966 -34.503614)
				)
			)
		)
	)
	(zone
		(layer "In5.Cu")
		(hatch none 0.5)
		(connect_pads
			(clearance 0)
		)
		(min_thickness 0.25)
		(keepout
			(tracks not_allowed)
			(vias allowed)
			(pads allowed)
			(copperpour not_allowed)
			(footprints allowed)
		)
		(placement
			(enabled no)
			(sheetname "")
		)
		(fill
			(thermal_gap 0.5)
			(thermal_bridge_width 0.5)
			(island_removal_mode 0)
		)
		(polygon
			(pts
				(arc
					(start 152.7175 -34.48558)
					(mid 152.20696 -34.99612)
					(end 152.7175 -35.50666)
				)
				(xy 152.87625 -35.50666)
				(arc
					(start 152.87625 -35.39109)
					(mid 152.864917 -35.310982)
					(end 152.8318 -35.237166)
				)
				(arc
					(start 152.8318 -35.237166)
					(mid 152.533457 -34.802999)
					(end 152.952704 -35.12185)
				)
				(arc
					(start 152.952704 -35.12185)
					(mid 153.012663 -35.23258)
					(end 153.039826 -35.35553)
				)
				(xy 153.04135 -35.3568) (xy 153.04135 -35.50666) (xy 153.201878 -35.50666) (xy 153.200608 -35.501326)
				(xy 153.20645 -35.49142) (xy 153.20645 -35.3568)
				(arc
					(start 153.207974 -35.35553)
					(mid 153.235175 -35.232594)
					(end 153.295096 -35.12185)
				)
				(arc
					(start 153.295096 -35.12185)
					(mid 153.714293 -34.803051)
					(end 153.416 -35.237166)
				)
				(arc
					(start 153.416 -35.237166)
					(mid 153.382892 -35.310985)
					(end 153.37155 -35.39109)
				)
				(xy 153.37155 -35.50412) (xy 153.372312 -35.50666)
				(arc
					(start 153.530046 -35.50666)
					(mid 154.04084 -34.996247)
					(end 153.5303 -34.48558)
				)
			)
		)
	)
	(zone
		(layer "In5.Cu")
		(hatch none 0.5)
		(connect_pads
			(clearance 0)
		)
		(min_thickness 0.25)
		(keepout
			(tracks not_allowed)
			(vias allowed)
			(pads allowed)
			(copperpour not_allowed)
			(footprints allowed)
		)
		(placement
			(enabled no)
			(sheetname "")
		)
		(fill
			(thermal_gap 0.5)
			(thermal_bridge_width 0.5)
			(island_removal_mode 0)
		)
		(polygon
			(pts
				(arc
					(start 335.69402 -210.385914)
					(mid 335.183226 -210.896327)
					(end 335.693766 -211.406994)
				)
				(arc
					(start 336.506566 -211.406994)
					(mid 337.017106 -210.896454)
					(end 336.506566 -210.385914)
				)
				(arc
					(start 336.351372 -210.385914)
					(mid 336.376433 -210.517637)
					(end 336.424778 -210.642708)
				)
				(arc
					(start 336.424778 -210.642708)
					(mid 336.663346 -211.111803)
					(end 336.28965 -210.74126)
				)
				(arc
					(start 336.28965 -210.74126)
					(mid 336.219252 -210.568959)
					(end 336.18551 -210.385914)
				)
				(arc
					(start 336.014822 -210.385914)
					(mid 335.981095 -210.568963)
					(end 335.910682 -210.74126)
				)
				(arc
					(start 335.910682 -210.74126)
					(mid 335.536994 -211.111792)
					(end 335.775554 -210.642708)
				)
				(arc
					(start 335.775554 -210.642708)
					(mid 335.823933 -210.517647)
					(end 335.84896 -210.385914)
				)
			)
		)
	)
	(zone
		(layer "In5.Cu")
		(hatch none 0.5)
		(connect_pads
			(clearance 0)
		)
		(min_thickness 0.25)
		(keepout
			(tracks not_allowed)
			(vias allowed)
			(pads allowed)
			(copperpour not_allowed)
			(footprints allowed)
		)
		(placement
			(enabled no)
			(sheetname "")
		)
		(fill
			(thermal_gap 0.5)
			(thermal_bridge_width 0.5)
			(island_removal_mode 0)
		)
		(polygon
			(pts
				(arc
					(start 63.693802 -210.385914)
					(mid 63.183008 -210.896327)
					(end 63.693548 -211.406994)
				)
				(arc
					(start 64.506348 -211.406994)
					(mid 65.016888 -210.896454)
					(end 64.506348 -210.385914)
				)
				(arc
					(start 64.360552 -210.385914)
					(mid 64.391055 -210.514869)
					(end 64.439038 -210.63839)
				)
				(arc
					(start 64.439038 -210.63839)
					(mid 64.651231 -211.120607)
					(end 64.299338 -210.72856)
				)
				(arc
					(start 64.299338 -210.72856)
					(mid 64.232631 -210.561486)
					(end 64.19342 -210.385914)
				)
				(arc
					(start 64.006476 -210.385914)
					(mid 63.967253 -210.561483)
					(end 63.900558 -210.72856)
				)
				(arc
					(start 63.900558 -210.72856)
					(mid 63.548681 -211.120583)
					(end 63.760858 -210.63839)
				)
				(arc
					(start 63.760858 -210.63839)
					(mid 63.808829 -210.514866)
					(end 63.839344 -210.385914)
				)
			)
		)
	)
	(zone
		(layer "In5.Cu")
		(hatch none 0.5)
		(connect_pads
			(clearance 0)
		)
		(min_thickness 0.25)
		(keepout
			(tracks not_allowed)
			(vias allowed)
			(pads allowed)
			(copperpour not_allowed)
			(footprints allowed)
		)
		(placement
			(enabled no)
			(sheetname "")
		)
		(fill
			(thermal_gap 0.5)
			(thermal_bridge_width 0.5)
			(island_removal_mode 0)
		)
		(polygon
			(pts
				(arc
					(start 286.893762 -210.385914)
					(mid 286.383222 -210.896454)
					(end 286.893762 -211.406994)
				)
				(arc
					(start 287.706308 -211.406994)
					(mid 288.217102 -210.896581)
					(end 287.706562 -210.385914)
				)
				(arc
					(start 287.551368 -210.385914)
					(mid 287.576429 -210.517637)
					(end 287.624774 -210.642708)
				)
				(arc
					(start 287.624774 -210.642708)
					(mid 287.863342 -211.111803)
					(end 287.489646 -210.74126)
				)
				(arc
					(start 287.489646 -210.74126)
					(mid 287.419248 -210.568959)
					(end 287.385506 -210.385914)
				)
				(arc
					(start 287.214818 -210.385914)
					(mid 287.181091 -210.568963)
					(end 287.110678 -210.74126)
				)
				(arc
					(start 287.110678 -210.74126)
					(mid 286.73699 -211.111792)
					(end 286.97555 -210.642708)
				)
				(arc
					(start 286.97555 -210.642708)
					(mid 287.023929 -210.517647)
					(end 287.048956 -210.385914)
				)
			)
		)
	)
	(zone
		(net "GND")
		(layer "In5.Cu")
		(hatch none 0.5)
		(connect_pads
			(clearance 0.5)
		)
		(min_thickness 0.25)
		(fill yes
			(thermal_gap 0.5)
			(thermal_bridge_width 0.5)
			(island_removal_mode 0)
		)
		(polygon
			(pts
				(arc
					(start 115.599972 -211.467954)
					(mid 113.243912 -212.443866)
					(end 112.268 -214.799926)
				)
				(xy 112.268 -219.976192) (xy 112.257078 -219.979494) (xy 113.536984 -219.979494)
				(arc
					(start 113.536984 -214.799926)
					(mid 114.141219 -213.341173)
					(end 115.599972 -212.736938)
				)
				(arc
					(start 131.400042 -212.736938)
					(mid 132.858795 -213.341173)
					(end 133.46303 -214.799926)
				)
				(xy 133.46303 -219.979494) (xy 134.742936 -219.979494) (xy 134.732014 -219.976192)
				(arc
					(start 134.732014 -214.799926)
					(mid 133.756102 -212.443866)
					(end 131.400042 -211.467954)
				)
			)
		)
	)
	(zone
		(net "DUT_VDDO_REF")
		(layer "In5.Cu")
		(hatch none 0.5)
		(connect_pads
			(clearance 0.5)
		)
		(min_thickness 0.25)
		(fill yes
			(thermal_gap 0.5)
			(thermal_bridge_width 0.5)
			(island_removal_mode 0)
		)
		(polygon
			(pts
				(xy 246.507 -40.132) (xy 247.65 -40.132) (xy 247.777 -40.259) (xy 247.777 -40.894) (xy 247.523 -41.148)
				(xy 240.792 -41.148) (xy 240.284 -40.64) (xy 240.284 -34.2138) (xy 239.3442 -33.274) (xy 238.887 -33.274)
				(xy 238.76 -33.401) (xy 238.76 -35.687) (xy 238.633 -35.814) (xy 237.871 -35.814) (xy 237.744 -35.687)
				(xy 237.744 -34.9504) (xy 238.2774 -34.417) (xy 238.2774 -33.1978) (xy 238.2774 -33.147) (xy 237.744 -32.6136)
				(xy 237.744 -32.1818) (xy 238.0234 -31.9024) (xy 238.2774 -31.9024) (xy 238.4044 -31.7754) (xy 238.4044 -29.3116)
				(xy 237.744 -28.6512) (xy 237.744 -27.0764) (xy 235.4834 -24.8158) (xy 235.4834 -20.955) (xy 232.7656 -18.2372)
				(xy 232.7656 -18.161) (xy 233.0704 -17.8562) (xy 237.49 -17.8562) (xy 240.1189 -20.4851) (xy 240.9571 -20.4851)
				(xy 242.927124 -20.4851) (xy 243.80317 -20.4851) (xy 244.194584 -20.876514) (xy 244.194584 -23.65883)
				(xy 243.627656 -24.225758) (xy 242.257072 -25.596342) (xy 240.793524 -25.596342) (xy 240.4618 -25.928066)
				(xy 240.4618 -32.7406) (xy 241.427 -33.7058) (xy 241.427 -33.782) (xy 241.935 -34.29) (xy 241.935 -37.592)
				(xy 242.316 -37.973) (xy 242.316 -38.862) (xy 241.935 -39.243) (xy 241.935 -40.386) (xy 242.316 -40.767)
				(xy 245.872 -40.767)
			)
		)
	)
	(zone
		(layer "In5.Cu")
		(hatch none 0.5)
		(connect_pads
			(clearance 0)
		)
		(min_thickness 0.25)
		(keepout
			(tracks not_allowed)
			(vias allowed)
			(pads allowed)
			(copperpour not_allowed)
			(footprints allowed)
		)
		(placement
			(enabled no)
			(sheetname "")
		)
		(fill
			(thermal_gap 0.5)
			(thermal_bridge_width 0.5)
			(island_removal_mode 0)
		)
		(polygon
			(pts
				(arc
					(start 51.693826 -210.385914)
					(mid 51.183032 -210.896327)
					(end 51.693572 -211.406994)
				)
				(arc
					(start 52.506372 -211.406994)
					(mid 53.016912 -210.896454)
					(end 52.506372 -210.385914)
				)
				(arc
					(start 52.360576 -210.385914)
					(mid 52.391079 -210.514869)
					(end 52.439062 -210.63839)
				)
				(arc
					(start 52.439062 -210.63839)
					(mid 52.651255 -211.120607)
					(end 52.299362 -210.72856)
				)
				(arc
					(start 52.299362 -210.72856)
					(mid 52.232655 -210.561486)
					(end 52.193444 -210.385914)
				)
				(arc
					(start 52.0065 -210.385914)
					(mid 51.967277 -210.561483)
					(end 51.900582 -210.72856)
				)
				(arc
					(start 51.900582 -210.72856)
					(mid 51.548705 -211.120583)
					(end 51.760882 -210.63839)
				)
				(arc
					(start 51.760882 -210.63839)
					(mid 51.808853 -210.514866)
					(end 51.839368 -210.385914)
				)
			)
		)
	)
	(zone
		(layer "In5.Cu")
		(hatch none 0.5)
		(connect_pads
			(clearance 0)
		)
		(min_thickness 0.25)
		(keepout
			(tracks not_allowed)
			(vias allowed)
			(pads allowed)
			(copperpour not_allowed)
			(footprints allowed)
		)
		(placement
			(enabled no)
			(sheetname "")
		)
		(fill
			(thermal_gap 0.5)
			(thermal_bridge_width 0.5)
			(island_removal_mode 0)
		)
		(polygon
			(pts
				(arc
					(start 301.65929 -34.515806)
					(mid 301.14875 -35.026346)
					(end 301.65929 -35.536886)
				)
				(arc
					(start 301.796196 -35.536886)
					(mid 301.7793 -35.406181)
					(end 301.737014 -35.281362)
				)
				(arc
					(start 301.737014 -35.281362)
					(mid 301.505845 -34.808053)
					(end 301.87392 -35.184842)
				)
				(arc
					(start 301.87392 -35.184842)
					(mid 301.935159 -35.348654)
					(end 301.960788 -35.521646)
				)
				(xy 301.96155 -35.522408) (xy 301.96155 -35.536886) (xy 302.12665 -35.536886) (xy 302.12665 -35.529012)
				(arc
					(start 302.127412 -35.52825)
					(mid 302.16145 -35.338175)
					(end 302.243236 -35.163252)
				)
				(arc
					(start 302.243236 -35.163252)
					(mid 302.646382 -34.824505)
					(end 302.369982 -35.272726)
				)
				(arc
					(start 302.369982 -35.272726)
					(mid 302.315208 -35.400122)
					(end 302.292258 -35.536886)
				)
				(arc
					(start 302.471836 -35.536886)
					(mid 302.98263 -35.026473)
					(end 302.47209 -34.515806)
				)
			)
		)
	)
	(zone
		(layer "In5.Cu")
		(hatch none 0.5)
		(connect_pads
			(clearance 0)
		)
		(min_thickness 0.25)
		(keepout
			(tracks not_allowed)
			(vias allowed)
			(pads allowed)
			(copperpour not_allowed)
			(footprints allowed)
		)
		(placement
			(enabled no)
			(sheetname "")
		)
		(fill
			(thermal_gap 0.5)
			(thermal_bridge_width 0.5)
			(island_removal_mode 0)
		)
		(polygon
			(pts
				(arc
					(start 157.694122 -210.385914)
					(mid 157.183328 -210.896327)
					(end 157.693868 -211.406994)
				)
				(arc
					(start 158.506668 -211.406994)
					(mid 159.017208 -210.896454)
					(end 158.506668 -210.385914)
				)
				(arc
					(start 158.351474 -210.385914)
					(mid 158.376535 -210.517637)
					(end 158.42488 -210.642708)
				)
				(arc
					(start 158.42488 -210.642708)
					(mid 158.663448 -211.111803)
					(end 158.289752 -210.74126)
				)
				(arc
					(start 158.289752 -210.74126)
					(mid 158.219354 -210.568959)
					(end 158.185612 -210.385914)
				)
				(arc
					(start 158.014924 -210.385914)
					(mid 157.981197 -210.568963)
					(end 157.910784 -210.74126)
				)
				(arc
					(start 157.910784 -210.74126)
					(mid 157.537096 -211.111792)
					(end 157.775656 -210.642708)
				)
				(arc
					(start 157.775656 -210.642708)
					(mid 157.824035 -210.517647)
					(end 157.849062 -210.385914)
				)
			)
		)
	)
	(zone
		(layer "In5.Cu")
		(hatch none 0.5)
		(connect_pads
			(clearance 0)
		)
		(min_thickness 0.25)
		(keepout
			(tracks not_allowed)
			(vias allowed)
			(pads allowed)
			(copperpour not_allowed)
			(footprints allowed)
		)
		(placement
			(enabled no)
			(sheetname "")
		)
		(fill
			(thermal_gap 0.5)
			(thermal_bridge_width 0.5)
			(island_removal_mode 0)
		)
		(polygon
			(pts
				(arc
					(start 107.693968 -210.385914)
					(mid 107.183174 -210.896327)
					(end 107.693714 -211.406994)
				)
				(arc
					(start 108.506514 -211.406994)
					(mid 109.017054 -210.896454)
					(end 108.506514 -210.385914)
				)
				(arc
					(start 108.360718 -210.385914)
					(mid 108.391221 -210.514869)
					(end 108.439204 -210.63839)
				)
				(arc
					(start 108.439204 -210.63839)
					(mid 108.651397 -211.120607)
					(end 108.299504 -210.72856)
				)
				(arc
					(start 108.299504 -210.72856)
					(mid 108.232797 -210.561486)
					(end 108.193586 -210.385914)
				)
				(arc
					(start 108.006642 -210.385914)
					(mid 107.967419 -210.561483)
					(end 107.900724 -210.72856)
				)
				(arc
					(start 107.900724 -210.72856)
					(mid 107.548847 -211.120583)
					(end 107.761024 -210.63839)
				)
				(arc
					(start 107.761024 -210.63839)
					(mid 107.808995 -210.514866)
					(end 107.83951 -210.385914)
				)
			)
		)
	)
	(zone
		(layer "In5.Cu")
		(hatch none 0.5)
		(connect_pads
			(clearance 0)
		)
		(min_thickness 0.25)
		(keepout
			(tracks not_allowed)
			(vias allowed)
			(pads allowed)
			(copperpour not_allowed)
			(footprints allowed)
		)
		(placement
			(enabled no)
			(sheetname "")
		)
		(fill
			(thermal_gap 0.5)
			(thermal_bridge_width 0.5)
			(island_removal_mode 0)
		)
		(polygon
			(pts
				(arc
					(start 141.694154 -210.385914)
					(mid 141.18336 -210.896327)
					(end 141.6939 -211.406994)
				)
				(arc
					(start 142.5067 -211.406994)
					(mid 143.01724 -210.896454)
					(end 142.5067 -210.385914)
				)
				(arc
					(start 142.348458 -210.385914)
					(mid 142.36794 -210.519508)
					(end 142.415768 -210.645756)
				)
				(arc
					(start 142.415768 -210.645756)
					(mid 142.671751 -211.10592)
					(end 142.284196 -210.749388)
				)
				(arc
					(start 142.284196 -210.749388)
					(mid 142.213224 -210.579535)
					(end 142.183612 -210.397852)
				)
				(xy 142.18285 -210.39709) (xy 142.18285 -210.385914) (xy 142.01775 -210.385914) (xy 142.01775 -210.39709)
				(arc
					(start 142.016988 -210.397852)
					(mid 141.987336 -210.579523)
					(end 141.916404 -210.749388)
				)
				(arc
					(start 141.916404 -210.749388)
					(mid 141.528827 -211.105947)
					(end 141.784832 -210.645756)
				)
				(arc
					(start 141.784832 -210.645756)
					(mid 141.832624 -210.519499)
					(end 141.852142 -210.385914)
				)
			)
		)
	)
	(zone
		(layer "In5.Cu")
		(hatch none 0.5)
		(connect_pads
			(clearance 0)
		)
		(min_thickness 0.25)
		(keepout
			(tracks not_allowed)
			(vias allowed)
			(pads allowed)
			(copperpour not_allowed)
			(footprints allowed)
		)
		(placement
			(enabled no)
			(sheetname "")
		)
		(fill
			(thermal_gap 0.5)
			(thermal_bridge_width 0.5)
			(island_removal_mode 0)
		)
		(polygon
			(pts
				(arc
					(start 196.893942 -210.385914)
					(mid 196.383148 -210.896327)
					(end 196.893688 -211.406994)
				)
				(arc
					(start 197.706488 -211.406994)
					(mid 198.217028 -210.896454)
					(end 197.706488 -210.385914)
				)
				(arc
					(start 197.551294 -210.385914)
					(mid 197.576355 -210.517637)
					(end 197.6247 -210.642708)
				)
				(arc
					(start 197.6247 -210.642708)
					(mid 197.863268 -211.111803)
					(end 197.489572 -210.74126)
				)
				(arc
					(start 197.489572 -210.74126)
					(mid 197.419174 -210.568959)
					(end 197.385432 -210.385914)
				)
				(arc
					(start 197.214744 -210.385914)
					(mid 197.181017 -210.568963)
					(end 197.110604 -210.74126)
				)
				(arc
					(start 197.110604 -210.74126)
					(mid 196.736916 -211.111792)
					(end 196.975476 -210.642708)
				)
				(arc
					(start 196.975476 -210.642708)
					(mid 197.023855 -210.517647)
					(end 197.048882 -210.385914)
				)
			)
		)
	)
	(zone
		(layer "In5.Cu")
		(hatch none 0.5)
		(connect_pads
			(clearance 0)
		)
		(min_thickness 0.25)
		(keepout
			(tracks not_allowed)
			(vias allowed)
			(pads allowed)
			(copperpour not_allowed)
			(footprints allowed)
		)
		(placement
			(enabled no)
			(sheetname "")
		)
		(fill
			(thermal_gap 0.5)
			(thermal_bridge_width 0.5)
			(island_removal_mode 0)
		)
		(polygon
			(pts
				(arc
					(start 87.290148 -76.589636)
					(mid 86.779608 -76.079096)
					(end 86.269068 -76.589636)
				)
				(arc
					(start 86.269068 -77.478382)
					(mid 86.779481 -77.989176)
					(end 87.290148 -77.478636)
				)
				(xy 87.290148 -77.281786) (xy 87.093298 -77.281786)
				(arc
					(start 87.017352 -77.357732)
					(mid 86.591008 -77.667236)
					(end 86.900512 -77.240892)
				)
				(xy 86.976458 -77.164946) (xy 87.024718 -77.116686) (xy 87.093298 -77.116686) (xy 87.290148 -77.116686)
				(xy 87.290148 -76.951586) (xy 87.093298 -76.951586) (xy 87.024718 -76.951586) (xy 86.976458 -76.903326)
				(arc
					(start 86.900512 -76.82738)
					(mid 86.591008 -76.401036)
					(end 87.017352 -76.71054)
				)
				(xy 87.093298 -76.786486) (xy 87.290148 -76.786486)
			)
		)
	)
	(zone
		(layer "In5.Cu")
		(hatch none 0.5)
		(connect_pads
			(clearance 0)
		)
		(min_thickness 0.25)
		(keepout
			(tracks not_allowed)
			(vias allowed)
			(pads allowed)
			(copperpour not_allowed)
			(footprints allowed)
		)
		(placement
			(enabled no)
			(sheetname "")
		)
		(fill
			(thermal_gap 0.5)
			(thermal_bridge_width 0.5)
			(island_removal_mode 0)
		)
		(polygon
			(pts
				(arc
					(start 332.494128 -210.385914)
					(mid 331.983334 -210.896327)
					(end 332.493874 -211.406994)
				)
				(arc
					(start 333.306674 -211.406994)
					(mid 333.817214 -210.896454)
					(end 333.306674 -210.385914)
				)
				(arc
					(start 333.15148 -210.385914)
					(mid 333.176541 -210.517637)
					(end 333.224886 -210.642708)
				)
				(arc
					(start 333.224886 -210.642708)
					(mid 333.463454 -211.111803)
					(end 333.089758 -210.74126)
				)
				(arc
					(start 333.089758 -210.74126)
					(mid 333.01936 -210.568959)
					(end 332.985618 -210.385914)
				)
				(arc
					(start 332.81493 -210.385914)
					(mid 332.781203 -210.568963)
					(end 332.71079 -210.74126)
				)
				(arc
					(start 332.71079 -210.74126)
					(mid 332.337102 -211.111792)
					(end 332.575662 -210.642708)
				)
				(arc
					(start 332.575662 -210.642708)
					(mid 332.624041 -210.517647)
					(end 332.649068 -210.385914)
				)
			)
		)
	)
	(zone
		(layer "In5.Cu")
		(hatch none 0.5)
		(connect_pads
			(clearance 0)
		)
		(min_thickness 0.25)
		(keepout
			(tracks not_allowed)
			(vias allowed)
			(pads allowed)
			(copperpour not_allowed)
			(footprints allowed)
		)
		(placement
			(enabled no)
			(sheetname "")
		)
		(fill
			(thermal_gap 0.5)
			(thermal_bridge_width 0.5)
			(island_removal_mode 0)
		)
		(polygon
			(pts
				(arc
					(start 268.98854 -13.843254)
					(mid 268.478127 -13.33246)
					(end 267.96746 -13.843)
				)
				(arc
					(start 267.96746 -14.6558)
					(mid 268.478 -15.16634)
					(end 268.98854 -14.6558)
				)
				(xy 268.98854 -14.443964)
				(arc
					(start 268.772386 -14.443964)
					(mid 268.719392 -14.450634)
					(end 268.66977 -14.47038)
				)
				(arc
					(start 268.66977 -14.47038)
					(mid 268.361687 -14.895858)
					(end 268.50467 -14.39037)
				)
				(arc
					(start 268.50467 -14.39037)
					(mid 268.610999 -14.315175)
					(end 268.736572 -14.280642)
				)
				(xy 268.738096 -14.278864) (xy 268.98854 -14.278864) (xy 268.98854 -14.113764) (xy 268.787372 -14.113764)
				(arc
					(start 268.786102 -14.112494)
					(mid 268.700388 -14.098602)
					(end 268.618462 -14.069822)
				)
				(arc
					(start 268.618462 -14.069822)
					(mid 268.271239 -13.674394)
					(end 268.728444 -13.934948)
				)
				(arc
					(start 268.728444 -13.934948)
					(mid 268.774554 -13.945198)
					(end 268.821662 -13.948664)
				)
				(xy 268.98854 -13.948664)
			)
		)
	)
	(zone
		(layer "In5.Cu")
		(hatch none 0.5)
		(connect_pads
			(clearance 0)
		)
		(min_thickness 0.25)
		(keepout
			(tracks not_allowed)
			(vias allowed)
			(pads allowed)
			(copperpour not_allowed)
			(footprints allowed)
		)
		(placement
			(enabled no)
			(sheetname "")
		)
		(fill
			(thermal_gap 0.5)
			(thermal_bridge_width 0.5)
			(island_removal_mode 0)
		)
		(polygon
			(pts
				(arc
					(start 186.56554 -24.999188)
					(mid 186.055127 -24.488394)
					(end 185.54446 -24.998934)
				)
				(arc
					(start 185.54446 -25.811734)
					(mid 186.055 -26.322274)
					(end 186.56554 -25.811734)
				)
				(xy 186.56554 -25.635204)
				(arc
					(start 186.450732 -25.635204)
					(mid 186.365338 -25.645741)
					(end 186.285124 -25.67686)
				)
				(arc
					(start 186.285124 -25.67686)
					(mid 185.880925 -26.013838)
					(end 186.154314 -25.564084)
				)
				(arc
					(start 186.154314 -25.564084)
					(mid 186.278514 -25.499838)
					(end 186.415426 -25.471374)
				)
				(xy 186.416442 -25.470104) (xy 186.56554 -25.470104) (xy 186.56554 -25.305004) (xy 186.416442 -25.305004)
				(arc
					(start 186.415426 -25.303734)
					(mid 186.294486 -25.282107)
					(end 186.181492 -25.233884)
				)
				(arc
					(start 186.181492 -25.233884)
					(mid 185.859162 -24.817821)
					(end 186.298332 -25.1079)
				)
				(arc
					(start 186.298332 -25.1079)
					(mid 186.37287 -25.131828)
					(end 186.450732 -25.139904)
				)
				(xy 186.56554 -25.139904)
			)
		)
	)
	(zone
		(layer "In5.Cu")
		(hatch none 0.5)
		(connect_pads
			(clearance 0)
		)
		(min_thickness 0.25)
		(keepout
			(tracks not_allowed)
			(vias allowed)
			(pads allowed)
			(copperpour not_allowed)
			(footprints allowed)
		)
		(placement
			(enabled no)
			(sheetname "")
		)
		(fill
			(thermal_gap 0.5)
			(thermal_bridge_width 0.5)
			(island_removal_mode 0)
		)
		(polygon
			(pts
				(arc
					(start 290.093908 -210.385914)
					(mid 289.583114 -210.896327)
					(end 290.093654 -211.406994)
				)
				(arc
					(start 290.906454 -211.406994)
					(mid 291.416994 -210.896454)
					(end 290.906454 -210.385914)
				)
				(arc
					(start 290.75126 -210.385914)
					(mid 290.776321 -210.517637)
					(end 290.824666 -210.642708)
				)
				(arc
					(start 290.824666 -210.642708)
					(mid 291.063234 -211.111803)
					(end 290.689538 -210.74126)
				)
				(arc
					(start 290.689538 -210.74126)
					(mid 290.61914 -210.568959)
					(end 290.585398 -210.385914)
				)
				(arc
					(start 290.41471 -210.385914)
					(mid 290.380983 -210.568963)
					(end 290.31057 -210.74126)
				)
				(arc
					(start 290.31057 -210.74126)
					(mid 289.936882 -211.111792)
					(end 290.175442 -210.642708)
				)
				(arc
					(start 290.175442 -210.642708)
					(mid 290.223821 -210.517647)
					(end 290.248848 -210.385914)
				)
			)
		)
	)
	(zone
		(layer "In5.Cu")
		(hatch none 0.5)
		(connect_pads
			(clearance 0)
		)
		(min_thickness 0.25)
		(keepout
			(tracks not_allowed)
			(vias allowed)
			(pads allowed)
			(copperpour not_allowed)
			(footprints allowed)
		)
		(placement
			(enabled no)
			(sheetname "")
		)
		(fill
			(thermal_gap 0.5)
			(thermal_bridge_width 0.5)
			(island_removal_mode 0)
		)
		(polygon
			(pts
				(arc
					(start 283.69387 -210.385914)
					(mid 283.183076 -210.896327)
					(end 283.693616 -211.406994)
				)
				(arc
					(start 284.506416 -211.406994)
					(mid 285.016956 -210.896454)
					(end 284.506416 -210.385914)
				)
				(xy 284.347666 -210.385914)
				(arc
					(start 284.347666 -210.4644)
					(mid 284.360458 -210.56193)
					(end 284.397958 -210.652868)
				)
				(arc
					(start 284.397958 -210.652868)
					(mid 284.686 -211.09355)
					(end 284.274006 -210.765898)
				)
				(arc
					(start 284.274006 -210.765898)
					(mid 284.211363 -210.638745)
					(end 284.183836 -210.499706)
				)
				(xy 284.182566 -210.49869) (xy 284.182566 -210.385914)
				(arc
					(start 284.014672 -210.385914)
					(mid 283.980945 -210.568963)
					(end 283.910532 -210.74126)
				)
				(arc
					(start 283.910532 -210.74126)
					(mid 283.536844 -211.111792)
					(end 283.775404 -210.642708)
				)
				(arc
					(start 283.775404 -210.642708)
					(mid 283.823783 -210.517647)
					(end 283.84881 -210.385914)
				)
			)
		)
	)
	(zone
		(layer "In5.Cu")
		(hatch none 0.5)
		(connect_pads
			(clearance 0)
		)
		(min_thickness 0.25)
		(keepout
			(tracks not_allowed)
			(vias allowed)
			(pads allowed)
			(copperpour not_allowed)
			(footprints allowed)
		)
		(placement
			(enabled no)
			(sheetname "")
		)
		(fill
			(thermal_gap 0.5)
			(thermal_bridge_width 0.5)
			(island_removal_mode 0)
		)
		(polygon
			(pts
				(arc
					(start 183.59374 -25.946354)
					(mid 183.083327 -25.43556)
					(end 182.57266 -25.9461)
				)
				(arc
					(start 182.57266 -26.7589)
					(mid 183.0832 -27.26944)
					(end 183.59374 -26.7589)
				)
				(xy 183.59374 -26.60015)
				(arc
					(start 183.383936 -26.60015)
					(mid 183.344866 -26.603515)
					(end 183.306974 -26.613612)
				)
				(arc
					(start 183.306974 -26.613612)
					(mid 182.922202 -26.971651)
					(end 183.162194 -26.504138)
				)
				(arc
					(start 183.162194 -26.504138)
					(mid 183.250809 -26.458389)
					(end 183.348122 -26.436574)
				)
				(xy 183.349646 -26.43505) (xy 183.59374 -26.43505) (xy 183.59374 -26.26995) (xy 183.453786 -26.26995)
				(arc
					(start 183.45277 -26.26868)
					(mid 183.320616 -26.243424)
					(end 183.19877 -26.186384)
				)
				(arc
					(start 183.19877 -26.186384)
					(mid 182.896357 -25.755883)
					(end 183.321452 -26.065988)
				)
				(arc
					(start 183.321452 -26.065988)
					(mid 183.402534 -26.09498)
					(end 183.488076 -26.10485)
				)
				(xy 183.59374 -26.10485)
			)
		)
	)
	(zone
		(layer "In5.Cu")
		(hatch none 0.5)
		(connect_pads
			(clearance 0)
		)
		(min_thickness 0.25)
		(keepout
			(tracks not_allowed)
			(vias allowed)
			(pads allowed)
			(copperpour not_allowed)
			(footprints allowed)
		)
		(placement
			(enabled no)
			(sheetname "")
		)
		(fill
			(thermal_gap 0.5)
			(thermal_bridge_width 0.5)
			(island_removal_mode 0)
		)
		(polygon
			(pts
				(arc
					(start 305.762914 -39.29888)
					(mid 305.252374 -39.80942)
					(end 305.762914 -40.31996)
				)
				(xy 305.921664 -40.31996) (xy 305.921664 -40.08501)
				(arc
					(start 305.883818 -40.047164)
					(mid 305.574314 -39.62082)
					(end 306.000658 -39.930324)
				)
				(xy 306.038504 -39.96817) (xy 306.086764 -40.01643) (xy 306.086764 -40.08501) (xy 306.086764 -40.31996)
				(xy 306.251864 -40.31996) (xy 306.251864 -40.08501) (xy 306.251864 -40.01643) (xy 306.300124 -39.96817)
				(arc
					(start 306.33797 -39.930324)
					(mid 306.764314 -39.62082)
					(end 306.45481 -40.047164)
				)
				(xy 306.416964 -40.08501) (xy 306.416964 -40.31996)
				(arc
					(start 306.57546 -40.31996)
					(mid 307.086254 -39.809547)
					(end 306.575714 -39.29888)
				)
			)
		)
	)
	(zone
		(layer "In5.Cu")
		(hatch none 0.5)
		(connect_pads
			(clearance 0)
		)
		(min_thickness 0.25)
		(keepout
			(tracks not_allowed)
			(vias allowed)
			(pads allowed)
			(copperpour not_allowed)
			(footprints allowed)
		)
		(placement
			(enabled no)
			(sheetname "")
		)
		(fill
			(thermal_gap 0.5)
			(thermal_bridge_width 0.5)
			(island_removal_mode 0)
		)
		(polygon
			(pts
				(arc
					(start 302.093884 -210.385914)
					(mid 301.58309 -210.896327)
					(end 302.09363 -211.406994)
				)
				(arc
					(start 302.90643 -211.406994)
					(mid 303.41697 -210.896454)
					(end 302.90643 -210.385914)
				)
				(arc
					(start 302.751236 -210.385914)
					(mid 302.776297 -210.517637)
					(end 302.824642 -210.642708)
				)
				(arc
					(start 302.824642 -210.642708)
					(mid 303.06321 -211.111803)
					(end 302.689514 -210.74126)
				)
				(arc
					(start 302.689514 -210.74126)
					(mid 302.619116 -210.568959)
					(end 302.585374 -210.385914)
				)
				(arc
					(start 302.414686 -210.385914)
					(mid 302.380959 -210.568963)
					(end 302.310546 -210.74126)
				)
				(arc
					(start 302.310546 -210.74126)
					(mid 301.936858 -211.111792)
					(end 302.175418 -210.642708)
				)
				(arc
					(start 302.175418 -210.642708)
					(mid 302.223797 -210.517647)
					(end 302.248824 -210.385914)
				)
			)
		)
	)
	(zone
		(layer "In5.Cu")
		(hatch none 0.5)
		(connect_pads
			(clearance 0)
		)
		(min_thickness 0.25)
		(keepout
			(tracks not_allowed)
			(vias allowed)
			(pads allowed)
			(copperpour not_allowed)
			(footprints allowed)
		)
		(placement
			(enabled no)
			(sheetname "")
		)
		(fill
			(thermal_gap 0.5)
			(thermal_bridge_width 0.5)
			(island_removal_mode 0)
		)
		(polygon
			(pts
				(arc
					(start 190.493904 -210.385914)
					(mid 189.98311 -210.896327)
					(end 190.49365 -211.406994)
				)
				(arc
					(start 191.30645 -211.406994)
					(mid 191.81699 -210.896454)
					(end 191.30645 -210.385914)
				)
				(arc
					(start 191.151256 -210.385914)
					(mid 191.176317 -210.517637)
					(end 191.224662 -210.642708)
				)
				(arc
					(start 191.224662 -210.642708)
					(mid 191.46323 -211.111803)
					(end 191.089534 -210.74126)
				)
				(arc
					(start 191.089534 -210.74126)
					(mid 191.019136 -210.568959)
					(end 190.985394 -210.385914)
				)
				(arc
					(start 190.814706 -210.385914)
					(mid 190.780979 -210.568963)
					(end 190.710566 -210.74126)
				)
				(arc
					(start 190.710566 -210.74126)
					(mid 190.336878 -211.111792)
					(end 190.575438 -210.642708)
				)
				(arc
					(start 190.575438 -210.642708)
					(mid 190.623817 -210.517647)
					(end 190.648844 -210.385914)
				)
			)
		)
	)
	(zone
		(layer "In5.Cu")
		(hatch none 0.5)
		(connect_pads
			(clearance 0)
		)
		(min_thickness 0.25)
		(keepout
			(tracks not_allowed)
			(vias allowed)
			(pads allowed)
			(copperpour not_allowed)
			(footprints allowed)
		)
		(placement
			(enabled no)
			(sheetname "")
		)
		(fill
			(thermal_gap 0.5)
			(thermal_bridge_width 0.5)
			(island_removal_mode 0)
		)
		(polygon
			(pts
				(arc
					(start 13.563854 -53.319172)
					(mid 13.05306 -53.829585)
					(end 13.5636 -54.340252)
				)
				(xy 13.7541 -54.340252) (xy 13.7541 -54.110128)
				(arc
					(start 13.701776 -54.057804)
					(mid 13.375028 -53.64114)
					(end 13.791692 -53.967888)
				)
				(xy 13.844016 -54.020212) (xy 13.8811 -54.057296) (xy 13.8811 -54.110128) (xy 13.8811 -54.340252)
				(xy 14.0589 -54.340252) (xy 14.0589 -54.110128) (xy 14.0589 -54.057296) (xy 14.095984 -54.020212)
				(arc
					(start 14.148308 -53.967888)
					(mid 14.564972 -53.64114)
					(end 14.238224 -54.057804)
				)
				(xy 14.1859 -54.110128) (xy 14.1859 -54.340252)
				(arc
					(start 14.3764 -54.340252)
					(mid 14.88694 -53.829712)
					(end 14.3764 -53.319172)
				)
			)
		)
	)
	(zone
		(layer "In5.Cu")
		(hatch none 0.5)
		(connect_pads
			(clearance 0)
		)
		(min_thickness 0.25)
		(keepout
			(tracks not_allowed)
			(vias allowed)
			(pads allowed)
			(copperpour not_allowed)
			(footprints allowed)
		)
		(placement
			(enabled no)
			(sheetname "")
		)
		(fill
			(thermal_gap 0.5)
			(thermal_bridge_width 0.5)
			(island_removal_mode 0)
		)
		(polygon
			(pts
				(arc
					(start 103.02494 -36.205668)
					(mid 102.5144 -35.695128)
					(end 102.00386 -36.205668)
				)
				(xy 102.00386 -36.402518) (xy 102.20071 -36.402518)
				(arc
					(start 102.276656 -36.326572)
					(mid 102.703 -36.017068)
					(end 102.393496 -36.443412)
				)
				(xy 102.31755 -36.519358) (xy 102.26929 -36.567618) (xy 102.20071 -36.567618) (xy 102.00386 -36.567618)
				(xy 102.00386 -36.732718) (xy 102.20071 -36.732718) (xy 102.26929 -36.732718) (xy 102.31755 -36.780978)
				(arc
					(start 102.393496 -36.856924)
					(mid 102.703 -37.283268)
					(end 102.276656 -36.973764)
				)
				(xy 102.20071 -36.897818) (xy 102.00386 -36.897818)
				(arc
					(start 102.00386 -37.094414)
					(mid 102.514273 -37.605208)
					(end 103.02494 -37.094668)
				)
			)
		)
	)
	(zone
		(layer "In5.Cu")
		(hatch none 0.5)
		(connect_pads
			(clearance 0)
		)
		(min_thickness 0.25)
		(keepout
			(tracks not_allowed)
			(vias allowed)
			(pads allowed)
			(copperpour not_allowed)
			(footprints allowed)
		)
		(placement
			(enabled no)
			(sheetname "")
		)
		(fill
			(thermal_gap 0.5)
			(thermal_bridge_width 0.5)
			(island_removal_mode 0)
		)
		(polygon
			(pts
				(arc
					(start 212.89391 -210.385914)
					(mid 212.383116 -210.896327)
					(end 212.893656 -211.406994)
				)
				(arc
					(start 213.706456 -211.406994)
					(mid 214.216996 -210.896454)
					(end 213.706456 -210.385914)
				)
				(arc
					(start 213.551262 -210.385914)
					(mid 213.576323 -210.517637)
					(end 213.624668 -210.642708)
				)
				(arc
					(start 213.624668 -210.642708)
					(mid 213.863236 -211.111803)
					(end 213.48954 -210.74126)
				)
				(arc
					(start 213.48954 -210.74126)
					(mid 213.419142 -210.568959)
					(end 213.3854 -210.385914)
				)
				(arc
					(start 213.214712 -210.385914)
					(mid 213.180985 -210.568963)
					(end 213.110572 -210.74126)
				)
				(arc
					(start 213.110572 -210.74126)
					(mid 212.736884 -211.111792)
					(end 212.975444 -210.642708)
				)
				(arc
					(start 212.975444 -210.642708)
					(mid 213.023823 -210.517647)
					(end 213.04885 -210.385914)
				)
			)
		)
	)
	(zone
		(layer "In5.Cu")
		(hatch none 0.5)
		(connect_pads
			(clearance 0)
		)
		(min_thickness 0.25)
		(keepout
			(tracks not_allowed)
			(vias allowed)
			(pads allowed)
			(copperpour not_allowed)
			(footprints allowed)
		)
		(placement
			(enabled no)
			(sheetname "")
		)
		(fill
			(thermal_gap 0.5)
			(thermal_bridge_width 0.5)
			(island_removal_mode 0)
		)
		(polygon
			(pts
				(arc
					(start 9.6647 -54.538372)
					(mid 9.15416 -55.048912)
					(end 9.6647 -55.559452)
				)
				(xy 9.8552 -55.559452) (xy 9.8552 -55.329328)
				(arc
					(start 9.802876 -55.277004)
					(mid 9.476128 -54.86034)
					(end 9.892792 -55.187088)
				)
				(xy 9.945116 -55.239412) (xy 9.9822 -55.276496) (xy 9.9822 -55.329328) (xy 9.9822 -55.559452) (xy 10.16 -55.559452)
				(xy 10.16 -55.329328) (xy 10.16 -55.276496) (xy 10.197084 -55.239412)
				(arc
					(start 10.249408 -55.187088)
					(mid 10.666072 -54.86034)
					(end 10.339324 -55.277004)
				)
				(xy 10.287 -55.329328) (xy 10.287 -55.559452)
				(arc
					(start 10.477246 -55.559452)
					(mid 10.98804 -55.049039)
					(end 10.4775 -54.538372)
				)
			)
		)
	)
	(zone
		(layer "In5.Cu")
		(hatch none 0.5)
		(connect_pads
			(clearance 0)
		)
		(min_thickness 0.25)
		(keepout
			(tracks not_allowed)
			(vias allowed)
			(pads allowed)
			(copperpour not_allowed)
			(footprints allowed)
		)
		(placement
			(enabled no)
			(sheetname "")
		)
		(fill
			(thermal_gap 0.5)
			(thermal_bridge_width 0.5)
			(island_removal_mode 0)
		)
		(polygon
			(pts
				(arc
					(start 328.375518 -34.408872)
					(mid 327.864978 -34.919412)
					(end 328.375518 -35.429952)
				)
				(xy 328.555096 -35.429952)
				(arc
					(start 328.555096 -35.395662)
					(mid 328.537664 -35.273809)
					(end 328.48677 -35.161728)
				)
				(arc
					(start 328.48677 -35.161728)
					(mid 328.194429 -34.723517)
					(end 328.609198 -35.04819)
				)
				(arc
					(start 328.609198 -35.04819)
					(mid 328.686142 -35.196536)
					(end 328.71918 -35.360356)
				)
				(xy 328.720196 -35.361372) (xy 328.720196 -35.429952) (xy 328.885296 -35.429952) (xy 328.885296 -35.361372)
				(arc
					(start 328.886058 -35.36061)
					(mid 328.910393 -35.209875)
					(end 328.96683 -35.068002)
				)
				(arc
					(start 328.96683 -35.068002)
					(mid 329.351591 -34.708514)
					(end 329.099926 -35.171126)
				)
				(arc
					(start 329.099926 -35.171126)
					(mid 329.062957 -35.280702)
					(end 329.050396 -35.395662)
				)
				(xy 329.050396 -35.429952)
				(arc
					(start 329.188064 -35.429952)
					(mid 329.698858 -34.919539)
					(end 329.188318 -34.408872)
				)
			)
		)
	)
	(zone
		(layer "In5.Cu")
		(hatch none 0.5)
		(connect_pads
			(clearance 0)
		)
		(min_thickness 0.25)
		(keepout
			(tracks not_allowed)
			(vias allowed)
			(pads allowed)
			(copperpour not_allowed)
			(footprints allowed)
		)
		(placement
			(enabled no)
			(sheetname "")
		)
		(fill
			(thermal_gap 0.5)
			(thermal_bridge_width 0.5)
			(island_removal_mode 0)
		)
		(polygon
			(pts
				(arc
					(start 148.093938 -210.385914)
					(mid 147.583144 -210.896327)
					(end 148.093684 -211.406994)
				)
				(arc
					(start 148.906484 -211.406994)
					(mid 149.417024 -210.896454)
					(end 148.906484 -210.385914)
				)
				(arc
					(start 148.75129 -210.385914)
					(mid 148.776351 -210.517637)
					(end 148.824696 -210.642708)
				)
				(arc
					(start 148.824696 -210.642708)
					(mid 149.063264 -211.111803)
					(end 148.689568 -210.74126)
				)
				(arc
					(start 148.689568 -210.74126)
					(mid 148.61917 -210.568959)
					(end 148.585428 -210.385914)
				)
				(arc
					(start 148.41474 -210.385914)
					(mid 148.381013 -210.568963)
					(end 148.3106 -210.74126)
				)
				(arc
					(start 148.3106 -210.74126)
					(mid 147.936912 -211.111792)
					(end 148.175472 -210.642708)
				)
				(arc
					(start 148.175472 -210.642708)
					(mid 148.223851 -210.517647)
					(end 148.248878 -210.385914)
				)
			)
		)
	)
	(zone
		(layer "In5.Cu")
		(hatch none 0.5)
		(connect_pads
			(clearance 0)
		)
		(min_thickness 0.25)
		(keepout
			(tracks not_allowed)
			(vias allowed)
			(pads allowed)
			(copperpour not_allowed)
			(footprints allowed)
		)
		(placement
			(enabled no)
			(sheetname "")
		)
		(fill
			(thermal_gap 0.5)
			(thermal_bridge_width 0.5)
			(island_removal_mode 0)
		)
		(polygon
			(pts
				(arc
					(start 298.893992 -210.385914)
					(mid 298.383198 -210.896327)
					(end 298.893738 -211.406994)
				)
				(arc
					(start 299.706538 -211.406994)
					(mid 300.217078 -210.896454)
					(end 299.706538 -210.385914)
				)
				(arc
					(start 299.551344 -210.385914)
					(mid 299.576405 -210.517637)
					(end 299.62475 -210.642708)
				)
				(arc
					(start 299.62475 -210.642708)
					(mid 299.863318 -211.111803)
					(end 299.489622 -210.74126)
				)
				(arc
					(start 299.489622 -210.74126)
					(mid 299.419224 -210.568959)
					(end 299.385482 -210.385914)
				)
				(arc
					(start 299.214794 -210.385914)
					(mid 299.181067 -210.568963)
					(end 299.110654 -210.74126)
				)
				(arc
					(start 299.110654 -210.74126)
					(mid 298.736966 -211.111792)
					(end 298.975526 -210.642708)
				)
				(arc
					(start 298.975526 -210.642708)
					(mid 299.023905 -210.517647)
					(end 299.048932 -210.385914)
				)
			)
		)
	)
	(zone
		(layer "In5.Cu")
		(hatch none 0.5)
		(connect_pads
			(clearance 0)
		)
		(min_thickness 0.25)
		(keepout
			(tracks not_allowed)
			(vias allowed)
			(pads allowed)
			(copperpour not_allowed)
			(footprints allowed)
		)
		(placement
			(enabled no)
			(sheetname "")
		)
		(fill
			(thermal_gap 0.5)
			(thermal_bridge_width 0.5)
			(island_removal_mode 0)
		)
		(polygon
			(pts
				(arc
					(start 66.893948 -210.385914)
					(mid 66.383154 -210.896327)
					(end 66.893694 -211.406994)
				)
				(arc
					(start 67.706494 -211.406994)
					(mid 68.217034 -210.896454)
					(end 67.706494 -210.385914)
				)
				(arc
					(start 67.560698 -210.385914)
					(mid 67.591201 -210.514869)
					(end 67.639184 -210.63839)
				)
				(arc
					(start 67.639184 -210.63839)
					(mid 67.851377 -211.120607)
					(end 67.499484 -210.72856)
				)
				(arc
					(start 67.499484 -210.72856)
					(mid 67.432777 -210.561486)
					(end 67.393566 -210.385914)
				)
				(arc
					(start 67.206622 -210.385914)
					(mid 67.167399 -210.561483)
					(end 67.100704 -210.72856)
				)
				(arc
					(start 67.100704 -210.72856)
					(mid 66.748827 -211.120583)
					(end 66.961004 -210.63839)
				)
				(arc
					(start 66.961004 -210.63839)
					(mid 67.008975 -210.514866)
					(end 67.03949 -210.385914)
				)
			)
		)
	)
	(zone
		(layer "In5.Cu")
		(hatch none 0.5)
		(connect_pads
			(clearance 0)
		)
		(min_thickness 0.25)
		(keepout
			(tracks not_allowed)
			(vias allowed)
			(pads allowed)
			(copperpour not_allowed)
			(footprints allowed)
		)
		(placement
			(enabled no)
			(sheetname "")
		)
		(fill
			(thermal_gap 0.5)
			(thermal_bridge_width 0.5)
			(island_removal_mode 0)
		)
		(polygon
			(pts
				(arc
					(start 160.894014 -210.385914)
					(mid 160.38322 -210.896327)
					(end 160.89376 -211.406994)
				)
				(arc
					(start 161.70656 -211.406994)
					(mid 162.2171 -210.896454)
					(end 161.70656 -210.385914)
				)
				(arc
					(start 161.551366 -210.385914)
					(mid 161.576427 -210.517637)
					(end 161.624772 -210.642708)
				)
				(arc
					(start 161.624772 -210.642708)
					(mid 161.86334 -211.111803)
					(end 161.489644 -210.74126)
				)
				(arc
					(start 161.489644 -210.74126)
					(mid 161.419246 -210.568959)
					(end 161.385504 -210.385914)
				)
				(arc
					(start 161.214816 -210.385914)
					(mid 161.181089 -210.568963)
					(end 161.110676 -210.74126)
				)
				(arc
					(start 161.110676 -210.74126)
					(mid 160.736988 -211.111792)
					(end 160.975548 -210.642708)
				)
				(arc
					(start 160.975548 -210.642708)
					(mid 161.023927 -210.517647)
					(end 161.048954 -210.385914)
				)
			)
		)
	)
	(zone
		(layer "In5.Cu")
		(hatch none 0.5)
		(connect_pads
			(clearance 0)
		)
		(min_thickness 0.25)
		(keepout
			(tracks not_allowed)
			(vias allowed)
			(pads allowed)
			(copperpour not_allowed)
			(footprints allowed)
		)
		(placement
			(enabled no)
			(sheetname "")
		)
		(fill
			(thermal_gap 0.5)
			(thermal_bridge_width 0.5)
			(island_removal_mode 0)
		)
		(polygon
			(pts
				(arc
					(start 299.430948 -35.678872)
					(mid 298.920154 -36.189285)
					(end 299.430694 -36.699952)
				)
				(xy 299.59935 -36.699952)
				(arc
					(start 299.59935 -36.6522)
					(mid 299.584059 -36.538533)
					(end 299.539152 -36.432998)
				)
				(arc
					(start 299.539152 -36.432998)
					(mid 299.251693 -35.991588)
					(end 299.663104 -36.320476)
				)
				(arc
					(start 299.663104 -36.320476)
					(mid 299.733163 -36.461952)
					(end 299.763434 -36.616894)
				)
				(xy 299.76445 -36.61791) (xy 299.76445 -36.699952) (xy 299.92955 -36.699952) (xy 299.92955 -36.61791)
				(arc
					(start 299.930566 -36.617148)
					(mid 299.956559 -36.468276)
					(end 300.016672 -36.32962)
				)
				(arc
					(start 300.016672 -36.32962)
					(mid 300.414516 -35.98482)
					(end 300.145704 -36.43757)
				)
				(arc
					(start 300.145704 -36.43757)
					(mid 300.107591 -36.541889)
					(end 300.09465 -36.6522)
				)
				(xy 300.09465 -36.699952)
				(arc
					(start 300.243494 -36.699952)
					(mid 300.754034 -36.189412)
					(end 300.243494 -35.678872)
				)
			)
		)
	)
	(zone
		(layer "In5.Cu")
		(hatch none 0.5)
		(connect_pads
			(clearance 0)
		)
		(min_thickness 0.25)
		(keepout
			(tracks not_allowed)
			(vias allowed)
			(pads allowed)
			(copperpour not_allowed)
			(footprints allowed)
		)
		(placement
			(enabled no)
			(sheetname "")
		)
		(fill
			(thermal_gap 0.5)
			(thermal_bridge_width 0.5)
			(island_removal_mode 0)
		)
		(polygon
			(pts
				(arc
					(start 101.293676 -210.385914)
					(mid 100.783136 -210.896454)
					(end 101.293676 -211.406994)
				)
				(arc
					(start 102.106222 -211.406994)
					(mid 102.617016 -210.896581)
					(end 102.106476 -210.385914)
				)
				(arc
					(start 101.96068 -210.385914)
					(mid 101.991183 -210.514869)
					(end 102.039166 -210.63839)
				)
				(arc
					(start 102.039166 -210.63839)
					(mid 102.251359 -211.120607)
					(end 101.899466 -210.72856)
				)
				(arc
					(start 101.899466 -210.72856)
					(mid 101.832759 -210.561486)
					(end 101.793548 -210.385914)
				)
				(arc
					(start 101.606604 -210.385914)
					(mid 101.567381 -210.561483)
					(end 101.500686 -210.72856)
				)
				(arc
					(start 101.500686 -210.72856)
					(mid 101.148809 -211.120583)
					(end 101.360986 -210.63839)
				)
				(arc
					(start 101.360986 -210.63839)
					(mid 101.408957 -210.514866)
					(end 101.439472 -210.385914)
				)
			)
		)
	)
	(zone
		(net "GND")
		(layer "In5.Cu")
		(hatch none 0.5)
		(connect_pads
			(clearance 0.5)
		)
		(min_thickness 0.25)
		(fill yes
			(thermal_gap 0.5)
			(thermal_bridge_width 0.5)
			(island_removal_mode 0)
		)
		(polygon
			(pts
				(xy 255.802638 -130.079242) (xy 239.707166 -146.174714) (xy 232.490518 -158.42107) (xy 232.451656 -159.343344)
				(xy 232.110026 -159.684974) (xy 232.110026 -165.269926)
				(arc
					(start 232.110026 -208.499964)
					(mid 231.240722 -210.59865)
					(end 229.142036 -211.467954)
				)
				(arc
					(start 221.600014 -211.467954)
					(mid 219.243954 -212.443866)
					(end 218.268042 -214.799926)
				)
				(xy 218.268042 -218.770962) (xy 219.537026 -218.770962)
				(arc
					(start 219.537026 -214.799926)
					(mid 220.141261 -213.341173)
					(end 221.600014 -212.736938)
				)
				(arc
					(start 229.142036 -212.736938)
					(mid 232.138029 -211.495957)
					(end 233.37901 -208.499964)
				)
				(arc
					(start 233.37901 -165.269926)
					(mid 233.974467 -163.832367)
					(end 235.412026 -163.23691)
				)
				(arc
					(start 249.871992 -163.23691)
					(mid 251.309551 -163.832367)
					(end 251.905008 -165.269926)
				)
				(arc
					(start 251.905008 -208.499964)
					(mid 253.145989 -211.495957)
					(end 256.141982 -212.736938)
				)
				(arc
					(start 257.400044 -212.736938)
					(mid 258.858797 -213.341173)
					(end 259.463032 -214.799926)
				)
				(xy 259.463032 -218.09075) (xy 260.732016 -218.09075)
				(arc
					(start 260.732016 -214.799926)
					(mid 260.567216 -213.765006)
					(end 260.089142 -212.832442)
				)
				(xy 260.089142 -191.049402) (xy 260.351524 -190.78702) (xy 264.812526 -173.641766) (xy 266.91209 -162.707574)
				(xy 262.013446 -132.7912) (xy 261.92607 -132.7912) (xy 259.214112 -130.079242)
			)
		)
	)
	(zone
		(layer "In5.Cu")
		(hatch none 0.5)
		(connect_pads
			(clearance 0)
		)
		(min_thickness 0.25)
		(keepout
			(tracks not_allowed)
			(vias allowed)
			(pads allowed)
			(copperpour not_allowed)
			(footprints allowed)
		)
		(placement
			(enabled no)
			(sheetname "")
		)
		(fill
			(thermal_gap 0.5)
			(thermal_bridge_width 0.5)
			(island_removal_mode 0)
		)
		(polygon
			(pts
				(arc
					(start 326.093836 -210.385914)
					(mid 325.583042 -210.896327)
					(end 326.093582 -211.406994)
				)
				(arc
					(start 326.906382 -211.406994)
					(mid 327.416922 -210.896454)
					(end 326.906382 -210.385914)
				)
				(arc
					(start 326.751188 -210.385914)
					(mid 326.776249 -210.517637)
					(end 326.824594 -210.642708)
				)
				(arc
					(start 326.824594 -210.642708)
					(mid 327.063162 -211.111803)
					(end 326.689466 -210.74126)
				)
				(arc
					(start 326.689466 -210.74126)
					(mid 326.619068 -210.568959)
					(end 326.585326 -210.385914)
				)
				(arc
					(start 326.414638 -210.385914)
					(mid 326.380911 -210.568963)
					(end 326.310498 -210.74126)
				)
				(arc
					(start 326.310498 -210.74126)
					(mid 325.93681 -211.111792)
					(end 326.17537 -210.642708)
				)
				(arc
					(start 326.17537 -210.642708)
					(mid 326.223749 -210.517647)
					(end 326.248776 -210.385914)
				)
			)
		)
	)
	(zone
		(layer "In5.Cu")
		(hatch none 0.5)
		(connect_pads
			(clearance 0)
		)
		(min_thickness 0.25)
		(keepout
			(tracks not_allowed)
			(vias allowed)
			(pads allowed)
			(copperpour not_allowed)
			(footprints allowed)
		)
		(placement
			(enabled no)
			(sheetname "")
		)
		(fill
			(thermal_gap 0.5)
			(thermal_bridge_width 0.5)
			(island_removal_mode 0)
		)
		(polygon
			(pts
				(xy 320.199512 -37.53612) (xy 320.199512 -37.392864)
				(arc
					(start 320.200782 -37.391848)
					(mid 320.227996 -37.256214)
					(end 320.289428 -37.13226)
				)
				(arc
					(start 320.289428 -37.13226)
					(mid 320.731167 -36.846129)
					(end 320.405506 -37.259514)
				)
				(arc
					(start 320.405506 -37.259514)
					(mid 320.374956 -37.340872)
					(end 320.364612 -37.427154)
				)
				(xy 320.364612 -37.53612)
				(arc
					(start 320.533776 -37.53612)
					(mid 321.044316 -37.02558)
					(end 320.533776 -36.51504)
				)
				(arc
					(start 319.72123 -36.51504)
					(mid 319.210436 -37.025453)
					(end 319.720976 -37.53612)
				)
				(xy 319.869312 -37.53612)
				(arc
					(start 319.869312 -37.427154)
					(mid 319.860487 -37.345235)
					(end 319.83426 -37.267134)
				)
				(arc
					(start 319.83426 -37.267134)
					(mid 319.53597 -36.833345)
					(end 319.957958 -37.148008)
				)
				(arc
					(start 319.957958 -37.148008)
					(mid 320.01008 -37.26547)
					(end 320.033396 -37.391848)
				)
				(xy 320.034412 -37.392864) (xy 320.034412 -37.53612)
			)
		)
	)
	(zone
		(layer "In5.Cu")
		(hatch none 0.5)
		(connect_pads
			(clearance 0)
		)
		(min_thickness 0.25)
		(keepout
			(tracks not_allowed)
			(vias allowed)
			(pads allowed)
			(copperpour not_allowed)
			(footprints allowed)
		)
		(placement
			(enabled no)
			(sheetname "")
		)
		(fill
			(thermal_gap 0.5)
			(thermal_bridge_width 0.5)
			(island_removal_mode 0)
		)
		(polygon
			(pts
				(arc
					(start 161.277554 -34.51098)
					(mid 160.76676 -35.021393)
					(end 161.2773 -35.53206)
				)
				(xy 161.43605 -35.53206)
				(arc
					(start 161.43605 -35.387534)
					(mid 161.42564 -35.320864)
					(end 161.39541 -35.260534)
				)
				(arc
					(start 161.39541 -35.260534)
					(mid 161.090598 -34.831204)
					(end 161.514028 -35.144202)
				)
				(arc
					(start 161.514028 -35.144202)
					(mid 161.572212 -35.241582)
					(end 161.599372 -35.35172)
				)
				(xy 161.60115 -35.353244) (xy 161.60115 -35.527234) (xy 161.60115 -35.53206) (xy 161.76625 -35.53206)
				(xy 161.76625 -35.353244)
				(arc
					(start 161.768028 -35.35172)
					(mid 161.795195 -35.241585)
					(end 161.853372 -35.144202)
				)
				(arc
					(start 161.853372 -35.144202)
					(mid 162.276819 -34.831186)
					(end 161.97199 -35.260534)
				)
				(arc
					(start 161.97199 -35.260534)
					(mid 161.941749 -35.32086)
					(end 161.93135 -35.387534)
				)
				(xy 161.93135 -35.527234) (xy 161.93135 -35.53206)
				(arc
					(start 162.0901 -35.53206)
					(mid 162.60064 -35.02152)
					(end 162.0901 -34.51098)
				)
			)
		)
	)
	(zone
		(layer "In5.Cu")
		(hatch none 0.5)
		(connect_pads
			(clearance 0)
		)
		(min_thickness 0.25)
		(keepout
			(tracks not_allowed)
			(vias allowed)
			(pads allowed)
			(copperpour not_allowed)
			(footprints allowed)
		)
		(placement
			(enabled no)
			(sheetname "")
		)
		(fill
			(thermal_gap 0.5)
			(thermal_bridge_width 0.5)
			(island_removal_mode 0)
		)
		(polygon
			(pts
				(arc
					(start 272.57883 -14.52245)
					(mid 272.06829 -14.01191)
					(end 271.55775 -14.52245)
				)
				(xy 271.55775 -14.657324)
				(arc
					(start 271.703546 -14.657324)
					(mid 271.765866 -14.651431)
					(end 271.825974 -14.633956)
				)
				(arc
					(start 271.825974 -14.633956)
					(mid 272.261153 -14.338182)
					(end 271.945862 -14.759432)
				)
				(arc
					(start 271.945862 -14.759432)
					(mid 271.845874 -14.801654)
					(end 271.739106 -14.821154)
				)
				(xy 271.737836 -14.822424) (xy 271.55775 -14.822424) (xy 271.55775 -14.987524) (xy 271.823688 -14.987524)
				(arc
					(start 271.825466 -14.989302)
					(mid 271.930178 -15.016099)
					(end 272.022316 -15.072614)
				)
				(arc
					(start 272.022316 -15.072614)
					(mid 272.202453 -15.565467)
					(end 271.861788 -15.16634)
				)
				(arc
					(start 271.861788 -15.16634)
					(mid 271.826239 -15.156075)
					(end 271.789398 -15.152624)
				)
				(xy 271.55775 -15.152624)
				(arc
					(start 271.55775 -15.334996)
					(mid 272.068163 -15.84579)
					(end 272.57883 -15.33525)
				)
			)
		)
	)
	(zone
		(layer "In5.Cu")
		(hatch none 0.5)
		(connect_pads
			(clearance 0)
		)
		(min_thickness 0.25)
		(keepout
			(tracks not_allowed)
			(vias allowed)
			(pads allowed)
			(copperpour not_allowed)
			(footprints allowed)
		)
		(placement
			(enabled no)
			(sheetname "")
		)
		(fill
			(thermal_gap 0.5)
			(thermal_bridge_width 0.5)
			(island_removal_mode 0)
		)
		(polygon
			(pts
				(arc
					(start 138.557254 -38.14826)
					(mid 138.04646 -38.658673)
					(end 138.557 -39.16934)
				)
				(xy 138.72845 -39.16934)
				(arc
					(start 138.72845 -38.9128)
					(mid 138.726909 -38.890116)
					(end 138.722354 -38.867842)
				)
				(arc
					(start 138.722354 -38.867842)
					(mid 138.32789 -38.522697)
					(end 138.820144 -38.702742)
				)
				(arc
					(start 138.820144 -38.702742)
					(mid 138.868194 -38.78466)
					(end 138.891518 -38.876732)
				)
				(xy 138.89355 -38.87851) (xy 138.89355 -39.16934) (xy 139.05865 -39.16934) (xy 139.05865 -38.85311)
				(arc
					(start 139.060682 -38.851078)
					(mid 139.077295 -38.781199)
					(end 139.10945 -38.716966)
				)
				(arc
					(start 139.10945 -38.716966)
					(mid 139.589118 -38.506928)
					(end 139.22375 -38.882066)
				)
				(xy 139.22375 -38.8874) (xy 139.22375 -39.16934)
				(arc
					(start 139.3698 -39.16934)
					(mid 139.88034 -38.6588)
					(end 139.3698 -38.14826)
				)
			)
		)
	)
	(zone
		(layer "In5.Cu")
		(hatch none 0.5)
		(connect_pads
			(clearance 0)
		)
		(min_thickness 0.25)
		(keepout
			(tracks not_allowed)
			(vias allowed)
			(pads allowed)
			(copperpour not_allowed)
			(footprints allowed)
		)
		(placement
			(enabled no)
			(sheetname "")
		)
		(fill
			(thermal_gap 0.5)
			(thermal_bridge_width 0.5)
			(island_removal_mode 0)
		)
		(polygon
			(pts
				(arc
					(start 310.425592 -34.5313)
					(mid 309.915052 -35.04184)
					(end 310.425592 -35.55238)
				)
				(arc
					(start 310.581294 -35.55238)
					(mid 310.556097 -35.420647)
					(end 310.507634 -35.295586)
				)
				(arc
					(start 310.507634 -35.295586)
					(mid 310.268211 -34.826551)
					(end 310.642508 -35.197034)
				)
				(arc
					(start 310.642508 -35.197034)
					(mid 310.713023 -35.369326)
					(end 310.746902 -35.55238)
				)
				(xy 310.91505 -35.55238) (xy 310.91505 -35.454844)
				(arc
					(start 310.916066 -35.453828)
					(mid 310.943765 -35.308531)
					(end 311.007252 -35.174936)
				)
				(arc
					(start 311.007252 -35.174936)
					(mid 311.415836 -34.842707)
					(end 311.132728 -35.286696)
				)
				(arc
					(start 311.132728 -35.286696)
					(mid 311.093513 -35.384557)
					(end 311.08015 -35.489134)
				)
				(xy 311.08015 -35.55238)
				(arc
					(start 311.238138 -35.55238)
					(mid 311.748932 -35.041967)
					(end 311.238392 -34.5313)
				)
			)
		)
	)
	(zone
		(layer "In5.Cu")
		(hatch none 0.5)
		(connect_pads
			(clearance 0)
		)
		(min_thickness 0.25)
		(keepout
			(tracks not_allowed)
			(vias allowed)
			(pads allowed)
			(copperpour not_allowed)
			(footprints allowed)
		)
		(placement
			(enabled no)
			(sheetname "")
		)
		(fill
			(thermal_gap 0.5)
			(thermal_bridge_width 0.5)
			(island_removal_mode 0)
		)
		(polygon
			(pts
				(arc
					(start 342.09355 -210.385914)
					(mid 341.58301 -210.896454)
					(end 342.09355 -211.406994)
				)
				(arc
					(start 342.906096 -211.406994)
					(mid 343.41689 -210.896581)
					(end 342.90635 -210.385914)
				)
				(xy 342.7476 -210.385914)
				(arc
					(start 342.7476 -210.490054)
					(mid 342.75942 -210.575519)
					(end 342.793828 -210.654646)
				)
				(arc
					(start 342.793828 -210.654646)
					(mid 343.089109 -211.0907)
					(end 342.671908 -210.769454)
				)
				(arc
					(start 342.671908 -210.769454)
					(mid 342.611099 -210.653452)
					(end 342.58377 -210.52536)
				)
				(xy 342.5825 -210.52409) (xy 342.5825 -210.385914) (xy 342.4174 -210.385914) (xy 342.4174 -210.52409)
				(arc
					(start 342.41613 -210.52536)
					(mid 342.388804 -210.653453)
					(end 342.327992 -210.769454)
				)
				(arc
					(start 342.327992 -210.769454)
					(mid 341.910843 -211.090645)
					(end 342.206072 -210.654646)
				)
				(arc
					(start 342.206072 -210.654646)
					(mid 342.240521 -210.575531)
					(end 342.2523 -210.490054)
				)
				(xy 342.2523 -210.385914)
			)
		)
	)
	(zone
		(layer "In5.Cu")
		(hatch none 0.5)
		(connect_pads
			(clearance 0)
		)
		(min_thickness 0.25)
		(keepout
			(tracks not_allowed)
			(vias allowed)
			(pads allowed)
			(copperpour not_allowed)
			(footprints allowed)
		)
		(placement
			(enabled no)
			(sheetname "")
		)
		(fill
			(thermal_gap 0.5)
			(thermal_bridge_width 0.5)
			(island_removal_mode 0)
		)
		(polygon
			(pts
				(arc
					(start 15.799054 -72.706484)
					(mid 15.28826 -73.216897)
					(end 15.7988 -73.727564)
				)
				(arc
					(start 16.6116 -73.727564)
					(mid 17.12214 -73.217024)
					(end 16.6116 -72.706484)
				)
				(xy 16.4211 -72.706484) (xy 16.4211 -72.936608)
				(arc
					(start 16.473424 -72.988932)
					(mid 16.800172 -73.405596)
					(end 16.383508 -73.078848)
				)
				(xy 16.331184 -73.026524) (xy 16.2941 -72.98944) (xy 16.2941 -72.936608) (xy 16.2941 -72.706484)
				(xy 16.1163 -72.706484) (xy 16.1163 -72.936608) (xy 16.1163 -72.98944) (xy 16.079216 -73.026524)
				(arc
					(start 16.026892 -73.078848)
					(mid 15.610228 -73.405596)
					(end 15.936976 -72.988932)
				)
				(xy 15.9893 -72.936608) (xy 15.9893 -72.706484)
			)
		)
	)
	(zone
		(layer "In5.Cu")
		(hatch none 0.5)
		(connect_pads
			(clearance 0)
		)
		(min_thickness 0.25)
		(keepout
			(tracks not_allowed)
			(vias allowed)
			(pads allowed)
			(copperpour not_allowed)
			(footprints allowed)
		)
		(placement
			(enabled no)
			(sheetname "")
		)
		(fill
			(thermal_gap 0.5)
			(thermal_bridge_width 0.5)
			(island_removal_mode 0)
		)
		(polygon
			(pts
				(arc
					(start 86.093808 -210.385914)
					(mid 85.583014 -210.896327)
					(end 86.093554 -211.406994)
				)
				(arc
					(start 86.906354 -211.406994)
					(mid 87.416894 -210.896454)
					(end 86.906354 -210.385914)
				)
				(arc
					(start 86.760558 -210.385914)
					(mid 86.791061 -210.514869)
					(end 86.839044 -210.63839)
				)
				(arc
					(start 86.839044 -210.63839)
					(mid 87.051237 -211.120607)
					(end 86.699344 -210.72856)
				)
				(arc
					(start 86.699344 -210.72856)
					(mid 86.632637 -210.561486)
					(end 86.593426 -210.385914)
				)
				(arc
					(start 86.406482 -210.385914)
					(mid 86.367259 -210.561483)
					(end 86.300564 -210.72856)
				)
				(arc
					(start 86.300564 -210.72856)
					(mid 85.948687 -211.120583)
					(end 86.160864 -210.63839)
				)
				(arc
					(start 86.160864 -210.63839)
					(mid 86.208835 -210.514866)
					(end 86.23935 -210.385914)
				)
			)
		)
	)
	(zone
		(layer "In5.Cu")
		(hatch none 0.5)
		(connect_pads
			(clearance 0)
		)
		(min_thickness 0.25)
		(keepout
			(tracks not_allowed)
			(vias allowed)
			(pads allowed)
			(copperpour not_allowed)
			(footprints allowed)
		)
		(placement
			(enabled no)
			(sheetname "")
		)
		(fill
			(thermal_gap 0.5)
			(thermal_bridge_width 0.5)
			(island_removal_mode 0)
		)
		(polygon
			(pts
				(arc
					(start 338.893658 -210.385914)
					(mid 338.383118 -210.896454)
					(end 338.893658 -211.406994)
				)
				(arc
					(start 339.706204 -211.406994)
					(mid 340.216998 -210.896581)
					(end 339.706458 -210.385914)
				)
				(arc
					(start 339.551264 -210.385914)
					(mid 339.576325 -210.517637)
					(end 339.62467 -210.642708)
				)
				(arc
					(start 339.62467 -210.642708)
					(mid 339.863238 -211.111803)
					(end 339.489542 -210.74126)
				)
				(arc
					(start 339.489542 -210.74126)
					(mid 339.419144 -210.568959)
					(end 339.385402 -210.385914)
				)
				(arc
					(start 339.214714 -210.385914)
					(mid 339.180987 -210.568963)
					(end 339.110574 -210.74126)
				)
				(arc
					(start 339.110574 -210.74126)
					(mid 338.736886 -211.111792)
					(end 338.975446 -210.642708)
				)
				(arc
					(start 338.975446 -210.642708)
					(mid 339.023825 -210.517647)
					(end 339.048852 -210.385914)
				)
			)
		)
	)
	(zone
		(layer "In5.Cu")
		(hatch none 0.5)
		(connect_pads
			(clearance 0)
		)
		(min_thickness 0.25)
		(keepout
			(tracks not_allowed)
			(vias allowed)
			(pads allowed)
			(copperpour not_allowed)
			(footprints allowed)
		)
		(placement
			(enabled no)
			(sheetname "")
		)
		(fill
			(thermal_gap 0.5)
			(thermal_bridge_width 0.5)
			(island_removal_mode 0)
		)
		(polygon
			(pts
				(arc
					(start 145.910554 -34.48558)
					(mid 145.39976 -34.995993)
					(end 145.9103 -35.50666)
				)
				(xy 146.06905 -35.50666)
				(arc
					(start 146.06905 -35.387534)
					(mid 146.057842 -35.309083)
					(end 146.025108 -35.236912)
				)
				(arc
					(start 146.025108 -35.236912)
					(mid 145.725854 -34.803399)
					(end 146.145758 -35.121342)
				)
				(arc
					(start 146.145758 -35.121342)
					(mid 146.205467 -35.230526)
					(end 146.232626 -35.351974)
				)
				(xy 146.23415 -35.353244) (xy 146.23415 -35.50666) (xy 146.39925 -35.50666) (xy 146.39925 -35.353244)
				(arc
					(start 146.400774 -35.351974)
					(mid 146.427905 -35.230515)
					(end 146.487642 -35.121342)
				)
				(arc
					(start 146.487642 -35.121342)
					(mid 146.907493 -34.803454)
					(end 146.608292 -35.236912)
				)
				(arc
					(start 146.608292 -35.236912)
					(mid 146.575565 -35.309085)
					(end 146.56435 -35.387534)
				)
				(xy 146.56435 -35.50666)
				(arc
					(start 146.7231 -35.50666)
					(mid 147.23364 -34.99612)
					(end 146.7231 -34.48558)
				)
			)
		)
	)
	(zone
		(layer "In5.Cu")
		(hatch none 0.5)
		(connect_pads
			(clearance 0)
		)
		(min_thickness 0.25)
		(keepout
			(tracks not_allowed)
			(vias allowed)
			(pads allowed)
			(copperpour not_allowed)
			(footprints allowed)
		)
		(placement
			(enabled no)
			(sheetname "")
		)
		(fill
			(thermal_gap 0.5)
			(thermal_bridge_width 0.5)
			(island_removal_mode 0)
		)
		(polygon
			(pts
				(arc
					(start 313.294014 -210.385914)
					(mid 312.78322 -210.896327)
					(end 313.29376 -211.406994)
				)
				(arc
					(start 314.10656 -211.406994)
					(mid 314.6171 -210.896454)
					(end 314.10656 -210.385914)
				)
				(arc
					(start 313.951366 -210.385914)
					(mid 313.976427 -210.517637)
					(end 314.024772 -210.642708)
				)
				(arc
					(start 314.024772 -210.642708)
					(mid 314.26334 -211.111803)
					(end 313.889644 -210.74126)
				)
				(arc
					(start 313.889644 -210.74126)
					(mid 313.819246 -210.568959)
					(end 313.785504 -210.385914)
				)
				(arc
					(start 313.614816 -210.385914)
					(mid 313.581089 -210.568963)
					(end 313.510676 -210.74126)
				)
				(arc
					(start 313.510676 -210.74126)
					(mid 313.136988 -211.111792)
					(end 313.375548 -210.642708)
				)
				(arc
					(start 313.375548 -210.642708)
					(mid 313.423927 -210.517647)
					(end 313.448954 -210.385914)
				)
			)
		)
	)
	(zone
		(layer "In5.Cu")
		(hatch none 0.5)
		(connect_pads
			(clearance 0)
		)
		(min_thickness 0.25)
		(keepout
			(tracks not_allowed)
			(vias allowed)
			(pads allowed)
			(copperpour not_allowed)
			(footprints allowed)
		)
		(placement
			(enabled no)
			(sheetname "")
		)
		(fill
			(thermal_gap 0.5)
			(thermal_bridge_width 0.5)
			(island_removal_mode 0)
		)
		(polygon
			(pts
				(arc
					(start 322.893944 -210.385914)
					(mid 322.38315 -210.896327)
					(end 322.89369 -211.406994)
				)
				(arc
					(start 323.70649 -211.406994)
					(mid 324.21703 -210.896454)
					(end 323.70649 -210.385914)
				)
				(arc
					(start 323.551296 -210.385914)
					(mid 323.576357 -210.517637)
					(end 323.624702 -210.642708)
				)
				(arc
					(start 323.624702 -210.642708)
					(mid 323.86327 -211.111803)
					(end 323.489574 -210.74126)
				)
				(arc
					(start 323.489574 -210.74126)
					(mid 323.419176 -210.568959)
					(end 323.385434 -210.385914)
				)
				(arc
					(start 323.214746 -210.385914)
					(mid 323.181019 -210.568963)
					(end 323.110606 -210.74126)
				)
				(arc
					(start 323.110606 -210.74126)
					(mid 322.736918 -211.111792)
					(end 322.975478 -210.642708)
				)
				(arc
					(start 322.975478 -210.642708)
					(mid 323.023857 -210.517647)
					(end 323.048884 -210.385914)
				)
			)
		)
	)
	(zone
		(layer "In5.Cu")
		(hatch none 0.5)
		(connect_pads
			(clearance 0)
		)
		(min_thickness 0.25)
		(keepout
			(tracks not_allowed)
			(vias allowed)
			(pads allowed)
			(copperpour not_allowed)
			(footprints allowed)
		)
		(placement
			(enabled no)
			(sheetname "")
		)
		(fill
			(thermal_gap 0.5)
			(thermal_bridge_width 0.5)
			(island_removal_mode 0)
		)
		(polygon
			(pts
				(arc
					(start 150.9141 -37.57676)
					(mid 150.40356 -38.0873)
					(end 150.9141 -38.59784)
				)
				(xy 151.07285 -38.59784)
				(arc
					(start 151.07285 -38.500304)
					(mid 151.062554 -38.411091)
					(end 151.03221 -38.326568)
				)
				(arc
					(start 151.03221 -38.326568)
					(mid 150.725382 -37.899237)
					(end 151.153368 -38.205156)
				)
				(arc
					(start 151.153368 -38.205156)
					(mid 151.211328 -38.329875)
					(end 151.236934 -38.464998)
				)
				(xy 151.23795 -38.466014) (xy 151.23795 -38.59784) (xy 151.40305 -38.59784) (xy 151.40305 -38.466014)
				(arc
					(start 151.404066 -38.464998)
					(mid 151.429678 -38.329877)
					(end 151.487632 -38.205156)
				)
				(arc
					(start 151.487632 -38.205156)
					(mid 151.91562 -37.899235)
					(end 151.60879 -38.326568)
				)
				(arc
					(start 151.60879 -38.326568)
					(mid 151.578444 -38.411091)
					(end 151.56815 -38.500304)
				)
				(xy 151.56815 -38.59784)
				(arc
					(start 151.726646 -38.59784)
					(mid 152.23744 -38.087427)
					(end 151.7269 -37.57676)
				)
			)
		)
	)
	(zone
		(layer "In5.Cu")
		(hatch none 0.5)
		(connect_pads
			(clearance 0)
		)
		(min_thickness 0.25)
		(keepout
			(tracks not_allowed)
			(vias allowed)
			(pads allowed)
			(copperpour not_allowed)
			(footprints allowed)
		)
		(placement
			(enabled no)
			(sheetname "")
		)
		(fill
			(thermal_gap 0.5)
			(thermal_bridge_width 0.5)
			(island_removal_mode 0)
		)
		(polygon
			(pts
				(arc
					(start 16.69034 -66.224404)
					(mid 16.179927 -65.71361)
					(end 15.66926 -66.22415)
				)
				(xy 15.66926 -66.41465) (xy 15.899384 -66.41465)
				(arc
					(start 15.951708 -66.362326)
					(mid 16.368372 -66.035578)
					(end 16.041624 -66.452242)
				)
				(xy 15.9893 -66.504566) (xy 15.952216 -66.54165) (xy 15.899384 -66.54165) (xy 15.66926 -66.54165)
				(xy 15.66926 -66.71945) (xy 15.899384 -66.71945) (xy 15.952216 -66.71945) (xy 15.9893 -66.756534)
				(arc
					(start 16.041624 -66.808858)
					(mid 16.368372 -67.225522)
					(end 15.951708 -66.898774)
				)
				(xy 15.899384 -66.84645) (xy 15.66926 -66.84645)
				(arc
					(start 15.66926 -67.03695)
					(mid 16.1798 -67.54749)
					(end 16.69034 -67.03695)
				)
			)
		)
	)
	(zone
		(layer "In5.Cu")
		(hatch none 0.5)
		(connect_pads
			(clearance 0)
		)
		(min_thickness 0.25)
		(keepout
			(tracks not_allowed)
			(vias allowed)
			(pads allowed)
			(copperpour not_allowed)
			(footprints allowed)
		)
		(placement
			(enabled no)
			(sheetname "")
		)
		(fill
			(thermal_gap 0.5)
			(thermal_bridge_width 0.5)
			(island_removal_mode 0)
		)
		(polygon
			(pts
				(arc
					(start 280.493978 -210.385914)
					(mid 279.983184 -210.896327)
					(end 280.493724 -211.406994)
				)
				(arc
					(start 281.306524 -211.406994)
					(mid 281.817064 -210.896454)
					(end 281.306524 -210.385914)
				)
				(arc
					(start 281.15133 -210.385914)
					(mid 281.176391 -210.517637)
					(end 281.224736 -210.642708)
				)
				(arc
					(start 281.224736 -210.642708)
					(mid 281.463304 -211.111803)
					(end 281.089608 -210.74126)
				)
				(arc
					(start 281.089608 -210.74126)
					(mid 281.01921 -210.568959)
					(end 280.985468 -210.385914)
				)
				(arc
					(start 280.81478 -210.385914)
					(mid 280.781053 -210.568963)
					(end 280.71064 -210.74126)
				)
				(arc
					(start 280.71064 -210.74126)
					(mid 280.336952 -211.111792)
					(end 280.575512 -210.642708)
				)
				(arc
					(start 280.575512 -210.642708)
					(mid 280.623891 -210.517647)
					(end 280.648918 -210.385914)
				)
			)
		)
	)
	(zone
		(layer "In5.Cu")
		(hatch none 0.5)
		(connect_pads
			(clearance 0)
		)
		(min_thickness 0.25)
		(keepout
			(tracks not_allowed)
			(vias allowed)
			(pads allowed)
			(copperpour not_allowed)
			(footprints allowed)
		)
		(placement
			(enabled no)
			(sheetname "")
		)
		(fill
			(thermal_gap 0.5)
			(thermal_bridge_width 0.5)
			(island_removal_mode 0)
		)
		(polygon
			(pts
				(arc
					(start 162.6997 -81.15046)
					(mid 162.18916 -81.661)
					(end 162.6997 -82.17154)
				)
				(arc
					(start 162.854894 -82.17154)
					(mid 162.829841 -82.039813)
					(end 162.781488 -81.914746)
				)
				(arc
					(start 162.781488 -81.914746)
					(mid 162.54292 -81.445651)
					(end 162.916616 -81.816194)
				)
				(arc
					(start 162.916616 -81.816194)
					(mid 162.986995 -81.988499)
					(end 163.020756 -82.17154)
				)
				(arc
					(start 163.191444 -82.17154)
					(mid 163.225162 -81.988486)
					(end 163.295584 -81.816194)
				)
				(arc
					(start 163.295584 -81.816194)
					(mid 163.669272 -81.445662)
					(end 163.430712 -81.914746)
				)
				(arc
					(start 163.430712 -81.914746)
					(mid 163.382349 -82.039811)
					(end 163.357306 -82.17154)
				)
				(arc
					(start 163.512246 -82.17154)
					(mid 164.02304 -81.661127)
					(end 163.5125 -81.15046)
				)
			)
		)
	)
	(zone
		(layer "In5.Cu")
		(hatch none 0.5)
		(connect_pads
			(clearance 0)
		)
		(min_thickness 0.25)
		(keepout
			(tracks not_allowed)
			(vias allowed)
			(pads allowed)
			(copperpour not_allowed)
			(footprints allowed)
		)
		(placement
			(enabled no)
			(sheetname "")
		)
		(fill
			(thermal_gap 0.5)
			(thermal_bridge_width 0.5)
			(island_removal_mode 0)
		)
		(polygon
			(pts
				(arc
					(start 312.67654 -35.675062)
					(mid 312.165746 -36.185475)
					(end 312.676286 -36.696142)
				)
				(arc
					(start 312.80989 -36.696142)
					(mid 312.79444 -36.56565)
					(end 312.753248 -36.440872)
				)
				(arc
					(start 312.753248 -36.440872)
					(mid 312.523015 -35.967441)
					(end 312.890408 -36.344606)
				)
				(arc
					(start 312.890408 -36.344606)
					(mid 312.949371 -36.504072)
					(end 312.974228 -36.672266)
				)
				(xy 312.97499 -36.673028) (xy 312.97499 -36.696142) (xy 313.14009 -36.696142) (xy 313.14009 -36.604448)
				(arc
					(start 313.14136 -36.603432)
					(mid 313.175275 -36.448429)
					(end 313.253374 -36.310316)
				)
				(arc
					(start 313.253374 -36.310316)
					(mid 313.674084 -35.993536)
					(end 313.373262 -36.425886)
				)
				(arc
					(start 313.373262 -36.425886)
					(mid 313.32265 -36.527012)
					(end 313.30519 -36.638738)
				)
				(xy 313.30519 -36.696142)
				(arc
					(start 313.489086 -36.696142)
					(mid 313.999626 -36.185602)
					(end 313.489086 -35.675062)
				)
			)
		)
	)
	(zone
		(layer "In5.Cu")
		(hatch none 0.5)
		(connect_pads
			(clearance 0)
		)
		(min_thickness 0.25)
		(keepout
			(tracks not_allowed)
			(vias allowed)
			(pads allowed)
			(copperpour not_allowed)
			(footprints allowed)
		)
		(placement
			(enabled no)
			(sheetname "")
		)
		(fill
			(thermal_gap 0.5)
			(thermal_bridge_width 0.5)
			(island_removal_mode 0)
		)
		(polygon
			(pts
				(arc
					(start 274.09394 -210.385914)
					(mid 273.583146 -210.896327)
					(end 274.093686 -211.406994)
				)
				(arc
					(start 274.906486 -211.406994)
					(mid 275.417026 -210.896454)
					(end 274.906486 -210.385914)
				)
				(arc
					(start 274.751292 -210.385914)
					(mid 274.776353 -210.517637)
					(end 274.824698 -210.642708)
				)
				(arc
					(start 274.824698 -210.642708)
					(mid 275.063266 -211.111803)
					(end 274.68957 -210.74126)
				)
				(arc
					(start 274.68957 -210.74126)
					(mid 274.619172 -210.568959)
					(end 274.58543 -210.385914)
				)
				(arc
					(start 274.414742 -210.385914)
					(mid 274.381015 -210.568963)
					(end 274.310602 -210.74126)
				)
				(arc
					(start 274.310602 -210.74126)
					(mid 273.936914 -211.111792)
					(end 274.175474 -210.642708)
				)
				(arc
					(start 274.175474 -210.642708)
					(mid 274.223853 -210.517647)
					(end 274.24888 -210.385914)
				)
			)
		)
	)
	(zone
		(layer "In5.Cu")
		(hatch none 0.5)
		(connect_pads
			(clearance 0)
		)
		(min_thickness 0.25)
		(keepout
			(tracks not_allowed)
			(vias allowed)
			(pads allowed)
			(copperpour not_allowed)
			(footprints allowed)
		)
		(placement
			(enabled no)
			(sheetname "")
		)
		(fill
			(thermal_gap 0.5)
			(thermal_bridge_width 0.5)
			(island_removal_mode 0)
		)
		(polygon
			(pts
				(arc
					(start 319.694052 -210.385914)
					(mid 319.183258 -210.896327)
					(end 319.693798 -211.406994)
				)
				(arc
					(start 320.506598 -211.406994)
					(mid 321.017138 -210.896454)
					(end 320.506598 -210.385914)
				)
				(arc
					(start 320.351404 -210.385914)
					(mid 320.376465 -210.517637)
					(end 320.42481 -210.642708)
				)
				(arc
					(start 320.42481 -210.642708)
					(mid 320.663378 -211.111803)
					(end 320.289682 -210.74126)
				)
				(arc
					(start 320.289682 -210.74126)
					(mid 320.219284 -210.568959)
					(end 320.185542 -210.385914)
				)
				(arc
					(start 320.014854 -210.385914)
					(mid 319.981127 -210.568963)
					(end 319.910714 -210.74126)
				)
				(arc
					(start 319.910714 -210.74126)
					(mid 319.537026 -211.111792)
					(end 319.775586 -210.642708)
				)
				(arc
					(start 319.775586 -210.642708)
					(mid 319.823965 -210.517647)
					(end 319.848992 -210.385914)
				)
			)
		)
	)
	(zone
		(layer "In5.Cu")
		(hatch none 0.5)
		(connect_pads
			(clearance 0)
		)
		(min_thickness 0.25)
		(keepout
			(tracks not_allowed)
			(vias allowed)
			(pads allowed)
			(copperpour not_allowed)
			(footprints allowed)
		)
		(placement
			(enabled no)
			(sheetname "")
		)
		(fill
			(thermal_gap 0.5)
			(thermal_bridge_width 0.5)
			(island_removal_mode 0)
		)
		(polygon
			(pts
				(arc
					(start 183.59374 -28.994354)
					(mid 183.083327 -28.48356)
					(end 182.57266 -28.9941)
				)
				(arc
					(start 182.57266 -29.8069)
					(mid 183.0832 -30.31744)
					(end 183.59374 -29.8069)
				)
				(xy 183.59374 -29.64815)
				(arc
					(start 183.488076 -29.64815)
					(mid 183.402535 -29.658023)
					(end 183.321452 -29.687012)
				)
				(arc
					(start 183.321452 -29.687012)
					(mid 182.896298 -29.997176)
					(end 183.19877 -29.566616)
				)
				(arc
					(start 183.19877 -29.566616)
					(mid 183.320639 -29.509645)
					(end 183.45277 -29.48432)
				)
				(xy 183.453786 -29.48305) (xy 183.59374 -29.48305) (xy 183.59374 -29.31795) (xy 183.453786 -29.31795)
				(arc
					(start 183.45277 -29.31668)
					(mid 183.320616 -29.291424)
					(end 183.19877 -29.234384)
				)
				(arc
					(start 183.19877 -29.234384)
					(mid 182.896357 -28.803883)
					(end 183.321452 -29.113988)
				)
				(arc
					(start 183.321452 -29.113988)
					(mid 183.402534 -29.14298)
					(end 183.488076 -29.15285)
				)
				(xy 183.59374 -29.15285)
			)
		)
	)
	(zone
		(layer "In5.Cu")
		(hatch none 0.5)
		(connect_pads
			(clearance 0)
		)
		(min_thickness 0.25)
		(keepout
			(tracks not_allowed)
			(vias allowed)
			(pads allowed)
			(copperpour not_allowed)
			(footprints allowed)
		)
		(placement
			(enabled no)
			(sheetname "")
		)
		(fill
			(thermal_gap 0.5)
			(thermal_bridge_width 0.5)
			(island_removal_mode 0)
		)
		(polygon
			(pts
				(arc
					(start 270.894048 -210.385914)
					(mid 270.383254 -210.896327)
					(end 270.893794 -211.406994)
				)
				(arc
					(start 271.706594 -211.406994)
					(mid 272.217134 -210.896454)
					(end 271.706594 -210.385914)
				)
				(arc
					(start 271.575276 -210.385914)
					(mid 271.589504 -210.516224)
					(end 271.629886 -210.64093)
				)
				(arc
					(start 271.629886 -210.64093)
					(mid 271.859833 -211.114845)
					(end 271.492472 -210.73745)
				)
				(arc
					(start 271.492472 -210.73745)
					(mid 271.435157 -210.581387)
					(end 271.410938 -210.416902)
				)
				(xy 271.410176 -210.41614) (xy 271.410176 -210.385914) (xy 271.245076 -210.385914) (xy 271.245076 -210.44789)
				(arc
					(start 271.24406 -210.448906)
					(mid 271.209375 -210.617453)
					(end 271.128236 -210.7692)
				)
				(arc
					(start 271.128236 -210.7692)
					(mid 270.710879 -211.090615)
					(end 271.006824 -210.6549)
				)
				(arc
					(start 271.006824 -210.6549)
					(mid 271.061281 -210.539671)
					(end 271.079976 -210.4136)
				)
				(xy 271.079976 -210.385914)
			)
		)
	)
	(zone
		(layer "In5.Cu")
		(hatch none 0.5)
		(connect_pads
			(clearance 0)
		)
		(min_thickness 0.25)
		(keepout
			(tracks not_allowed)
			(vias allowed)
			(pads allowed)
			(copperpour not_allowed)
			(footprints allowed)
		)
		(placement
			(enabled no)
			(sheetname "")
		)
		(fill
			(thermal_gap 0.5)
			(thermal_bridge_width 0.5)
			(island_removal_mode 0)
		)
		(polygon
			(pts
				(arc
					(start 20.396454 -86.91626)
					(mid 19.88566 -87.426673)
					(end 20.3962 -87.93734)
				)
				(arc
					(start 21.209 -87.93734)
					(mid 21.71954 -87.4268)
					(end 21.209 -86.91626)
				)
				(xy 21.044154 -86.91626)
				(arc
					(start 21.044154 -87.098632)
					(mid 21.052734 -87.141678)
					(end 21.077174 -87.178134)
				)
				(arc
					(start 21.088096 -87.189056)
					(mid 21.3976 -87.6154)
					(end 20.971256 -87.305896)
				)
				(xy 20.960334 -87.294974) (xy 20.936204 -87.270844)
				(arc
					(start 20.936204 -87.267288)
					(mid 20.900268 -87.20482)
					(end 20.881594 -87.135208)
				)
				(xy 20.879054 -87.132922) (xy 20.879054 -86.91626) (xy 20.713954 -86.91626) (xy 20.713954 -87.132922)
				(arc
					(start 20.711668 -87.134954)
					(mid 20.690506 -87.216161)
					(end 20.648168 -87.288624)
				)
				(xy 20.648168 -87.291672)
				(arc
					(start 20.633944 -87.305896)
					(mid 20.207801 -87.615601)
					(end 20.516596 -87.188802)
				)
				(arc
					(start 20.516596 -87.188802)
					(mid 20.540533 -87.146512)
					(end 20.548854 -87.098632)
				)
				(xy 20.548854 -86.91626)
			)
		)
	)
	(zone
		(layer "In5.Cu")
		(hatch none 0.5)
		(connect_pads
			(clearance 0)
		)
		(min_thickness 0.25)
		(keepout
			(tracks not_allowed)
			(vias allowed)
			(pads allowed)
			(copperpour not_allowed)
			(footprints allowed)
		)
		(placement
			(enabled no)
			(sheetname "")
		)
		(fill
			(thermal_gap 0.5)
			(thermal_bridge_width 0.5)
			(island_removal_mode 0)
		)
		(polygon
			(pts
				(arc
					(start 92.224098 -185.217816)
					(mid 92.263168 -185.204401)
					(end 92.296488 -185.17997)
				)
				(xy 92.435172 -185.041286) (xy 92.333826 -184.93994)
				(arc
					(start 92.332048 -184.941718)
					(mid 91.61018 -184.941718)
					(end 91.61018 -185.663586)
				)
				(xy 91.608402 -185.665364) (xy 92.18295 -186.240166) (xy 92.183204 -186.240166)
				(arc
					(start 92.184982 -186.238388)
					(mid 92.90685 -186.238388)
					(end 92.90685 -185.51652)
				)
				(xy 92.908628 -185.514742) (xy 92.785692 -185.391806)
				(arc
					(start 92.647262 -185.530236)
					(mid 92.633402 -185.550979)
					(end 92.628466 -185.575448)
				)
				(arc
					(start 92.628466 -185.623962)
					(mid 92.545916 -186.144049)
					(end 92.463366 -185.623962)
				)
				(xy 92.463366 -185.541158)
				(arc
					(start 92.466414 -185.53811)
					(mid 92.480824 -185.487689)
					(end 92.506292 -185.441844)
				)
				(xy 92.506292 -185.437526) (xy 92.530422 -185.413396) (xy 92.668852 -185.274966) (xy 92.552012 -185.158126)
				(xy 92.389198 -185.32094)
				(arc
					(start 92.385896 -185.32094)
					(mid 92.315212 -185.362205)
					(end 92.236036 -185.382916)
				)
				(xy 92.234004 -185.385202)
				(arc
					(start 92.224606 -185.385202)
					(mid 91.704442 -185.303322)
					(end 92.224098 -185.217816)
				)
			)
		)
	)
	(zone
		(layer "In5.Cu")
		(hatch none 0.5)
		(connect_pads
			(clearance 0)
		)
		(min_thickness 0.25)
		(keepout
			(tracks not_allowed)
			(vias allowed)
			(pads allowed)
			(copperpour not_allowed)
			(footprints allowed)
		)
		(placement
			(enabled no)
			(sheetname "")
		)
		(fill
			(thermal_gap 0.5)
			(thermal_bridge_width 0.5)
			(island_removal_mode 0)
		)
		(polygon
			(pts
				(xy 324.086982 -35.479482) (xy 324.086982 -35.429952)
				(arc
					(start 324.087998 -35.42919)
					(mid 324.119767 -35.258944)
					(end 324.194678 -35.1028)
				)
				(arc
					(start 324.194678 -35.1028)
					(mid 324.602819 -34.769849)
					(end 324.3199 -35.214052)
				)
				(arc
					(start 324.3199 -35.214052)
					(mid 324.269327 -35.334631)
					(end 324.252082 -35.464242)
				)
				(xy 324.252082 -35.479482)
				(arc
					(start 324.42531 -35.479482)
					(mid 324.93585 -34.968942)
					(end 324.42531 -34.458402)
				)
				(arc
					(start 323.612764 -34.458402)
					(mid 323.10197 -34.968815)
					(end 323.61251 -35.479482)
				)
				(xy 323.756782 -35.479482)
				(arc
					(start 323.756782 -35.463734)
					(mid 323.742799 -35.338994)
					(end 323.701664 -35.220402)
				)
				(arc
					(start 323.701664 -35.220402)
					(mid 323.44822 -34.758981)
					(end 323.834252 -35.117024)
				)
				(arc
					(start 323.834252 -35.117024)
					(mid 323.895221 -35.268229)
					(end 323.92112 -35.42919)
				)
				(xy 323.921882 -35.429952) (xy 323.921882 -35.479482)
			)
		)
	)
	(zone
		(layer "In5.Cu")
		(hatch none 0.5)
		(connect_pads
			(clearance 0)
		)
		(min_thickness 0.25)
		(keepout
			(tracks not_allowed)
			(vias allowed)
			(pads allowed)
			(copperpour not_allowed)
			(footprints allowed)
		)
		(placement
			(enabled no)
			(sheetname "")
		)
		(fill
			(thermal_gap 0.5)
			(thermal_bridge_width 0.5)
			(island_removal_mode 0)
		)
		(polygon
			(pts
				(arc
					(start 98.094038 -210.385914)
					(mid 97.583244 -210.896327)
					(end 98.093784 -211.406994)
				)
				(arc
					(start 98.906584 -211.406994)
					(mid 99.417124 -210.896454)
					(end 98.906584 -210.385914)
				)
				(arc
					(start 98.760788 -210.385914)
					(mid 98.791291 -210.514869)
					(end 98.839274 -210.63839)
				)
				(arc
					(start 98.839274 -210.63839)
					(mid 99.051467 -211.120607)
					(end 98.699574 -210.72856)
				)
				(arc
					(start 98.699574 -210.72856)
					(mid 98.632867 -210.561486)
					(end 98.593656 -210.385914)
				)
				(arc
					(start 98.406712 -210.385914)
					(mid 98.367489 -210.561483)
					(end 98.300794 -210.72856)
				)
				(arc
					(start 98.300794 -210.72856)
					(mid 97.948917 -211.120583)
					(end 98.161094 -210.63839)
				)
				(arc
					(start 98.161094 -210.63839)
					(mid 98.209065 -210.514866)
					(end 98.23958 -210.385914)
				)
			)
		)
	)
	(zone
		(net "P1V26_STBY")
		(layer "In5.Cu")
		(hatch none 0.5)
		(connect_pads
			(clearance 0.5)
		)
		(min_thickness 0.25)
		(fill yes
			(thermal_gap 0.5)
			(thermal_bridge_width 0.5)
			(island_removal_mode 0)
		)
		(polygon
			(pts
				(xy 34.417 -125.603) (xy 34.417 -122.428) (xy 30.2768 -118.2878) (xy 18.034 -118.2878) (xy 16.9418 -117.1956)
				(xy 16.51 -117.1956) (xy 16.129 -116.8146) (xy 16.129 -115.2652) (xy 16.129 -114.827812) (xy 16.283686 -114.673126)
				(xy 17.140682 -114.673126) (xy 20.312126 -114.673126) (xy 20.4216 -114.7826) (xy 20.9042 -115.2652)
				(xy 21.971 -116.332) (xy 23.5204 -116.332) (xy 23.8252 -116.0272) (xy 38.1 -116.0272) (xy 43.0784 -121.0056)
				(xy 43.18 -121.1072) (xy 43.18 -127.3048) (xy 43.0657 -127.4191) (xy 42.545 -127.9398) (xy 42.545 -128.27)
				(xy 43.307 -129.032) (xy 43.307 -133.096) (xy 42.926 -133.477) (xy 42.164 -133.477) (xy 41.7322 -133.477)
				(xy 41.4274 -133.1722) (xy 41.4274 -130.0734) (xy 40.4876 -129.1336) (xy 36.957 -129.1336) (xy 36.1188 -129.9718)
				(xy 36.1188 -132.6388) (xy 37.5158 -134.0358) (xy 37.5158 -134.62) (xy 37.3888 -134.747) (xy 36.576 -134.747)
				(xy 35.941 -134.112) (xy 34.671 -134.112) (xy 33.782 -133.223) (xy 33.782 -132.461) (xy 34.544 -131.699)
				(xy 34.544 -130.683) (xy 33.909 -130.048) (xy 33.909 -128.905) (xy 34.417 -128.397)
			)
		)
	)
	(zone
		(layer "In5.Cu")
		(hatch none 0.5)
		(connect_pads
			(clearance 0)
		)
		(min_thickness 0.25)
		(keepout
			(tracks not_allowed)
			(vias allowed)
			(pads allowed)
			(copperpour not_allowed)
			(footprints allowed)
		)
		(placement
			(enabled no)
			(sheetname "")
		)
		(fill
			(thermal_gap 0.5)
			(thermal_bridge_width 0.5)
			(island_removal_mode 0)
		)
		(polygon
			(pts
				(arc
					(start 277.293832 -210.385914)
					(mid 276.783038 -210.896327)
					(end 277.293578 -211.406994)
				)
				(arc
					(start 278.106378 -211.406994)
					(mid 278.616918 -210.896454)
					(end 278.106378 -210.385914)
				)
				(arc
					(start 277.951184 -210.385914)
					(mid 277.976245 -210.517637)
					(end 278.02459 -210.642708)
				)
				(arc
					(start 278.02459 -210.642708)
					(mid 278.263158 -211.111803)
					(end 277.889462 -210.74126)
				)
				(arc
					(start 277.889462 -210.74126)
					(mid 277.819064 -210.568959)
					(end 277.785322 -210.385914)
				)
				(arc
					(start 277.614634 -210.385914)
					(mid 277.580907 -210.568963)
					(end 277.510494 -210.74126)
				)
				(arc
					(start 277.510494 -210.74126)
					(mid 277.136806 -211.111792)
					(end 277.375366 -210.642708)
				)
				(arc
					(start 277.375366 -210.642708)
					(mid 277.423745 -210.517647)
					(end 277.448772 -210.385914)
				)
			)
		)
	)
	(zone
		(layer "In5.Cu")
		(hatch none 0.5)
		(connect_pads
			(clearance 0)
		)
		(min_thickness 0.25)
		(keepout
			(tracks not_allowed)
			(vias allowed)
			(pads allowed)
			(copperpour not_allowed)
			(footprints allowed)
		)
		(placement
			(enabled no)
			(sheetname "")
		)
		(fill
			(thermal_gap 0.5)
			(thermal_bridge_width 0.5)
			(island_removal_mode 0)
		)
		(polygon
			(pts
				(arc
					(start 181.47284 -12.18438)
					(mid 181.399202 -12.214882)
					(end 181.3687 -12.28852)
				)
				(xy 181.3687 -12.64412) (xy 181.369716 -12.659106) (xy 181.369716 -13.338302) (xy 181.3687 -13.35278)
				(arc
					(start 181.3687 -13.70838)
					(mid 181.399202 -13.782018)
					(end 181.47284 -13.81252)
				)
				(arc
					(start 182.299356 -13.81252)
					(mid 182.315161 -13.816293)
					(end 182.33136 -13.8176)
				)
				(arc
					(start 182.68696 -13.8176)
					(mid 182.760598 -13.787098)
					(end 182.7911 -13.71346)
				)
				(xy 182.7911 -13.35786)
				(arc
					(start 182.7911 -12.676124)
					(mid 182.794873 -12.660319)
					(end 182.79618 -12.64412)
				)
				(arc
					(start 182.79618 -12.28852)
					(mid 182.765678 -12.214882)
					(end 182.69204 -12.18438)
				)
				(xy 182.33644 -12.18438) (xy 182.32628 -12.184888) (xy 181.838346 -12.184888) (xy 181.82844 -12.18438)
			)
		)
	)
	(zone
		(layer "In5.Cu")
		(hatch none 0.5)
		(connect_pads
			(clearance 0)
		)
		(min_thickness 0.25)
		(keepout
			(tracks not_allowed)
			(vias allowed)
			(pads allowed)
			(copperpour not_allowed)
			(footprints allowed)
		)
		(placement
			(enabled no)
			(sheetname "")
		)
		(fill
			(thermal_gap 0.5)
			(thermal_bridge_width 0.5)
			(island_removal_mode 0)
		)
		(polygon
			(pts
				(arc
					(start 310.093868 -210.385914)
					(mid 309.583328 -210.896454)
					(end 310.093868 -211.406994)
				)
				(arc
					(start 310.906414 -211.406994)
					(mid 311.417208 -210.896581)
					(end 310.906668 -210.385914)
				)
				(arc
					(start 310.751474 -210.385914)
					(mid 310.776535 -210.517637)
					(end 310.82488 -210.642708)
				)
				(arc
					(start 310.82488 -210.642708)
					(mid 311.063448 -211.111803)
					(end 310.689752 -210.74126)
				)
				(arc
					(start 310.689752 -210.74126)
					(mid 310.619354 -210.568959)
					(end 310.585612 -210.385914)
				)
				(arc
					(start 310.414924 -210.385914)
					(mid 310.381197 -210.568963)
					(end 310.310784 -210.74126)
				)
				(arc
					(start 310.310784 -210.74126)
					(mid 309.937096 -211.111792)
					(end 310.175656 -210.642708)
				)
				(arc
					(start 310.175656 -210.642708)
					(mid 310.224035 -210.517647)
					(end 310.249062 -210.385914)
				)
			)
		)
	)
	(zone
		(layer "In5.Cu")
		(hatch none 0.5)
		(connect_pads
			(clearance 0)
		)
		(min_thickness 0.25)
		(keepout
			(tracks not_allowed)
			(vias allowed)
			(pads allowed)
			(copperpour not_allowed)
			(footprints allowed)
		)
		(placement
			(enabled no)
			(sheetname "")
		)
		(fill
			(thermal_gap 0.5)
			(thermal_bridge_width 0.5)
			(island_removal_mode 0)
		)
		(polygon
			(pts
				(arc
					(start 203.29398 -210.385914)
					(mid 202.783186 -210.896327)
					(end 203.293726 -211.406994)
				)
				(arc
					(start 204.106526 -211.406994)
					(mid 204.617066 -210.896454)
					(end 204.106526 -210.385914)
				)
				(arc
					(start 203.951332 -210.385914)
					(mid 203.976393 -210.517637)
					(end 204.024738 -210.642708)
				)
				(arc
					(start 204.024738 -210.642708)
					(mid 204.263306 -211.111803)
					(end 203.88961 -210.74126)
				)
				(arc
					(start 203.88961 -210.74126)
					(mid 203.819212 -210.568959)
					(end 203.78547 -210.385914)
				)
				(arc
					(start 203.614782 -210.385914)
					(mid 203.581055 -210.568963)
					(end 203.510642 -210.74126)
				)
				(arc
					(start 203.510642 -210.74126)
					(mid 203.136954 -211.111792)
					(end 203.375514 -210.642708)
				)
				(arc
					(start 203.375514 -210.642708)
					(mid 203.423893 -210.517647)
					(end 203.44892 -210.385914)
				)
			)
		)
	)
	(zone
		(layer "In5.Cu")
		(hatch none 0.5)
		(connect_pads
			(clearance 0)
		)
		(min_thickness 0.25)
		(keepout
			(tracks not_allowed)
			(vias allowed)
			(pads allowed)
			(copperpour not_allowed)
			(footprints allowed)
		)
		(placement
			(enabled no)
			(sheetname "")
		)
		(fill
			(thermal_gap 0.5)
			(thermal_bridge_width 0.5)
			(island_removal_mode 0)
		)
		(polygon
			(pts
				(arc
					(start 154.493976 -210.385914)
					(mid 153.983182 -210.896327)
					(end 154.493722 -211.406994)
				)
				(arc
					(start 155.306522 -211.406994)
					(mid 155.817062 -210.896454)
					(end 155.306522 -210.385914)
				)
				(arc
					(start 155.151328 -210.385914)
					(mid 155.176389 -210.517637)
					(end 155.224734 -210.642708)
				)
				(arc
					(start 155.224734 -210.642708)
					(mid 155.463302 -211.111803)
					(end 155.089606 -210.74126)
				)
				(arc
					(start 155.089606 -210.74126)
					(mid 155.019208 -210.568959)
					(end 154.985466 -210.385914)
				)
				(arc
					(start 154.814778 -210.385914)
					(mid 154.781051 -210.568963)
					(end 154.710638 -210.74126)
				)
				(arc
					(start 154.710638 -210.74126)
					(mid 154.33695 -211.111792)
					(end 154.57551 -210.642708)
				)
				(arc
					(start 154.57551 -210.642708)
					(mid 154.623889 -210.517647)
					(end 154.648916 -210.385914)
				)
			)
		)
	)
	(zone
		(layer "In5.Cu")
		(hatch none 0.5)
		(connect_pads
			(clearance 0)
		)
		(min_thickness 0.25)
		(keepout
			(tracks not_allowed)
			(vias allowed)
			(pads allowed)
			(copperpour not_allowed)
			(footprints allowed)
		)
		(placement
			(enabled no)
			(sheetname "")
		)
		(fill
			(thermal_gap 0.5)
			(thermal_bridge_width 0.5)
			(island_removal_mode 0)
		)
		(polygon
			(pts
				(arc
					(start 89.293954 -210.385914)
					(mid 88.78316 -210.896327)
					(end 89.2937 -211.406994)
				)
				(arc
					(start 90.1065 -211.406994)
					(mid 90.61704 -210.896454)
					(end 90.1065 -210.385914)
				)
				(arc
					(start 89.960704 -210.385914)
					(mid 89.991207 -210.514869)
					(end 90.03919 -210.63839)
				)
				(arc
					(start 90.03919 -210.63839)
					(mid 90.251383 -211.120607)
					(end 89.89949 -210.72856)
				)
				(arc
					(start 89.89949 -210.72856)
					(mid 89.832783 -210.561486)
					(end 89.793572 -210.385914)
				)
				(arc
					(start 89.606628 -210.385914)
					(mid 89.567405 -210.561483)
					(end 89.50071 -210.72856)
				)
				(arc
					(start 89.50071 -210.72856)
					(mid 89.148833 -211.120583)
					(end 89.36101 -210.63839)
				)
				(arc
					(start 89.36101 -210.63839)
					(mid 89.408981 -210.514866)
					(end 89.439496 -210.385914)
				)
			)
		)
	)
	(zone
		(layer "In5.Cu")
		(hatch none 0.5)
		(connect_pads
			(clearance 0)
		)
		(min_thickness 0.25)
		(keepout
			(tracks not_allowed)
			(vias allowed)
			(pads allowed)
			(copperpour not_allowed)
			(footprints allowed)
		)
		(placement
			(enabled no)
			(sheetname "")
		)
		(fill
			(thermal_gap 0.5)
			(thermal_bridge_width 0.5)
			(island_removal_mode 0)
		)
		(polygon
			(pts
				(arc
					(start 18.8468 -54.487572)
					(mid 18.33626 -54.998112)
					(end 18.8468 -55.508652)
				)
				(xy 19.0373 -55.508652) (xy 19.0373 -55.278528)
				(arc
					(start 18.984976 -55.226204)
					(mid 18.658228 -54.80954)
					(end 19.074892 -55.136288)
				)
				(xy 19.127216 -55.188612) (xy 19.1643 -55.225696) (xy 19.1643 -55.278528) (xy 19.1643 -55.508652)
				(xy 19.3421 -55.508652) (xy 19.3421 -55.278528) (xy 19.3421 -55.225696) (xy 19.379184 -55.188612)
				(arc
					(start 19.431508 -55.136288)
					(mid 19.848172 -54.80954)
					(end 19.521424 -55.226204)
				)
				(xy 19.4691 -55.278528) (xy 19.4691 -55.508652)
				(arc
					(start 19.659346 -55.508652)
					(mid 20.17014 -54.998239)
					(end 19.6596 -54.487572)
				)
			)
		)
	)
	(zone
		(net "DUT_VDDO")
		(layer "In5.Cu")
		(hatch none 0.5)
		(connect_pads
			(clearance 0.5)
		)
		(min_thickness 0.25)
		(fill yes
			(thermal_gap 0.5)
			(thermal_bridge_width 0.5)
			(island_removal_mode 0)
		)
		(polygon
			(pts
				(xy 235.712 -37.973) (xy 234.569 -37.973) (xy 234.315 -38.227) (xy 234.315 -41.021) (xy 234.569 -41.275)
				(xy 238.125 -41.275) (xy 238.252 -41.148) (xy 238.252 -40.132) (xy 237.871 -39.751) (xy 235.966 -39.751)
				(xy 235.839 -39.624) (xy 235.839 -38.1)
			)
		)
	)
	(zone
		(layer "In5.Cu")
		(hatch none 0.5)
		(connect_pads
			(clearance 0)
		)
		(min_thickness 0.25)
		(keepout
			(tracks not_allowed)
			(vias allowed)
			(pads allowed)
			(copperpour not_allowed)
			(footprints allowed)
		)
		(placement
			(enabled no)
			(sheetname "")
		)
		(fill
			(thermal_gap 0.5)
			(thermal_bridge_width 0.5)
			(island_removal_mode 0)
		)
		(polygon
			(pts
				(arc
					(start 14.68374 -67.638676)
					(mid 14.173327 -67.127882)
					(end 13.66266 -67.638422)
				)
				(arc
					(start 13.66266 -68.451222)
					(mid 14.1732 -68.961762)
					(end 14.68374 -68.451222)
				)
				(xy 14.68374 -68.2625) (xy 14.451838 -68.2625)
				(arc
					(start 14.401292 -68.313046)
					(mid 13.984628 -68.639794)
					(end 14.311376 -68.22313)
				)
				(xy 14.361922 -68.172584) (xy 14.399006 -68.1355) (xy 14.451838 -68.1355) (xy 14.68374 -68.1355)
				(xy 14.68374 -67.9577) (xy 14.455394 -67.9577) (xy 14.402562 -67.9577) (xy 14.365478 -67.920616)
				(arc
					(start 14.311376 -67.866514)
					(mid 13.984628 -67.44985)
					(end 14.401292 -67.776598)
				)
				(xy 14.455394 -67.8307) (xy 14.68374 -67.8307)
			)
		)
	)
	(zone
		(layer "In5.Cu")
		(hatch none 0.5)
		(connect_pads
			(clearance 0)
		)
		(min_thickness 0.25)
		(keepout
			(tracks not_allowed)
			(vias allowed)
			(pads allowed)
			(copperpour not_allowed)
			(footprints allowed)
		)
		(placement
			(enabled no)
			(sheetname "")
		)
		(fill
			(thermal_gap 0.5)
			(thermal_bridge_width 0.5)
			(island_removal_mode 0)
		)
		(polygon
			(pts
				(arc
					(start 54.893718 -210.385914)
					(mid 54.383178 -210.896454)
					(end 54.893718 -211.406994)
				)
				(arc
					(start 55.706264 -211.406994)
					(mid 56.217058 -210.896581)
					(end 55.706518 -210.385914)
				)
				(arc
					(start 55.560722 -210.385914)
					(mid 55.591225 -210.514869)
					(end 55.639208 -210.63839)
				)
				(arc
					(start 55.639208 -210.63839)
					(mid 55.851401 -211.120607)
					(end 55.499508 -210.72856)
				)
				(arc
					(start 55.499508 -210.72856)
					(mid 55.432801 -210.561486)
					(end 55.39359 -210.385914)
				)
				(arc
					(start 55.206646 -210.385914)
					(mid 55.167423 -210.561483)
					(end 55.100728 -210.72856)
				)
				(arc
					(start 55.100728 -210.72856)
					(mid 54.748851 -211.120583)
					(end 54.961028 -210.63839)
				)
				(arc
					(start 54.961028 -210.63839)
					(mid 55.008999 -210.514866)
					(end 55.039514 -210.385914)
				)
			)
		)
	)
	(zone
		(layer "In5.Cu")
		(hatch none 0.5)
		(connect_pads
			(clearance 0)
		)
		(min_thickness 0.25)
		(keepout
			(tracks not_allowed)
			(vias allowed)
			(pads allowed)
			(copperpour not_allowed)
			(footprints allowed)
		)
		(placement
			(enabled no)
			(sheetname "")
		)
		(fill
			(thermal_gap 0.5)
			(thermal_bridge_width 0.5)
			(island_removal_mode 0)
		)
		(polygon
			(pts
				(arc
					(start 264.49401 -210.385914)
					(mid 263.983216 -210.896327)
					(end 264.493756 -211.406994)
				)
				(arc
					(start 265.306556 -211.406994)
					(mid 265.817096 -210.896454)
					(end 265.306556 -210.385914)
				)
				(xy 265.18235 -210.385914)
				(arc
					(start 265.18235 -210.397344)
					(mid 265.194761 -210.521363)
					(end 265.231626 -210.640422)
				)
				(arc
					(start 265.231626 -210.640422)
					(mid 265.458644 -211.115338)
					(end 265.093704 -210.735926)
				)
				(arc
					(start 265.093704 -210.735926)
					(mid 265.040636 -210.587955)
					(end 265.018012 -210.432396)
				)
				(xy 265.01725 -210.431634) (xy 265.01725 -210.385914) (xy 264.85215 -210.385914) (xy 264.85215 -210.431888)
				(arc
					(start 264.851134 -210.432904)
					(mid 264.814633 -210.610356)
					(end 264.728452 -210.769708)
				)
				(arc
					(start 264.728452 -210.769708)
					(mid 264.310441 -211.090212)
					(end 264.607294 -210.655154)
				)
				(arc
					(start 264.607294 -210.655154)
					(mid 264.666663 -210.532411)
					(end 264.68705 -210.397598)
				)
				(xy 264.68705 -210.385914)
			)
		)
	)
	(zone
		(layer "In5.Cu")
		(hatch none 0.5)
		(connect_pads
			(clearance 0)
		)
		(min_thickness 0.25)
		(keepout
			(tracks not_allowed)
			(vias allowed)
			(pads allowed)
			(copperpour not_allowed)
			(footprints allowed)
		)
		(placement
			(enabled no)
			(sheetname "")
		)
		(fill
			(thermal_gap 0.5)
			(thermal_bridge_width 0.5)
			(island_removal_mode 0)
		)
		(polygon
			(pts
				(arc
					(start 193.69405 -210.385914)
					(mid 193.183256 -210.896327)
					(end 193.693796 -211.406994)
				)
				(arc
					(start 194.506596 -211.406994)
					(mid 195.017136 -210.896454)
					(end 194.506596 -210.385914)
				)
				(arc
					(start 194.351402 -210.385914)
					(mid 194.376463 -210.517637)
					(end 194.424808 -210.642708)
				)
				(arc
					(start 194.424808 -210.642708)
					(mid 194.663376 -211.111803)
					(end 194.28968 -210.74126)
				)
				(arc
					(start 194.28968 -210.74126)
					(mid 194.219282 -210.568959)
					(end 194.18554 -210.385914)
				)
				(arc
					(start 194.014852 -210.385914)
					(mid 193.981125 -210.568963)
					(end 193.910712 -210.74126)
				)
				(arc
					(start 193.910712 -210.74126)
					(mid 193.537024 -211.111792)
					(end 193.775584 -210.642708)
				)
				(arc
					(start 193.775584 -210.642708)
					(mid 193.823963 -210.517647)
					(end 193.84899 -210.385914)
				)
			)
		)
	)
	(zone
		(layer "In5.Cu")
		(hatch none 0.5)
		(connect_pads
			(clearance 0)
		)
		(min_thickness 0.25)
		(keepout
			(tracks not_allowed)
			(vias allowed)
			(pads allowed)
			(copperpour not_allowed)
			(footprints allowed)
		)
		(placement
			(enabled no)
			(sheetname "")
		)
		(fill
			(thermal_gap 0.5)
			(thermal_bridge_width 0.5)
			(island_removal_mode 0)
		)
		(polygon
			(pts
				(arc
					(start 18.852388 -81.39684)
					(mid 18.341594 -81.907253)
					(end 18.852134 -82.41792)
				)
				(arc
					(start 19.664934 -82.41792)
					(mid 20.175474 -81.90738)
					(end 19.664934 -81.39684)
				)
				(xy 19.506184 -81.39684) (xy 19.506184 -81.63179)
				(arc
					(start 19.54403 -81.669636)
					(mid 19.853534 -82.09598)
					(end 19.42719 -81.786476)
				)
				(xy 19.389344 -81.74863) (xy 19.341084 -81.70037) (xy 19.341084 -81.63179) (xy 19.341084 -81.39684)
				(xy 19.175984 -81.39684) (xy 19.175984 -81.63179) (xy 19.175984 -81.70037) (xy 19.127724 -81.74863)
				(arc
					(start 19.089878 -81.786476)
					(mid 18.663534 -82.09598)
					(end 18.973038 -81.669636)
				)
				(xy 19.010884 -81.63179) (xy 19.010884 -81.39684)
			)
		)
	)
	(zone
		(layer "In5.Cu")
		(hatch none 0.5)
		(connect_pads
			(clearance 0)
		)
		(min_thickness 0.25)
		(keepout
			(tracks not_allowed)
			(vias allowed)
			(pads allowed)
			(copperpour not_allowed)
			(footprints allowed)
		)
		(placement
			(enabled no)
			(sheetname "")
		)
		(fill
			(thermal_gap 0.5)
			(thermal_bridge_width 0.5)
			(island_removal_mode 0)
		)
		(polygon
			(pts
				(arc
					(start 168.212516 -88.646254)
					(mid 167.702103 -88.13546)
					(end 167.191436 -88.646)
				)
				(xy 167.191436 -88.806528) (xy 167.424608 -88.806528)
				(arc
					(start 167.464232 -88.766904)
					(mid 167.890576 -88.4574)
					(end 167.581072 -88.883744)
				)
				(xy 167.541448 -88.923368) (xy 167.493188 -88.971628) (xy 167.424608 -88.971628) (xy 167.191436 -88.971628)
				(xy 167.191436 -89.136728) (xy 167.428164 -89.136728) (xy 167.496744 -89.136728) (xy 167.545004 -89.184988)
				(arc
					(start 167.581072 -89.221056)
					(mid 167.890576 -89.6474)
					(end 167.464232 -89.337896)
				)
				(xy 167.428164 -89.301828) (xy 167.191436 -89.301828)
				(arc
					(start 167.191436 -89.4588)
					(mid 167.701976 -89.96934)
					(end 168.212516 -89.4588)
				)
			)
		)
	)
	(zone
		(layer "In5.Cu")
		(hatch none 0.5)
		(connect_pads
			(clearance 0)
		)
		(min_thickness 0.25)
		(keepout
			(tracks not_allowed)
			(vias allowed)
			(pads allowed)
			(copperpour not_allowed)
			(footprints allowed)
		)
		(placement
			(enabled no)
			(sheetname "")
		)
		(fill
			(thermal_gap 0.5)
			(thermal_bridge_width 0.5)
			(island_removal_mode 0)
		)
		(polygon
			(pts
				(arc
					(start 82.893916 -210.385914)
					(mid 82.383122 -210.896327)
					(end 82.893662 -211.406994)
				)
				(arc
					(start 83.706462 -211.406994)
					(mid 84.217002 -210.896454)
					(end 83.706462 -210.385914)
				)
				(arc
					(start 83.560666 -210.385914)
					(mid 83.591169 -210.514869)
					(end 83.639152 -210.63839)
				)
				(arc
					(start 83.639152 -210.63839)
					(mid 83.851345 -211.120607)
					(end 83.499452 -210.72856)
				)
				(arc
					(start 83.499452 -210.72856)
					(mid 83.432745 -210.561486)
					(end 83.393534 -210.385914)
				)
				(arc
					(start 83.20659 -210.385914)
					(mid 83.167367 -210.561483)
					(end 83.100672 -210.72856)
				)
				(arc
					(start 83.100672 -210.72856)
					(mid 82.748795 -211.120583)
					(end 82.960972 -210.63839)
				)
				(arc
					(start 82.960972 -210.63839)
					(mid 83.008943 -210.514866)
					(end 83.039458 -210.385914)
				)
			)
		)
	)
	(zone
		(layer "In5.Cu")
		(hatch none 0.5)
		(connect_pads
			(clearance 0)
		)
		(min_thickness 0.25)
		(keepout
			(tracks not_allowed)
			(vias allowed)
			(pads allowed)
			(copperpour not_allowed)
			(footprints allowed)
		)
		(placement
			(enabled no)
			(sheetname "")
		)
		(fill
			(thermal_gap 0.5)
			(thermal_bridge_width 0.5)
			(island_removal_mode 0)
		)
		(polygon
			(pts
				(arc
					(start 289.2298 -34.503614)
					(mid 288.71926 -35.014154)
					(end 289.2298 -35.524694)
				)
				(xy 289.374326 -35.524694) (xy 289.37585 -35.497008)
				(arc
					(start 289.37585 -35.458146)
					(mid 289.364106 -35.357128)
					(end 289.329368 -35.26155)
				)
				(arc
					(start 289.329368 -35.26155)
					(mid 289.057646 -34.810823)
					(end 289.457892 -35.152584)
				)
				(arc
					(start 289.457892 -35.152584)
					(mid 289.515003 -35.282962)
					(end 289.539934 -35.423094)
				)
				(xy 289.54095 -35.42411) (xy 289.54095 -35.524694) (xy 289.705542 -35.524694) (xy 289.70605 -35.498024)
				(xy 289.70605 -35.42411)
				(arc
					(start 289.70732 -35.423094)
					(mid 289.738066 -35.275266)
					(end 289.808412 -35.141662)
				)
				(arc
					(start 289.808412 -35.141662)
					(mid 290.225029 -34.819675)
					(end 289.930332 -35.255962)
				)
				(arc
					(start 289.930332 -35.255962)
					(mid 289.886283 -35.352954)
					(end 289.87115 -35.4584)
				)
				(xy 289.87115 -35.496754) (xy 289.87115 -35.498024) (xy 289.87115 -35.524694)
				(arc
					(start 290.042346 -35.524694)
					(mid 290.55314 -35.014281)
					(end 290.0426 -34.503614)
				)
			)
		)
	)
	(zone
		(layer "In5.Cu")
		(hatch none 0.5)
		(connect_pads
			(clearance 0)
		)
		(min_thickness 0.25)
		(keepout
			(tracks not_allowed)
			(vias allowed)
			(pads allowed)
			(copperpour not_allowed)
			(footprints allowed)
		)
		(placement
			(enabled no)
			(sheetname "")
		)
		(fill
			(thermal_gap 0.5)
			(thermal_bridge_width 0.5)
			(island_removal_mode 0)
		)
		(polygon
			(pts
				(arc
					(start 137.5664 -34.482786)
					(mid 137.05586 -34.993326)
					(end 137.5664 -35.503866)
				)
				(xy 137.72515 -35.503866)
				(arc
					(start 137.72515 -35.207702)
					(mid 137.335748 -34.859317)
					(end 137.831322 -35.025076)
				)
				(arc
					(start 137.831322 -35.025076)
					(mid 137.868745 -35.090697)
					(end 137.887964 -35.16376)
				)
				(xy 137.89025 -35.166046) (xy 137.89025 -35.49777) (xy 137.89025 -35.503866) (xy 138.05535 -35.503866)
				(xy 138.05535 -35.166046)
				(arc
					(start 138.057636 -35.16376)
					(mid 138.076812 -35.090679)
					(end 138.114278 -35.025076)
				)
				(arc
					(start 138.114278 -35.025076)
					(mid 138.609905 -34.859286)
					(end 138.22045 -35.207702)
				)
				(xy 138.22045 -35.49777) (xy 138.220704 -35.503866)
				(arc
					(start 138.378946 -35.503866)
					(mid 138.88974 -34.993453)
					(end 138.3792 -34.482786)
				)
			)
		)
	)
	(zone
		(layer "In5.Cu")
		(hatch none 0.5)
		(connect_pads
			(clearance 0)
		)
		(min_thickness 0.25)
		(keepout
			(tracks not_allowed)
			(vias allowed)
			(pads allowed)
			(copperpour not_allowed)
			(footprints allowed)
		)
		(placement
			(enabled no)
			(sheetname "")
		)
		(fill
			(thermal_gap 0.5)
			(thermal_bridge_width 0.5)
			(island_removal_mode 0)
		)
		(polygon
			(pts
				(arc
					(start 104.494076 -210.385914)
					(mid 103.983282 -210.896327)
					(end 104.493822 -211.406994)
				)
				(arc
					(start 105.306622 -211.406994)
					(mid 105.817162 -210.896454)
					(end 105.306622 -210.385914)
				)
				(arc
					(start 105.160826 -210.385914)
					(mid 105.191329 -210.514869)
					(end 105.239312 -210.63839)
				)
				(arc
					(start 105.239312 -210.63839)
					(mid 105.451505 -211.120607)
					(end 105.099612 -210.72856)
				)
				(arc
					(start 105.099612 -210.72856)
					(mid 105.032905 -210.561486)
					(end 104.993694 -210.385914)
				)
				(arc
					(start 104.80675 -210.385914)
					(mid 104.767527 -210.561483)
					(end 104.700832 -210.72856)
				)
				(arc
					(start 104.700832 -210.72856)
					(mid 104.348955 -211.120583)
					(end 104.561132 -210.63839)
				)
				(arc
					(start 104.561132 -210.63839)
					(mid 104.609103 -210.514866)
					(end 104.639618 -210.385914)
				)
			)
		)
	)
	(zone
		(layer "In5.Cu")
		(hatch none 0.5)
		(connect_pads
			(clearance 0)
		)
		(min_thickness 0.25)
		(keepout
			(tracks not_allowed)
			(vias allowed)
			(pads allowed)
			(copperpour not_allowed)
			(footprints allowed)
		)
		(placement
			(enabled no)
			(sheetname "")
		)
		(fill
			(thermal_gap 0.5)
			(thermal_bridge_width 0.5)
			(island_removal_mode 0)
		)
		(polygon
			(pts
				(arc
					(start 144.894046 -210.385914)
					(mid 144.383252 -210.896327)
					(end 144.893792 -211.406994)
				)
				(arc
					(start 145.706592 -211.406994)
					(mid 146.217132 -210.896454)
					(end 145.706592 -210.385914)
				)
				(xy 145.547842 -210.385914)
				(arc
					(start 145.547842 -210.3882)
					(mid 145.56388 -210.521545)
					(end 145.611088 -210.64728)
				)
				(arc
					(start 145.611088 -210.64728)
					(mid 145.876056 -211.102352)
					(end 145.481294 -210.753706)
				)
				(arc
					(start 145.481294 -210.753706)
					(mid 145.412514 -210.594361)
					(end 145.383504 -210.423252)
				)
				(xy 145.382742 -210.42249) (xy 145.382742 -210.385914) (xy 145.217642 -210.385914) (xy 145.217642 -210.42249)
				(arc
					(start 145.21688 -210.423252)
					(mid 145.187825 -210.594347)
					(end 145.11909 -210.753706)
				)
				(arc
					(start 145.11909 -210.753706)
					(mid 144.724271 -211.102421)
					(end 144.989296 -210.64728)
				)
				(arc
					(start 144.989296 -210.64728)
					(mid 145.036494 -210.521543)
					(end 145.052542 -210.3882)
				)
				(xy 145.052542 -210.385914)
			)
		)
	)
	(zone
		(layer "In5.Cu")
		(hatch none 0.5)
		(connect_pads
			(clearance 0)
		)
		(min_thickness 0.25)
		(keepout
			(tracks not_allowed)
			(vias allowed)
			(pads allowed)
			(copperpour not_allowed)
			(footprints allowed)
		)
		(placement
			(enabled no)
			(sheetname "")
		)
		(fill
			(thermal_gap 0.5)
			(thermal_bridge_width 0.5)
			(island_removal_mode 0)
		)
		(polygon
			(pts
				(arc
					(start 131.089654 -34.762694)
					(mid 130.57886 -35.273107)
					(end 131.0894 -35.783774)
				)
				(xy 131.24815 -35.783774)
				(arc
					(start 131.24815 -35.48761)
					(mid 130.858748 -35.139225)
					(end 131.354322 -35.304984)
				)
				(arc
					(start 131.354322 -35.304984)
					(mid 131.391745 -35.370605)
					(end 131.410964 -35.443668)
				)
				(xy 131.41325 -35.445954) (xy 131.41325 -35.783774) (xy 131.57835 -35.783774) (xy 131.57835 -35.445954)
				(arc
					(start 131.580636 -35.443668)
					(mid 131.599812 -35.370587)
					(end 131.637278 -35.304984)
				)
				(arc
					(start 131.637278 -35.304984)
					(mid 132.132905 -35.139194)
					(end 131.74345 -35.48761)
				)
				(xy 131.74345 -35.783774)
				(arc
					(start 131.9022 -35.783774)
					(mid 132.41274 -35.273234)
					(end 131.9022 -34.762694)
				)
			)
		)
	)
	(zone
		(layer "In5.Cu")
		(hatch none 0.5)
		(connect_pads
			(clearance 0)
		)
		(min_thickness 0.25)
		(keepout
			(tracks not_allowed)
			(vias allowed)
			(pads allowed)
			(copperpour not_allowed)
			(footprints allowed)
		)
		(placement
			(enabled no)
			(sheetname "")
		)
		(fill
			(thermal_gap 0.5)
			(thermal_bridge_width 0.5)
			(island_removal_mode 0)
		)
		(polygon
			(pts
				(arc
					(start 172.745654 -95.683832)
					(mid 172.23486 -96.194245)
					(end 172.7454 -96.704912)
				)
				(xy 172.94225 -96.704912) (xy 172.94225 -96.508062)
				(arc
					(start 172.866304 -96.432116)
					(mid 172.5568 -96.005772)
					(end 172.983144 -96.315276)
				)
				(xy 173.05909 -96.391222) (xy 173.10735 -96.439482) (xy 173.10735 -96.508062) (xy 173.10735 -96.704912)
				(xy 173.27245 -96.704912) (xy 173.27245 -96.508062) (xy 173.27245 -96.439482) (xy 173.32071 -96.391222)
				(arc
					(start 173.396656 -96.315276)
					(mid 173.823 -96.005772)
					(end 173.513496 -96.432116)
				)
				(xy 173.505876 -96.439482) (xy 173.43755 -96.508062) (xy 173.43755 -96.704912)
				(arc
					(start 173.6344 -96.704912)
					(mid 174.14494 -96.194372)
					(end 173.6344 -95.683832)
				)
			)
		)
	)
	(zone
		(layer "In5.Cu")
		(hatch none 0.5)
		(connect_pads
			(clearance 0)
		)
		(min_thickness 0.25)
		(keepout
			(tracks not_allowed)
			(vias allowed)
			(pads allowed)
			(copperpour not_allowed)
			(footprints allowed)
		)
		(placement
			(enabled no)
			(sheetname "")
		)
		(fill
			(thermal_gap 0.5)
			(thermal_bridge_width 0.5)
			(island_removal_mode 0)
		)
		(polygon
			(pts
				(arc
					(start 183.59374 -19.850354)
					(mid 183.083327 -19.33956)
					(end 182.57266 -19.8501)
				)
				(arc
					(start 182.57266 -20.6629)
					(mid 183.0832 -21.17344)
					(end 183.59374 -20.6629)
				)
				(xy 183.59374 -20.512786)
				(arc
					(start 183.410606 -20.512786)
					(mid 183.361348 -20.516663)
					(end 183.313324 -20.52828)
				)
				(arc
					(start 183.313324 -20.52828)
					(mid 182.912697 -20.867935)
					(end 183.172354 -20.41144)
				)
				(arc
					(start 183.172354 -20.41144)
					(mid 183.270183 -20.368793)
					(end 183.375046 -20.348956)
				)
				(xy 183.376316 -20.347686) (xy 183.59374 -20.347686) (xy 183.59374 -20.182586) (xy 183.360822 -20.182586)
				(arc
					(start 183.359552 -20.181062)
					(mid 183.250473 -20.158022)
					(end 183.150764 -20.108164)
				)
				(arc
					(start 183.150764 -20.108164)
					(mid 182.929994 -19.63172)
					(end 183.30291 -20.001484)
				)
				(arc
					(start 183.30291 -20.001484)
					(mid 183.348319 -20.013481)
					(end 183.395112 -20.017486)
				)
				(xy 183.59374 -20.017486)
			)
		)
	)
	(zone
		(net "GND")
		(layer "In5.Cu")
		(hatch none 0.5)
		(connect_pads
			(clearance 0.5)
		)
		(min_thickness 0.25)
		(fill yes
			(thermal_gap 0.5)
			(thermal_bridge_width 0.5)
			(island_removal_mode 0)
		)
		(polygon
			(pts
				(arc
					(start 123.637548 4.236974)
					(mid 122.762871 3.874671)
					(end 122.400568 2.999994)
				)
				(arc
					(start 122.400568 1.999996)
					(mid 121.591301 0.046251)
					(end 119.637556 -0.763016)
				)
				(arc
					(start 53.950108 -0.763016)
					(mid 53.075431 -1.125319)
					(end 52.713128 -1.999996)
				)
				(arc
					(start 52.713128 -24.010112)
					(mid 51.903861 -25.963857)
					(end 49.950116 -26.773124)
				)
				(arc
					(start 1.999996 -26.773124)
					(mid 1.125319 -27.135427)
					(end 0.763016 -28.010104)
				)
				(arc
					(start 0.763016 -212.499956)
					(mid 0.832426 -212.667528)
					(end 0.999998 -212.736938)
				)
				(arc
					(start 25.4 -212.736938)
					(mid 25.613236 -212.748041)
					(end 25.82418 -212.781134)
				)
				(arc
					(start 25.82418 -211.495132)
					(mid 25.612524 -211.474773)
					(end 25.4 -211.467954)
				)
				(xy 2.032 -211.467954) (xy 2.032 -92.602304) (xy 3.854704 -90.7796) (xy 3.854704 -70.806818) (xy 3.854704 -55.937912)
				(xy 6.05028 -53.742336) (xy 6.255766 -53.742336) (xy 7.33933 -52.658772) (xy 7.355332 -52.658772)
				(xy 7.625334 -52.38877) (xy 15.729204 -52.38877) (xy 15.879826 -52.539392) (xy 16.375126 -52.539392)
				(xy 16.533622 -52.380896) (xy 24.790146 -52.380896) (xy 25.091136 -52.079906) (xy 25.091136 -49.224438)
				(xy 26.462228 -47.853346) (xy 26.462228 -42.122852) (xy 31.068772 -37.516308) (xy 33.536382 -35.048698)
				(xy 50.437542 -35.048698) (xy 55.29707 -30.18917) (xy 55.29707 -25.02027) (xy 55.783988 -24.533352)
				(xy 66.868548 -24.533352) (xy 73.303384 -30.968188) (xy 91.17711 -30.968188) (xy 93.361764 -28.783534)
				(arc
					(start 120.145302 -1.999996)
					(mid 122.641698 -0.689404)
					(end 123.669044 1.936242)
				)
				(xy 123.643136 1.936242) (xy 123.606052 1.973326) (xy 123.606052 2.026158) (xy 123.643136 2.063242)
				(xy 123.669552 2.063242) (xy 123.669552 2.96799) (xy 125.174502 2.96799) (xy 125.174502 4.236974)
			)
		)
	)
	(zone
		(net "GND")
		(layer "In5.Cu")
		(hatch none 0.5)
		(connect_pads
			(clearance 0.5)
		)
		(min_thickness 0.25)
		(fill yes
			(thermal_gap 0.5)
			(thermal_bridge_width 0.5)
			(island_removal_mode 0)
		)
		(polygon
			(pts
				(xy 265.957558 4.236974) (xy 265.957558 2.96799) (xy 273.299682 2.96799) (xy 287.293812 -11.02614)
				(xy 328.31913 -11.02614) (xy 329.368912 -12.075922) (xy 329.368912 -29.045916) (xy 334.967326 -34.64433)
				(xy 347.170248 -34.64433) (xy 353.568 -41.042082) (xy 353.568 -69.109336) (xy 353.51212 -69.109336)
				(xy 341.485728 -81.135728) (xy 341.503 -81.153) (xy 337.058 -85.598) (xy 337.058 -97.409) (xy 333.502 -100.965)
				(xy 332.232 -100.965) (xy 331.851 -100.584) (xy 331.851 -98.806) (xy 333.375 -97.282) (xy 333.375 -85.852)
				(xy 332.994 -85.471) (xy 323.596 -85.471) (xy 323.088 -85.979) (xy 322.199 -85.979) (xy 322.072 -85.852)
				(xy 322.072 -85.09) (xy 318.86271 -81.88071) (xy 300.50232 -81.88071) (xy 298.402756 -83.980274)
				(xy 298.402756 -97.53854) (xy 298.490386 -97.62617) (xy 309.162196 -157.240224) (xy 319.7098 -172.9486)
				(xy 329.0824 -186.7916) (xy 345.683078 -205.79588)
				(arc
					(start 345.683078 -212.074506)
					(mid 344.642888 -213.264361)
					(end 344.268044 -214.799672)
				)
				(xy 344.268044 -218.09075) (xy 345.537028 -218.09075)
				(arc
					(start 345.537028 -214.799926)
					(mid 346.141263 -213.341173)
					(end 347.600016 -212.736938)
				)
				(arc
					(start 354.600002 -212.736938)
					(mid 354.767574 -212.667528)
					(end 354.836984 -212.499956)
				)
				(arc
					(start 354.836984 -19.459956)
					(mid 353.888159 -19.123385)
					(end 353.486974 -18.200116)
				)
				(arc
					(start 353.486974 -10.199878)
					(mid 353.888305 -9.276765)
					(end 354.836984 -8.940038)
				)
				(xy 354.836984 -1.167384) (xy 354.5332 -0.8636) (xy 332.105 -0.8636) (xy 330.962 0.2794) (xy 330.962 3.932174)
				(xy 330.6572 4.236974)
			)
		)
	)
	(zone
		(layer "In5.Cu")
		(hatch none 0.5)
		(connect_pads
			(clearance 0)
		)
		(min_thickness 0.25)
		(keepout
			(tracks not_allowed)
			(vias allowed)
			(pads allowed)
			(copperpour not_allowed)
			(footprints allowed)
		)
		(placement
			(enabled no)
			(sheetname "")
		)
		(fill
			(thermal_gap 0.5)
			(thermal_bridge_width 0.5)
			(island_removal_mode 0)
		)
		(polygon
			(pts
				(arc
					(start 22.555454 -53.045614)
					(mid 22.04466 -53.556027)
					(end 22.5552 -54.066694)
				)
				(xy 22.7203 -54.066694) (xy 22.7203 -53.81117)
				(arc
					(start 22.693376 -53.784246)
					(mid 22.366628 -53.367582)
					(end 22.783292 -53.69433)
				)
				(xy 22.810216 -53.721254) (xy 22.8473 -53.758338) (xy 22.8473 -53.81117) (xy 22.8473 -54.066694)
				(xy 23.0251 -54.066694) (xy 23.0251 -53.86197) (xy 23.0251 -53.809138) (xy 23.062184 -53.772054)
				(arc
					(start 23.139908 -53.69433)
					(mid 23.556572 -53.367582)
					(end 23.229824 -53.784246)
				)
				(xy 23.1521 -53.86197) (xy 23.1521 -54.066694)
				(arc
					(start 23.368 -54.066694)
					(mid 23.87854 -53.556154)
					(end 23.368 -53.045614)
				)
			)
		)
	)
	(zone
		(layer "In5.Cu")
		(hatch none 0.5)
		(connect_pads
			(clearance 0)
		)
		(min_thickness 0.25)
		(keepout
			(tracks not_allowed)
			(vias allowed)
			(pads allowed)
			(copperpour not_allowed)
			(footprints allowed)
		)
		(placement
			(enabled no)
			(sheetname "")
		)
		(fill
			(thermal_gap 0.5)
			(thermal_bridge_width 0.5)
			(island_removal_mode 0)
		)
		(polygon
			(pts
				(arc
					(start 176.093882 -210.385914)
					(mid 175.583088 -210.896327)
					(end 176.093628 -211.406994)
				)
				(arc
					(start 176.906428 -211.406994)
					(mid 177.416968 -210.896454)
					(end 176.906428 -210.385914)
				)
				(xy 176.73955 -210.385914)
				(arc
					(start 176.73955 -210.464908)
					(mid 176.753553 -210.563602)
					(end 176.79416 -210.654646)
				)
				(arc
					(start 176.79416 -210.654646)
					(mid 177.08853 -211.091355)
					(end 176.671986 -210.7692)
				)
				(arc
					(start 176.671986 -210.7692)
					(mid 176.60506 -210.641162)
					(end 176.57572 -210.499706)
				)
				(xy 176.57445 -210.49869) (xy 176.57445 -210.385914) (xy 176.40935 -210.385914) (xy 176.40935 -210.49869)
				(arc
					(start 176.408334 -210.499706)
					(mid 176.382457 -210.636127)
					(end 176.324006 -210.762088)
				)
				(arc
					(start 176.324006 -210.762088)
					(mid 175.91739 -211.096625)
					(end 176.197768 -210.650836)
				)
				(arc
					(start 176.197768 -210.650836)
					(mid 176.232422 -210.560466)
					(end 176.24425 -210.4644)
				)
				(xy 176.24425 -210.385914)
			)
		)
	)
	(zone
		(layer "In5.Cu")
		(hatch none 0.5)
		(connect_pads
			(clearance 0)
		)
		(min_thickness 0.25)
		(keepout
			(tracks not_allowed)
			(vias allowed)
			(pads allowed)
			(copperpour not_allowed)
			(footprints allowed)
		)
		(placement
			(enabled no)
			(sheetname "")
		)
		(fill
			(thermal_gap 0.5)
			(thermal_bridge_width 0.5)
			(island_removal_mode 0)
		)
		(polygon
			(pts
				(arc
					(start 200.093834 -210.385914)
					(mid 199.58304 -210.896327)
					(end 200.09358 -211.406994)
				)
				(arc
					(start 200.90638 -211.406994)
					(mid 201.41692 -210.896454)
					(end 200.90638 -210.385914)
				)
				(arc
					(start 200.751186 -210.385914)
					(mid 200.776247 -210.517637)
					(end 200.824592 -210.642708)
				)
				(arc
					(start 200.824592 -210.642708)
					(mid 201.06316 -211.111803)
					(end 200.689464 -210.74126)
				)
				(arc
					(start 200.689464 -210.74126)
					(mid 200.619066 -210.568959)
					(end 200.585324 -210.385914)
				)
				(arc
					(start 200.414636 -210.385914)
					(mid 200.380909 -210.568963)
					(end 200.310496 -210.74126)
				)
				(arc
					(start 200.310496 -210.74126)
					(mid 199.936808 -211.111792)
					(end 200.175368 -210.642708)
				)
				(arc
					(start 200.175368 -210.642708)
					(mid 200.223747 -210.517647)
					(end 200.248774 -210.385914)
				)
			)
		)
	)
	(zone
		(layer "In5.Cu")
		(hatch none 0.5)
		(connect_pads
			(clearance 0)
		)
		(min_thickness 0.25)
		(keepout
			(tracks not_allowed)
			(vias allowed)
			(pads allowed)
			(copperpour not_allowed)
			(footprints allowed)
		)
		(placement
			(enabled no)
			(sheetname "")
		)
		(fill
			(thermal_gap 0.5)
			(thermal_bridge_width 0.5)
			(island_removal_mode 0)
		)
		(polygon
			(pts
				(arc
					(start 303.8348 -35.773614)
					(mid 303.32426 -36.284154)
					(end 303.8348 -36.794694)
				)
				(arc
					(start 303.96561 -36.794694)
					(mid 303.93204 -36.668337)
					(end 303.885854 -36.546028)
				)
				(arc
					(start 303.885854 -36.546028)
					(mid 303.704377 -36.051742)
					(end 304.030634 -36.465002)
				)
				(arc
					(start 304.030634 -36.465002)
					(mid 304.092137 -36.626771)
					(end 304.134012 -36.794694)
				)
				(arc
					(start 304.348388 -36.794694)
					(mid 304.390281 -36.626777)
					(end 304.451766 -36.465002)
				)
				(arc
					(start 304.451766 -36.465002)
					(mid 304.778011 -36.051763)
					(end 304.596546 -36.546028)
				)
				(arc
					(start 304.596546 -36.546028)
					(mid 304.550381 -36.668344)
					(end 304.51679 -36.794694)
				)
				(arc
					(start 304.647346 -36.794694)
					(mid 305.15814 -36.284281)
					(end 304.6476 -35.773614)
				)
			)
		)
	)
	(zone
		(layer "In5.Cu")
		(hatch none 0.5)
		(connect_pads
			(clearance 0)
		)
		(min_thickness 0.25)
		(keepout
			(tracks not_allowed)
			(vias allowed)
			(pads allowed)
			(copperpour not_allowed)
			(footprints allowed)
		)
		(placement
			(enabled no)
			(sheetname "")
		)
		(fill
			(thermal_gap 0.5)
			(thermal_bridge_width 0.5)
			(island_removal_mode 0)
		)
		(polygon
			(pts
				(arc
					(start 138.494008 -210.385914)
					(mid 137.983214 -210.896327)
					(end 138.493754 -211.406994)
				)
				(arc
					(start 139.306554 -211.406994)
					(mid 139.817094 -210.896454)
					(end 139.306554 -210.385914)
				)
				(arc
					(start 139.151106 -210.385914)
					(mid 139.176159 -210.517641)
					(end 139.224512 -210.642708)
				)
				(arc
					(start 139.224512 -210.642708)
					(mid 139.463935 -211.111743)
					(end 139.089638 -210.74126)
				)
				(arc
					(start 139.089638 -210.74126)
					(mid 139.019122 -210.568971)
					(end 138.985244 -210.385914)
				)
				(xy 138.819128 -210.385914) (xy 138.819382 -210.40217)
				(arc
					(start 138.81862 -210.403186)
					(mid 138.790945 -210.584723)
					(end 138.719052 -210.753706)
				)
				(arc
					(start 138.719052 -210.753706)
					(mid 138.324765 -211.1028)
					(end 138.589258 -210.647534)
				)
				(arc
					(start 138.589258 -210.647534)
					(mid 138.637273 -210.520608)
					(end 138.653774 -210.385914)
				)
			)
		)
	)
	(zone
		(layer "In5.Cu")
		(hatch none 0.5)
		(connect_pads
			(clearance 0)
		)
		(min_thickness 0.25)
		(keepout
			(tracks not_allowed)
			(vias allowed)
			(pads allowed)
			(copperpour not_allowed)
			(footprints allowed)
		)
		(placement
			(enabled no)
			(sheetname "")
		)
		(fill
			(thermal_gap 0.5)
			(thermal_bridge_width 0.5)
			(island_removal_mode 0)
		)
		(polygon
			(pts
				(arc
					(start 216.093802 -210.385914)
					(mid 215.583008 -210.896327)
					(end 216.093548 -211.406994)
				)
				(arc
					(start 216.906348 -211.406994)
					(mid 217.416888 -210.896454)
					(end 216.906348 -210.385914)
				)
				(arc
					(start 216.751154 -210.385914)
					(mid 216.776215 -210.517637)
					(end 216.82456 -210.642708)
				)
				(arc
					(start 216.82456 -210.642708)
					(mid 217.063128 -211.111803)
					(end 216.689432 -210.74126)
				)
				(arc
					(start 216.689432 -210.74126)
					(mid 216.619034 -210.568959)
					(end 216.585292 -210.385914)
				)
				(arc
					(start 216.414604 -210.385914)
					(mid 216.380877 -210.568963)
					(end 216.310464 -210.74126)
				)
				(arc
					(start 216.310464 -210.74126)
					(mid 215.936776 -211.111792)
					(end 216.175336 -210.642708)
				)
				(arc
					(start 216.175336 -210.642708)
					(mid 216.223715 -210.517647)
					(end 216.248742 -210.385914)
				)
			)
		)
	)
	(zone
		(layer "In5.Cu")
		(hatch none 0.5)
		(connect_pads
			(clearance 0)
		)
		(min_thickness 0.25)
		(keepout
			(tracks not_allowed)
			(vias allowed)
			(pads allowed)
			(copperpour not_allowed)
			(footprints allowed)
		)
		(placement
			(enabled no)
			(sheetname "")
		)
		(fill
			(thermal_gap 0.5)
			(thermal_bridge_width 0.5)
			(island_removal_mode 0)
		)
		(polygon
			(pts
				(arc
					(start 58.051954 -195.75526)
					(mid 57.54116 -196.265673)
					(end 58.0517 -196.77634)
				)
				(arc
					(start 58.8645 -196.77634)
					(mid 59.37504 -196.2658)
					(end 58.8645 -195.75526)
				)
				(xy 58.70575 -195.75526)
				(arc
					(start 58.70575 -195.8086)
					(mid 58.719533 -195.917952)
					(end 58.760106 -196.020436)
				)
				(arc
					(start 58.760106 -196.020436)
					(mid 59.04083 -196.465823)
					(end 58.634122 -196.131434)
				)
				(arc
					(start 58.634122 -196.131434)
					(mid 58.569597 -195.99355)
					(end 58.541666 -195.843906)
				)
				(xy 58.54065 -195.84289) (xy 58.54065 -195.75526) (xy 58.37555 -195.75526) (xy 58.37555 -195.777104)
				(arc
					(start 58.374788 -195.777866)
					(mid 58.345622 -195.955516)
					(end 58.275982 -196.121528)
				)
				(arc
					(start 58.275982 -196.121528)
					(mid 57.884286 -196.47338)
					(end 58.145172 -196.016118)
				)
				(arc
					(start 58.145172 -196.016118)
					(mid 58.192354 -195.889346)
					(end 58.210196 -195.75526)
				)
			)
		)
	)
	(zone
		(layer "In5.Cu")
		(hatch none 0.5)
		(connect_pads
			(clearance 0)
		)
		(min_thickness 0.25)
		(keepout
			(tracks not_allowed)
			(vias allowed)
			(pads allowed)
			(copperpour not_allowed)
			(footprints allowed)
		)
		(placement
			(enabled no)
			(sheetname "")
		)
		(fill
			(thermal_gap 0.5)
			(thermal_bridge_width 0.5)
			(island_removal_mode 0)
		)
		(polygon
			(pts
				(arc
					(start 267.693902 -210.385914)
					(mid 267.183108 -210.896327)
					(end 267.693648 -211.406994)
				)
				(arc
					(start 268.506448 -211.406994)
					(mid 269.016988 -210.896454)
					(end 268.506448 -210.385914)
				)
				(xy 268.347698 -210.385914)
				(arc
					(start 268.347698 -210.5152)
					(mid 268.35859 -210.588971)
					(end 268.39037 -210.656424)
				)
				(arc
					(start 268.39037 -210.656424)
					(mid 268.69174 -211.088171)
					(end 268.270482 -210.772248)
				)
				(arc
					(start 268.270482 -210.772248)
					(mid 268.211344 -210.667858)
					(end 268.184122 -210.551014)
				)
				(xy 268.182598 -210.54949) (xy 268.182598 -210.385914) (xy 268.017498 -210.385914) (xy 268.017498 -210.54949)
				(arc
					(start 268.015974 -210.551014)
					(mid 267.988731 -210.66785)
					(end 267.929614 -210.772248)
				)
				(arc
					(start 267.929614 -210.772248)
					(mid 267.508332 -211.088196)
					(end 267.809726 -210.656424)
				)
				(arc
					(start 267.809726 -210.656424)
					(mid 267.841467 -210.588959)
					(end 267.852398 -210.5152)
				)
				(xy 267.852398 -210.385914)
			)
		)
	)
	(zone
		(layers "In5.Cu" "In6.Cu")
		(hatch none 0.5)
		(connect_pads
			(clearance 0)
		)
		(min_thickness 0.25)
		(keepout
			(tracks not_allowed)
			(vias allowed)
			(pads allowed)
			(copperpour not_allowed)
			(footprints allowed)
		)
		(placement
			(enabled no)
			(sheetname "")
		)
		(fill yes
			(thermal_gap 0.5)
			(thermal_bridge_width 0.5)
			(island_removal_mode 0)
		)
		(polygon
			(pts
				(arc
					(start 50.927 -129.48666)
					(mid 50.855158 -129.516418)
					(end 50.8254 -129.58826)
				)
				(arc
					(start 50.8254 -130.9624)
					(mid 50.855158 -131.034242)
					(end 50.927 -131.064)
				)
				(arc
					(start 52.1462 -131.064)
					(mid 52.218042 -131.034242)
					(end 52.2478 -130.9624)
				)
				(arc
					(start 52.2478 -129.58826)
					(mid 52.218042 -129.516418)
					(end 52.1462 -129.48666)
				)
			)
		)
	)
	(zone
		(layers "In5.Cu" "In6.Cu")
		(hatch none 0.5)
		(connect_pads
			(clearance 0)
		)
		(min_thickness 0.25)
		(keepout
			(tracks not_allowed)
			(vias allowed)
			(pads allowed)
			(copperpour not_allowed)
			(footprints allowed)
		)
		(placement
			(enabled no)
			(sheetname "")
		)
		(fill yes
			(thermal_gap 0.5)
			(thermal_bridge_width 0.5)
			(island_removal_mode 0)
		)
		(polygon
			(pts
				(arc
					(start 268.540484 -17.09166)
					(mid 268.468642 -17.121418)
					(end 268.438884 -17.19326)
				)
				(arc
					(start 268.438884 -18.5674)
					(mid 268.468642 -18.639242)
					(end 268.540484 -18.669)
				)
				(arc
					(start 269.759684 -18.669)
					(mid 269.831526 -18.639242)
					(end 269.861284 -18.5674)
				)
				(arc
					(start 269.861284 -17.19326)
					(mid 269.831526 -17.121418)
					(end 269.759684 -17.09166)
				)
			)
		)
	)
	(zone
		(layers "In5.Cu" "In6.Cu")
		(hatch none 0.5)
		(connect_pads
			(clearance 0)
		)
		(min_thickness 0.25)
		(keepout
			(tracks not_allowed)
			(vias allowed)
			(pads allowed)
			(copperpour not_allowed)
			(footprints allowed)
		)
		(placement
			(enabled no)
			(sheetname "")
		)
		(fill yes
			(thermal_gap 0.5)
			(thermal_bridge_width 0.5)
			(island_removal_mode 0)
		)
		(polygon
			(pts
				(arc
					(start 52.063904 -52.197)
					(mid 52.093662 -52.268842)
					(end 52.165504 -52.2986)
				)
				(arc
					(start 53.539644 -52.2986)
					(mid 53.611486 -52.268842)
					(end 53.641244 -52.197)
				)
				(arc
					(start 53.641244 -50.9778)
					(mid 53.611486 -50.905958)
					(end 53.539644 -50.8762)
				)
				(arc
					(start 52.165504 -50.8762)
					(mid 52.093662 -50.905958)
					(end 52.063904 -50.9778)
				)
			)
		)
	)
	(zone
		(layers "In5.Cu" "In6.Cu")
		(hatch none 0.5)
		(connect_pads
			(clearance 0)
		)
		(min_thickness 0.25)
		(keepout
			(tracks not_allowed)
			(vias allowed)
			(pads allowed)
			(copperpour not_allowed)
			(footprints allowed)
		)
		(placement
			(enabled no)
			(sheetname "")
		)
		(fill yes
			(thermal_gap 0.5)
			(thermal_bridge_width 0.5)
			(island_removal_mode 0)
		)
		(polygon
			(pts
				(arc
					(start 50.923698 -129.492502)
					(mid 50.851856 -129.52226)
					(end 50.822098 -129.594102)
				)
				(arc
					(start 50.822098 -130.968242)
					(mid 50.851856 -131.040084)
					(end 50.923698 -131.069842)
				)
				(arc
					(start 52.142898 -131.069842)
					(mid 52.21474 -131.040084)
					(end 52.244498 -130.968242)
				)
				(arc
					(start 52.244498 -129.594102)
					(mid 52.21474 -129.52226)
					(end 52.142898 -129.492502)
				)
			)
		)
	)
	(zone
		(layers "In5.Cu" "In6.Cu")
		(hatch none 0.5)
		(connect_pads
			(clearance 0)
		)
		(min_thickness 0.25)
		(keepout
			(tracks not_allowed)
			(vias allowed)
			(pads allowed)
			(copperpour not_allowed)
			(footprints allowed)
		)
		(placement
			(enabled no)
			(sheetname "")
		)
		(fill yes
			(thermal_gap 0.5)
			(thermal_bridge_width 0.5)
			(island_removal_mode 0)
		)
		(polygon
			(pts
				(arc
					(start 271.5514 -7.9756)
					(mid 271.479558 -8.005358)
					(end 271.4498 -8.0772)
				)
				(arc
					(start 271.4498 -9.4488)
					(mid 271.479558 -9.520642)
					(end 271.5514 -9.5504)
				)
				(arc
					(start 272.7706 -9.5504)
					(mid 272.842442 -9.520642)
					(end 272.8722 -9.4488)
				)
				(arc
					(start 272.8722 -8.0772)
					(mid 272.842442 -8.005358)
					(end 272.7706 -7.9756)
				)
			)
		)
	)
	(zone
		(layers "In5.Cu" "In6.Cu")
		(hatch none 0.5)
		(connect_pads
			(clearance 0)
		)
		(min_thickness 0.25)
		(keepout
			(tracks not_allowed)
			(vias allowed)
			(pads allowed)
			(copperpour not_allowed)
			(footprints allowed)
		)
		(placement
			(enabled no)
			(sheetname "")
		)
		(fill yes
			(thermal_gap 0.5)
			(thermal_bridge_width 0.5)
			(island_removal_mode 0)
		)
		(polygon
			(pts
				(arc
					(start 270.4084 -4.9276)
					(mid 270.336558 -4.957358)
					(end 270.3068 -5.0292)
				)
				(arc
					(start 270.3068 -6.4008)
					(mid 270.336558 -6.472642)
					(end 270.4084 -6.5024)
				)
				(arc
					(start 271.6276 -6.5024)
					(mid 271.699442 -6.472642)
					(end 271.7292 -6.4008)
				)
				(arc
					(start 271.7292 -5.0292)
					(mid 271.699442 -4.957358)
					(end 271.6276 -4.9276)
				)
			)
		)
	)
	(zone
		(net "GND")
		(layer "In6.Cu")
		(hatch none 0.5)
		(connect_pads
			(clearance 0.5)
		)
		(min_thickness 0.25)
		(fill yes
			(thermal_gap 0.5)
			(thermal_bridge_width 0.5)
			(island_removal_mode 0)
		)
		(polygon
			(pts
				(arc
					(start 123.637548 4.236974)
					(mid 122.762871 3.874671)
					(end 122.400568 2.999994)
				)
				(arc
					(start 122.400568 1.999996)
					(mid 121.591301 0.046251)
					(end 119.637556 -0.763016)
				)
				(arc
					(start 53.950108 -0.763016)
					(mid 53.075431 -1.125319)
					(end 52.713128 -1.999996)
				)
				(arc
					(start 52.713128 -24.010112)
					(mid 51.903861 -25.963857)
					(end 49.950116 -26.773124)
				)
				(arc
					(start 1.999996 -26.773124)
					(mid 1.125319 -27.135427)
					(end 0.763016 -28.010104)
				)
				(arc
					(start 0.763016 -212.499956)
					(mid 0.832426 -212.667528)
					(end 0.999998 -212.736938)
				)
				(arc
					(start 25.4 -212.736938)
					(mid 26.858753 -213.341173)
					(end 27.462988 -214.799926)
				)
				(xy 27.462988 -221.136972)
				(arc
					(start 28.000198 -221.136972)
					(mid 28.89312 -221.506938)
					(end 29.263086 -222.39986)
				)
				(xy 29.263086 -225.460052) (xy 73.337928 -225.460052)
				(arc
					(start 73.337928 -222.600012)
					(mid 73.343892 -222.44689)
					(end 73.361804 -222.294704)
				)
				(arc
					(start 73.361804 -222.294704)
					(mid 73.927667 -221.197654)
					(end 75.03668 -220.655642)
				)
				(arc
					(start 75.03668 -220.655642)
					(mid 75.299952 -220.636928)
					(end 75.563222 -220.655642)
				)
				(arc
					(start 75.563222 -220.655642)
					(mid 76.777453 -221.309057)
					(end 77.261974 -222.600012)
				)
				(xy 77.261974 -225.460052) (xy 111.736886 -225.460052)
				(arc
					(start 111.736886 -222.39986)
					(mid 112.106852 -221.506938)
					(end 112.999774 -221.136972)
				)
				(xy 113.536984 -221.136972)
				(arc
					(start 113.536984 -214.799926)
					(mid 114.141219 -213.341173)
					(end 115.599972 -212.736938)
				)
				(arc
					(start 131.400042 -212.736938)
					(mid 132.858795 -213.341173)
					(end 133.46303 -214.799926)
				)
				(xy 133.46303 -221.136972)
				(arc
					(start 134.00024 -221.136972)
					(mid 134.893162 -221.506938)
					(end 135.263128 -222.39986)
				)
				(xy 135.263128 -225.460052) (xy 179.33797 -225.460052)
				(arc
					(start 179.33797 -222.600012)
					(mid 179.343934 -222.44689)
					(end 179.361846 -222.294704)
				)
				(arc
					(start 179.361846 -222.294704)
					(mid 179.927709 -221.197654)
					(end 181.036722 -220.655642)
				)
				(arc
					(start 181.036722 -220.655642)
					(mid 181.299994 -220.636928)
					(end 181.563264 -220.655642)
				)
				(arc
					(start 181.563264 -220.655642)
					(mid 182.777495 -221.309057)
					(end 183.262016 -222.600012)
				)
				(xy 183.262016 -225.460052) (xy 217.736928 -225.460052)
				(arc
					(start 217.736928 -222.39986)
					(mid 218.106894 -221.506938)
					(end 218.999816 -221.136972)
				)
				(xy 219.537026 -221.136972)
				(arc
					(start 219.537026 -214.799926)
					(mid 220.141261 -213.341173)
					(end 221.600014 -212.736938)
				)
				(arc
					(start 229.142036 -212.736938)
					(mid 232.138029 -211.495957)
					(end 233.37901 -208.499964)
				)
				(arc
					(start 233.37901 -165.269926)
					(mid 233.974467 -163.832367)
					(end 235.412026 -163.23691)
				)
				(arc
					(start 249.871992 -163.23691)
					(mid 251.309551 -163.832367)
					(end 251.905008 -165.269926)
				)
				(arc
					(start 251.905008 -208.499964)
					(mid 253.145989 -211.495957)
					(end 256.141982 -212.736938)
				)
				(arc
					(start 257.400044 -212.736938)
					(mid 258.858797 -213.341173)
					(end 259.463032 -214.799926)
				)
				(xy 259.463032 -221.136972)
				(arc
					(start 260.000242 -221.136972)
					(mid 260.893164 -221.506938)
					(end 261.26313 -222.39986)
				)
				(xy 261.26313 -225.460052) (xy 305.337972 -225.460052)
				(arc
					(start 305.337972 -222.600012)
					(mid 305.343936 -222.44689)
					(end 305.361848 -222.294704)
				)
				(arc
					(start 305.361848 -222.294704)
					(mid 305.927711 -221.197654)
					(end 307.036724 -220.655642)
				)
				(arc
					(start 307.036724 -220.655642)
					(mid 307.299996 -220.636928)
					(end 307.563266 -220.655642)
				)
				(arc
					(start 307.563266 -220.655642)
					(mid 308.777497 -221.309057)
					(end 309.262018 -222.600012)
				)
				(xy 309.262018 -225.460052) (xy 343.73693 -225.460052)
				(arc
					(start 343.73693 -222.39986)
					(mid 344.106896 -221.506938)
					(end 344.999818 -221.136972)
				)
				(xy 345.537028 -221.136972)
				(arc
					(start 345.537028 -214.799926)
					(mid 346.141263 -213.341173)
					(end 347.600016 -212.736938)
				)
				(arc
					(start 354.600002 -212.736938)
					(mid 354.767574 -212.667528)
					(end 354.836984 -212.499956)
				)
				(xy 354.836984 -19.463004)
				(arc
					(start 354.749862 -19.463004)
					(mid 353.856865 -19.093113)
					(end 353.486974 -18.200116)
				)
				(arc
					(start 353.486974 -10.199878)
					(mid 353.856865 -9.306881)
					(end 354.749862 -8.93699)
				)
				(xy 354.836984 -8.93699)
				(arc
					(start 354.836984 -0.999998)
					(mid 354.767574 -0.832426)
					(end 354.600002 -0.763016)
				)
				(arc
					(start 332.749906 -0.763016)
					(mid 331.503267 -0.246641)
					(end 330.986892 0.999998)
				)
				(arc
					(start 330.986892 3.999992)
					(mid 330.917482 4.167564)
					(end 330.74991 4.236974)
				)
			)
		)
		(polygon
			(pts
				(arc
					(start 341.306404 -222.805244)
					(mid 341.816944 -222.294704)
					(end 341.306404 -221.784164)
				)
				(arc
					(start 340.49335 -221.784164)
					(mid 339.983064 -222.294831)
					(end 340.493604 -222.805244)
				)
			)
		)
		(polygon
			(pts
				(arc
					(start 338.106766 -222.805244)
					(mid 338.617052 -222.294577)
					(end 338.106512 -221.784164)
				)
				(arc
					(start 337.293712 -221.784164)
					(mid 336.783172 -222.294704)
					(end 337.293712 -222.805244)
				)
			)
		)
		(polygon
			(pts
				(arc
					(start 334.90662 -222.805244)
					(mid 335.416906 -222.294577)
					(end 334.906366 -221.784164)
				)
				(arc
					(start 334.093566 -221.784164)
					(mid 333.583026 -222.294704)
					(end 334.093566 -222.805244)
				)
			)
		)
		(polygon
			(pts
				(arc
					(start 331.706728 -222.805244)
					(mid 332.217014 -222.294577)
					(end 331.706474 -221.784164)
				)
				(arc
					(start 330.893674 -221.784164)
					(mid 330.383134 -222.294704)
					(end 330.893674 -222.805244)
				)
			)
		)
		(polygon
			(pts
				(arc
					(start 328.506836 -222.805244)
					(mid 329.017122 -222.294577)
					(end 328.506582 -221.784164)
				)
				(arc
					(start 327.693782 -221.784164)
					(mid 327.183242 -222.294704)
					(end 327.693782 -222.805244)
				)
			)
		)
		(polygon
			(pts
				(arc
					(start 325.30669 -222.805244)
					(mid 325.816976 -222.294577)
					(end 325.306436 -221.784164)
				)
				(arc
					(start 324.493636 -221.784164)
					(mid 323.983096 -222.294704)
					(end 324.493636 -222.805244)
				)
			)
		)
		(polygon
			(pts
				(arc
					(start 322.106798 -222.805244)
					(mid 322.617084 -222.294577)
					(end 322.106544 -221.784164)
				)
				(arc
					(start 321.293744 -221.784164)
					(mid 320.783204 -222.294704)
					(end 321.293744 -222.805244)
				)
			)
		)
		(polygon
			(pts
				(arc
					(start 318.906652 -222.805244)
					(mid 319.416938 -222.294577)
					(end 318.906398 -221.784164)
				)
				(arc
					(start 318.093598 -221.784164)
					(mid 317.583058 -222.294704)
					(end 318.093598 -222.805244)
				)
			)
		)
		(polygon
			(pts
				(arc
					(start 315.70676 -222.805244)
					(mid 316.217046 -222.294577)
					(end 315.706506 -221.784164)
				)
				(arc
					(start 314.893706 -221.784164)
					(mid 314.383166 -222.294704)
					(end 314.893706 -222.805244)
				)
			)
		)
		(polygon
			(pts
				(arc
					(start 312.506614 -222.805244)
					(mid 313.0169 -222.294577)
					(end 312.50636 -221.784164)
				)
				(arc
					(start 311.69356 -221.784164)
					(mid 311.18302 -222.294704)
					(end 311.69356 -222.805244)
				)
			)
		)
		(polygon
			(pts
				(arc
					(start 301.306738 -222.805244)
					(mid 301.817024 -222.294577)
					(end 301.306484 -221.784164)
				)
				(arc
					(start 300.493684 -221.784164)
					(mid 299.983144 -222.294704)
					(end 300.493684 -222.805244)
				)
			)
		)
		(polygon
			(pts
				(arc
					(start 295.7068 -222.805244)
					(mid 296.217086 -222.294577)
					(end 295.706546 -221.784164)
				)
				(arc
					(start 294.893746 -221.784164)
					(mid 294.383206 -222.294704)
					(end 294.893746 -222.805244)
				)
			)
		)
		(polygon
			(pts
				(arc
					(start 292.506654 -222.805244)
					(mid 293.01694 -222.294577)
					(end 292.5064 -221.784164)
				)
				(arc
					(start 291.6936 -221.784164)
					(mid 291.18306 -222.294704)
					(end 291.6936 -222.805244)
				)
			)
		)
		(polygon
			(pts
				(arc
					(start 289.306762 -222.805244)
					(mid 289.817048 -222.294577)
					(end 289.306508 -221.784164)
				)
				(arc
					(start 288.493708 -221.784164)
					(mid 287.983168 -222.294704)
					(end 288.493708 -222.805244)
				)
			)
		)
		(polygon
			(pts
				(arc
					(start 286.106616 -222.805244)
					(mid 286.616902 -222.294577)
					(end 286.106362 -221.784164)
				)
				(arc
					(start 285.293562 -221.784164)
					(mid 284.783022 -222.294704)
					(end 285.293562 -222.805244)
				)
			)
		)
		(polygon
			(pts
				(arc
					(start 282.906724 -222.805244)
					(mid 283.41701 -222.294577)
					(end 282.90647 -221.784164)
				)
				(arc
					(start 282.09367 -221.784164)
					(mid 281.58313 -222.294704)
					(end 282.09367 -222.805244)
				)
			)
		)
		(polygon
			(pts
				(arc
					(start 279.706832 -222.805244)
					(mid 280.217118 -222.294577)
					(end 279.706578 -221.784164)
				)
				(arc
					(start 278.893778 -221.784164)
					(mid 278.383238 -222.294704)
					(end 278.893778 -222.805244)
				)
			)
		)
		(polygon
			(pts
				(arc
					(start 276.506686 -222.805244)
					(mid 277.016972 -222.294577)
					(end 276.506432 -221.784164)
				)
				(arc
					(start 275.693632 -221.784164)
					(mid 275.183092 -222.294704)
					(end 275.693632 -222.805244)
				)
			)
		)
		(polygon
			(pts
				(arc
					(start 273.306794 -222.805244)
					(mid 273.81708 -222.294577)
					(end 273.30654 -221.784164)
				)
				(arc
					(start 272.49374 -221.784164)
					(mid 271.9832 -222.294704)
					(end 272.49374 -222.805244)
				)
			)
		)
		(polygon
			(pts
				(arc
					(start 266.906756 -222.805244)
					(mid 267.417042 -222.294577)
					(end 266.906502 -221.784164)
				)
				(arc
					(start 266.093702 -221.784164)
					(mid 265.583162 -222.294704)
					(end 266.093702 -222.805244)
				)
			)
		)
		(polygon
			(pts
				(arc
					(start 263.70661 -222.805244)
					(mid 264.216896 -222.294577)
					(end 263.706356 -221.784164)
				)
				(arc
					(start 262.893556 -221.784164)
					(mid 262.383016 -222.294704)
					(end 262.893556 -222.805244)
				)
			)
		)
		(polygon
			(pts
				(arc
					(start 215.306656 -222.805244)
					(mid 215.816942 -222.294577)
					(end 215.306402 -221.784164)
				)
				(arc
					(start 214.493602 -221.784164)
					(mid 213.983062 -222.294704)
					(end 214.493602 -222.805244)
				)
			)
		)
		(polygon
			(pts
				(arc
					(start 212.106764 -222.805244)
					(mid 212.61705 -222.294577)
					(end 212.10651 -221.784164)
				)
				(arc
					(start 211.29371 -221.784164)
					(mid 210.78317 -222.294704)
					(end 211.29371 -222.805244)
				)
			)
		)
		(polygon
			(pts
				(arc
					(start 205.706726 -222.805244)
					(mid 206.217012 -222.294577)
					(end 205.706472 -221.784164)
				)
				(arc
					(start 204.893672 -221.784164)
					(mid 204.383132 -222.294704)
					(end 204.893672 -222.805244)
				)
			)
		)
		(polygon
			(pts
				(arc
					(start 202.506834 -222.805244)
					(mid 203.01712 -222.294577)
					(end 202.50658 -221.784164)
				)
				(arc
					(start 201.69378 -221.784164)
					(mid 201.18324 -222.294704)
					(end 201.69378 -222.805244)
				)
			)
		)
		(polygon
			(pts
				(arc
					(start 199.306688 -222.805244)
					(mid 199.816974 -222.294577)
					(end 199.306434 -221.784164)
				)
				(arc
					(start 198.493634 -221.784164)
					(mid 197.983094 -222.294704)
					(end 198.493634 -222.805244)
				)
			)
		)
		(polygon
			(pts
				(arc
					(start 196.106796 -222.805244)
					(mid 196.617082 -222.294577)
					(end 196.106542 -221.784164)
				)
				(arc
					(start 195.293742 -221.784164)
					(mid 194.783202 -222.294704)
					(end 195.293742 -222.805244)
				)
			)
		)
		(polygon
			(pts
				(arc
					(start 192.90665 -222.805244)
					(mid 193.416936 -222.294577)
					(end 192.906396 -221.784164)
				)
				(arc
					(start 192.093596 -221.784164)
					(mid 191.583056 -222.294704)
					(end 192.093596 -222.805244)
				)
			)
		)
		(polygon
			(pts
				(arc
					(start 189.706758 -222.805244)
					(mid 190.217044 -222.294577)
					(end 189.706504 -221.784164)
				)
				(arc
					(start 188.893704 -221.784164)
					(mid 188.383164 -222.294704)
					(end 188.893704 -222.805244)
				)
			)
		)
		(polygon
			(pts
				(arc
					(start 186.506358 -222.805244)
					(mid 187.016898 -222.294704)
					(end 186.506358 -221.784164)
				)
				(arc
					(start 185.693304 -221.784164)
					(mid 185.183018 -222.294831)
					(end 185.693558 -222.805244)
				)
			)
		)
		(polygon
			(pts
				(arc
					(start 175.306736 -222.805244)
					(mid 175.817022 -222.294577)
					(end 175.306482 -221.784164)
				)
				(arc
					(start 174.493682 -221.784164)
					(mid 173.983142 -222.294704)
					(end 174.493682 -222.805244)
				)
			)
		)
		(polygon
			(pts
				(arc
					(start 172.106844 -222.805244)
					(mid 172.61713 -222.294577)
					(end 172.10659 -221.784164)
				)
				(arc
					(start 171.29379 -221.784164)
					(mid 170.78325 -222.294704)
					(end 171.29379 -222.805244)
				)
			)
		)
		(polygon
			(pts
				(arc
					(start 168.906698 -222.805244)
					(mid 169.416984 -222.294577)
					(end 168.906444 -221.784164)
				)
				(arc
					(start 168.093644 -221.784164)
					(mid 167.583104 -222.294704)
					(end 168.093644 -222.805244)
				)
			)
		)
		(polygon
			(pts
				(arc
					(start 165.706806 -222.805244)
					(mid 166.217092 -222.294577)
					(end 165.706552 -221.784164)
				)
				(arc
					(start 164.893752 -221.784164)
					(mid 164.383212 -222.294704)
					(end 164.893752 -222.805244)
				)
			)
		)
		(polygon
			(pts
				(arc
					(start 160.106614 -222.805244)
					(mid 160.6169 -222.294577)
					(end 160.10636 -221.784164)
				)
				(arc
					(start 159.29356 -221.784164)
					(mid 158.78302 -222.294704)
					(end 159.29356 -222.805244)
				)
			)
		)
		(polygon
			(pts
				(arc
					(start 156.906722 -222.805244)
					(mid 157.417008 -222.294577)
					(end 156.906468 -221.784164)
				)
				(arc
					(start 156.093668 -221.784164)
					(mid 155.583128 -222.294704)
					(end 156.093668 -222.805244)
				)
			)
		)
		(polygon
			(pts
				(arc
					(start 153.70683 -222.805244)
					(mid 154.217116 -222.294577)
					(end 153.706576 -221.784164)
				)
				(arc
					(start 152.893776 -221.784164)
					(mid 152.383236 -222.294704)
					(end 152.893776 -222.805244)
				)
			)
		)
		(polygon
			(pts
				(arc
					(start 150.506684 -222.805244)
					(mid 151.01697 -222.294577)
					(end 150.50643 -221.784164)
				)
				(arc
					(start 149.69363 -221.784164)
					(mid 149.18309 -222.294704)
					(end 149.69363 -222.805244)
				)
			)
		)
		(polygon
			(pts
				(arc
					(start 147.306792 -222.805244)
					(mid 147.817078 -222.294577)
					(end 147.306538 -221.784164)
				)
				(arc
					(start 146.493738 -221.784164)
					(mid 145.983198 -222.294704)
					(end 146.493738 -222.805244)
				)
			)
		)
		(polygon
			(pts
				(arc
					(start 144.106646 -222.805244)
					(mid 144.616932 -222.294577)
					(end 144.106392 -221.784164)
				)
				(arc
					(start 143.293592 -221.784164)
					(mid 142.783052 -222.294704)
					(end 143.293592 -222.805244)
				)
			)
		)
		(polygon
			(pts
				(arc
					(start 140.906754 -222.805244)
					(mid 141.41704 -222.294577)
					(end 140.9065 -221.784164)
				)
				(arc
					(start 140.0937 -221.784164)
					(mid 139.58316 -222.294704)
					(end 140.0937 -222.805244)
				)
			)
		)
		(polygon
			(pts
				(arc
					(start 137.706608 -222.805244)
					(mid 138.216894 -222.294577)
					(end 137.706354 -221.784164)
				)
				(arc
					(start 136.893554 -221.784164)
					(mid 136.383014 -222.294704)
					(end 136.893554 -222.805244)
				)
			)
		)
		(polygon
			(pts
				(arc
					(start 106.906568 -222.805244)
					(mid 107.416854 -222.294577)
					(end 106.906314 -221.784164)
				)
				(arc
					(start 106.093514 -221.784164)
					(mid 105.582974 -222.294704)
					(end 106.093514 -222.805244)
				)
			)
		)
		(polygon
			(pts
				(arc
					(start 103.706422 -222.805244)
					(mid 104.216708 -222.294577)
					(end 103.706168 -221.784164)
				)
				(arc
					(start 102.893368 -221.784164)
					(mid 102.382828 -222.294704)
					(end 102.893368 -222.805244)
				)
			)
		)
		(polygon
			(pts
				(arc
					(start 100.50653 -222.805244)
					(mid 101.016816 -222.294577)
					(end 100.506276 -221.784164)
				)
				(arc
					(start 99.693476 -221.784164)
					(mid 99.182936 -222.294704)
					(end 99.693476 -222.805244)
				)
			)
		)
		(polygon
			(pts
				(arc
					(start 97.306638 -222.805244)
					(mid 97.816924 -222.294577)
					(end 97.306384 -221.784164)
				)
				(arc
					(start 96.493584 -221.784164)
					(mid 95.983044 -222.294704)
					(end 96.493584 -222.805244)
				)
			)
		)
		(polygon
			(pts
				(arc
					(start 91.706446 -222.805244)
					(mid 92.216732 -222.294577)
					(end 91.706192 -221.784164)
				)
				(arc
					(start 90.893392 -221.784164)
					(mid 90.382852 -222.294704)
					(end 90.893392 -222.805244)
				)
			)
		)
		(polygon
			(pts
				(arc
					(start 88.506554 -222.805244)
					(mid 89.01684 -222.294577)
					(end 88.5063 -221.784164)
				)
				(arc
					(start 87.6935 -221.784164)
					(mid 87.18296 -222.294704)
					(end 87.6935 -222.805244)
				)
			)
		)
		(polygon
			(pts
				(arc
					(start 85.306408 -222.805244)
					(mid 85.816694 -222.294577)
					(end 85.306154 -221.784164)
				)
				(arc
					(start 84.493354 -221.784164)
					(mid 83.982814 -222.294704)
					(end 84.493354 -222.805244)
				)
			)
		)
		(polygon
			(pts
				(arc
					(start 82.106516 -222.805244)
					(mid 82.616802 -222.294577)
					(end 82.106262 -221.784164)
				)
				(arc
					(start 81.293462 -221.784164)
					(mid 80.782922 -222.294704)
					(end 81.293462 -222.805244)
				)
			)
		)
		(polygon
			(pts
				(arc
					(start 69.30644 -222.805244)
					(mid 69.816726 -222.294577)
					(end 69.306186 -221.784164)
				)
				(arc
					(start 68.493386 -221.784164)
					(mid 67.982846 -222.294704)
					(end 68.493386 -222.805244)
				)
			)
		)
		(polygon
			(pts
				(arc
					(start 66.106548 -222.805244)
					(mid 66.616834 -222.294577)
					(end 66.106294 -221.784164)
				)
				(arc
					(start 65.293494 -221.784164)
					(mid 64.782954 -222.294704)
					(end 65.293494 -222.805244)
				)
			)
		)
		(polygon
			(pts
				(arc
					(start 60.506356 -222.805244)
					(mid 61.016642 -222.294577)
					(end 60.506102 -221.784164)
				)
				(arc
					(start 59.693302 -221.784164)
					(mid 59.182762 -222.294704)
					(end 59.693302 -222.805244)
				)
			)
		)
		(polygon
			(pts
				(arc
					(start 57.306464 -222.805244)
					(mid 57.81675 -222.294577)
					(end 57.30621 -221.784164)
				)
				(arc
					(start 56.49341 -221.784164)
					(mid 55.98287 -222.294704)
					(end 56.49341 -222.805244)
				)
			)
		)
		(polygon
			(pts
				(arc
					(start 54.106572 -222.805244)
					(mid 54.616858 -222.294577)
					(end 54.106318 -221.784164)
				)
				(arc
					(start 53.293518 -221.784164)
					(mid 52.782978 -222.294704)
					(end 53.293518 -222.805244)
				)
			)
		)
		(polygon
			(pts
				(arc
					(start 50.906426 -221.916244)
					(mid 51.416712 -221.405577)
					(end 50.906172 -220.895164)
				)
				(arc
					(start 50.093372 -220.895164)
					(mid 49.582832 -221.405704)
					(end 50.093372 -221.916244)
				)
			)
		)
		(polygon
			(pts
				(arc
					(start 178.409854 -221.18574)
					(mid 178.92014 -220.675073)
					(end 178.4096 -220.16466)
				)
				(arc
					(start 177.5968 -220.16466)
					(mid 177.08626 -220.6752)
					(end 177.5968 -221.18574)
				)
			)
		)
		(polygon
			(pts
				(arc
					(start 304.562002 -220.779086)
					(mid 305.056286 -220.252798)
					(end 304.529998 -219.758514)
				)
				(xy 304.529998 -219.755974) (xy 303.717198 -219.781374)
				(arc
					(start 303.717198 -219.783914)
					(mid 303.222914 -220.310202)
					(end 303.749202 -220.804486)
				)
				(xy 303.749202 -220.807026) (xy 304.561748 -220.781626) (xy 304.562002 -220.781372)
			)
		)
		(polygon
			(pts
				(arc
					(start 72.517254 -220.52534)
					(mid 73.02754 -220.014673)
					(end 72.517 -219.50426)
				)
				(arc
					(start 71.7042 -219.50426)
					(mid 71.19366 -220.0148)
					(end 71.7042 -220.52534)
				)
			)
		)
		(polygon
			(pts
				(arc
					(start 78.982824 -220.392244)
					(mid 79.49311 -219.881577)
					(end 78.98257 -219.371164)
				)
				(arc
					(start 78.16977 -219.371164)
					(mid 77.65923 -219.881704)
					(end 78.16977 -220.392244)
				)
			)
		)
		(polygon
			(pts
				(arc
					(start 342.906604 -211.406994)
					(mid 343.41689 -210.896327)
					(end 342.90635 -210.385914)
				)
				(arc
					(start 342.09355 -210.385914)
					(mid 341.58301 -210.896454)
					(end 342.09355 -211.406994)
				)
			)
		)
		(polygon
			(pts
				(arc
					(start 339.706712 -211.406994)
					(mid 340.216998 -210.896327)
					(end 339.706458 -210.385914)
				)
				(arc
					(start 338.893658 -210.385914)
					(mid 338.383118 -210.896454)
					(end 338.893658 -211.406994)
				)
			)
		)
		(polygon
			(pts
				(arc
					(start 336.506566 -211.406994)
					(mid 337.017106 -210.896454)
					(end 336.506566 -210.385914)
				)
				(arc
					(start 335.693512 -210.385914)
					(mid 335.183226 -210.896581)
					(end 335.693766 -211.406994)
				)
			)
		)
		(polygon
			(pts
				(arc
					(start 333.306674 -211.406994)
					(mid 333.817214 -210.896454)
					(end 333.306674 -210.385914)
				)
				(arc
					(start 332.49362 -210.385914)
					(mid 331.983334 -210.896581)
					(end 332.493874 -211.406994)
				)
			)
		)
		(polygon
			(pts
				(arc
					(start 326.906382 -211.406994)
					(mid 327.416922 -210.896454)
					(end 326.906382 -210.385914)
				)
				(arc
					(start 326.093328 -210.385914)
					(mid 325.583042 -210.896581)
					(end 326.093582 -211.406994)
				)
			)
		)
		(polygon
			(pts
				(arc
					(start 323.70649 -211.406994)
					(mid 324.21703 -210.896454)
					(end 323.70649 -210.385914)
				)
				(arc
					(start 322.893436 -210.385914)
					(mid 322.38315 -210.896581)
					(end 322.89369 -211.406994)
				)
			)
		)
		(polygon
			(pts
				(arc
					(start 320.506598 -211.406994)
					(mid 321.017138 -210.896454)
					(end 320.506598 -210.385914)
				)
				(arc
					(start 319.693544 -210.385914)
					(mid 319.183258 -210.896581)
					(end 319.693798 -211.406994)
				)
			)
		)
		(polygon
			(pts
				(arc
					(start 317.306706 -211.406994)
					(mid 317.817246 -210.896454)
					(end 317.306706 -210.385914)
				)
				(arc
					(start 316.493652 -210.385914)
					(mid 315.983366 -210.896581)
					(end 316.493906 -211.406994)
				)
			)
		)
		(polygon
			(pts
				(arc
					(start 314.10656 -211.406994)
					(mid 314.6171 -210.896454)
					(end 314.10656 -210.385914)
				)
				(arc
					(start 313.293506 -210.385914)
					(mid 312.78322 -210.896581)
					(end 313.29376 -211.406994)
				)
			)
		)
		(polygon
			(pts
				(arc
					(start 310.906922 -211.406994)
					(mid 311.417208 -210.896327)
					(end 310.906668 -210.385914)
				)
				(arc
					(start 310.093868 -210.385914)
					(mid 309.583328 -210.896454)
					(end 310.093868 -211.406994)
				)
			)
		)
		(polygon
			(pts
				(arc
					(start 302.90643 -211.406994)
					(mid 303.41697 -210.896454)
					(end 302.90643 -210.385914)
				)
				(arc
					(start 302.093376 -210.385914)
					(mid 301.58309 -210.896581)
					(end 302.09363 -211.406994)
				)
			)
		)
		(polygon
			(pts
				(arc
					(start 299.706538 -211.406994)
					(mid 300.217078 -210.896454)
					(end 299.706538 -210.385914)
				)
				(arc
					(start 298.893484 -210.385914)
					(mid 298.383198 -210.896581)
					(end 298.893738 -211.406994)
				)
			)
		)
		(polygon
			(pts
				(arc
					(start 294.106346 -211.406994)
					(mid 294.616886 -210.896454)
					(end 294.106346 -210.385914)
				)
				(arc
					(start 293.293292 -210.385914)
					(mid 292.783006 -210.896581)
					(end 293.293546 -211.406994)
				)
			)
		)
		(polygon
			(pts
				(arc
					(start 290.906454 -211.406994)
					(mid 291.416994 -210.896454)
					(end 290.906454 -210.385914)
				)
				(arc
					(start 290.0934 -210.385914)
					(mid 289.583114 -210.896581)
					(end 290.093654 -211.406994)
				)
			)
		)
		(polygon
			(pts
				(arc
					(start 287.706816 -211.406994)
					(mid 288.217102 -210.896327)
					(end 287.706562 -210.385914)
				)
				(arc
					(start 286.893762 -210.385914)
					(mid 286.383222 -210.896454)
					(end 286.893762 -211.406994)
				)
			)
		)
		(polygon
			(pts
				(arc
					(start 284.506416 -211.406994)
					(mid 285.016956 -210.896454)
					(end 284.506416 -210.385914)
				)
				(arc
					(start 283.693362 -210.385914)
					(mid 283.183076 -210.896581)
					(end 283.693616 -211.406994)
				)
			)
		)
		(polygon
			(pts
				(arc
					(start 281.306524 -211.406994)
					(mid 281.817064 -210.896454)
					(end 281.306524 -210.385914)
				)
				(arc
					(start 280.49347 -210.385914)
					(mid 279.983184 -210.896581)
					(end 280.493724 -211.406994)
				)
			)
		)
		(polygon
			(pts
				(arc
					(start 278.106378 -211.406994)
					(mid 278.616918 -210.896454)
					(end 278.106378 -210.385914)
				)
				(arc
					(start 277.293324 -210.385914)
					(mid 276.783038 -210.896581)
					(end 277.293578 -211.406994)
				)
			)
		)
		(polygon
			(pts
				(arc
					(start 274.906486 -211.406994)
					(mid 275.417026 -210.896454)
					(end 274.906486 -210.385914)
				)
				(arc
					(start 274.093432 -210.385914)
					(mid 273.583146 -210.896581)
					(end 274.093686 -211.406994)
				)
			)
		)
		(polygon
			(pts
				(arc
					(start 271.706594 -211.406994)
					(mid 272.217134 -210.896454)
					(end 271.706594 -210.385914)
				)
				(arc
					(start 270.89354 -210.385914)
					(mid 270.383254 -210.896581)
					(end 270.893794 -211.406994)
				)
			)
		)
		(polygon
			(pts
				(arc
					(start 268.506448 -211.406994)
					(mid 269.016988 -210.896454)
					(end 268.506448 -210.385914)
				)
				(arc
					(start 267.693394 -210.385914)
					(mid 267.183108 -210.896581)
					(end 267.693648 -211.406994)
				)
			)
		)
		(polygon
			(pts
				(arc
					(start 265.306556 -211.406994)
					(mid 265.817096 -210.896454)
					(end 265.306556 -210.385914)
				)
				(arc
					(start 264.493502 -210.385914)
					(mid 263.983216 -210.896581)
					(end 264.493756 -211.406994)
				)
			)
		)
		(polygon
			(pts
				(arc
					(start 216.906348 -211.406994)
					(mid 217.416888 -210.896454)
					(end 216.906348 -210.385914)
				)
				(arc
					(start 216.093294 -210.385914)
					(mid 215.583008 -210.896581)
					(end 216.093548 -211.406994)
				)
			)
		)
		(polygon
			(pts
				(arc
					(start 213.706456 -211.406994)
					(mid 214.216996 -210.896454)
					(end 213.706456 -210.385914)
				)
				(arc
					(start 212.893402 -210.385914)
					(mid 212.383116 -210.896581)
					(end 212.893656 -211.406994)
				)
			)
		)
		(polygon
			(pts
				(arc
					(start 207.306418 -211.406994)
					(mid 207.816958 -210.896454)
					(end 207.306418 -210.385914)
				)
				(arc
					(start 206.493364 -210.385914)
					(mid 205.983078 -210.896581)
					(end 206.493618 -211.406994)
				)
			)
		)
		(polygon
			(pts
				(arc
					(start 204.106526 -211.406994)
					(mid 204.617066 -210.896454)
					(end 204.106526 -210.385914)
				)
				(arc
					(start 203.293472 -210.385914)
					(mid 202.783186 -210.896581)
					(end 203.293726 -211.406994)
				)
			)
		)
		(polygon
			(pts
				(arc
					(start 200.90638 -211.406994)
					(mid 201.41692 -210.896454)
					(end 200.90638 -210.385914)
				)
				(arc
					(start 200.093326 -210.385914)
					(mid 199.58304 -210.896581)
					(end 200.09358 -211.406994)
				)
			)
		)
		(polygon
			(pts
				(arc
					(start 197.706488 -211.406994)
					(mid 198.217028 -210.896454)
					(end 197.706488 -210.385914)
				)
				(arc
					(start 196.893434 -210.385914)
					(mid 196.383148 -210.896581)
					(end 196.893688 -211.406994)
				)
			)
		)
		(polygon
			(pts
				(arc
					(start 194.506596 -211.406994)
					(mid 195.017136 -210.896454)
					(end 194.506596 -210.385914)
				)
				(arc
					(start 193.693542 -210.385914)
					(mid 193.183256 -210.896581)
					(end 193.693796 -211.406994)
				)
			)
		)
		(polygon
			(pts
				(arc
					(start 191.30645 -211.406994)
					(mid 191.81699 -210.896454)
					(end 191.30645 -210.385914)
				)
				(arc
					(start 190.493396 -210.385914)
					(mid 189.98311 -210.896581)
					(end 190.49365 -211.406994)
				)
			)
		)
		(polygon
			(pts
				(arc
					(start 188.106558 -211.406994)
					(mid 188.617098 -210.896454)
					(end 188.106558 -210.385914)
				)
				(arc
					(start 187.293504 -210.385914)
					(mid 186.783218 -210.896581)
					(end 187.293758 -211.406994)
				)
			)
		)
		(polygon
			(pts
				(arc
					(start 184.906412 -211.406994)
					(mid 185.416952 -210.896454)
					(end 184.906412 -210.385914)
				)
				(arc
					(start 184.093358 -210.385914)
					(mid 183.583072 -210.896581)
					(end 184.093612 -211.406994)
				)
			)
		)
		(polygon
			(pts
				(arc
					(start 176.906428 -211.406994)
					(mid 177.416968 -210.896454)
					(end 176.906428 -210.385914)
				)
				(arc
					(start 176.093374 -210.385914)
					(mid 175.583088 -210.896581)
					(end 176.093628 -211.406994)
				)
			)
		)
		(polygon
			(pts
				(arc
					(start 173.706536 -211.406994)
					(mid 174.217076 -210.896454)
					(end 173.706536 -210.385914)
				)
				(arc
					(start 172.893482 -210.385914)
					(mid 172.383196 -210.896581)
					(end 172.893736 -211.406994)
				)
			)
		)
		(polygon
			(pts
				(arc
					(start 170.50639 -211.406994)
					(mid 171.01693 -210.896454)
					(end 170.50639 -210.385914)
				)
				(arc
					(start 169.693336 -210.385914)
					(mid 169.18305 -210.896581)
					(end 169.69359 -211.406994)
				)
			)
		)
		(polygon
			(pts
				(arc
					(start 167.306498 -211.406994)
					(mid 167.817038 -210.896454)
					(end 167.306498 -210.385914)
				)
				(arc
					(start 166.493444 -210.385914)
					(mid 165.983158 -210.896581)
					(end 166.493698 -211.406994)
				)
			)
		)
		(polygon
			(pts
				(arc
					(start 161.70656 -211.406994)
					(mid 162.2171 -210.896454)
					(end 161.70656 -210.385914)
				)
				(arc
					(start 160.893506 -210.385914)
					(mid 160.38322 -210.896581)
					(end 160.89376 -211.406994)
				)
			)
		)
		(polygon
			(pts
				(arc
					(start 158.506668 -211.406994)
					(mid 159.017208 -210.896454)
					(end 158.506668 -210.385914)
				)
				(arc
					(start 157.693614 -210.385914)
					(mid 157.183328 -210.896581)
					(end 157.693868 -211.406994)
				)
			)
		)
		(polygon
			(pts
				(arc
					(start 155.306522 -211.406994)
					(mid 155.817062 -210.896454)
					(end 155.306522 -210.385914)
				)
				(arc
					(start 154.493468 -210.385914)
					(mid 153.983182 -210.896581)
					(end 154.493722 -211.406994)
				)
			)
		)
		(polygon
			(pts
				(arc
					(start 152.10663 -211.406994)
					(mid 152.61717 -210.896454)
					(end 152.10663 -210.385914)
				)
				(arc
					(start 151.293576 -210.385914)
					(mid 150.78329 -210.896581)
					(end 151.29383 -211.406994)
				)
			)
		)
		(polygon
			(pts
				(arc
					(start 148.906484 -211.406994)
					(mid 149.417024 -210.896454)
					(end 148.906484 -210.385914)
				)
				(arc
					(start 148.09343 -210.385914)
					(mid 147.583144 -210.896581)
					(end 148.093684 -211.406994)
				)
			)
		)
		(polygon
			(pts
				(arc
					(start 145.706592 -211.406994)
					(mid 146.217132 -210.896454)
					(end 145.706592 -210.385914)
				)
				(arc
					(start 144.893538 -210.385914)
					(mid 144.383252 -210.896581)
					(end 144.893792 -211.406994)
				)
			)
		)
		(polygon
			(pts
				(arc
					(start 142.5067 -211.406994)
					(mid 143.01724 -210.896454)
					(end 142.5067 -210.385914)
				)
				(arc
					(start 141.693646 -210.385914)
					(mid 141.18336 -210.896581)
					(end 141.6939 -211.406994)
				)
			)
		)
		(polygon
			(pts
				(arc
					(start 139.306554 -211.406994)
					(mid 139.817094 -210.896454)
					(end 139.306554 -210.385914)
				)
				(arc
					(start 138.4935 -210.385914)
					(mid 137.983214 -210.896581)
					(end 138.493754 -211.406994)
				)
			)
		)
		(polygon
			(pts
				(arc
					(start 108.506514 -211.406994)
					(mid 109.017054 -210.896454)
					(end 108.506514 -210.385914)
				)
				(arc
					(start 107.69346 -210.385914)
					(mid 107.183174 -210.896581)
					(end 107.693714 -211.406994)
				)
			)
		)
		(polygon
			(pts
				(arc
					(start 105.306622 -211.406994)
					(mid 105.817162 -210.896454)
					(end 105.306622 -210.385914)
				)
				(arc
					(start 104.493568 -210.385914)
					(mid 103.983282 -210.896581)
					(end 104.493822 -211.406994)
				)
			)
		)
		(polygon
			(pts
				(arc
					(start 102.10673 -211.406994)
					(mid 102.617016 -210.896327)
					(end 102.106476 -210.385914)
				)
				(arc
					(start 101.293676 -210.385914)
					(mid 100.783136 -210.896454)
					(end 101.293676 -211.406994)
				)
			)
		)
		(polygon
			(pts
				(arc
					(start 98.906584 -211.406994)
					(mid 99.417124 -210.896454)
					(end 98.906584 -210.385914)
				)
				(arc
					(start 98.09353 -210.385914)
					(mid 97.583244 -210.896581)
					(end 98.093784 -211.406994)
				)
			)
		)
		(polygon
			(pts
				(arc
					(start 93.306392 -211.406994)
					(mid 93.816932 -210.896454)
					(end 93.306392 -210.385914)
				)
				(arc
					(start 92.493338 -210.385914)
					(mid 91.983052 -210.896581)
					(end 92.493592 -211.406994)
				)
			)
		)
		(polygon
			(pts
				(arc
					(start 90.1065 -211.406994)
					(mid 90.61704 -210.896454)
					(end 90.1065 -210.385914)
				)
				(arc
					(start 89.293446 -210.385914)
					(mid 88.78316 -210.896581)
					(end 89.2937 -211.406994)
				)
			)
		)
		(polygon
			(pts
				(arc
					(start 86.906354 -211.406994)
					(mid 87.416894 -210.896454)
					(end 86.906354 -210.385914)
				)
				(arc
					(start 86.0933 -210.385914)
					(mid 85.583014 -210.896581)
					(end 86.093554 -211.406994)
				)
			)
		)
		(polygon
			(pts
				(arc
					(start 83.706462 -211.406994)
					(mid 84.217002 -210.896454)
					(end 83.706462 -210.385914)
				)
				(arc
					(start 82.893408 -210.385914)
					(mid 82.383122 -210.896581)
					(end 82.893662 -211.406994)
				)
			)
		)
		(polygon
			(pts
				(arc
					(start 80.506316 -211.406994)
					(mid 81.016856 -210.896454)
					(end 80.506316 -210.385914)
				)
				(arc
					(start 79.693262 -210.385914)
					(mid 79.182976 -210.896581)
					(end 79.693516 -211.406994)
				)
			)
		)
		(polygon
			(pts
				(arc
					(start 70.906386 -211.406994)
					(mid 71.416926 -210.896454)
					(end 70.906386 -210.385914)
				)
				(arc
					(start 70.093332 -210.385914)
					(mid 69.583046 -210.896581)
					(end 70.093586 -211.406994)
				)
			)
		)
		(polygon
			(pts
				(arc
					(start 67.706494 -211.406994)
					(mid 68.217034 -210.896454)
					(end 67.706494 -210.385914)
				)
				(arc
					(start 66.89344 -210.385914)
					(mid 66.383154 -210.896581)
					(end 66.893694 -211.406994)
				)
			)
		)
		(polygon
			(pts
				(arc
					(start 64.506348 -211.406994)
					(mid 65.016888 -210.896454)
					(end 64.506348 -210.385914)
				)
				(arc
					(start 63.693294 -210.385914)
					(mid 63.183008 -210.896581)
					(end 63.693548 -211.406994)
				)
			)
		)
		(polygon
			(pts
				(arc
					(start 58.90641 -211.406994)
					(mid 59.41695 -210.896454)
					(end 58.90641 -210.385914)
				)
				(arc
					(start 58.093356 -210.385914)
					(mid 57.58307 -210.896581)
					(end 58.09361 -211.406994)
				)
			)
		)
		(polygon
			(pts
				(arc
					(start 55.706772 -211.406994)
					(mid 56.217058 -210.896327)
					(end 55.706518 -210.385914)
				)
				(arc
					(start 54.893718 -210.385914)
					(mid 54.383178 -210.896454)
					(end 54.893718 -211.406994)
				)
			)
		)
		(polygon
			(pts
				(arc
					(start 52.506372 -211.406994)
					(mid 53.016912 -210.896454)
					(end 52.506372 -210.385914)
				)
				(arc
					(start 51.693318 -210.385914)
					(mid 51.183032 -210.896581)
					(end 51.693572 -211.406994)
				)
			)
		)
		(polygon
			(pts
				(arc
					(start 49.30648 -211.406994)
					(mid 49.81702 -210.896454)
					(end 49.30648 -210.385914)
				)
				(arc
					(start 48.493426 -210.385914)
					(mid 47.98314 -210.896581)
					(end 48.49368 -211.406994)
				)
			)
		)
		(polygon
			(pts
				(arc
					(start 50.95748 -209.222594)
					(mid 51.46802 -208.712054)
					(end 50.95748 -208.201514)
				)
				(arc
					(start 50.144426 -208.201514)
					(mid 49.63414 -208.712181)
					(end 50.14468 -209.222594)
				)
			)
		)
		(polygon
			(pts
				(arc
					(start 58.8645 -196.77634)
					(mid 59.37504 -196.2658)
					(end 58.8645 -195.75526)
				)
				(arc
					(start 58.051446 -195.75526)
					(mid 57.54116 -196.265927)
					(end 58.0517 -196.77634)
				)
			)
		)
		(polygon
			(pts
				(arc
					(start 92.332048 -184.941718)
					(mid 91.61018 -184.941718)
					(end 91.61018 -185.663586)
				)
				(xy 91.608402 -185.665364) (xy 92.18295 -186.240166) (xy 92.183204 -186.240166)
				(arc
					(start 92.184982 -186.238388)
					(mid 92.90685 -186.238388)
					(end 92.90685 -185.51652)
				)
				(xy 92.908628 -185.514742) (xy 92.333826 -184.93994)
			)
		)
		(polygon
			(pts
				(arc
					(start 94.202504 -184.15254)
					(mid 94.71279 -183.641873)
					(end 94.20225 -183.13146)
				)
				(arc
					(start 93.38945 -183.13146)
					(mid 92.87891 -183.642)
					(end 93.38945 -184.15254)
				)
			)
		)
		(polygon
			(pts
				(arc
					(start 26.74112 -142.580106)
					(mid 26.128853 -141.96822)
					(end 25.51684 -142.58036)
				)
				(arc
					(start 25.51684 -143.69796)
					(mid 26.12898 -144.3101)
					(end 26.74112 -143.69796)
				)
			)
		)
		(polygon
			(pts
				(arc
					(start 52.2478 -129.58826)
					(mid 52.218042 -129.516418)
					(end 52.1462 -129.48666)
				)
				(arc
					(start 50.927 -129.48666)
					(mid 50.855158 -129.516418)
					(end 50.8254 -129.58826)
				)
				(arc
					(start 50.8254 -130.9624)
					(mid 50.855158 -131.034242)
					(end 50.927 -131.064)
				)
				(arc
					(start 52.1462 -131.064)
					(mid 52.218042 -131.034242)
					(end 52.2478 -130.9624)
				)
			)
		)
		(polygon
			(pts
				(arc
					(start 66.143378 -128.189736)
					(mid 66.653918 -127.679196)
					(end 66.143378 -127.168656)
				)
				(arc
					(start 65.330324 -127.168656)
					(mid 64.820038 -127.679323)
					(end 65.330578 -128.189736)
				)
			)
		)
		(polygon
			(pts
				(arc
					(start 23.77694 -113.994946)
					(mid 23.164673 -113.38306)
					(end 22.55266 -113.9952)
				)
				(arc
					(start 22.55266 -115.1128)
					(mid 23.1648 -115.72494)
					(end 23.77694 -115.1128)
				)
			)
		)
		(polygon
			(pts
				(arc
					(start 25.085294 -111.4044)
					(mid 24.473154 -110.79226)
					(end 23.861014 -111.4044)
				)
				(arc
					(start 23.861014 -112.522254)
					(mid 24.473281 -113.13414)
					(end 25.085294 -112.522)
				)
			)
		)
		(polygon
			(pts
				(arc
					(start 28.47594 -105.502202)
					(mid 27.610308 -105.502202)
					(end 27.610308 -106.367834)
				)
				(xy 27.60853 -106.369612) (xy 28.398978 -107.16006)
				(arc
					(start 28.400756 -107.158282)
					(mid 29.266388 -107.158282)
					(end 29.266388 -106.29265)
				)
				(xy 29.268166 -106.290872) (xy 28.477972 -105.500678) (xy 28.477464 -105.500678)
			)
		)
		(polygon
			(pts
				(arc
					(start 173.6344 -96.704912)
					(mid 174.14494 -96.194372)
					(end 173.6344 -95.683832)
				)
				(arc
					(start 172.745146 -95.683832)
					(mid 172.23486 -96.194499)
					(end 172.7454 -96.704912)
				)
			)
		)
		(polygon
			(pts
				(arc
					(start 168.212516 -88.645746)
					(mid 167.701849 -88.13546)
					(end 167.191436 -88.646)
				)
				(arc
					(start 167.191436 -89.4588)
					(mid 167.701976 -89.96934)
					(end 168.212516 -89.4588)
				)
			)
		)
		(polygon
			(pts
				(arc
					(start 21.209 -87.93734)
					(mid 21.71954 -87.4268)
					(end 21.209 -86.91626)
				)
				(arc
					(start 20.395946 -86.91626)
					(mid 19.88566 -87.426927)
					(end 20.3962 -87.93734)
				)
			)
		)
		(polygon
			(pts
				(arc
					(start 16.9672 -87.65794)
					(mid 17.57934 -87.0458)
					(end 16.9672 -86.43366)
				)
				(arc
					(start 15.8496 -86.43366)
					(mid 15.23746 -87.0458)
					(end 15.8496 -87.65794)
				)
			)
		)
		(polygon
			(pts
				(arc
					(start 56.86298 -85.210396)
					(mid 56.250713 -84.59851)
					(end 55.6387 -85.21065)
				)
				(arc
					(start 55.6387 -86.32825)
					(mid 56.25084 -86.94039)
					(end 56.86298 -86.32825)
				)
			)
		)
		(polygon
			(pts
				(arc
					(start 19.664934 -82.41792)
					(mid 20.175474 -81.90738)
					(end 19.664934 -81.39684)
				)
				(arc
					(start 18.85188 -81.39684)
					(mid 18.341594 -81.907507)
					(end 18.852134 -82.41792)
				)
			)
		)
		(polygon
			(pts
				(arc
					(start 163.512754 -82.17154)
					(mid 164.02304 -81.660873)
					(end 163.5125 -81.15046)
				)
				(arc
					(start 162.6997 -81.15046)
					(mid 162.18916 -81.661)
					(end 162.6997 -82.17154)
				)
			)
		)
		(polygon
			(pts
				(arc
					(start 103.2383 -81.000346)
					(mid 102.626033 -80.38846)
					(end 102.01402 -81.0006)
				)
				(arc
					(start 102.01402 -82.1182)
					(mid 102.62616 -82.73034)
					(end 103.2383 -82.1182)
				)
			)
		)
		(polygon
			(pts
				(arc
					(start 87.290148 -76.589636)
					(mid 86.779608 -76.079096)
					(end 86.269068 -76.589636)
				)
				(arc
					(start 86.269068 -77.47889)
					(mid 86.779735 -77.989176)
					(end 87.290148 -77.478636)
				)
			)
		)
		(polygon
			(pts
				(arc
					(start 16.6116 -73.727564)
					(mid 17.12214 -73.217024)
					(end 16.6116 -72.706484)
				)
				(arc
					(start 15.798546 -72.706484)
					(mid 15.28826 -73.217151)
					(end 15.7988 -73.727564)
				)
			)
		)
		(polygon
			(pts
				(arc
					(start 19.38655 -73.721214)
					(mid 19.89709 -73.210674)
					(end 19.38655 -72.700134)
				)
				(arc
					(start 18.573496 -72.700134)
					(mid 18.06321 -73.210801)
					(end 18.57375 -73.721214)
				)
			)
		)
		(polygon
			(pts
				(arc
					(start 14.68374 -67.638168)
					(mid 14.173073 -67.127882)
					(end 13.66266 -67.638422)
				)
				(arc
					(start 13.66266 -68.451222)
					(mid 14.1732 -68.961762)
					(end 14.68374 -68.451222)
				)
			)
		)
		(polygon
			(pts
				(arc
					(start 16.69034 -66.223896)
					(mid 16.179673 -65.71361)
					(end 15.66926 -66.22415)
				)
				(arc
					(start 15.66926 -67.03695)
					(mid 16.1798 -67.54749)
					(end 16.69034 -67.03695)
				)
			)
		)
		(polygon
			(pts
				(arc
					(start 19.812 -58.851546)
					(mid 20.42414 -58.239406)
					(end 19.812 -57.627266)
				)
				(arc
					(start 18.6944 -57.627266)
					(mid 18.08226 -58.239406)
					(end 18.6944 -58.851546)
				)
			)
		)
		(polygon
			(pts
				(arc
					(start 23.535386 -57.300876)
					(mid 24.147526 -56.688736)
					(end 23.535386 -56.076596)
				)
				(arc
					(start 22.417786 -56.076596)
					(mid 21.805646 -56.688736)
					(end 22.417786 -57.300876)
				)
			)
		)
		(polygon
			(pts
				(arc
					(start 10.477754 -55.559452)
					(mid 10.98804 -55.048785)
					(end 10.4775 -54.538372)
				)
				(arc
					(start 9.6647 -54.538372)
					(mid 9.15416 -55.048912)
					(end 9.6647 -55.559452)
				)
			)
		)
		(polygon
			(pts
				(arc
					(start 19.659854 -55.508652)
					(mid 20.17014 -54.997985)
					(end 19.6596 -54.487572)
				)
				(arc
					(start 18.8468 -54.487572)
					(mid 18.33626 -54.998112)
					(end 18.8468 -55.508652)
				)
			)
		)
		(polygon
			(pts
				(arc
					(start 14.3764 -54.340252)
					(mid 14.88694 -53.829712)
					(end 14.3764 -53.319172)
				)
				(arc
					(start 13.563346 -53.319172)
					(mid 13.05306 -53.829839)
					(end 13.5636 -54.340252)
				)
			)
		)
		(polygon
			(pts
				(arc
					(start 23.368 -54.066694)
					(mid 23.87854 -53.556154)
					(end 23.368 -53.045614)
				)
				(arc
					(start 22.554946 -53.045614)
					(mid 22.04466 -53.556281)
					(end 22.5552 -54.066694)
				)
			)
		)
		(polygon
			(pts
				(arc
					(start 53.641244 -50.9778)
					(mid 53.611486 -50.905958)
					(end 53.539644 -50.8762)
				)
				(arc
					(start 52.165504 -50.8762)
					(mid 52.093662 -50.905958)
					(end 52.063904 -50.9778)
				)
				(arc
					(start 52.063904 -52.197)
					(mid 52.093662 -52.268842)
					(end 52.165504 -52.2986)
				)
				(arc
					(start 53.539644 -52.2986)
					(mid 53.611486 -52.268842)
					(end 53.641244 -52.197)
				)
			)
		)
		(polygon
			(pts
				(arc
					(start 203.7588 -50.29454)
					(mid 204.26934 -49.784)
					(end 203.7588 -49.27346)
				)
				(arc
					(start 202.945746 -49.27346)
					(mid 202.43546 -49.784127)
					(end 202.946 -50.29454)
				)
			)
		)
		(polygon
			(pts
				(arc
					(start 201.171302 -50.339752)
					(mid 201.780139 -49.724183)
					(end 201.164444 -49.115472)
				)
				(arc
					(start 200.046844 -49.122076)
					(mid 199.43826 -49.737772)
					(end 200.053956 -50.346356)
				)
			)
		)
		(polygon
			(pts
				(arc
					(start 53.305964 -48.387508)
					(mid 53.816504 -47.876968)
					(end 53.305964 -47.366428)
				)
				(arc
					(start 52.399184 -47.366428)
					(mid 51.888898 -47.877095)
					(end 52.399438 -48.387508)
				)
			)
		)
		(polygon
			(pts
				(arc
					(start 198.429118 -45.590206)
					(mid 197.816851 -44.97832)
					(end 197.204838 -45.59046)
				)
				(arc
					(start 197.204838 -46.70806)
					(mid 197.816978 -47.3202)
					(end 198.429118 -46.70806)
				)
			)
		)
		(polygon
			(pts
				(arc
					(start 212.0646 -44.5516)
					(mid 212.027403 -44.461797)
					(end 211.9376 -44.4246)
				)
				(arc
					(start 210.6168 -44.4246)
					(mid 210.526997 -44.461797)
					(end 210.4898 -44.5516)
				)
				(arc
					(start 210.4898 -45.847)
					(mid 210.526997 -45.936803)
					(end 210.6168 -45.974)
				)
				(arc
					(start 211.9376 -45.974)
					(mid 212.027403 -45.936803)
					(end 212.0646 -45.847)
				)
			)
		)
		(polygon
			(pts
				(arc
					(start 201.97318 -44.714922)
					(mid 201.36104 -44.102782)
					(end 200.7489 -44.714922)
				)
				(arc
					(start 200.7489 -45.832776)
					(mid 201.361167 -46.444662)
					(end 201.97318 -45.832522)
				)
			)
		)
		(polygon
			(pts
				(arc
					(start 132.358384 -41.604946)
					(mid 131.746117 -40.99306)
					(end 131.134104 -41.6052)
				)
				(arc
					(start 131.134104 -42.7228)
					(mid 131.746244 -43.33494)
					(end 132.358384 -42.7228)
				)
			)
		)
		(polygon
			(pts
				(arc
					(start 306.575968 -40.31996)
					(mid 307.086254 -39.809293)
					(end 306.575714 -39.29888)
				)
				(arc
					(start 305.762914 -39.29888)
					(mid 305.252374 -39.80942)
					(end 305.762914 -40.31996)
				)
			)
		)
		(polygon
			(pts
				(arc
					(start 102.44074 -38.916356)
					(mid 101.930073 -38.40607)
					(end 101.41966 -38.91661)
				)
				(arc
					(start 101.41966 -39.80561)
					(mid 101.9302 -40.31615)
					(end 102.44074 -39.80561)
				)
			)
		)
		(polygon
			(pts
				(arc
					(start 139.3698 -39.16934)
					(mid 139.88034 -38.6588)
					(end 139.3698 -38.14826)
				)
				(arc
					(start 138.556746 -38.14826)
					(mid 138.04646 -38.658927)
					(end 138.557 -39.16934)
				)
			)
		)
		(polygon
			(pts
				(arc
					(start 151.727154 -38.59784)
					(mid 152.23744 -38.087173)
					(end 151.7269 -37.57676)
				)
				(arc
					(start 150.9141 -37.57676)
					(mid 150.40356 -38.0873)
					(end 150.9141 -38.59784)
				)
			)
		)
		(polygon
			(pts
				(arc
					(start 162.598354 -38.52164)
					(mid 163.10864 -38.010973)
					(end 162.5981 -37.50056)
				)
				(arc
					(start 161.7853 -37.50056)
					(mid 161.27476 -38.0111)
					(end 161.7853 -38.52164)
				)
			)
		)
		(polygon
			(pts
				(arc
					(start 320.53403 -37.53612)
					(mid 321.044316 -37.025453)
					(end 320.533776 -36.51504)
				)
				(arc
					(start 319.720722 -36.51504)
					(mid 319.210436 -37.025707)
					(end 319.720976 -37.53612)
				)
			)
		)
		(polygon
			(pts
				(arc
					(start 304.647854 -36.794694)
					(mid 305.15814 -36.284027)
					(end 304.6476 -35.773614)
				)
				(arc
					(start 303.8348 -35.773614)
					(mid 303.32426 -36.284154)
					(end 303.8348 -36.794694)
				)
			)
		)
		(polygon
			(pts
				(arc
					(start 103.02494 -36.205668)
					(mid 102.5144 -35.695128)
					(end 102.00386 -36.205668)
				)
				(arc
					(start 102.00386 -37.094922)
					(mid 102.514527 -37.605208)
					(end 103.02494 -37.094668)
				)
			)
		)
		(polygon
			(pts
				(arc
					(start 300.243494 -36.699952)
					(mid 300.754034 -36.189412)
					(end 300.243494 -35.678872)
				)
				(arc
					(start 299.43044 -35.678872)
					(mid 298.920154 -36.189539)
					(end 299.430694 -36.699952)
				)
			)
		)
		(polygon
			(pts
				(arc
					(start 313.489086 -36.696142)
					(mid 313.999626 -36.185602)
					(end 313.489086 -35.675062)
				)
				(arc
					(start 312.676032 -35.675062)
					(mid 312.165746 -36.185729)
					(end 312.676286 -36.696142)
				)
			)
		)
		(polygon
			(pts
				(arc
					(start 326.782176 -36.472114)
					(mid 327.292462 -35.961447)
					(end 326.781922 -35.451034)
				)
				(arc
					(start 325.969122 -35.451034)
					(mid 325.458582 -35.961574)
					(end 325.969122 -36.472114)
				)
			)
		)
		(polygon
			(pts
				(arc
					(start 134.665212 -36.250372)
					(mid 135.175498 -35.739705)
					(end 134.664958 -35.229292)
				)
				(arc
					(start 133.852158 -35.229292)
					(mid 133.341618 -35.739832)
					(end 133.852158 -36.250372)
				)
			)
		)
		(polygon
			(pts
				(arc
					(start 131.9022 -35.783774)
					(mid 132.41274 -35.273234)
					(end 131.9022 -34.762694)
				)
				(arc
					(start 131.089146 -34.762694)
					(mid 130.57886 -35.273361)
					(end 131.0894 -35.783774)
				)
			)
		)
		(polygon
			(pts
				(arc
					(start 294.971978 -35.69081)
					(mid 295.482518 -35.18027)
					(end 294.971978 -34.66973)
				)
				(arc
					(start 294.158924 -34.66973)
					(mid 293.648638 -35.180397)
					(end 294.159178 -35.69081)
				)
			)
		)
		(polygon
			(pts
				(arc
					(start 311.238646 -35.55238)
					(mid 311.748932 -35.041713)
					(end 311.238392 -34.5313)
				)
				(arc
					(start 310.425592 -34.5313)
					(mid 309.915052 -35.04184)
					(end 310.425592 -35.55238)
				)
			)
		)
		(polygon
			(pts
				(arc
					(start 302.472344 -35.536886)
					(mid 302.98263 -35.026219)
					(end 302.47209 -34.515806)
				)
				(arc
					(start 301.65929 -34.515806)
					(mid 301.14875 -35.026346)
					(end 301.65929 -35.536886)
				)
			)
		)
		(polygon
			(pts
				(arc
					(start 162.0901 -35.53206)
					(mid 162.60064 -35.02152)
					(end 162.0901 -34.51098)
				)
				(arc
					(start 161.277046 -34.51098)
					(mid 160.76676 -35.021647)
					(end 161.2773 -35.53206)
				)
			)
		)
		(polygon
			(pts
				(arc
					(start 159.467804 -35.53206)
					(mid 159.978344 -35.02152)
					(end 159.467804 -34.51098)
				)
				(arc
					(start 158.65475 -34.51098)
					(mid 158.144464 -35.021647)
					(end 158.655004 -35.53206)
				)
			)
		)
		(polygon
			(pts
				(arc
					(start 315.696854 -35.524694)
					(mid 316.20714 -35.014027)
					(end 315.6966 -34.503614)
				)
				(arc
					(start 314.8838 -34.503614)
					(mid 314.37326 -35.014154)
					(end 314.8838 -35.524694)
				)
			)
		)
		(polygon
			(pts
				(arc
					(start 290.042854 -35.524694)
					(mid 290.55314 -35.014027)
					(end 290.0426 -34.503614)
				)
				(arc
					(start 289.2298 -34.503614)
					(mid 288.71926 -35.014154)
					(end 289.2298 -35.524694)
				)
			)
		)
		(polygon
			(pts
				(arc
					(start 149.314154 -35.51174)
					(mid 149.82444 -35.001073)
					(end 149.3139 -34.49066)
				)
				(arc
					(start 148.5011 -34.49066)
					(mid 147.99056 -35.0012)
					(end 148.5011 -35.51174)
				)
			)
		)
		(polygon
			(pts
				(arc
					(start 153.530554 -35.50666)
					(mid 154.04084 -34.995993)
					(end 153.5303 -34.48558)
				)
				(arc
					(start 152.7175 -34.48558)
					(mid 152.20696 -34.99612)
					(end 152.7175 -35.50666)
				)
			)
		)
		(polygon
			(pts
				(arc
					(start 146.7231 -35.50666)
					(mid 147.23364 -34.99612)
					(end 146.7231 -34.48558)
				)
				(arc
					(start 145.910046 -34.48558)
					(mid 145.39976 -34.996247)
					(end 145.9103 -35.50666)
				)
			)
		)
		(polygon
			(pts
				(arc
					(start 138.379454 -35.503866)
					(mid 138.88974 -34.993199)
					(end 138.3792 -34.482786)
				)
				(arc
					(start 137.5664 -34.482786)
					(mid 137.05586 -34.993326)
					(end 137.5664 -35.503866)
				)
			)
		)
		(polygon
			(pts
				(arc
					(start 324.425564 -35.479482)
					(mid 324.93585 -34.968815)
					(end 324.42531 -34.458402)
				)
				(arc
					(start 323.612256 -34.458402)
					(mid 323.10197 -34.969069)
					(end 323.61251 -35.479482)
				)
			)
		)
		(polygon
			(pts
				(arc
					(start 329.188572 -35.429952)
					(mid 329.698858 -34.919285)
					(end 329.188318 -34.408872)
				)
				(arc
					(start 328.375518 -34.408872)
					(mid 327.864978 -34.919412)
					(end 328.375518 -35.429952)
				)
			)
		)
		(polygon
			(pts
				(arc
					(start 285.498794 -33.051496)
					(mid 284.988254 -32.540956)
					(end 284.477714 -33.051496)
				)
				(arc
					(start 284.477714 -33.86455)
					(mid 284.988381 -34.374836)
					(end 285.498794 -33.864296)
				)
			)
		)
		(polygon
			(pts
				(arc
					(start 183.59374 -28.993846)
					(mid 183.083073 -28.48356)
					(end 182.57266 -28.9941)
				)
				(arc
					(start 182.57266 -29.8069)
					(mid 183.0832 -30.31744)
					(end 183.59374 -29.8069)
				)
			)
		)
		(polygon
			(pts
				(arc
					(start 183.59374 -25.945846)
					(mid 183.083073 -25.43556)
					(end 182.57266 -25.9461)
				)
				(arc
					(start 182.57266 -26.7589)
					(mid 183.0832 -27.26944)
					(end 183.59374 -26.7589)
				)
			)
		)
		(polygon
			(pts
				(arc
					(start 186.56554 -24.99868)
					(mid 186.054873 -24.488394)
					(end 185.54446 -24.998934)
				)
				(arc
					(start 185.54446 -25.811734)
					(mid 186.055 -26.322274)
					(end 186.56554 -25.811734)
				)
			)
		)
		(polygon
			(pts
				(arc
					(start 145.435066 -24.22525)
					(mid 145.17939 -23.379349)
					(end 144.333468 -23.635208)
				)
				(xy 144.331436 -23.633938) (xy 143.581374 -25.033986)
				(arc
					(start 143.583406 -25.035256)
					(mid 143.839438 -25.881076)
					(end 144.685258 -25.625044)
				)
				(xy 144.68729 -25.626314) (xy 145.437352 -24.22652) (xy 145.437098 -24.226266)
			)
		)
		(polygon
			(pts
				(arc
					(start 298.435014 -24.22525)
					(mid 298.179338 -23.379349)
					(end 297.333416 -23.635208)
				)
				(xy 297.331384 -23.633938) (xy 296.581322 -25.033986)
				(arc
					(start 296.583354 -25.035256)
					(mid 296.839386 -25.881076)
					(end 297.685206 -25.625044)
				)
				(xy 297.687238 -25.626314) (xy 298.4373 -24.22652) (xy 298.437046 -24.226266)
			)
		)
		(polygon
			(pts
				(arc
					(start 324.935342 -24.224996)
					(mid 324.67931 -23.379176)
					(end 323.83349 -23.635208)
				)
				(xy 323.831458 -23.633938) (xy 323.081396 -25.033732) (xy 323.08165 -25.033986)
				(arc
					(start 323.083682 -25.035002)
					(mid 323.339358 -25.880903)
					(end 324.18528 -25.625044)
				)
				(xy 324.187312 -25.626314) (xy 324.937374 -24.226266)
			)
		)
		(polygon
			(pts
				(arc
					(start 322.68541 -24.224996)
					(mid 322.429378 -23.379176)
					(end 321.583558 -23.635208)
				)
				(xy 321.581526 -23.633938) (xy 320.831464 -25.033732) (xy 320.831718 -25.033986)
				(arc
					(start 320.83375 -25.035002)
					(mid 321.089426 -25.880903)
					(end 321.935348 -25.625044)
				)
				(xy 321.93738 -25.626314) (xy 322.687442 -24.226266)
			)
		)
		(polygon
			(pts
				(arc
					(start 313.935364 -24.224996)
					(mid 313.679332 -23.379176)
					(end 312.833512 -23.635208)
				)
				(xy 312.83148 -23.633938) (xy 312.081418 -25.033732) (xy 312.081672 -25.033986)
				(arc
					(start 312.083704 -25.035002)
					(mid 312.33938 -25.880903)
					(end 313.185302 -25.625044)
				)
				(xy 313.187334 -25.626314) (xy 313.937396 -24.226266)
			)
		)
		(polygon
			(pts
				(arc
					(start 311.685432 -24.224996)
					(mid 311.4294 -23.379176)
					(end 310.58358 -23.635208)
				)
				(xy 310.581548 -23.633938) (xy 309.831486 -25.033732) (xy 309.83174 -25.033986)
				(arc
					(start 309.833772 -25.035002)
					(mid 310.089448 -25.880903)
					(end 310.93537 -25.625044)
				)
				(xy 310.937402 -25.626314) (xy 311.687464 -24.226266)
			)
		)
		(polygon
			(pts
				(arc
					(start 302.935386 -24.224996)
					(mid 302.679354 -23.379176)
					(end 301.833534 -23.635208)
				)
				(xy 301.831502 -23.633938) (xy 301.08144 -25.033732) (xy 301.081694 -25.033986)
				(arc
					(start 301.083726 -25.035002)
					(mid 301.339402 -25.880903)
					(end 302.185324 -25.625044)
				)
				(xy 302.187356 -25.626314) (xy 302.937418 -24.226266)
			)
		)
		(polygon
			(pts
				(arc
					(start 300.6852 -24.224996)
					(mid 300.429168 -23.379176)
					(end 299.583348 -23.635208)
				)
				(arc
					(start 298.837604 -25.027636)
					(mid 299.085738 -25.879089)
					(end 299.935392 -25.625044)
				)
			)
		)
		(polygon
			(pts
				(arc
					(start 291.935408 -24.224996)
					(mid 291.679376 -23.379176)
					(end 290.833556 -23.635208)
				)
				(xy 290.831524 -23.633938) (xy 290.081462 -25.033732) (xy 290.081716 -25.033986)
				(arc
					(start 290.083748 -25.035002)
					(mid 290.339424 -25.880903)
					(end 291.185346 -25.625044)
				)
				(xy 291.187378 -25.626314) (xy 291.93744 -24.226266)
			)
		)
		(polygon
			(pts
				(arc
					(start 289.685222 -24.224996)
					(mid 289.42919 -23.379176)
					(end 288.58337 -23.635208)
				)
				(arc
					(start 287.837626 -25.027636)
					(mid 288.08576 -25.879089)
					(end 288.935414 -25.625044)
				)
			)
		)
		(polygon
			(pts
				(arc
					(start 287.43529 -24.224996)
					(mid 287.179258 -23.379176)
					(end 286.333438 -23.635208)
				)
				(xy 286.331406 -23.633938) (xy 285.581344 -25.033732) (xy 285.581598 -25.033986)
				(arc
					(start 285.58363 -25.035002)
					(mid 285.839306 -25.880903)
					(end 286.685228 -25.625044)
				)
				(xy 286.68726 -25.626314) (xy 287.437322 -24.226266)
			)
		)
		(polygon
			(pts
				(arc
					(start 171.935394 -24.224996)
					(mid 171.679362 -23.379176)
					(end 170.833542 -23.635208)
				)
				(xy 170.83151 -23.633938) (xy 170.081448 -25.033732) (xy 170.081702 -25.033986)
				(arc
					(start 170.083734 -25.035002)
					(mid 170.33941 -25.880903)
					(end 171.185332 -25.625044)
				)
				(xy 171.187364 -25.626314) (xy 171.937426 -24.226266)
			)
		)
		(polygon
			(pts
				(arc
					(start 169.685462 -24.224996)
					(mid 169.42943 -23.379176)
					(end 168.58361 -23.635208)
				)
				(xy 168.581578 -23.633938) (xy 167.831516 -25.033732) (xy 167.83177 -25.033986)
				(arc
					(start 167.833802 -25.035002)
					(mid 168.089478 -25.880903)
					(end 168.9354 -25.625044)
				)
				(xy 168.937432 -25.626314) (xy 169.687494 -24.226266)
			)
		)
		(polygon
			(pts
				(arc
					(start 160.935416 -24.224996)
					(mid 160.679384 -23.379176)
					(end 159.833564 -23.635208)
				)
				(xy 159.831532 -23.633938) (xy 159.08147 -25.033732) (xy 159.081724 -25.033986)
				(arc
					(start 159.083756 -25.035002)
					(mid 159.339432 -25.880903)
					(end 160.185354 -25.625044)
				)
				(xy 160.187386 -25.626314) (xy 160.937448 -24.226266)
			)
		)
		(polygon
			(pts
				(arc
					(start 158.685484 -24.224996)
					(mid 158.429452 -23.379176)
					(end 157.583632 -23.635208)
				)
				(xy 157.5816 -23.633938) (xy 156.831538 -25.033732) (xy 156.831792 -25.033986)
				(arc
					(start 156.833824 -25.035002)
					(mid 157.0895 -25.880903)
					(end 157.935422 -25.625044)
				)
				(xy 157.937454 -25.626314) (xy 158.687516 -24.226266)
			)
		)
		(polygon
			(pts
				(arc
					(start 149.935438 -24.224996)
					(mid 149.679406 -23.379176)
					(end 148.833586 -23.635208)
				)
				(xy 148.831554 -23.633938) (xy 148.081492 -25.033732) (xy 148.081746 -25.033986)
				(arc
					(start 148.083778 -25.035002)
					(mid 148.339454 -25.880903)
					(end 149.185376 -25.625044)
				)
				(xy 149.187408 -25.626314) (xy 149.93747 -24.226266)
			)
		)
		(polygon
			(pts
				(arc
					(start 147.685252 -24.224996)
					(mid 147.42922 -23.379176)
					(end 146.5834 -23.635208)
				)
				(arc
					(start 145.837656 -25.027636)
					(mid 146.08579 -25.879089)
					(end 146.935444 -25.625044)
				)
			)
		)
		(polygon
			(pts
				(arc
					(start 138.93546 -24.224996)
					(mid 138.679428 -23.379176)
					(end 137.833608 -23.635208)
				)
				(xy 137.831576 -23.633938) (xy 137.081514 -25.033732) (xy 137.081768 -25.033986)
				(arc
					(start 137.0838 -25.035002)
					(mid 137.339476 -25.880903)
					(end 138.185398 -25.625044)
				)
				(xy 138.18743 -25.626314) (xy 138.937492 -24.226266)
			)
		)
		(polygon
			(pts
				(arc
					(start 136.685274 -24.224996)
					(mid 136.429242 -23.379176)
					(end 135.583422 -23.635208)
				)
				(arc
					(start 134.837678 -25.027636)
					(mid 135.085812 -25.879089)
					(end 135.935466 -25.625044)
				)
			)
		)
		(polygon
			(pts
				(arc
					(start 134.435342 -24.224996)
					(mid 134.17931 -23.379176)
					(end 133.33349 -23.635208)
				)
				(xy 133.331458 -23.633938) (xy 132.581396 -25.033732) (xy 132.58165 -25.033986)
				(arc
					(start 132.583682 -25.035002)
					(mid 132.839358 -25.880903)
					(end 133.68528 -25.625044)
				)
				(xy 133.687312 -25.626314) (xy 134.437374 -24.226266)
			)
		)
		(polygon
			(pts
				(arc
					(start 320.43116 -24.232616)
					(mid 320.183026 -23.381163)
					(end 319.333372 -23.635208)
				)
				(arc
					(start 318.583564 -25.035256)
					(mid 318.596918 -25.648738)
					(end 319.128648 -25.95499)
				)
				(arc
					(start 319.128648 -25.95499)
					(mid 319.453069 -25.867706)
					(end 319.685416 -25.625044)
				)
			)
		)
		(polygon
			(pts
				(arc
					(start 309.431182 -24.232616)
					(mid 309.183048 -23.381163)
					(end 308.333394 -23.635208)
				)
				(arc
					(start 307.583586 -25.035256)
					(mid 307.839618 -25.881076)
					(end 308.685438 -25.625044)
				)
			)
		)
		(polygon
			(pts
				(arc
					(start 167.431212 -24.232616)
					(mid 167.183078 -23.381163)
					(end 166.333424 -23.635208)
				)
				(arc
					(start 165.583616 -25.035256)
					(mid 165.839648 -25.881076)
					(end 166.685468 -25.625044)
				)
			)
		)
		(polygon
			(pts
				(arc
					(start 156.431234 -24.232616)
					(mid 156.1831 -23.381163)
					(end 155.333446 -23.635208)
				)
				(arc
					(start 154.583638 -25.035256)
					(mid 154.83967 -25.881076)
					(end 155.68549 -25.625044)
				)
			)
		)
		(polygon
			(pts
				(arc
					(start 183.59374 -23.6601)
					(mid 183.0832 -23.14956)
					(end 182.57266 -23.6601)
				)
				(arc
					(start 182.57266 -24.473154)
					(mid 183.083327 -24.98344)
					(end 183.59374 -24.4729)
				)
			)
		)
		(polygon
			(pts
				(arc
					(start 283.005276 -20.15617)
					(mid 282.284107 -20.118381)
					(end 282.246578 -20.83943)
				)
				(xy 282.244546 -20.841208) (xy 282.788614 -21.44522)
				(arc
					(start 282.790646 -21.443442)
					(mid 283.511498 -21.481034)
					(end 283.54909 -20.760182)
				)
				(xy 283.551122 -20.758404) (xy 283.007308 -20.154646) (xy 283.0068 -20.154646)
			)
		)
		(polygon
			(pts
				(arc
					(start 160.935162 -20.425156)
					(mid 160.679486 -19.579255)
					(end 159.833564 -19.835114)
				)
				(xy 159.831532 -19.833844) (xy 159.08147 -21.233892)
				(arc
					(start 159.083502 -21.235162)
					(mid 159.339534 -22.080982)
					(end 160.185354 -21.82495)
				)
				(xy 160.187386 -21.82622) (xy 160.937448 -20.426426) (xy 160.937194 -20.426172)
			)
		)
		(polygon
			(pts
				(arc
					(start 158.68523 -20.425156)
					(mid 158.429554 -19.579255)
					(end 157.583632 -19.835114)
				)
				(xy 157.5816 -19.833844) (xy 156.831538 -21.233892)
				(arc
					(start 156.83357 -21.235162)
					(mid 157.089602 -22.080982)
					(end 157.935422 -21.82495)
				)
				(xy 157.937454 -21.82622) (xy 158.687516 -20.426426) (xy 158.687262 -20.426172)
			)
		)
		(polygon
			(pts
				(arc
					(start 324.935088 -20.425156)
					(mid 324.679412 -19.579255)
					(end 323.83349 -19.835114)
				)
				(xy 323.831458 -19.833844) (xy 323.081396 -21.233892)
				(arc
					(start 323.083428 -21.235162)
					(mid 323.33946 -22.080982)
					(end 324.18528 -21.82495)
				)
				(xy 324.187312 -21.82622) (xy 324.937374 -20.426426) (xy 324.93712 -20.426172)
			)
		)
		(polygon
			(pts
				(arc
					(start 322.685156 -20.425156)
					(mid 322.42948 -19.579255)
					(end 321.583558 -19.835114)
				)
				(xy 321.581526 -19.833844) (xy 320.831464 -21.233892)
				(arc
					(start 320.833496 -21.235162)
					(mid 321.089528 -22.080982)
					(end 321.935348 -21.82495)
				)
				(xy 321.93738 -21.82622) (xy 322.687442 -20.426426) (xy 322.687188 -20.426172)
			)
		)
		(polygon
			(pts
				(arc
					(start 313.93511 -20.425156)
					(mid 313.679434 -19.579255)
					(end 312.833512 -19.835114)
				)
				(xy 312.83148 -19.833844) (xy 312.081418 -21.233892)
				(arc
					(start 312.08345 -21.235162)
					(mid 312.339482 -22.080982)
					(end 313.185302 -21.82495)
				)
				(xy 313.187334 -21.82622) (xy 313.937396 -20.426426) (xy 313.937142 -20.426172)
			)
		)
		(polygon
			(pts
				(arc
					(start 311.685178 -20.425156)
					(mid 311.429502 -19.579255)
					(end 310.58358 -19.835114)
				)
				(xy 310.581548 -19.833844) (xy 309.831486 -21.233892)
				(arc
					(start 309.833518 -21.235162)
					(mid 310.08955 -22.080982)
					(end 310.93537 -21.82495)
				)
				(xy 310.937402 -21.82622) (xy 311.687464 -20.426426) (xy 311.68721 -20.426172)
			)
		)
		(polygon
			(pts
				(arc
					(start 171.93514 -20.425156)
					(mid 171.679464 -19.579255)
					(end 170.833542 -19.835114)
				)
				(xy 170.83151 -19.833844) (xy 170.081448 -21.233892)
				(arc
					(start 170.08348 -21.235162)
					(mid 170.339512 -22.080982)
					(end 171.185332 -21.82495)
				)
				(xy 171.187364 -21.82622) (xy 171.937426 -20.426426) (xy 171.937172 -20.426172)
			)
		)
		(polygon
			(pts
				(arc
					(start 169.685208 -20.425156)
					(mid 169.429532 -19.579255)
					(end 168.58361 -19.835114)
				)
				(xy 168.581578 -19.833844) (xy 167.831516 -21.233892)
				(arc
					(start 167.833548 -21.235162)
					(mid 168.08958 -22.080982)
					(end 168.9354 -21.82495)
				)
				(xy 168.937432 -21.82622) (xy 169.687494 -20.426426) (xy 169.68724 -20.426172)
			)
		)
		(polygon
			(pts
				(arc
					(start 149.935184 -20.425156)
					(mid 149.679508 -19.579255)
					(end 148.833586 -19.835114)
				)
				(xy 148.831554 -19.833844) (xy 148.081492 -21.233892)
				(arc
					(start 148.083524 -21.235162)
					(mid 148.339556 -22.080982)
					(end 149.185376 -21.82495)
				)
				(xy 149.187408 -21.82622) (xy 149.93747 -20.426426) (xy 149.937216 -20.426172)
			)
		)
		(polygon
			(pts
				(arc
					(start 302.935132 -20.425156)
					(mid 302.679456 -19.579255)
					(end 301.833534 -19.835114)
				)
				(xy 301.831502 -19.833844) (xy 301.08144 -21.233892)
				(arc
					(start 301.083472 -21.235162)
					(mid 301.339504 -22.080982)
					(end 302.185324 -21.82495)
				)
				(xy 302.187356 -21.82622) (xy 302.937418 -20.426426) (xy 302.937164 -20.426172)
			)
		)
		(polygon
			(pts
				(arc
					(start 291.935408 -20.424902)
					(mid 291.679376 -19.579082)
					(end 290.833556 -19.835114)
				)
				(xy 290.831524 -19.833844) (xy 290.081462 -21.233638) (xy 290.081716 -21.233892)
				(arc
					(start 290.083748 -21.234908)
					(mid 290.339424 -22.080809)
					(end 291.185346 -21.82495)
				)
				(xy 291.187378 -21.82622) (xy 291.93744 -20.426172)
			)
		)
		(polygon
			(pts
				(arc
					(start 289.685222 -20.424902)
					(mid 289.42919 -19.579082)
					(end 288.58337 -19.835114)
				)
				(arc
					(start 287.837626 -21.227542)
					(mid 288.08576 -22.078995)
					(end 288.935414 -21.82495)
				)
			)
		)
		(polygon
			(pts
				(arc
					(start 138.93546 -20.424902)
					(mid 138.679428 -19.579082)
					(end 137.833608 -19.835114)
				)
				(xy 137.831576 -19.833844) (xy 137.081514 -21.233638) (xy 137.081768 -21.233892)
				(arc
					(start 137.0838 -21.234908)
					(mid 137.339476 -22.080809)
					(end 138.185398 -21.82495)
				)
				(xy 138.18743 -21.82622) (xy 138.937492 -20.426172)
			)
		)
		(polygon
			(pts
				(arc
					(start 136.685274 -20.424902)
					(mid 136.429242 -19.579082)
					(end 135.583422 -19.835114)
				)
				(arc
					(start 134.837678 -21.227542)
					(mid 135.085812 -22.078995)
					(end 135.935466 -21.82495)
				)
			)
		)
		(polygon
			(pts
				(arc
					(start 147.681188 -20.432522)
					(mid 147.433054 -19.581069)
					(end 146.5834 -19.835114)
				)
				(arc
					(start 145.833592 -21.235162)
					(mid 146.089624 -22.080982)
					(end 146.935444 -21.82495)
				)
			)
		)
		(polygon
			(pts
				(arc
					(start 300.681136 -20.432522)
					(mid 300.433002 -19.581069)
					(end 299.583348 -19.835114)
				)
				(arc
					(start 298.83354 -21.235162)
					(mid 299.089572 -22.080982)
					(end 299.935392 -21.82495)
				)
			)
		)
		(polygon
			(pts
				(arc
					(start 183.59374 -19.849846)
					(mid 183.083073 -19.33956)
					(end 182.57266 -19.8501)
				)
				(arc
					(start 182.57266 -20.6629)
					(mid 183.0832 -21.17344)
					(end 183.59374 -20.6629)
				)
			)
		)
		(polygon
			(pts
				(arc
					(start 280.761186 -17.965928)
					(mid 280.258647 -17.447516)
					(end 279.740106 -17.949926)
				)
				(arc
					(start 279.72766 -18.762726)
					(mid 280.230326 -19.28114)
					(end 280.74874 -18.778474)
				)
			)
		)
		(polygon
			(pts
				(arc
					(start 269.863824 -17.194022)
					(mid 269.834066 -17.12218)
					(end 269.762224 -17.092422)
				)
				(arc
					(start 268.543024 -17.092422)
					(mid 268.471182 -17.12218)
					(end 268.441424 -17.194022)
				)
				(arc
					(start 268.441424 -18.568162)
					(mid 268.471182 -18.640004)
					(end 268.543024 -18.669762)
				)
				(arc
					(start 269.762224 -18.669762)
					(mid 269.834066 -18.640004)
					(end 269.863824 -18.568162)
				)
			)
		)
		(polygon
			(pts
				(arc
					(start 324.935088 -16.625316)
					(mid 324.679564 -15.779496)
					(end 323.833744 -16.03502)
				)
				(xy 323.831458 -16.03375) (xy 323.081396 -17.433544) (xy 323.08165 -17.433798)
				(arc
					(start 323.083682 -17.434814)
					(mid 323.339206 -18.280634)
					(end 324.185026 -18.02511)
				)
				(xy 324.187312 -18.02638) (xy 324.937374 -16.626586)
			)
		)
		(polygon
			(pts
				(arc
					(start 322.685156 -16.625316)
					(mid 322.429632 -15.779496)
					(end 321.583812 -16.03502)
				)
				(xy 321.581526 -16.03375) (xy 320.831464 -17.433544) (xy 320.831718 -17.433798)
				(arc
					(start 320.83375 -17.434814)
					(mid 321.089274 -18.280634)
					(end 321.935094 -18.02511)
				)
				(xy 321.93738 -18.02638) (xy 322.687442 -16.626586)
			)
		)
		(polygon
			(pts
				(arc
					(start 313.93511 -16.625316)
					(mid 313.679586 -15.779496)
					(end 312.833766 -16.03502)
				)
				(xy 312.83148 -16.03375) (xy 312.081418 -17.433544) (xy 312.081672 -17.433798)
				(arc
					(start 312.083704 -17.434814)
					(mid 312.339228 -18.280634)
					(end 313.185048 -18.02511)
				)
				(xy 313.187334 -18.02638) (xy 313.937396 -16.626586)
			)
		)
		(polygon
			(pts
				(arc
					(start 311.685178 -16.625316)
					(mid 311.429654 -15.779496)
					(end 310.583834 -16.03502)
				)
				(xy 310.581548 -16.03375) (xy 309.831486 -17.433544) (xy 309.83174 -17.433798)
				(arc
					(start 309.833772 -17.434814)
					(mid 310.089296 -18.280634)
					(end 310.935116 -18.02511)
				)
				(xy 310.937402 -18.02638) (xy 311.687464 -16.626586)
			)
		)
		(polygon
			(pts
				(arc
					(start 302.935132 -16.625316)
					(mid 302.679608 -15.779496)
					(end 301.833788 -16.03502)
				)
				(xy 301.831502 -16.03375) (xy 301.08144 -17.433544) (xy 301.081694 -17.433798)
				(arc
					(start 301.083726 -17.434814)
					(mid 301.33925 -18.280634)
					(end 302.18507 -18.02511)
				)
				(xy 302.187356 -18.02638) (xy 302.937418 -16.626586)
			)
		)
		(polygon
			(pts
				(arc
					(start 291.935154 -16.625316)
					(mid 291.67963 -15.779496)
					(end 290.83381 -16.03502)
				)
				(xy 290.831524 -16.03375) (xy 290.081462 -17.433544) (xy 290.081716 -17.433798)
				(arc
					(start 290.083748 -17.434814)
					(mid 290.339272 -18.280634)
					(end 291.185092 -18.02511)
				)
				(xy 291.187378 -18.02638) (xy 291.93744 -16.626586)
			)
		)
		(polygon
			(pts
				(arc
					(start 171.93514 -16.625316)
					(mid 171.679616 -15.779496)
					(end 170.833796 -16.03502)
				)
				(xy 170.83151 -16.03375) (xy 170.081448 -17.433544) (xy 170.081702 -17.433798)
				(arc
					(start 170.083734 -17.434814)
					(mid 170.339258 -18.280634)
					(end 171.185078 -18.02511)
				)
				(xy 171.187364 -18.02638) (xy 171.937426 -16.626586)
			)
		)
		(polygon
			(pts
				(arc
					(start 169.685208 -16.625316)
					(mid 169.429684 -15.779496)
					(end 168.583864 -16.03502)
				)
				(xy 168.581578 -16.03375) (xy 167.831516 -17.433544) (xy 167.83177 -17.433798)
				(arc
					(start 167.833802 -17.434814)
					(mid 168.089326 -18.280634)
					(end 168.935146 -18.02511)
				)
				(xy 168.937432 -18.02638) (xy 169.687494 -16.626586)
			)
		)
		(polygon
			(pts
				(arc
					(start 160.935162 -16.625316)
					(mid 160.679638 -15.779496)
					(end 159.833818 -16.03502)
				)
				(xy 159.831532 -16.03375) (xy 159.08147 -17.433544) (xy 159.081724 -17.433798)
				(arc
					(start 159.083756 -17.434814)
					(mid 159.33928 -18.280634)
					(end 160.1851 -18.02511)
				)
				(xy 160.187386 -18.02638) (xy 160.937448 -16.626586)
			)
		)
		(polygon
			(pts
				(arc
					(start 158.68523 -16.625316)
					(mid 158.429706 -15.779496)
					(end 157.583886 -16.03502)
				)
				(xy 157.5816 -16.03375) (xy 156.831538 -17.433544) (xy 156.831792 -17.433798)
				(arc
					(start 156.833824 -17.434814)
					(mid 157.089348 -18.280634)
					(end 157.935168 -18.02511)
				)
				(xy 157.937454 -18.02638) (xy 158.687516 -16.626586)
			)
		)
		(polygon
			(pts
				(arc
					(start 149.935184 -16.625316)
					(mid 149.67966 -15.779496)
					(end 148.83384 -16.03502)
				)
				(xy 148.831554 -16.03375) (xy 148.081492 -17.433544) (xy 148.081746 -17.433798)
				(arc
					(start 148.083778 -17.434814)
					(mid 148.339302 -18.280634)
					(end 149.185122 -18.02511)
				)
				(xy 149.187408 -18.02638) (xy 149.93747 -16.626586)
			)
		)
		(polygon
			(pts
				(arc
					(start 138.935206 -16.625316)
					(mid 138.679682 -15.779496)
					(end 137.833862 -16.03502)
				)
				(xy 137.831576 -16.03375) (xy 137.081514 -17.433544) (xy 137.081768 -17.433798)
				(arc
					(start 137.0838 -17.434814)
					(mid 137.339324 -18.280634)
					(end 138.185144 -18.02511)
				)
				(xy 138.18743 -18.02638) (xy 138.937492 -16.626586)
			)
		)
		(polygon
			(pts
				(arc
					(start 300.6852 -16.625062)
					(mid 300.429168 -15.779242)
					(end 299.583348 -16.035274)
				)
				(xy 299.581316 -16.034004) (xy 298.831508 -17.433544) (xy 298.831762 -17.433798)
				(arc
					(start 298.833794 -17.434814)
					(mid 299.08947 -18.280715)
					(end 299.935392 -18.024856)
				)
				(xy 299.937424 -18.026126) (xy 300.687232 -16.626332)
			)
		)
		(polygon
			(pts
				(arc
					(start 289.685222 -16.625062)
					(mid 289.42919 -15.779242)
					(end 288.58337 -16.035274)
				)
				(xy 288.581338 -16.034004) (xy 287.83153 -17.433544) (xy 287.831784 -17.433798)
				(arc
					(start 287.833816 -17.434814)
					(mid 288.089492 -18.280715)
					(end 288.935414 -18.024856)
				)
				(xy 288.937446 -18.026126) (xy 289.687254 -16.626332)
			)
		)
		(polygon
			(pts
				(arc
					(start 147.685252 -16.625062)
					(mid 147.42922 -15.779242)
					(end 146.5834 -16.035274)
				)
				(xy 146.581368 -16.034004) (xy 145.83156 -17.433544) (xy 145.831814 -17.433798)
				(arc
					(start 145.833846 -17.434814)
					(mid 146.089522 -18.280715)
					(end 146.935444 -18.024856)
				)
				(xy 146.937476 -18.026126) (xy 147.687284 -16.626332)
			)
		)
		(polygon
			(pts
				(arc
					(start 136.685274 -16.625062)
					(mid 136.429242 -15.779242)
					(end 135.583422 -16.035274)
				)
				(xy 135.58139 -16.034004) (xy 134.831582 -17.433544) (xy 134.831836 -17.433798)
				(arc
					(start 134.833868 -17.434814)
					(mid 135.089544 -18.280715)
					(end 135.935466 -18.024856)
				)
				(xy 135.937498 -18.026126) (xy 136.687306 -16.626332)
			)
		)
		(polygon
			(pts
				(arc
					(start 272.57883 -14.52245)
					(mid 272.06829 -14.01191)
					(end 271.55775 -14.52245)
				)
				(arc
					(start 271.55775 -15.335504)
					(mid 272.068417 -15.84579)
					(end 272.57883 -15.33525)
				)
			)
		)
		(polygon
			(pts
				(arc
					(start 268.98854 -13.842746)
					(mid 268.477873 -13.33246)
					(end 267.96746 -13.843)
				)
				(arc
					(start 267.96746 -14.6558)
					(mid 268.478 -15.16634)
					(end 268.98854 -14.6558)
				)
			)
		)
		(polygon
			(pts
				(xy 181.82082 -12.16406)
				(arc
					(start 181.46522 -12.16406)
					(mid 181.373621 -12.202001)
					(end 181.33568 -12.2936)
				)
				(arc
					(start 181.33568 -13.6906)
					(mid 181.373621 -13.782199)
					(end 181.46522 -13.82014)
				)
				(arc
					(start 182.68442 -13.82014)
					(mid 182.776019 -13.782199)
					(end 182.81396 -13.6906)
				)
				(arc
					(start 182.81396 -12.2936)
					(mid 182.776019 -12.202001)
					(end 182.68442 -12.16406)
				)
				(xy 182.32882 -12.16406) (xy 182.310786 -12.16533) (xy 181.838854 -12.16533)
			)
		)
		(polygon
			(pts
				(arc
					(start 291.935154 -12.825222)
					(mid 291.679478 -11.979321)
					(end 290.833556 -12.23518)
				)
				(xy 290.831524 -12.23391) (xy 290.081462 -13.633958)
				(arc
					(start 290.083494 -13.635228)
					(mid 290.339526 -14.481048)
					(end 291.185346 -14.225016)
				)
				(xy 291.187378 -14.226286) (xy 291.93744 -12.826492) (xy 291.937186 -12.826238)
			)
		)
		(polygon
			(pts
				(arc
					(start 287.435036 -12.825222)
					(mid 287.17936 -11.979321)
					(end 286.333438 -12.23518)
				)
				(xy 286.331406 -12.23391) (xy 285.581344 -13.633958)
				(arc
					(start 285.583376 -13.635228)
					(mid 285.839408 -14.481048)
					(end 286.685228 -14.225016)
				)
				(xy 286.68726 -14.226286) (xy 287.437322 -12.826492) (xy 287.437068 -12.826238)
			)
		)
		(polygon
			(pts
				(arc
					(start 138.935206 -12.825222)
					(mid 138.67953 -11.979321)
					(end 137.833608 -12.23518)
				)
				(xy 137.831576 -12.23391) (xy 137.081514 -13.633958)
				(arc
					(start 137.083546 -13.635228)
					(mid 137.339578 -14.481048)
					(end 138.185398 -14.225016)
				)
				(xy 138.18743 -14.226286) (xy 138.937492 -12.826492) (xy 138.937238 -12.826238)
			)
		)
		(polygon
			(pts
				(arc
					(start 134.435088 -12.825222)
					(mid 134.179412 -11.979321)
					(end 133.33349 -12.23518)
				)
				(xy 133.331458 -12.23391) (xy 132.581396 -13.633958)
				(arc
					(start 132.583428 -13.635228)
					(mid 132.83946 -14.481048)
					(end 133.68528 -14.225016)
				)
				(xy 133.687312 -14.226286) (xy 134.437374 -12.826492) (xy 134.43712 -12.826238)
			)
		)
		(polygon
			(pts
				(arc
					(start 324.935342 -12.824968)
					(mid 324.67931 -11.979148)
					(end 323.83349 -12.23518)
				)
				(xy 323.831458 -12.23391) (xy 323.081396 -13.633704) (xy 323.08165 -13.633958)
				(arc
					(start 323.083682 -13.634974)
					(mid 323.339358 -14.480875)
					(end 324.18528 -14.225016)
				)
				(xy 324.187312 -14.226286) (xy 324.937374 -12.826238)
			)
		)
		(polygon
			(pts
				(arc
					(start 322.68541 -12.824968)
					(mid 322.429378 -11.979148)
					(end 321.583558 -12.23518)
				)
				(xy 321.581526 -12.23391) (xy 320.831464 -13.633704) (xy 320.831718 -13.633958)
				(arc
					(start 320.83375 -13.634974)
					(mid 321.089426 -14.480875)
					(end 321.935348 -14.225016)
				)
				(xy 321.93738 -14.226286) (xy 322.687442 -12.826238)
			)
		)
		(polygon
			(pts
				(arc
					(start 320.435224 -12.824968)
					(mid 320.179192 -11.979148)
					(end 319.333372 -12.23518)
				)
				(arc
					(start 318.587628 -13.627608)
					(mid 318.835762 -14.479061)
					(end 319.685416 -14.225016)
				)
			)
		)
		(polygon
			(pts
				(arc
					(start 313.935364 -12.824968)
					(mid 313.679332 -11.979148)
					(end 312.833512 -12.23518)
				)
				(xy 312.83148 -12.23391) (xy 312.081418 -13.633704) (xy 312.081672 -13.633958)
				(arc
					(start 312.083704 -13.634974)
					(mid 312.33938 -14.480875)
					(end 313.185302 -14.225016)
				)
				(xy 313.187334 -14.226286) (xy 313.937396 -12.826238)
			)
		)
		(polygon
			(pts
				(arc
					(start 311.685432 -12.824968)
					(mid 311.4294 -11.979148)
					(end 310.58358 -12.23518)
				)
				(xy 310.581548 -12.23391) (xy 309.831486 -13.633704) (xy 309.83174 -13.633958)
				(arc
					(start 309.833772 -13.634974)
					(mid 310.089448 -14.480875)
					(end 310.93537 -14.225016)
				)
				(xy 310.937402 -14.226286) (xy 311.687464 -12.826238)
			)
		)
		(polygon
			(pts
				(arc
					(start 309.435246 -12.824968)
					(mid 309.179214 -11.979148)
					(end 308.333394 -12.23518)
				)
				(arc
					(start 307.58765 -13.627608)
					(mid 307.835784 -14.479061)
					(end 308.685438 -14.225016)
				)
			)
		)
		(polygon
			(pts
				(arc
					(start 302.935386 -12.824968)
					(mid 302.679354 -11.979148)
					(end 301.833534 -12.23518)
				)
				(xy 301.831502 -12.23391) (xy 301.08144 -13.633704) (xy 301.081694 -13.633958)
				(arc
					(start 301.083726 -13.634974)
					(mid 301.339402 -14.480875)
					(end 302.185324 -14.225016)
				)
				(xy 302.187356 -14.226286) (xy 302.937418 -12.826238)
			)
		)
		(polygon
			(pts
				(arc
					(start 300.6852 -12.824968)
					(mid 300.429168 -11.979148)
					(end 299.583348 -12.23518)
				)
				(arc
					(start 298.837604 -13.627608)
					(mid 299.085738 -14.479061)
					(end 299.935392 -14.225016)
				)
			)
		)
		(polygon
			(pts
				(arc
					(start 298.435268 -12.824968)
					(mid 298.179236 -11.979148)
					(end 297.333416 -12.23518)
				)
				(xy 297.331384 -12.23391) (xy 296.581322 -13.633704) (xy 296.581576 -13.633958)
				(arc
					(start 296.583608 -13.634974)
					(mid 296.839284 -14.480875)
					(end 297.685206 -14.225016)
				)
				(xy 297.687238 -14.226286) (xy 298.4373 -12.826238)
			)
		)
		(polygon
			(pts
				(arc
					(start 171.935394 -12.824968)
					(mid 171.679362 -11.979148)
					(end 170.833542 -12.23518)
				)
				(xy 170.83151 -12.23391) (xy 170.081448 -13.633704) (xy 170.081702 -13.633958)
				(arc
					(start 170.083734 -13.634974)
					(mid 170.33941 -14.480875)
					(end 171.185332 -14.225016)
				)
				(xy 171.187364 -14.226286) (xy 171.937426 -12.826238)
			)
		)
		(polygon
			(pts
				(arc
					(start 169.685462 -12.824968)
					(mid 169.42943 -11.979148)
					(end 168.58361 -12.23518)
				)
				(xy 168.581578 -12.23391) (xy 167.831516 -13.633704) (xy 167.83177 -13.633958)
				(arc
					(start 167.833802 -13.634974)
					(mid 168.089478 -14.480875)
					(end 168.9354 -14.225016)
				)
				(xy 168.937432 -14.226286) (xy 169.687494 -12.826238)
			)
		)
		(polygon
			(pts
				(arc
					(start 167.435276 -12.824968)
					(mid 167.179244 -11.979148)
					(end 166.333424 -12.23518)
				)
				(arc
					(start 165.58768 -13.627608)
					(mid 165.835814 -14.479061)
					(end 166.685468 -14.225016)
				)
			)
		)
		(polygon
			(pts
				(arc
					(start 160.935416 -12.824968)
					(mid 160.679384 -11.979148)
					(end 159.833564 -12.23518)
				)
				(xy 159.831532 -12.23391) (xy 159.08147 -13.633704) (xy 159.081724 -13.633958)
				(arc
					(start 159.083756 -13.634974)
					(mid 159.339432 -14.480875)
					(end 160.185354 -14.225016)
				)
				(xy 160.187386 -14.226286) (xy 160.937448 -12.826238)
			)
		)
		(polygon
			(pts
				(arc
					(start 158.685484 -12.824968)
					(mid 158.429452 -11.979148)
					(end 157.583632 -12.23518)
				)
				(xy 157.5816 -12.23391) (xy 156.831538 -13.633704) (xy 156.831792 -13.633958)
				(arc
					(start 156.833824 -13.634974)
					(mid 157.0895 -14.480875)
					(end 157.935422 -14.225016)
				)
				(xy 157.937454 -14.226286) (xy 158.687516 -12.826238)
			)
		)
		(polygon
			(pts
				(arc
					(start 156.435298 -12.824968)
					(mid 156.179266 -11.979148)
					(end 155.333446 -12.23518)
				)
				(arc
					(start 154.587702 -13.627608)
					(mid 154.835836 -14.479061)
					(end 155.68549 -14.225016)
				)
			)
		)
		(polygon
			(pts
				(arc
					(start 149.935438 -12.824968)
					(mid 149.679406 -11.979148)
					(end 148.833586 -12.23518)
				)
				(xy 148.831554 -12.23391) (xy 148.081492 -13.633704) (xy 148.081746 -13.633958)
				(arc
					(start 148.083778 -13.634974)
					(mid 148.339454 -14.480875)
					(end 149.185376 -14.225016)
				)
				(xy 149.187408 -14.226286) (xy 149.93747 -12.826238)
			)
		)
		(polygon
			(pts
				(arc
					(start 147.685252 -12.824968)
					(mid 147.42922 -11.979148)
					(end 146.5834 -12.23518)
				)
				(arc
					(start 145.837656 -13.627608)
					(mid 146.08579 -14.479061)
					(end 146.935444 -14.225016)
				)
			)
		)
		(polygon
			(pts
				(arc
					(start 145.43532 -12.824968)
					(mid 145.179288 -11.979148)
					(end 144.333468 -12.23518)
				)
				(xy 144.331436 -12.23391) (xy 143.581374 -13.633704) (xy 143.581628 -13.633958)
				(arc
					(start 143.58366 -13.634974)
					(mid 143.839336 -14.480875)
					(end 144.685258 -14.225016)
				)
				(xy 144.68729 -14.226286) (xy 145.437352 -12.826238)
			)
		)
		(polygon
			(pts
				(arc
					(start 289.681158 -12.832588)
					(mid 289.433024 -11.981135)
					(end 288.58337 -12.23518)
				)
				(arc
					(start 287.833562 -13.635228)
					(mid 288.089594 -14.481048)
					(end 288.935414 -14.225016)
				)
			)
		)
		(polygon
			(pts
				(arc
					(start 136.68121 -12.832588)
					(mid 136.433076 -11.981135)
					(end 135.583422 -12.23518)
				)
				(arc
					(start 134.833614 -13.635228)
					(mid 135.089646 -14.481048)
					(end 135.935466 -14.225016)
				)
			)
		)
		(polygon
			(pts
				(arc
					(start 185.069226 -11.6967)
					(mid 184.558559 -11.186414)
					(end 184.048146 -11.696954)
				)
				(arc
					(start 184.048146 -12.509754)
					(mid 184.558686 -13.020294)
					(end 185.069226 -12.509754)
				)
			)
		)
		(polygon
			(pts
				(arc
					(start 272.8722 -8.0772)
					(mid 272.842442 -8.005358)
					(end 272.7706 -7.9756)
				)
				(arc
					(start 271.5514 -7.9756)
					(mid 271.479558 -8.005358)
					(end 271.4498 -8.0772)
				)
				(arc
					(start 271.4498 -9.4488)
					(mid 271.479558 -9.520642)
					(end 271.5514 -9.5504)
				)
				(arc
					(start 272.7706 -9.5504)
					(mid 272.842442 -9.520642)
					(end 272.8722 -9.4488)
				)
			)
		)
		(polygon
			(pts
				(arc
					(start 184.443624 -8.91667)
					(mid 184.95391 -8.406003)
					(end 184.44337 -7.89559)
				)
				(arc
					(start 183.63057 -7.89559)
					(mid 183.12003 -8.40613)
					(end 183.63057 -8.91667)
				)
			)
		)
		(polygon
			(pts
				(arc
					(start 271.19834 -8.353298)
					(mid 270.687673 -7.843012)
					(end 270.17726 -8.353552)
				)
				(arc
					(start 270.17726 -9.166352)
					(mid 270.6878 -9.676892)
					(end 271.19834 -9.166352)
				)
			)
		)
		(polygon
			(pts
				(xy 181.88686 -6.19252)
				(arc
					(start 181.53126 -6.19252)
					(mid 181.457622 -6.223022)
					(end 181.42712 -6.29666)
				)
				(xy 181.42712 -6.65226) (xy 181.428136 -6.667246) (xy 181.428136 -7.346442) (xy 181.42712 -7.36092)
				(arc
					(start 181.42712 -7.71652)
					(mid 181.457622 -7.790158)
					(end 181.53126 -7.82066)
				)
				(arc
					(start 182.357776 -7.82066)
					(mid 182.373581 -7.824433)
					(end 182.38978 -7.82574)
				)
				(arc
					(start 182.74538 -7.82574)
					(mid 182.819018 -7.795238)
					(end 182.84952 -7.7216)
				)
				(arc
					(start 182.84952 -6.684264)
					(mid 182.853293 -6.668459)
					(end 182.8546 -6.65226)
				)
				(arc
					(start 182.8546 -6.29666)
					(mid 182.824098 -6.223022)
					(end 182.75046 -6.19252)
				)
				(xy 182.39486 -6.19252) (xy 182.3847 -6.193028) (xy 181.896766 -6.193028)
			)
		)
		(polygon
			(pts
				(arc
					(start 271.7292 -5.0292)
					(mid 271.699442 -4.957358)
					(end 271.6276 -4.9276)
				)
				(arc
					(start 270.4084 -4.9276)
					(mid 270.336558 -4.957358)
					(end 270.3068 -5.0292)
				)
				(arc
					(start 270.3068 -6.4008)
					(mid 270.336558 -6.472642)
					(end 270.4084 -6.5024)
				)
				(arc
					(start 271.6276 -6.5024)
					(mid 271.699442 -6.472642)
					(end 271.7292 -6.4008)
				)
			)
		)
		(polygon
			(pts
				(arc
					(start 270.05534 -5.305298)
					(mid 269.544673 -4.795012)
					(end 269.03426 -5.305552)
				)
				(arc
					(start 269.03426 -6.118352)
					(mid 269.5448 -6.628892)
					(end 270.05534 -6.118352)
				)
			)
		)
	)
	(zone
		(layer "In6.Cu")
		(hatch none 0.5)
		(connect_pads
			(clearance 0)
		)
		(min_thickness 0.25)
		(keepout
			(tracks not_allowed)
			(vias allowed)
			(pads allowed)
			(copperpour not_allowed)
			(footprints allowed)
		)
		(placement
			(enabled no)
			(sheetname "")
		)
		(fill
			(thermal_gap 0.5)
			(thermal_bridge_width 0.5)
			(island_removal_mode 0)
		)
		(polygon
			(pts
				(arc
					(start 210.6168 -44.4246)
					(mid 210.526997 -44.461797)
					(end 210.4898 -44.5516)
				)
				(arc
					(start 210.4898 -45.847)
					(mid 210.526997 -45.936803)
					(end 210.6168 -45.974)
				)
				(arc
					(start 211.9376 -45.974)
					(mid 212.027403 -45.936803)
					(end 212.0646 -45.847)
				)
				(arc
					(start 212.0646 -44.5516)
					(mid 212.027403 -44.461797)
					(end 211.9376 -44.4246)
				)
			)
		)
	)
	(zone
		(layer "Cmts.User")
		(hatch none 0.5)
		(connect_pads
			(clearance 0)
		)
		(min_thickness 0.25)
		(keepout
			(tracks allowed)
			(vias allowed)
			(pads allowed)
			(copperpour allowed)
			(footprints allowed)
		)
		(placement
			(enabled no)
			(sheetname "")
		)
		(fill
			(thermal_gap 0.5)
			(thermal_bridge_width 0.5)
			(island_removal_mode 0)
		)
		(polygon
			(pts
				(xy 279.893268 -211.4042) (xy 279.893268 -210.3628) (xy 281.849068 -210.3628) (xy 281.849068 -211.4042)
			)
		)
	)
	(zone
		(layer "Cmts.User")
		(hatch none 0.5)
		(connect_pads
			(clearance 0)
		)
		(min_thickness 0.25)
		(keepout
			(tracks allowed)
			(vias allowed)
			(pads allowed)
			(copperpour allowed)
			(footprints allowed)
		)
		(placement
			(enabled no)
			(sheetname "")
		)
		(fill
			(thermal_gap 0.5)
			(thermal_bridge_width 0.5)
			(island_removal_mode 0)
		)
		(polygon
			(pts
				(xy 161.199068 -38.527482) (xy 161.199068 -37.486082) (xy 163.154868 -37.486082) (xy 163.154868 -38.527482)
			)
		)
	)
	(zone
		(layer "Cmts.User")
		(hatch none 0.5)
		(connect_pads
			(clearance 0)
		)
		(min_thickness 0.25)
		(keepout
			(tracks allowed)
			(vias allowed)
			(pads allowed)
			(copperpour allowed)
			(footprints allowed)
		)
		(placement
			(enabled no)
			(sheetname "")
		)
		(fill
			(thermal_gap 0.5)
			(thermal_bridge_width 0.5)
			(island_removal_mode 0)
		)
		(polygon
			(pts
				(xy 132.186172 -26.503884) (xy 132.186172 -11.625834) (xy 139.398756 -11.625834) (xy 139.398756 -26.503884)
			)
		)
	)
	(zone
		(layer "Cmts.User")
		(hatch none 0.5)
		(connect_pads
			(clearance 0)
		)
		(min_thickness 0.25)
		(keepout
			(tracks allowed)
			(vias allowed)
			(pads allowed)
			(copperpour allowed)
			(footprints allowed)
		)
		(placement
			(enabled no)
			(sheetname "")
		)
		(fill
			(thermal_gap 0.5)
			(thermal_bridge_width 0.5)
			(island_removal_mode 0)
		)
		(polygon
			(pts
				(xy 286.293306 -211.4042) (xy 286.293306 -210.3628) (xy 288.249106 -210.3628) (xy 288.249106 -211.4042)
			)
		)
	)
	(zone
		(layer "Cmts.User")
		(hatch none 0.5)
		(connect_pads
			(clearance 0)
		)
		(min_thickness 0.25)
		(keepout
			(tracks allowed)
			(vias allowed)
			(pads allowed)
			(copperpour allowed)
			(footprints allowed)
		)
		(placement
			(enabled no)
			(sheetname "")
		)
		(fill
			(thermal_gap 0.5)
			(thermal_bridge_width 0.5)
			(island_removal_mode 0)
		)
		(polygon
			(pts
				(xy 20.224496 -54.444646) (xy 20.224496 -55.486046) (xy 18.268696 -55.486046) (xy 18.268696 -54.444646)
			)
		)
	)
	(zone
		(layer "Cmts.User")
		(hatch none 0.5)
		(connect_pads
			(clearance 0)
		)
		(min_thickness 0.25)
		(keepout
			(tracks allowed)
			(vias allowed)
			(pads allowed)
			(copperpour allowed)
			(footprints allowed)
		)
		(placement
			(enabled no)
			(sheetname "")
		)
		(fill
			(thermal_gap 0.5)
			(thermal_bridge_width 0.5)
			(island_removal_mode 0)
		)
		(polygon
			(pts
				(xy 145.338038 -35.518852) (xy 145.338038 -34.477452) (xy 147.293838 -34.477452) (xy 147.293838 -35.518852)
			)
		)
	)
	(zone
		(layer "Cmts.User")
		(hatch none 0.5)
		(connect_pads
			(clearance 0)
		)
		(min_thickness 0.25)
		(keepout
			(tracks allowed)
			(vias allowed)
			(pads allowed)
			(copperpour allowed)
			(footprints allowed)
		)
		(placement
			(enabled no)
			(sheetname "")
		)
		(fill
			(thermal_gap 0.5)
			(thermal_bridge_width 0.5)
			(island_removal_mode 0)
		)
		(polygon
			(pts
				(xy 153.893266 -211.4042) (xy 153.893266 -210.3628) (xy 155.849066 -210.3628) (xy 155.849066 -211.4042)
			)
		)
	)
	(zone
		(layer "Cmts.User")
		(hatch none 0.5)
		(connect_pads
			(clearance 0)
		)
		(min_thickness 0.25)
		(keepout
			(tracks allowed)
			(vias allowed)
			(pads allowed)
			(copperpour allowed)
			(footprints allowed)
		)
		(placement
			(enabled no)
			(sheetname "")
		)
		(fill
			(thermal_gap 0.5)
			(thermal_bridge_width 0.5)
			(island_removal_mode 0)
		)
		(polygon
			(pts
				(xy 136.9949 -35.519106) (xy 136.9949 -34.477706) (xy 138.9507 -34.477706) (xy 138.9507 -35.519106)
			)
		)
	)
	(zone
		(layer "Cmts.User")
		(hatch none 0.5)
		(connect_pads
			(clearance 0)
		)
		(min_thickness 0.25)
		(keepout
			(tracks allowed)
			(vias allowed)
			(pads allowed)
			(copperpour allowed)
			(footprints allowed)
		)
		(placement
			(enabled no)
			(sheetname "")
		)
		(fill
			(thermal_gap 0.5)
			(thermal_bridge_width 0.5)
			(island_removal_mode 0)
		)
		(polygon
			(pts
				(xy 49.492916 -221.91345) (xy 49.492916 -220.87205) (xy 51.448716 -220.87205) (xy 51.448716 -221.91345)
			)
		)
	)
	(zone
		(layer "Cmts.User")
		(hatch none 0.5)
		(connect_pads
			(clearance 0)
		)
		(min_thickness 0.25)
		(keepout
			(tracks allowed)
			(vias allowed)
			(pads allowed)
			(copperpour allowed)
			(footprints allowed)
		)
		(placement
			(enabled no)
			(sheetname "")
		)
		(fill
			(thermal_gap 0.5)
			(thermal_bridge_width 0.5)
			(island_removal_mode 0)
		)
		(polygon
			(pts
				(xy 101.408992 -38.30066) (xy 102.450392 -38.30066) (xy 102.450392 -40.25646) (xy 101.408992 -40.25646)
			)
		)
	)
	(zone
		(layer "Cmts.User")
		(hatch none 0.5)
		(connect_pads
			(clearance 0)
		)
		(min_thickness 0.25)
		(keepout
			(tracks allowed)
			(vias allowed)
			(pads allowed)
			(copperpour allowed)
			(footprints allowed)
		)
		(placement
			(enabled no)
			(sheetname "")
		)
		(fill
			(thermal_gap 0.5)
			(thermal_bridge_width 0.5)
			(island_removal_mode 0)
		)
		(polygon
			(pts
				(xy 47.893224 -211.4042) (xy 47.893224 -210.3628) (xy 49.849024 -210.3628) (xy 49.849024 -211.4042)
			)
		)
	)
	(zone
		(layer "Cmts.User")
		(hatch none 0.5)
		(connect_pads
			(clearance 0)
		)
		(min_thickness 0.25)
		(keepout
			(tracks allowed)
			(vias allowed)
			(pads allowed)
			(copperpour allowed)
			(footprints allowed)
		)
		(placement
			(enabled no)
			(sheetname "")
		)
		(fill
			(thermal_gap 0.5)
			(thermal_bridge_width 0.5)
			(island_removal_mode 0)
		)
		(polygon
			(pts
				(xy 288.629344 -35.5219) (xy 288.629344 -34.4805) (xy 290.585144 -34.4805) (xy 290.585144 -35.5219)
			)
		)
	)
	(zone
		(layer "Cmts.User")
		(hatch none 0.5)
		(connect_pads
			(clearance 0)
		)
		(min_thickness 0.25)
		(keepout
			(tracks allowed)
			(vias allowed)
			(pads allowed)
			(copperpour allowed)
			(footprints allowed)
		)
		(placement
			(enabled no)
			(sheetname "")
		)
		(fill
			(thermal_gap 0.5)
			(thermal_bridge_width 0.5)
			(island_removal_mode 0)
		)
		(polygon
			(pts
				(xy 323.041772 -35.491166) (xy 323.041772 -34.449766) (xy 324.997572 -34.449766) (xy 324.997572 -35.491166)
			)
		)
	)
	(zone
		(layer "Cmts.User")
		(hatch none 0.5)
		(connect_pads
			(clearance 0)
		)
		(min_thickness 0.25)
		(keepout
			(tracks allowed)
			(vias allowed)
			(pads allowed)
			(copperpour allowed)
			(footprints allowed)
		)
		(placement
			(enabled no)
			(sheetname "")
		)
		(fill
			(thermal_gap 0.5)
			(thermal_bridge_width 0.5)
			(island_removal_mode 0)
		)
		(polygon
			(pts
				(xy 283.093414 -211.4042) (xy 283.093414 -210.3628) (xy 285.049214 -210.3628) (xy 285.049214 -211.4042)
			)
		)
	)
	(zone
		(layer "Cmts.User")
		(hatch none 0.5)
		(connect_pads
			(clearance 0)
		)
		(min_thickness 0.25)
		(keepout
			(tracks allowed)
			(vias allowed)
			(pads allowed)
			(copperpour allowed)
			(footprints allowed)
		)
		(placement
			(enabled no)
			(sheetname "")
		)
		(fill
			(thermal_gap 0.5)
			(thermal_bridge_width 0.5)
			(island_removal_mode 0)
		)
		(polygon
			(pts
				(xy 92.788994 -184.149746) (xy 92.788994 -183.108346) (xy 94.744794 -183.108346) (xy 94.744794 -184.149746)
			)
		)
	)
	(zone
		(layer "Cmts.User")
		(hatch none 0.5)
		(connect_pads
			(clearance 0)
		)
		(min_thickness 0.25)
		(keepout
			(tracks allowed)
			(vias allowed)
			(pads allowed)
			(copperpour allowed)
			(footprints allowed)
		)
		(placement
			(enabled no)
			(sheetname "")
		)
		(fill
			(thermal_gap 0.5)
			(thermal_bridge_width 0.5)
			(island_removal_mode 0)
		)
		(polygon
			(pts
				(xy 183.493156 -211.4042) (xy 183.493156 -210.3628) (xy 185.448956 -210.3628) (xy 185.448956 -211.4042)
			)
		)
	)
	(zone
		(layer "Cmts.User")
		(hatch none 0.5)
		(connect_pads
			(clearance 0)
		)
		(min_thickness 0.25)
		(keepout
			(tracks allowed)
			(vias allowed)
			(pads allowed)
			(copperpour allowed)
			(footprints allowed)
		)
		(placement
			(enabled no)
			(sheetname "")
		)
		(fill
			(thermal_gap 0.5)
			(thermal_bridge_width 0.5)
			(island_removal_mode 0)
		)
		(polygon
			(pts
				(xy 183.059324 -8.925306) (xy 183.059324 -7.883906) (xy 185.015124 -7.883906) (xy 185.015124 -8.925306)
			)
		)
	)
	(zone
		(layer "Cmts.User")
		(hatch none 0.5)
		(connect_pads
			(clearance 0)
		)
		(min_thickness 0.25)
		(keepout
			(tracks allowed)
			(vias allowed)
			(pads allowed)
			(copperpour allowed)
			(footprints allowed)
		)
		(placement
			(enabled no)
			(sheetname "")
		)
		(fill
			(thermal_gap 0.5)
			(thermal_bridge_width 0.5)
			(island_removal_mode 0)
		)
		(polygon
			(pts
				(xy 88.693244 -211.4042) (xy 88.693244 -210.3628) (xy 90.649044 -210.3628) (xy 90.649044 -211.4042)
			)
		)
	)
	(zone
		(layer "Cmts.User")
		(hatch none 0.5)
		(connect_pads
			(clearance 0)
		)
		(min_thickness 0.25)
		(keepout
			(tracks allowed)
			(vias allowed)
			(pads allowed)
			(copperpour allowed)
			(footprints allowed)
		)
		(placement
			(enabled no)
			(sheetname "")
		)
		(fill
			(thermal_gap 0.5)
			(thermal_bridge_width 0.5)
			(island_removal_mode 0)
		)
		(polygon
			(pts
				(xy 196.293232 -211.4042) (xy 196.293232 -210.3628) (xy 198.249032 -210.3628) (xy 198.249032 -211.4042)
			)
		)
	)
	(zone
		(layer "Cmts.User")
		(hatch none 0.5)
		(connect_pads
			(clearance 0)
		)
		(min_thickness 0.25)
		(keepout
			(tracks allowed)
			(vias allowed)
			(pads allowed)
			(copperpour allowed)
			(footprints allowed)
		)
		(placement
			(enabled no)
			(sheetname "")
		)
		(fill
			(thermal_gap 0.5)
			(thermal_bridge_width 0.5)
			(island_removal_mode 0)
		)
		(polygon
			(pts
				(xy 285.18612 -26.503884) (xy 285.18612 -11.625834) (xy 292.398704 -11.625834) (xy 292.398704 -26.503884)
			)
		)
	)
	(zone
		(layer "Cmts.User")
		(hatch none 0.5)
		(connect_pads
			(clearance 0)
		)
		(min_thickness 0.25)
		(keepout
			(tracks allowed)
			(vias allowed)
			(pads allowed)
			(copperpour allowed)
			(footprints allowed)
		)
		(placement
			(enabled no)
			(sheetname "")
		)
		(fill
			(thermal_gap 0.5)
			(thermal_bridge_width 0.5)
			(island_removal_mode 0)
		)
		(polygon
			(pts
				(xy 158.067248 -35.539172) (xy 158.067248 -34.497772) (xy 160.023048 -34.497772) (xy 160.023048 -35.539172)
			)
		)
	)
	(zone
		(layer "Cmts.User")
		(hatch none 0.5)
		(connect_pads
			(clearance 0)
		)
		(min_thickness 0.25)
		(keepout
			(tracks allowed)
			(vias allowed)
			(pads allowed)
			(copperpour allowed)
			(footprints allowed)
		)
		(placement
			(enabled no)
			(sheetname "")
		)
		(fill
			(thermal_gap 0.5)
			(thermal_bridge_width 0.5)
			(island_removal_mode 0)
		)
		(polygon
			(pts
				(xy 131.241546 -43.504104) (xy 131.241546 -41.573704) (xy 132.308346 -41.573704) (xy 132.308346 -43.504104)
			)
		)
	)
	(zone
		(layer "Cmts.User")
		(hatch none 0.5)
		(connect_pads
			(clearance 0)
		)
		(min_thickness 0.25)
		(keepout
			(tracks allowed)
			(vias allowed)
			(pads allowed)
			(copperpour allowed)
			(footprints allowed)
		)
		(placement
			(enabled no)
			(sheetname "")
		)
		(fill
			(thermal_gap 0.5)
			(thermal_bridge_width 0.5)
			(island_removal_mode 0)
		)
		(polygon
			(pts
				(xy 319.09766 -37.547296) (xy 319.09766 -36.505896) (xy 321.05346 -36.505896) (xy 321.05346 -37.547296)
			)
		)
	)
	(zone
		(layer "Cmts.User")
		(hatch none 0.5)
		(connect_pads
			(clearance 0)
		)
		(min_thickness 0.25)
		(keepout
			(tracks allowed)
			(vias allowed)
			(pads allowed)
			(copperpour allowed)
			(footprints allowed)
		)
		(placement
			(enabled no)
			(sheetname "")
		)
		(fill
			(thermal_gap 0.5)
			(thermal_bridge_width 0.5)
			(island_removal_mode 0)
		)
		(polygon
			(pts
				(xy 263.8933 -211.4042) (xy 263.8933 -210.3628) (xy 265.8491 -210.3628) (xy 265.8491 -211.4042)
			)
		)
	)
	(zone
		(layer "Cmts.User")
		(hatch none 0.5)
		(connect_pads
			(clearance 0)
		)
		(min_thickness 0.25)
		(keepout
			(tracks allowed)
			(vias allowed)
			(pads allowed)
			(copperpour allowed)
			(footprints allowed)
		)
		(placement
			(enabled no)
			(sheetname "")
		)
		(fill
			(thermal_gap 0.5)
			(thermal_bridge_width 0.5)
			(island_removal_mode 0)
		)
		(polygon
			(pts
				(xy 54.293262 -211.4042) (xy 54.293262 -210.3628) (xy 56.249062 -210.3628) (xy 56.249062 -211.4042)
			)
		)
	)
	(zone
		(layer "Cmts.User")
		(hatch none 0.5)
		(connect_pads
			(clearance 0)
		)
		(min_thickness 0.25)
		(keepout
			(tracks allowed)
			(vias allowed)
			(pads allowed)
			(copperpour allowed)
			(footprints allowed)
		)
		(placement
			(enabled no)
			(sheetname "")
		)
		(fill
			(thermal_gap 0.5)
			(thermal_bridge_width 0.5)
			(island_removal_mode 0)
		)
		(polygon
			(pts
				(xy 14.90345 -53.315616) (xy 14.90345 -54.357016) (xy 12.94765 -54.357016) (xy 12.94765 -53.315616)
			)
		)
	)
	(zone
		(layer "Cmts.User")
		(hatch none 0.5)
		(connect_pads
			(clearance 0)
		)
		(min_thickness 0.25)
		(keepout
			(tracks allowed)
			(vias allowed)
			(pads allowed)
			(copperpour allowed)
			(footprints allowed)
		)
		(placement
			(enabled no)
			(sheetname "")
		)
		(fill
			(thermal_gap 0.5)
			(thermal_bridge_width 0.5)
			(island_removal_mode 0)
		)
		(polygon
			(pts
				(xy 71.141844 -220.522546) (xy 71.141844 -219.481146) (xy 73.097644 -219.481146) (xy 73.097644 -220.522546)
			)
		)
	)
	(zone
		(layer "Cmts.User")
		(hatch none 0.5)
		(connect_pads
			(clearance 0)
		)
		(min_thickness 0.25)
		(keepout
			(tracks allowed)
			(vias allowed)
			(pads allowed)
			(copperpour allowed)
			(footprints allowed)
		)
		(placement
			(enabled no)
			(sheetname "")
		)
		(fill
			(thermal_gap 0.5)
			(thermal_bridge_width 0.5)
			(island_removal_mode 0)
		)
		(polygon
			(pts
				(xy 271.541494 -15.893034) (xy 271.541494 -13.962634) (xy 272.608294 -13.962634) (xy 272.608294 -15.893034)
			)
		)
	)
	(zone
		(layer "Cmts.User")
		(hatch none 0.5)
		(connect_pads
			(clearance 0)
		)
		(min_thickness 0.25)
		(keepout
			(tracks allowed)
			(vias allowed)
			(pads allowed)
			(copperpour allowed)
			(footprints allowed)
		)
		(placement
			(enabled no)
			(sheetname "")
		)
		(fill
			(thermal_gap 0.5)
			(thermal_bridge_width 0.5)
			(island_removal_mode 0)
		)
		(polygon
			(pts
				(xy 14.698218 -69.023738) (xy 13.656818 -69.023738) (xy 13.656818 -67.067938) (xy 14.698218 -67.067938)
			)
		)
	)
	(zone
		(layer "Cmts.User")
		(hatch none 0.5)
		(connect_pads
			(clearance 0)
		)
		(min_thickness 0.25)
		(keepout
			(tracks allowed)
			(vias allowed)
			(pads allowed)
			(copperpour allowed)
			(footprints allowed)
		)
		(placement
			(enabled no)
			(sheetname "")
		)
		(fill
			(thermal_gap 0.5)
			(thermal_bridge_width 0.5)
			(island_removal_mode 0)
		)
		(polygon
			(pts
				(xy 152.094946 -35.518852) (xy 152.094946 -34.477452) (xy 154.050746 -34.477452) (xy 154.050746 -35.518852)
			)
		)
	)
	(zone
		(layer "Cmts.User")
		(hatch none 0.5)
		(connect_pads
			(clearance 0)
		)
		(min_thickness 0.25)
		(keepout
			(tracks allowed)
			(vias allowed)
			(pads allowed)
			(copperpour allowed)
			(footprints allowed)
		)
		(placement
			(enabled no)
			(sheetname "")
		)
		(fill
			(thermal_gap 0.5)
			(thermal_bridge_width 0.5)
			(island_removal_mode 0)
		)
		(polygon
			(pts
				(xy 25.425146 -144.202404) (xy 25.425146 -142.272004) (xy 26.491946 -142.272004) (xy 26.491946 -144.202404)
			)
		)
	)
	(zone
		(layer "Cmts.User")
		(hatch none 0.5)
		(connect_pads
			(clearance 0)
		)
		(min_thickness 0.25)
		(keepout
			(tracks allowed)
			(vias allowed)
			(pads allowed)
			(copperpour allowed)
			(footprints allowed)
		)
		(placement
			(enabled no)
			(sheetname "")
		)
		(fill
			(thermal_gap 0.5)
			(thermal_bridge_width 0.5)
			(island_removal_mode 0)
		)
		(polygon
			(pts
				(xy 283.209238 -21.836126) (xy 281.844242 -20.47113) (xy 282.598622 -19.71675) (xy 283.963618 -21.081746)
			)
		)
	)
	(zone
		(layer "Cmts.User")
		(hatch none 0.5)
		(connect_pads
			(clearance 0)
		)
		(min_thickness 0.25)
		(keepout
			(tracks allowed)
			(vias allowed)
			(pads allowed)
			(copperpour allowed)
			(footprints allowed)
		)
		(placement
			(enabled no)
			(sheetname "")
		)
		(fill
			(thermal_gap 0.5)
			(thermal_bridge_width 0.5)
			(island_removal_mode 0)
		)
		(polygon
			(pts
				(xy 301.058834 -35.534092) (xy 301.058834 -34.492692) (xy 303.014634 -34.492692) (xy 303.014634 -35.534092)
			)
		)
	)
	(zone
		(layer "Cmts.User")
		(hatch none 0.5)
		(connect_pads
			(clearance 0)
		)
		(min_thickness 0.25)
		(keepout
			(tracks allowed)
			(vias allowed)
			(pads allowed)
			(copperpour allowed)
			(footprints allowed)
		)
		(placement
			(enabled no)
			(sheetname "")
		)
		(fill
			(thermal_gap 0.5)
			(thermal_bridge_width 0.5)
			(island_removal_mode 0)
		)
		(polygon
			(pts
				(xy 215.493092 -211.4042) (xy 215.493092 -210.3628) (xy 217.448892 -210.3628) (xy 217.448892 -211.4042)
			)
		)
	)
	(zone
		(layer "Cmts.User")
		(hatch none 0.5)
		(connect_pads
			(clearance 0)
		)
		(min_thickness 0.25)
		(keepout
			(tracks allowed)
			(vias allowed)
			(pads allowed)
			(copperpour allowed)
			(footprints allowed)
		)
		(placement
			(enabled no)
			(sheetname "")
		)
		(fill
			(thermal_gap 0.5)
			(thermal_bridge_width 0.5)
			(island_removal_mode 0)
		)
		(polygon
			(pts
				(xy 79.09306 -211.4042) (xy 79.09306 -210.3628) (xy 81.04886 -210.3628) (xy 81.04886 -211.4042)
			)
		)
	)
	(zone
		(layer "Cmts.User")
		(hatch none 0.5)
		(connect_pads
			(clearance 0)
		)
		(min_thickness 0.25)
		(keepout
			(tracks allowed)
			(vias allowed)
			(pads allowed)
			(copperpour allowed)
			(footprints allowed)
		)
		(placement
			(enabled no)
			(sheetname "")
		)
		(fill
			(thermal_gap 0.5)
			(thermal_bridge_width 0.5)
			(island_removal_mode 0)
		)
		(polygon
			(pts
				(xy 341.493094 -211.4042) (xy 341.493094 -210.3628) (xy 343.448894 -210.3628) (xy 343.448894 -211.4042)
			)
		)
	)
	(zone
		(layer "Cmts.User")
		(hatch none 0.5)
		(connect_pads
			(clearance 0)
		)
		(min_thickness 0.25)
		(keepout
			(tracks allowed)
			(vias allowed)
			(pads allowed)
			(copperpour allowed)
			(footprints allowed)
		)
		(placement
			(enabled no)
			(sheetname "")
		)
		(fill
			(thermal_gap 0.5)
			(thermal_bridge_width 0.5)
			(island_removal_mode 0)
		)
		(polygon
			(pts
				(xy 309.493158 -211.4042) (xy 309.493158 -210.3628) (xy 311.448958 -210.3628) (xy 311.448958 -211.4042)
			)
		)
	)
	(zone
		(layer "Cmts.User")
		(hatch none 0.5)
		(connect_pads
			(clearance 0)
		)
		(min_thickness 0.25)
		(keepout
			(tracks allowed)
			(vias allowed)
			(pads allowed)
			(copperpour allowed)
			(footprints allowed)
		)
		(placement
			(enabled no)
			(sheetname "")
		)
		(fill
			(thermal_gap 0.5)
			(thermal_bridge_width 0.5)
			(island_removal_mode 0)
		)
		(polygon
			(pts
				(xy 172.157644 -96.519746) (xy 172.157644 -95.478346) (xy 174.113444 -95.478346) (xy 174.113444 -96.519746)
			)
		)
	)
	(zone
		(layer "Cmts.User")
		(hatch none 0.5)
		(connect_pads
			(clearance 0)
		)
		(min_thickness 0.25)
		(keepout
			(tracks allowed)
			(vias allowed)
			(pads allowed)
			(copperpour allowed)
			(footprints allowed)
		)
		(placement
			(enabled no)
			(sheetname "")
		)
		(fill
			(thermal_gap 0.5)
			(thermal_bridge_width 0.5)
			(island_removal_mode 0)
		)
		(polygon
			(pts
				(xy 315.893196 -211.4042) (xy 315.893196 -210.3628) (xy 317.848996 -210.3628) (xy 317.848996 -211.4042)
			)
		)
	)
	(zone
		(layer "Cmts.User")
		(hatch none 0.5)
		(connect_pads
			(clearance 0)
		)
		(min_thickness 0.25)
		(keepout
			(tracks allowed)
			(vias allowed)
			(pads allowed)
			(copperpour allowed)
			(footprints allowed)
		)
		(placement
			(enabled no)
			(sheetname "")
		)
		(fill
			(thermal_gap 0.5)
			(thermal_bridge_width 0.5)
			(island_removal_mode 0)
		)
		(polygon
			(pts
				(xy 182.549546 -30.372304) (xy 182.549546 -28.441904) (xy 183.616346 -28.441904) (xy 183.616346 -30.372304)
			)
		)
	)
	(zone
		(layer "Cmts.User")
		(hatch none 0.5)
		(connect_pads
			(clearance 0)
		)
		(min_thickness 0.25)
		(keepout
			(tracks allowed)
			(vias allowed)
			(pads allowed)
			(copperpour allowed)
			(footprints allowed)
		)
		(placement
			(enabled no)
			(sheetname "")
		)
		(fill
			(thermal_gap 0.5)
			(thermal_bridge_width 0.5)
			(island_removal_mode 0)
		)
		(polygon
			(pts
				(xy 160.70453 -35.549078) (xy 160.70453 -34.507678) (xy 162.66033 -34.507678) (xy 162.66033 -35.549078)
			)
		)
	)
	(zone
		(layer "Cmts.User")
		(hatch none 0.5)
		(connect_pads
			(clearance 0)
		)
		(min_thickness 0.25)
		(keepout
			(tracks allowed)
			(vias allowed)
			(pads allowed)
			(copperpour allowed)
			(footprints allowed)
		)
		(placement
			(enabled no)
			(sheetname "")
		)
		(fill
			(thermal_gap 0.5)
			(thermal_bridge_width 0.5)
			(island_removal_mode 0)
		)
		(polygon
			(pts
				(xy 165.186106 -26.503884) (xy 165.186106 -11.625834) (xy 172.39869 -11.625834) (xy 172.39869 -26.503884)
			)
		)
	)
	(zone
		(layer "Cmts.User")
		(hatch none 0.5)
		(connect_pads
			(clearance 0)
		)
		(min_thickness 0.25)
		(keepout
			(tracks allowed)
			(vias allowed)
			(pads allowed)
			(copperpour allowed)
			(footprints allowed)
		)
		(placement
			(enabled no)
			(sheetname "")
		)
		(fill
			(thermal_gap 0.5)
			(thermal_bridge_width 0.5)
			(island_removal_mode 0)
		)
		(polygon
			(pts
				(xy 133.273038 -36.255452) (xy 133.273038 -35.214052) (xy 135.228838 -35.214052) (xy 135.228838 -36.255452)
			)
		)
	)
	(zone
		(layer "Cmts.User")
		(hatch none 0.5)
		(connect_pads
			(clearance 0)
		)
		(min_thickness 0.25)
		(keepout
			(tracks allowed)
			(vias allowed)
			(pads allowed)
			(copperpour allowed)
			(footprints allowed)
		)
		(placement
			(enabled no)
			(sheetname "")
		)
		(fill
			(thermal_gap 0.5)
			(thermal_bridge_width 0.5)
			(island_removal_mode 0)
		)
		(polygon
			(pts
				(xy 150.693374 -211.4042) (xy 150.693374 -210.3628) (xy 152.649174 -210.3628) (xy 152.649174 -211.4042)
			)
		)
	)
	(zone
		(layer "Cmts.User")
		(hatch none 0.5)
		(connect_pads
			(clearance 0)
		)
		(min_thickness 0.25)
		(keepout
			(tracks allowed)
			(vias allowed)
			(pads allowed)
			(copperpour allowed)
			(footprints allowed)
		)
		(placement
			(enabled no)
			(sheetname "")
		)
		(fill
			(thermal_gap 0.5)
			(thermal_bridge_width 0.5)
			(island_removal_mode 0)
		)
		(polygon
			(pts
				(xy 165.893242 -211.4042) (xy 165.893242 -210.3628) (xy 167.849042 -210.3628) (xy 167.849042 -211.4042)
			)
		)
	)
	(zone
		(layer "Cmts.User")
		(hatch none 0.5)
		(connect_pads
			(clearance 0)
		)
		(min_thickness 0.25)
		(keepout
			(tracks allowed)
			(vias allowed)
			(pads allowed)
			(copperpour allowed)
			(footprints allowed)
		)
		(placement
			(enabled no)
			(sheetname "")
		)
		(fill
			(thermal_gap 0.5)
			(thermal_bridge_width 0.5)
			(island_removal_mode 0)
		)
		(polygon
			(pts
				(xy 91.893136 -211.4042) (xy 91.893136 -210.3628) (xy 93.848936 -210.3628) (xy 93.848936 -211.4042)
			)
		)
	)
	(zone
		(layer "Cmts.User")
		(hatch none 0.5)
		(connect_pads
			(clearance 0)
		)
		(min_thickness 0.25)
		(keepout
			(tracks allowed)
			(vias allowed)
			(pads allowed)
			(copperpour allowed)
			(footprints allowed)
		)
		(placement
			(enabled no)
			(sheetname "")
		)
		(fill
			(thermal_gap 0.5)
			(thermal_bridge_width 0.5)
			(island_removal_mode 0)
		)
		(polygon
			(pts
				(xy 11.022076 -54.489096) (xy 11.022076 -55.530496) (xy 9.066276 -55.530496) (xy 9.066276 -54.489096)
			)
		)
	)
	(zone
		(layer "Cmts.User")
		(hatch none 0.5)
		(connect_pads
			(clearance 0)
		)
		(min_thickness 0.25)
		(keepout
			(tracks allowed)
			(vias allowed)
			(pads allowed)
			(copperpour allowed)
			(footprints allowed)
		)
		(placement
			(enabled no)
			(sheetname "")
		)
		(fill
			(thermal_gap 0.5)
			(thermal_bridge_width 0.5)
			(island_removal_mode 0)
		)
		(polygon
			(pts
				(xy 135.8646 -222.9104) (xy 135.8646 -221.5896) (xy 218.8464 -221.5896) (xy 218.8464 -222.9104)
			)
		)
	)
	(zone
		(layer "Cmts.User")
		(hatch none 0.5)
		(connect_pads
			(clearance 0)
		)
		(min_thickness 0.25)
		(keepout
			(tracks allowed)
			(vias allowed)
			(pads allowed)
			(copperpour allowed)
			(footprints allowed)
		)
		(placement
			(enabled no)
			(sheetname "")
		)
		(fill
			(thermal_gap 0.5)
			(thermal_bridge_width 0.5)
			(island_removal_mode 0)
		)
		(polygon
			(pts
				(xy 16.713962 -67.579494) (xy 15.672562 -67.579494) (xy 15.672562 -65.623694) (xy 16.713962 -65.623694)
			)
		)
	)
	(zone
		(layer "Cmts.User")
		(hatch none 0.5)
		(connect_pads
			(clearance 0)
		)
		(min_thickness 0.25)
		(keepout
			(tracks allowed)
			(vias allowed)
			(pads allowed)
			(copperpour allowed)
			(footprints allowed)
		)
		(placement
			(enabled no)
			(sheetname "")
		)
		(fill
			(thermal_gap 0.5)
			(thermal_bridge_width 0.5)
			(island_removal_mode 0)
		)
		(polygon
			(pts
				(xy 319.093342 -211.4042) (xy 319.093342 -210.3628) (xy 321.049142 -210.3628) (xy 321.049142 -211.4042)
			)
		)
	)
	(zone
		(layer "Cmts.User")
		(hatch none 0.5)
		(connect_pads
			(clearance 0)
		)
		(min_thickness 0.25)
		(keepout
			(tracks allowed)
			(vias allowed)
			(pads allowed)
			(copperpour allowed)
			(footprints allowed)
		)
		(placement
			(enabled no)
			(sheetname "")
		)
		(fill
			(thermal_gap 0.5)
			(thermal_bridge_width 0.5)
			(island_removal_mode 0)
		)
		(polygon
			(pts
				(xy 21.79066 -86.953344) (xy 21.79066 -87.994744) (xy 19.83486 -87.994744) (xy 19.83486 -86.953344)
			)
		)
	)
	(zone
		(layer "Cmts.User")
		(hatch none 0.5)
		(connect_pads
			(clearance 0)
		)
		(min_thickness 0.25)
		(keepout
			(tracks allowed)
			(vias allowed)
			(pads allowed)
			(copperpour allowed)
			(footprints allowed)
		)
		(placement
			(enabled no)
			(sheetname "")
		)
		(fill
			(thermal_gap 0.5)
			(thermal_bridge_width 0.5)
			(island_removal_mode 0)
		)
		(polygon
			(pts
				(xy 312.693304 -211.4042) (xy 312.693304 -210.3628) (xy 314.649104 -210.3628) (xy 314.649104 -211.4042)
			)
		)
	)
	(zone
		(layer "Cmts.User")
		(hatch none 0.5)
		(connect_pads
			(clearance 0)
		)
		(min_thickness 0.25)
		(keepout
			(tracks allowed)
			(vias allowed)
			(pads allowed)
			(copperpour allowed)
			(footprints allowed)
		)
		(placement
			(enabled no)
			(sheetname "")
		)
		(fill
			(thermal_gap 0.5)
			(thermal_bridge_width 0.5)
			(island_removal_mode 0)
		)
		(polygon
			(pts
				(xy 185.486548 -45.866558) (xy 184.445148 -45.866558) (xy 184.445148 -43.910758) (xy 185.486548 -43.910758)
			)
		)
	)
	(zone
		(layer "Cmts.User")
		(hatch none 0.5)
		(connect_pads
			(clearance 0)
		)
		(min_thickness 0.25)
		(keepout
			(tracks allowed)
			(vias allowed)
			(pads allowed)
			(copperpour allowed)
			(footprints allowed)
		)
		(placement
			(enabled no)
			(sheetname "")
		)
		(fill
			(thermal_gap 0.5)
			(thermal_bridge_width 0.5)
			(island_removal_mode 0)
		)
		(polygon
			(pts
				(xy 331.893164 -211.4042) (xy 331.893164 -210.3628) (xy 333.848964 -210.3628) (xy 333.848964 -211.4042)
			)
		)
	)
	(zone
		(layer "Cmts.User")
		(hatch none 0.5)
		(connect_pads
			(clearance 0)
		)
		(min_thickness 0.25)
		(keepout
			(tracks allowed)
			(vias allowed)
			(pads allowed)
			(copperpour allowed)
			(footprints allowed)
		)
		(placement
			(enabled no)
			(sheetname "")
		)
		(fill
			(thermal_gap 0.5)
			(thermal_bridge_width 0.5)
			(island_removal_mode 0)
		)
		(polygon
			(pts
				(xy 77.607414 -220.38945) (xy 77.607414 -219.34805) (xy 79.563214 -219.34805) (xy 79.563214 -220.38945)
			)
		)
	)
	(zone
		(layer "Cmts.User")
		(hatch none 0.5)
		(connect_pads
			(clearance 0)
		)
		(min_thickness 0.25)
		(keepout
			(tracks allowed)
			(vias allowed)
			(pads allowed)
			(copperpour allowed)
			(footprints allowed)
		)
		(placement
			(enabled no)
			(sheetname "")
		)
		(fill
			(thermal_gap 0.5)
			(thermal_bridge_width 0.5)
			(island_removal_mode 0)
		)
		(polygon
			(pts
				(xy 82.293206 -211.4042) (xy 82.293206 -210.3628) (xy 84.249006 -210.3628) (xy 84.249006 -211.4042)
			)
		)
	)
	(zone
		(layer "Cmts.User")
		(hatch none 0.5)
		(connect_pads
			(clearance 0)
		)
		(min_thickness 0.25)
		(keepout
			(tracks allowed)
			(vias allowed)
			(pads allowed)
			(copperpour allowed)
			(footprints allowed)
		)
		(placement
			(enabled no)
			(sheetname "")
		)
		(fill
			(thermal_gap 0.5)
			(thermal_bridge_width 0.5)
			(island_removal_mode 0)
		)
		(polygon
			(pts
				(xy 261.7724 -222.9358) (xy 261.7724 -221.615) (xy 344.7542 -221.615) (xy 344.7542 -222.9358)
			)
		)
	)
	(zone
		(layer "Cmts.User")
		(hatch none 0.5)
		(connect_pads
			(clearance 0)
		)
		(min_thickness 0.25)
		(keepout
			(tracks allowed)
			(vias allowed)
			(pads allowed)
			(copperpour allowed)
			(footprints allowed)
		)
		(placement
			(enabled no)
			(sheetname "")
		)
		(fill
			(thermal_gap 0.5)
			(thermal_bridge_width 0.5)
			(island_removal_mode 0)
		)
		(polygon
			(pts
				(xy 186.693302 -211.4042) (xy 186.693302 -210.3628) (xy 188.649102 -210.3628) (xy 188.649102 -211.4042)
			)
		)
	)
	(zone
		(layer "Cmts.User")
		(hatch none 0.5)
		(connect_pads
			(clearance 0)
		)
		(min_thickness 0.25)
		(keepout
			(tracks allowed)
			(vias allowed)
			(pads allowed)
			(copperpour allowed)
			(footprints allowed)
		)
		(placement
			(enabled no)
			(sheetname "")
		)
		(fill
			(thermal_gap 0.5)
			(thermal_bridge_width 0.5)
			(island_removal_mode 0)
		)
		(polygon
			(pts
				(xy 327.809098 -35.43554) (xy 327.809098 -34.39414) (xy 329.764898 -34.39414) (xy 329.764898 -35.43554)
			)
		)
	)
	(zone
		(layer "Cmts.User")
		(hatch none 0.5)
		(connect_pads
			(clearance 0)
		)
		(min_thickness 0.25)
		(keepout
			(tracks allowed)
			(vias allowed)
			(pads allowed)
			(copperpour allowed)
			(footprints allowed)
		)
		(placement
			(enabled no)
			(sheetname "")
		)
		(fill
			(thermal_gap 0.5)
			(thermal_bridge_width 0.5)
			(island_removal_mode 0)
		)
		(polygon
			(pts
				(xy 29.7434 -223.012) (xy 29.7434 -221.6912) (xy 112.7252 -221.6912) (xy 112.7252 -223.012)
			)
		)
	)
	(zone
		(layer "Cmts.User")
		(hatch none 0.5)
		(connect_pads
			(clearance 0)
		)
		(min_thickness 0.25)
		(keepout
			(tracks allowed)
			(vias allowed)
			(pads allowed)
			(copperpour allowed)
			(footprints allowed)
		)
		(placement
			(enabled no)
			(sheetname "")
		)
		(fill
			(thermal_gap 0.5)
			(thermal_bridge_width 0.5)
			(island_removal_mode 0)
		)
		(polygon
			(pts
				(xy 141.093444 -211.4042) (xy 141.093444 -210.3628) (xy 143.049244 -210.3628) (xy 143.049244 -211.4042)
			)
		)
	)
	(zone
		(layer "Cmts.User")
		(hatch none 0.5)
		(connect_pads
			(clearance 0)
		)
		(min_thickness 0.25)
		(keepout
			(tracks allowed)
			(vias allowed)
			(pads allowed)
			(copperpour allowed)
			(footprints allowed)
		)
		(placement
			(enabled no)
			(sheetname "")
		)
		(fill
			(thermal_gap 0.5)
			(thermal_bridge_width 0.5)
			(island_removal_mode 0)
		)
		(polygon
			(pts
				(xy 26.543 -142.113) (xy 26.543 -124.7902) (xy 25.654 -124.7902) (xy 25.654 -118.872) (xy 26.543 -118.872)
				(xy 49.784 -118.872) (xy 49.784 -125.984) (xy 49.9364 -126.1364) (xy 53.594 -126.1364) (xy 53.7718 -126.3142)
				(xy 53.7718 -130.3528) (xy 53.6448 -130.4798) (xy 49.9618 -130.4798) (xy 49.784 -130.6576) (xy 49.784 -142.113)
				(xy 41.4274 -142.113) (xy 41.3258 -142.2146) (xy 41.3258 -143.9926) (xy 41.2242 -144.0942) (xy 40.64 -144.0942)
				(xy 40.5638 -144.018) (xy 40.5638 -142.1384) (xy 40.5384 -142.113) (xy 32.0802 -142.113) (xy 32.0802 -144.3482)
				(xy 31.9786 -144.4498) (xy 30.8864 -144.4498) (xy 30.7594 -144.3228) (xy 30.7594 -142.113)
			)
		)
	)
	(zone
		(layer "Cmts.User")
		(hatch none 0.5)
		(connect_pads
			(clearance 0)
		)
		(min_thickness 0.25)
		(keepout
			(tracks allowed)
			(vias allowed)
			(pads allowed)
			(copperpour allowed)
			(footprints allowed)
		)
		(placement
			(enabled no)
			(sheetname "")
		)
		(fill
			(thermal_gap 0.5)
			(thermal_bridge_width 0.5)
			(island_removal_mode 0)
		)
		(polygon
			(pts
				(xy 292.69309 -211.4042) (xy 292.69309 -210.3628) (xy 294.64889 -210.3628) (xy 294.64889 -211.4042)
			)
		)
	)
	(zone
		(layer "Cmts.User")
		(hatch none 0.5)
		(connect_pads
			(clearance 0)
		)
		(min_thickness 0.25)
		(keepout
			(tracks allowed)
			(vias allowed)
			(pads allowed)
			(copperpour allowed)
			(footprints allowed)
		)
		(placement
			(enabled no)
			(sheetname "")
		)
		(fill
			(thermal_gap 0.5)
			(thermal_bridge_width 0.5)
			(island_removal_mode 0)
		)
		(polygon
			(pts
				(xy 130.512312 -35.796982) (xy 130.512312 -34.755582) (xy 132.468112 -34.755582) (xy 132.468112 -35.796982)
			)
		)
	)
	(zone
		(layer "Cmts.User")
		(hatch none 0.5)
		(connect_pads
			(clearance 0)
		)
		(min_thickness 0.25)
		(keepout
			(tracks allowed)
			(vias allowed)
			(pads allowed)
			(copperpour allowed)
			(footprints allowed)
		)
		(placement
			(enabled no)
			(sheetname "")
		)
		(fill
			(thermal_gap 0.5)
			(thermal_bridge_width 0.5)
			(island_removal_mode 0)
		)
		(polygon
			(pts
				(xy 85.493098 -211.4042) (xy 85.493098 -210.3628) (xy 87.448898 -210.3628) (xy 87.448898 -211.4042)
			)
		)
	)
	(zone
		(layer "Cmts.User")
		(hatch none 0.5)
		(connect_pads
			(clearance 0)
		)
		(min_thickness 0.25)
		(keepout
			(tracks allowed)
			(vias allowed)
			(pads allowed)
			(copperpour allowed)
			(footprints allowed)
		)
		(placement
			(enabled no)
			(sheetname "")
		)
		(fill
			(thermal_gap 0.5)
			(thermal_bridge_width 0.5)
			(island_removal_mode 0)
		)
		(polygon
			(pts
				(xy 137.983722 -38.97503) (xy 137.983722 -37.93363) (xy 139.939522 -37.93363) (xy 139.939522 -38.97503)
			)
		)
	)
	(zone
		(layer "Cmts.User")
		(hatch none 0.5)
		(connect_pads
			(clearance 0)
		)
		(min_thickness 0.25)
		(keepout
			(tracks allowed)
			(vias allowed)
			(pads allowed)
			(copperpour allowed)
			(footprints allowed)
		)
		(placement
			(enabled no)
			(sheetname "")
		)
		(fill
			(thermal_gap 0.5)
			(thermal_bridge_width 0.5)
			(island_removal_mode 0)
		)
		(polygon
			(pts
				(xy 167.195754 -88.081104) (xy 168.237154 -88.081104) (xy 168.237154 -90.036904) (xy 167.195754 -90.036904)
			)
		)
	)
	(zone
		(layer "Cmts.User")
		(hatch none 0.5)
		(connect_pads
			(clearance 0)
		)
		(min_thickness 0.25)
		(keepout
			(tracks allowed)
			(vias allowed)
			(pads allowed)
			(copperpour allowed)
			(footprints allowed)
		)
		(placement
			(enabled no)
			(sheetname "")
		)
		(fill
			(thermal_gap 0.5)
			(thermal_bridge_width 0.5)
			(island_removal_mode 0)
		)
		(polygon
			(pts
				(xy 309.825136 -35.549586) (xy 309.825136 -34.508186) (xy 311.780936 -34.508186) (xy 311.780936 -35.549586)
			)
		)
	)
	(zone
		(layer "Cmts.User")
		(hatch none 0.5)
		(connect_pads
			(clearance 0)
		)
		(min_thickness 0.25)
		(keepout
			(tracks allowed)
			(vias allowed)
			(pads allowed)
			(copperpour allowed)
			(footprints allowed)
		)
		(placement
			(enabled no)
			(sheetname "")
		)
		(fill
			(thermal_gap 0.5)
			(thermal_bridge_width 0.5)
			(island_removal_mode 0)
		)
		(polygon
			(pts
				(xy 270.293338 -211.4042) (xy 270.293338 -210.3628) (xy 272.249138 -210.3628) (xy 272.249138 -211.4042)
			)
		)
	)
	(zone
		(layer "Cmts.User")
		(hatch none 0.5)
		(connect_pads
			(clearance 0)
		)
		(min_thickness 0.25)
		(keepout
			(tracks allowed)
			(vias allowed)
			(pads allowed)
			(copperpour allowed)
			(footprints allowed)
		)
		(placement
			(enabled no)
			(sheetname "")
		)
		(fill
			(thermal_gap 0.5)
			(thermal_bridge_width 0.5)
			(island_removal_mode 0)
		)
		(polygon
			(pts
				(xy 325.493126 -211.4042) (xy 325.493126 -210.3628) (xy 327.448926 -210.3628) (xy 327.448926 -211.4042)
			)
		)
	)
	(zone
		(layer "Cmts.User")
		(hatch none 0.5)
		(connect_pads
			(clearance 0)
		)
		(min_thickness 0.25)
		(keepout
			(tracks allowed)
			(vias allowed)
			(pads allowed)
			(copperpour allowed)
			(footprints allowed)
		)
		(placement
			(enabled no)
			(sheetname "")
		)
		(fill
			(thermal_gap 0.5)
			(thermal_bridge_width 0.5)
			(island_removal_mode 0)
		)
		(polygon
			(pts
				(xy 57.493408 -211.4042) (xy 57.493408 -210.3628) (xy 59.449208 -210.3628) (xy 59.449208 -211.4042)
			)
		)
	)
	(zone
		(layer "Cmts.User")
		(hatch none 0.5)
		(connect_pads
			(clearance 0)
		)
		(min_thickness 0.25)
		(keepout
			(tracks allowed)
			(vias allowed)
			(pads allowed)
			(copperpour allowed)
			(footprints allowed)
		)
		(placement
			(enabled no)
			(sheetname "")
		)
		(fill
			(thermal_gap 0.5)
			(thermal_bridge_width 0.5)
			(island_removal_mode 0)
		)
		(polygon
			(pts
				(xy 160.293304 -211.4042) (xy 160.293304 -210.3628) (xy 162.249104 -210.3628) (xy 162.249104 -211.4042)
			)
		)
	)
	(zone
		(layer "Cmts.User")
		(hatch none 0.5)
		(connect_pads
			(clearance 0)
		)
		(min_thickness 0.25)
		(keepout
			(tracks allowed)
			(vias allowed)
			(pads allowed)
			(copperpour allowed)
			(footprints allowed)
		)
		(placement
			(enabled no)
			(sheetname "")
		)
		(fill
			(thermal_gap 0.5)
			(thermal_bridge_width 0.5)
			(island_removal_mode 0)
		)
		(polygon
			(pts
				(xy 103.893366 -211.4042) (xy 103.893366 -210.3628) (xy 105.849166 -210.3628) (xy 105.849166 -211.4042)
			)
		)
	)
	(zone
		(layer "Cmts.User")
		(hatch none 0.5)
		(connect_pads
			(clearance 0)
		)
		(min_thickness 0.25)
		(keepout
			(tracks allowed)
			(vias allowed)
			(pads allowed)
			(copperpour allowed)
			(footprints allowed)
		)
		(placement
			(enabled no)
			(sheetname "")
		)
		(fill
			(thermal_gap 0.5)
			(thermal_bridge_width 0.5)
			(island_removal_mode 0)
		)
		(polygon
			(pts
				(xy 189.190376 -44.67225) (xy 189.190376 -45.71365) (xy 187.234576 -45.71365) (xy 187.234576 -44.67225)
			)
		)
	)
	(zone
		(layer "Cmts.User")
		(hatch none 0.5)
		(connect_pads
			(clearance 0)
		)
		(min_thickness 0.25)
		(keepout
			(tracks allowed)
			(vias allowed)
			(pads allowed)
			(copperpour allowed)
			(footprints allowed)
		)
		(placement
			(enabled no)
			(sheetname "")
		)
		(fill
			(thermal_gap 0.5)
			(thermal_bridge_width 0.5)
			(island_removal_mode 0)
		)
		(polygon
			(pts
				(xy 298.293282 -211.4042) (xy 298.293282 -210.3628) (xy 300.249082 -210.3628) (xy 300.249082 -211.4042)
			)
		)
	)
	(zone
		(layer "Cmts.User")
		(hatch none 0.5)
		(connect_pads
			(clearance 0)
		)
		(min_thickness 0.25)
		(keepout
			(tracks allowed)
			(vias allowed)
			(pads allowed)
			(copperpour allowed)
			(footprints allowed)
		)
		(placement
			(enabled no)
			(sheetname "")
		)
		(fill
			(thermal_gap 0.5)
			(thermal_bridge_width 0.5)
			(island_removal_mode 0)
		)
		(polygon
			(pts
				(xy 182.549546 -25.038304) (xy 182.549546 -23.107904) (xy 183.616346 -23.107904) (xy 183.616346 -25.038304)
			)
		)
	)
	(zone
		(layer "Cmts.User")
		(hatch none 0.5)
		(connect_pads
			(clearance 0)
		)
		(min_thickness 0.25)
		(keepout
			(tracks allowed)
			(vias allowed)
			(pads allowed)
			(copperpour allowed)
			(footprints allowed)
		)
		(placement
			(enabled no)
			(sheetname "")
		)
		(fill
			(thermal_gap 0.5)
			(thermal_bridge_width 0.5)
			(island_removal_mode 0)
		)
		(polygon
			(pts
				(xy 301.493174 -211.4042) (xy 301.493174 -210.3628) (xy 303.448974 -210.3628) (xy 303.448974 -211.4042)
			)
		)
	)
	(zone
		(layer "Cmts.User")
		(hatch none 0.5)
		(connect_pads
			(clearance 0)
		)
		(min_thickness 0.25)
		(keepout
			(tracks allowed)
			(vias allowed)
			(pads allowed)
			(copperpour allowed)
			(footprints allowed)
		)
		(placement
			(enabled no)
			(sheetname "")
		)
		(fill
			(thermal_gap 0.5)
			(thermal_bridge_width 0.5)
			(island_removal_mode 0)
		)
		(polygon
			(pts
				(xy 137.893298 -211.4042) (xy 137.893298 -210.3628) (xy 139.849098 -210.3628) (xy 139.849098 -211.4042)
			)
		)
	)
	(zone
		(layer "Cmts.User")
		(hatch none 0.5)
		(connect_pads
			(clearance 0)
		)
		(min_thickness 0.25)
		(keepout
			(tracks allowed)
			(vias allowed)
			(pads allowed)
			(copperpour allowed)
			(footprints allowed)
		)
		(placement
			(enabled no)
			(sheetname "")
		)
		(fill
			(thermal_gap 0.5)
			(thermal_bridge_width 0.5)
			(island_removal_mode 0)
		)
		(polygon
			(pts
				(xy 55.835296 -84.755228) (xy 56.876696 -84.755228) (xy 56.876696 -86.711028) (xy 55.835296 -86.711028)
			)
		)
	)
	(zone
		(layer "Cmts.User")
		(hatch none 0.5)
		(connect_pads
			(clearance 0)
		)
		(min_thickness 0.25)
		(keepout
			(tracks allowed)
			(vias allowed)
			(pads allowed)
			(copperpour allowed)
			(footprints allowed)
		)
		(placement
			(enabled no)
			(sheetname "")
		)
		(fill
			(thermal_gap 0.5)
			(thermal_bridge_width 0.5)
			(island_removal_mode 0)
		)
		(polygon
			(pts
				(xy 199.665844 -50.25771) (xy 199.665844 -49.21631) (xy 201.621644 -49.21631) (xy 201.621644 -50.25771)
			)
		)
	)
	(zone
		(layer "Cmts.User")
		(hatch none 0.5)
		(connect_pads
			(clearance 0)
		)
		(min_thickness 0.25)
		(keepout
			(tracks allowed)
			(vias allowed)
			(pads allowed)
			(copperpour allowed)
			(footprints allowed)
		)
		(placement
			(enabled no)
			(sheetname "")
		)
		(fill
			(thermal_gap 0.5)
			(thermal_bridge_width 0.5)
			(island_removal_mode 0)
		)
		(polygon
			(pts
				(xy 57.489344 -196.775832) (xy 57.489344 -195.734432) (xy 59.445144 -195.734432) (xy 59.445144 -196.775832)
			)
		)
	)
	(zone
		(layer "Cmts.User")
		(hatch none 0.5)
		(connect_pads
			(clearance 0)
		)
		(min_thickness 0.25)
		(keepout
			(tracks allowed)
			(vias allowed)
			(pads allowed)
			(copperpour allowed)
			(footprints allowed)
		)
		(placement
			(enabled no)
			(sheetname "")
		)
		(fill
			(thermal_gap 0.5)
			(thermal_bridge_width 0.5)
			(island_removal_mode 0)
		)
		(polygon
			(pts
				(xy 20.19046 -81.390744) (xy 20.19046 -82.432144) (xy 18.23466 -82.432144) (xy 18.23466 -81.390744)
			)
		)
	)
	(zone
		(layer "Cmts.User")
		(hatch none 0.5)
		(connect_pads
			(clearance 0)
		)
		(min_thickness 0.25)
		(keepout
			(tracks allowed)
			(vias allowed)
			(pads allowed)
			(copperpour allowed)
			(footprints allowed)
		)
		(placement
			(enabled no)
			(sheetname "")
		)
		(fill
			(thermal_gap 0.5)
			(thermal_bridge_width 0.5)
			(island_removal_mode 0)
		)
		(polygon
			(pts
				(xy 205.893162 -211.4042) (xy 205.893162 -210.3628) (xy 207.848962 -210.3628) (xy 207.848962 -211.4042)
			)
		)
	)
	(zone
		(layer "Cmts.User")
		(hatch none 0.5)
		(connect_pads
			(clearance 0)
		)
		(min_thickness 0.25)
		(keepout
			(tracks allowed)
			(vias allowed)
			(pads allowed)
			(copperpour allowed)
			(footprints allowed)
		)
		(placement
			(enabled no)
			(sheetname "")
		)
		(fill
			(thermal_gap 0.5)
			(thermal_bridge_width 0.5)
			(island_removal_mode 0)
		)
		(polygon
			(pts
				(xy 314.3758 -35.5346) (xy 314.3758 -34.4678) (xy 316.2046 -34.4678) (xy 316.2046 -35.5346)
			)
		)
	)
	(zone
		(layer "Cmts.User")
		(hatch none 0.5)
		(connect_pads
			(clearance 0)
		)
		(min_thickness 0.25)
		(keepout
			(tracks allowed)
			(vias allowed)
			(pads allowed)
			(copperpour allowed)
			(footprints allowed)
		)
		(placement
			(enabled no)
			(sheetname "")
		)
		(fill
			(thermal_gap 0.5)
			(thermal_bridge_width 0.5)
			(island_removal_mode 0)
		)
		(polygon
			(pts
				(xy 23.965662 -111.01832) (xy 25.007062 -111.01832) (xy 25.007062 -112.97412) (xy 23.965662 -112.97412)
			)
		)
	)
	(zone
		(layer "Cmts.User")
		(hatch none 0.5)
		(connect_pads
			(clearance 0)
		)
		(min_thickness 0.25)
		(keepout
			(tracks allowed)
			(vias allowed)
			(pads allowed)
			(copperpour allowed)
			(footprints allowed)
		)
		(placement
			(enabled no)
			(sheetname "")
		)
		(fill
			(thermal_gap 0.5)
			(thermal_bridge_width 0.5)
			(island_removal_mode 0)
		)
		(polygon
			(pts
				(xy 69.49313 -211.4042) (xy 69.49313 -210.3628) (xy 71.44893 -210.3628) (xy 71.44893 -211.4042)
			)
		)
	)
	(zone
		(layer "Cmts.User")
		(hatch none 0.5)
		(connect_pads
			(clearance 0)
		)
		(min_thickness 0.25)
		(keepout
			(tracks allowed)
			(vias allowed)
			(pads allowed)
			(copperpour allowed)
			(footprints allowed)
		)
		(placement
			(enabled no)
			(sheetname "")
		)
		(fill
			(thermal_gap 0.5)
			(thermal_bridge_width 0.5)
			(island_removal_mode 0)
		)
		(polygon
			(pts
				(xy 147.493228 -211.4042) (xy 147.493228 -210.3628) (xy 149.449028 -210.3628) (xy 149.449028 -211.4042)
			)
		)
	)
	(zone
		(layer "Cmts.User")
		(hatch none 0.5)
		(connect_pads
			(clearance 0)
		)
		(min_thickness 0.25)
		(keepout
			(tracks allowed)
			(vias allowed)
			(pads allowed)
			(copperpour allowed)
			(footprints allowed)
		)
		(placement
			(enabled no)
			(sheetname "")
		)
		(fill
			(thermal_gap 0.5)
			(thermal_bridge_width 0.5)
			(island_removal_mode 0)
		)
		(polygon
			(pts
				(xy 325.41591 -36.49091) (xy 325.41591 -35.44951) (xy 327.37171 -35.44951) (xy 327.37171 -36.49091)
			)
		)
	)
	(zone
		(layer "Cmts.User")
		(hatch none 0.5)
		(connect_pads
			(clearance 0)
		)
		(min_thickness 0.25)
		(keepout
			(tracks allowed)
			(vias allowed)
			(pads allowed)
			(copperpour allowed)
			(footprints allowed)
		)
		(placement
			(enabled no)
			(sheetname "")
		)
		(fill
			(thermal_gap 0.5)
			(thermal_bridge_width 0.5)
			(island_removal_mode 0)
		)
		(polygon
			(pts
				(xy 303.259744 -36.7919) (xy 303.259744 -35.7505) (xy 305.215544 -35.7505) (xy 305.215544 -36.7919)
			)
		)
	)
	(zone
		(layer "Cmts.User")
		(hatch none 0.5)
		(connect_pads
			(clearance 0)
		)
		(min_thickness 0.25)
		(keepout
			(tracks allowed)
			(vias allowed)
			(pads allowed)
			(copperpour allowed)
			(footprints allowed)
		)
		(placement
			(enabled no)
			(sheetname "")
		)
		(fill
			(thermal_gap 0.5)
			(thermal_bridge_width 0.5)
			(island_removal_mode 0)
		)
		(polygon
			(pts
				(xy 97.493328 -211.4042) (xy 97.493328 -210.3628) (xy 99.449128 -210.3628) (xy 99.449128 -211.4042)
			)
		)
	)
	(zone
		(layer "Cmts.User")
		(hatch none 0.5)
		(connect_pads
			(clearance 0)
		)
		(min_thickness 0.25)
		(keepout
			(tracks allowed)
			(vias allowed)
			(pads allowed)
			(copperpour allowed)
			(footprints allowed)
		)
		(placement
			(enabled no)
			(sheetname "")
		)
		(fill
			(thermal_gap 0.5)
			(thermal_bridge_width 0.5)
			(island_removal_mode 0)
		)
		(polygon
			(pts
				(xy 335.093056 -211.4042) (xy 335.093056 -210.3628) (xy 337.048856 -210.3628) (xy 337.048856 -211.4042)
			)
		)
	)
	(zone
		(layer "Cmts.User")
		(hatch none 0.5)
		(connect_pads
			(clearance 0)
		)
		(min_thickness 0.25)
		(keepout
			(tracks allowed)
			(vias allowed)
			(pads allowed)
			(copperpour allowed)
			(footprints allowed)
		)
		(placement
			(enabled no)
			(sheetname "")
		)
		(fill
			(thermal_gap 0.5)
			(thermal_bridge_width 0.5)
			(island_removal_mode 0)
		)
		(polygon
			(pts
				(xy 189.893194 -211.4042) (xy 189.893194 -210.3628) (xy 191.848994 -210.3628) (xy 191.848994 -211.4042)
			)
		)
	)
	(zone
		(layer "Cmts.User")
		(hatch none 0.5)
		(connect_pads
			(clearance 0)
		)
		(min_thickness 0.25)
		(keepout
			(tracks allowed)
			(vias allowed)
			(pads allowed)
			(copperpour allowed)
			(footprints allowed)
		)
		(placement
			(enabled no)
			(sheetname "")
		)
		(fill
			(thermal_gap 0.5)
			(thermal_bridge_width 0.5)
			(island_removal_mode 0)
		)
		(polygon
			(pts
				(xy 273.49323 -211.4042) (xy 273.49323 -210.3628) (xy 275.44903 -210.3628) (xy 275.44903 -211.4042)
			)
		)
	)
	(zone
		(layer "Cmts.User")
		(hatch none 0.5)
		(connect_pads
			(clearance 0)
		)
		(min_thickness 0.25)
		(keepout
			(tracks allowed)
			(vias allowed)
			(pads allowed)
			(copperpour allowed)
			(footprints allowed)
		)
		(placement
			(enabled no)
			(sheetname "")
		)
		(fill
			(thermal_gap 0.5)
			(thermal_bridge_width 0.5)
			(island_removal_mode 0)
		)
		(polygon
			(pts
				(xy 202.69327 -211.4042) (xy 202.69327 -210.3628) (xy 204.64907 -210.3628) (xy 204.64907 -211.4042)
			)
		)
	)
	(zone
		(layer "Cmts.User")
		(hatch none 0.5)
		(connect_pads
			(clearance 0)
		)
		(min_thickness 0.25)
		(keepout
			(tracks allowed)
			(vias allowed)
			(pads allowed)
			(copperpour allowed)
			(footprints allowed)
		)
		(placement
			(enabled no)
			(sheetname "")
		)
		(fill
			(thermal_gap 0.5)
			(thermal_bridge_width 0.5)
			(island_removal_mode 0)
		)
		(polygon
			(pts
				(xy 162.137344 -82.168746) (xy 162.137344 -81.127346) (xy 164.093144 -81.127346) (xy 164.093144 -82.168746)
			)
		)
	)
	(zone
		(layer "Cmts.User")
		(hatch none 0.5)
		(connect_pads
			(clearance 0)
		)
		(min_thickness 0.25)
		(keepout
			(tracks allowed)
			(vias allowed)
			(pads allowed)
			(copperpour allowed)
			(footprints allowed)
		)
		(placement
			(enabled no)
			(sheetname "")
		)
		(fill
			(thermal_gap 0.5)
			(thermal_bridge_width 0.5)
			(island_removal_mode 0)
		)
		(polygon
			(pts
				(xy 172.29328 -211.4042) (xy 172.29328 -210.3628) (xy 174.24908 -210.3628) (xy 174.24908 -211.4042)
			)
		)
	)
	(zone
		(layer "Cmts.User")
		(hatch none 0.5)
		(connect_pads
			(clearance 0)
		)
		(min_thickness 0.25)
		(keepout
			(tracks allowed)
			(vias allowed)
			(pads allowed)
			(copperpour allowed)
			(footprints allowed)
		)
		(placement
			(enabled no)
			(sheetname "")
		)
		(fill
			(thermal_gap 0.5)
			(thermal_bridge_width 0.5)
			(island_removal_mode 0)
		)
		(polygon
			(pts
				(xy 182.549546 -21.228304) (xy 182.549546 -19.297904) (xy 183.616346 -19.297904) (xy 183.616346 -21.228304)
			)
		)
	)
	(zone
		(layer "Cmts.User")
		(hatch none 0.5)
		(connect_pads
			(clearance 0)
		)
		(min_thickness 0.25)
		(keepout
			(tracks allowed)
			(vias allowed)
			(pads allowed)
			(copperpour allowed)
			(footprints allowed)
		)
		(placement
			(enabled no)
			(sheetname "")
		)
		(fill
			(thermal_gap 0.5)
			(thermal_bridge_width 0.5)
			(island_removal_mode 0)
		)
		(polygon
			(pts
				(xy 193.09334 -211.4042) (xy 193.09334 -210.3628) (xy 195.04914 -210.3628) (xy 195.04914 -211.4042)
			)
		)
	)
	(zone
		(layer "Cmts.User")
		(hatch none 0.5)
		(connect_pads
			(clearance 0)
		)
		(min_thickness 0.25)
		(keepout
			(tracks allowed)
			(vias allowed)
			(pads allowed)
			(copperpour allowed)
			(footprints allowed)
		)
		(placement
			(enabled no)
			(sheetname "")
		)
		(fill
			(thermal_gap 0.5)
			(thermal_bridge_width 0.5)
			(island_removal_mode 0)
		)
		(polygon
			(pts
				(xy 86.261702 -76.028296) (xy 87.303102 -76.028296) (xy 87.303102 -77.984096) (xy 86.261702 -77.984096)
			)
		)
	)
	(zone
		(layer "Cmts.User")
		(hatch none 0.5)
		(connect_pads
			(clearance 0)
		)
		(min_thickness 0.25)
		(keepout
			(tracks allowed)
			(vias allowed)
			(pads allowed)
			(copperpour allowed)
			(footprints allowed)
		)
		(placement
			(enabled no)
			(sheetname "")
		)
		(fill
			(thermal_gap 0.5)
			(thermal_bridge_width 0.5)
			(island_removal_mode 0)
		)
		(polygon
			(pts
				(xy 267.093446 -211.4042) (xy 267.093446 -210.3628) (xy 269.049246 -210.3628) (xy 269.049246 -211.4042)
			)
		)
	)
	(zone
		(layer "Cmts.User")
		(hatch none 0.5)
		(connect_pads
			(clearance 0)
		)
		(min_thickness 0.25)
		(keepout
			(tracks allowed)
			(vias allowed)
			(pads allowed)
			(copperpour allowed)
			(footprints allowed)
		)
		(placement
			(enabled no)
			(sheetname "")
		)
		(fill
			(thermal_gap 0.5)
			(thermal_bridge_width 0.5)
			(island_removal_mode 0)
		)
		(polygon
			(pts
				(xy 144.293336 -211.4042) (xy 144.293336 -210.3628) (xy 146.249136 -210.3628) (xy 146.249136 -211.4042)
			)
		)
	)
	(zone
		(layer "Cmts.User")
		(hatch none 0.5)
		(connect_pads
			(clearance 0)
		)
		(min_thickness 0.25)
		(keepout
			(tracks allowed)
			(vias allowed)
			(pads allowed)
			(copperpour allowed)
			(footprints allowed)
		)
		(placement
			(enabled no)
			(sheetname "")
		)
		(fill
			(thermal_gap 0.5)
			(thermal_bridge_width 0.5)
			(island_removal_mode 0)
		)
		(polygon
			(pts
				(xy 143.18615 -26.503884) (xy 143.18615 -11.625834) (xy 150.398734 -11.625834) (xy 150.398734 -26.503884)
			)
		)
	)
	(zone
		(layer "Cmts.User")
		(hatch none 0.5)
		(connect_pads
			(clearance 0)
		)
		(min_thickness 0.25)
		(keepout
			(tracks allowed)
			(vias allowed)
			(pads allowed)
			(copperpour allowed)
			(footprints allowed)
		)
		(placement
			(enabled no)
			(sheetname "")
		)
		(fill
			(thermal_gap 0.5)
			(thermal_bridge_width 0.5)
			(island_removal_mode 0)
		)
		(polygon
			(pts
				(xy 269.018766 -6.679438) (xy 269.018766 -4.749038) (xy 270.085566 -4.749038) (xy 270.085566 -6.679438)
			)
		)
	)
	(zone
		(layer "Cmts.User")
		(hatch none 0.5)
		(connect_pads
			(clearance 0)
		)
		(min_thickness 0.25)
		(keepout
			(tracks allowed)
			(vias allowed)
			(pads allowed)
			(copperpour allowed)
			(footprints allowed)
		)
		(placement
			(enabled no)
			(sheetname "")
		)
		(fill
			(thermal_gap 0.5)
			(thermal_bridge_width 0.5)
			(island_removal_mode 0)
		)
		(polygon
			(pts
				(xy 322.293234 -211.4042) (xy 322.293234 -210.3628) (xy 324.249034 -210.3628) (xy 324.249034 -211.4042)
			)
		)
	)
	(zone
		(layer "Cmts.User")
		(hatch none 0.5)
		(connect_pads
			(clearance 0)
		)
		(min_thickness 0.25)
		(keepout
			(tracks allowed)
			(vias allowed)
			(pads allowed)
			(copperpour allowed)
			(footprints allowed)
		)
		(placement
			(enabled no)
			(sheetname "")
		)
		(fill
			(thermal_gap 0.5)
			(thermal_bridge_width 0.5)
			(island_removal_mode 0)
		)
		(polygon
			(pts
				(xy 20.244054 -57.752488) (xy 20.244054 -58.793888) (xy 18.288254 -58.793888) (xy 18.288254 -57.752488)
			)
		)
	)
	(zone
		(layer "Cmts.User")
		(hatch none 0.5)
		(connect_pads
			(clearance 0)
		)
		(min_thickness 0.25)
		(keepout
			(tracks allowed)
			(vias allowed)
			(pads allowed)
			(copperpour allowed)
			(footprints allowed)
		)
		(placement
			(enabled no)
			(sheetname "")
		)
		(fill
			(thermal_gap 0.5)
			(thermal_bridge_width 0.5)
			(island_removal_mode 0)
		)
		(polygon
			(pts
				(xy 284.4546 -34.3916) (xy 284.4546 -32.4612) (xy 285.5214 -32.4612) (xy 285.5214 -34.3916)
			)
		)
	)
	(zone
		(layer "Cmts.User")
		(hatch none 0.5)
		(connect_pads
			(clearance 0)
		)
		(min_thickness 0.25)
		(keepout
			(tracks allowed)
			(vias allowed)
			(pads allowed)
			(copperpour allowed)
			(footprints allowed)
		)
		(placement
			(enabled no)
			(sheetname "")
		)
		(fill
			(thermal_gap 0.5)
			(thermal_bridge_width 0.5)
			(island_removal_mode 0)
		)
		(polygon
			(pts
				(xy 293.584884 -35.707828) (xy 293.584884 -34.666428) (xy 295.540684 -34.666428) (xy 295.540684 -35.707828)
			)
		)
	)
	(zone
		(layer "Cmts.User")
		(hatch none 0.5)
		(connect_pads
			(clearance 0)
		)
		(min_thickness 0.25)
		(keepout
			(tracks allowed)
			(vias allowed)
			(pads allowed)
			(copperpour allowed)
			(footprints allowed)
		)
		(placement
			(enabled no)
			(sheetname "")
		)
		(fill
			(thermal_gap 0.5)
			(thermal_bridge_width 0.5)
			(island_removal_mode 0)
		)
		(polygon
			(pts
				(xy 147.938744 -35.508946) (xy 147.938744 -34.467546) (xy 149.894544 -34.467546) (xy 149.894544 -35.508946)
			)
		)
	)
	(zone
		(layer "Cmts.User")
		(hatch none 0.5)
		(connect_pads
			(clearance 0)
		)
		(min_thickness 0.25)
		(keepout
			(tracks allowed)
			(vias allowed)
			(pads allowed)
			(copperpour allowed)
			(footprints allowed)
		)
		(placement
			(enabled no)
			(sheetname "")
		)
		(fill
			(thermal_gap 0.5)
			(thermal_bridge_width 0.5)
			(island_removal_mode 0)
		)
		(polygon
			(pts
				(xy 49.544224 -209.2198) (xy 49.544224 -208.1784) (xy 51.500024 -208.1784) (xy 51.500024 -209.2198)
			)
		)
	)
	(zone
		(layer "Cmts.User")
		(hatch none 0.5)
		(connect_pads
			(clearance 0)
		)
		(min_thickness 0.25)
		(keepout
			(tracks allowed)
			(vias allowed)
			(pads allowed)
			(copperpour allowed)
			(footprints allowed)
		)
		(placement
			(enabled no)
			(sheetname "")
		)
		(fill
			(thermal_gap 0.5)
			(thermal_bridge_width 0.5)
			(island_removal_mode 0)
		)
		(polygon
			(pts
				(xy 202.383644 -50.291746) (xy 202.383644 -49.250346) (xy 204.339444 -49.250346) (xy 204.339444 -50.291746)
			)
		)
	)
	(zone
		(layer "Cmts.User")
		(hatch none 0.5)
		(connect_pads
			(clearance 0)
		)
		(min_thickness 0.25)
		(keepout
			(tracks allowed)
			(vias allowed)
			(pads allowed)
			(copperpour allowed)
			(footprints allowed)
		)
		(placement
			(enabled no)
			(sheetname "")
		)
		(fill
			(thermal_gap 0.5)
			(thermal_bridge_width 0.5)
			(island_removal_mode 0)
		)
		(polygon
			(pts
				(xy 267.944346 -15.183104) (xy 267.944346 -13.252704) (xy 269.011146 -13.252704) (xy 269.011146 -15.183104)
			)
		)
	)
	(zone
		(layer "Cmts.User")
		(hatch none 0.5)
		(connect_pads
			(clearance 0)
		)
		(min_thickness 0.25)
		(keepout
			(tracks allowed)
			(vias allowed)
			(pads allowed)
			(copperpour allowed)
			(footprints allowed)
		)
		(placement
			(enabled no)
			(sheetname "")
		)
		(fill
			(thermal_gap 0.5)
			(thermal_bridge_width 0.5)
			(island_removal_mode 0)
		)
		(polygon
			(pts
				(xy 305.180492 -40.327834) (xy 305.180492 -39.286434) (xy 307.136292 -39.286434) (xy 307.136292 -40.327834)
			)
		)
	)
	(zone
		(layer "Cmts.User")
		(hatch none 0.5)
		(connect_pads
			(clearance 0)
		)
		(min_thickness 0.25)
		(keepout
			(tracks allowed)
			(vias allowed)
			(pads allowed)
			(copperpour allowed)
			(footprints allowed)
		)
		(placement
			(enabled no)
			(sheetname "")
		)
		(fill
			(thermal_gap 0.5)
			(thermal_bridge_width 0.5)
			(island_removal_mode 0)
		)
		(polygon
			(pts
				(xy 91.201748 -185.270648) (xy 91.938094 -184.534048) (xy 93.321124 -185.917078) (xy 92.584778 -186.653424)
			)
		)
	)
	(zone
		(layer "Cmts.User")
		(hatch none 0.5)
		(connect_pads
			(clearance 0)
		)
		(min_thickness 0.25)
		(keepout
			(tracks allowed)
			(vias allowed)
			(pads allowed)
			(copperpour allowed)
			(footprints allowed)
		)
		(placement
			(enabled no)
			(sheetname "")
		)
		(fill
			(thermal_gap 0.5)
			(thermal_bridge_width 0.5)
			(island_removal_mode 0)
		)
		(polygon
			(pts
				(xy 27.36723 -106.010964) (xy 28.103576 -105.274618) (xy 29.486606 -106.657394) (xy 28.750006 -107.393994)
			)
		)
	)
	(zone
		(layer "Cmts.User")
		(hatch none 0.5)
		(connect_pads
			(clearance 0)
		)
		(min_thickness 0.25)
		(keepout
			(tracks allowed)
			(vias allowed)
			(pads allowed)
			(copperpour allowed)
			(footprints allowed)
		)
		(placement
			(enabled no)
			(sheetname "")
		)
		(fill
			(thermal_gap 0.5)
			(thermal_bridge_width 0.5)
			(island_removal_mode 0)
		)
		(polygon
			(pts
				(xy 303.170844 -220.776546) (xy 303.170844 -219.735146) (xy 305.126644 -219.735146) (xy 305.126644 -220.776546)
			)
		)
	)
	(zone
		(layer "Cmts.User")
		(hatch none 0.5)
		(connect_pads
			(clearance 0)
		)
		(min_thickness 0.25)
		(keepout
			(tracks allowed)
			(vias allowed)
			(pads allowed)
			(copperpour allowed)
			(footprints allowed)
		)
		(placement
			(enabled no)
			(sheetname "")
		)
		(fill
			(thermal_gap 0.5)
			(thermal_bridge_width 0.5)
			(island_removal_mode 0)
		)
		(polygon
			(pts
				(xy 199.493124 -211.4042) (xy 199.493124 -210.3628) (xy 201.448924 -210.3628) (xy 201.448924 -211.4042)
			)
		)
	)
	(zone
		(layer "Cmts.User")
		(hatch none 0.5)
		(connect_pads
			(clearance 0)
		)
		(min_thickness 0.25)
		(keepout
			(tracks allowed)
			(vias allowed)
			(pads allowed)
			(copperpour allowed)
			(footprints allowed)
		)
		(placement
			(enabled no)
			(sheetname "")
		)
		(fill
			(thermal_gap 0.5)
			(thermal_bridge_width 0.5)
			(island_removal_mode 0)
		)
		(polygon
			(pts
				(xy 100.718366 -211.4042) (xy 100.718366 -210.3628) (xy 102.674166 -210.3628) (xy 102.674166 -211.4042)
			)
		)
	)
	(zone
		(layer "Cmts.User")
		(hatch none 0.5)
		(connect_pads
			(clearance 0)
		)
		(min_thickness 0.25)
		(keepout
			(tracks allowed)
			(vias allowed)
			(pads allowed)
			(copperpour allowed)
			(footprints allowed)
		)
		(placement
			(enabled no)
			(sheetname "")
		)
		(fill
			(thermal_gap 0.5)
			(thermal_bridge_width 0.5)
			(island_removal_mode 0)
		)
		(polygon
			(pts
				(xy 19.295618 -77.553312) (xy 19.295618 -78.594712) (xy 17.339818 -78.594712) (xy 17.339818 -77.553312)
			)
		)
	)
	(zone
		(layer "Cmts.User")
		(hatch none 0.5)
		(connect_pads
			(clearance 0)
		)
		(min_thickness 0.25)
		(keepout
			(tracks allowed)
			(vias allowed)
			(pads allowed)
			(copperpour allowed)
			(footprints allowed)
		)
		(placement
			(enabled no)
			(sheetname "")
		)
		(fill
			(thermal_gap 0.5)
			(thermal_bridge_width 0.5)
			(island_removal_mode 0)
		)
		(polygon
			(pts
				(xy 184.046114 -11.172444) (xy 185.087514 -11.172444) (xy 185.087514 -13.128244) (xy 184.046114 -13.128244)
			)
		)
	)
	(zone
		(layer "Cmts.User")
		(hatch none 0.5)
		(connect_pads
			(clearance 0)
		)
		(min_thickness 0.25)
		(keepout
			(tracks allowed)
			(vias allowed)
			(pads allowed)
			(copperpour allowed)
			(footprints allowed)
		)
		(placement
			(enabled no)
			(sheetname "")
		)
		(fill
			(thermal_gap 0.5)
			(thermal_bridge_width 0.5)
			(island_removal_mode 0)
		)
		(polygon
			(pts
				(xy 169.093134 -211.4042) (xy 169.093134 -210.3628) (xy 171.048934 -210.3628) (xy 171.048934 -211.4042)
			)
		)
	)
	(zone
		(layer "Cmts.User")
		(hatch none 0.5)
		(connect_pads
			(clearance 0)
		)
		(min_thickness 0.25)
		(keepout
			(tracks allowed)
			(vias allowed)
			(pads allowed)
			(copperpour allowed)
			(footprints allowed)
		)
		(placement
			(enabled no)
			(sheetname "")
		)
		(fill
			(thermal_gap 0.5)
			(thermal_bridge_width 0.5)
			(island_removal_mode 0)
		)
		(polygon
			(pts
				(xy 175.493172 -211.4042) (xy 175.493172 -210.3628) (xy 177.448972 -210.3628) (xy 177.448972 -211.4042)
			)
		)
	)
	(zone
		(layer "Cmts.User")
		(hatch none 0.5)
		(connect_pads
			(clearance 0)
		)
		(min_thickness 0.25)
		(keepout
			(tracks allowed)
			(vias allowed)
			(pads allowed)
			(copperpour allowed)
			(footprints allowed)
		)
		(placement
			(enabled no)
			(sheetname "")
		)
		(fill
			(thermal_gap 0.5)
			(thermal_bridge_width 0.5)
			(island_removal_mode 0)
		)
		(polygon
			(pts
				(xy 296.186098 -26.503884) (xy 296.186098 -11.625834) (xy 303.398682 -11.625834) (xy 303.398682 -26.503884)
			)
		)
	)
	(zone
		(layer "Cmts.User")
		(hatch none 0.5)
		(connect_pads
			(clearance 0)
		)
		(min_thickness 0.25)
		(keepout
			(tracks allowed)
			(vias allowed)
			(pads allowed)
			(copperpour allowed)
			(footprints allowed)
		)
		(placement
			(enabled no)
			(sheetname "")
		)
		(fill
			(thermal_gap 0.5)
			(thermal_bridge_width 0.5)
			(island_removal_mode 0)
		)
		(polygon
			(pts
				(xy 182.549546 -27.324304) (xy 182.549546 -25.393904) (xy 183.616346 -25.393904) (xy 183.616346 -27.324304)
			)
		)
	)
	(zone
		(layer "Cmts.User")
		(hatch none 0.5)
		(connect_pads
			(clearance 0)
		)
		(min_thickness 0.25)
		(keepout
			(tracks allowed)
			(vias allowed)
			(pads allowed)
			(copperpour allowed)
			(footprints allowed)
		)
		(placement
			(enabled no)
			(sheetname "")
		)
		(fill
			(thermal_gap 0.5)
			(thermal_bridge_width 0.5)
			(island_removal_mode 0)
		)
		(polygon
			(pts
				(xy 66.293238 -211.4042) (xy 66.293238 -210.3628) (xy 68.249038 -210.3628) (xy 68.249038 -211.4042)
			)
		)
	)
	(zone
		(layer "Cmts.User")
		(hatch none 0.5)
		(connect_pads
			(clearance 0)
		)
		(min_thickness 0.25)
		(keepout
			(tracks allowed)
			(vias allowed)
			(pads allowed)
			(copperpour allowed)
			(footprints allowed)
		)
		(placement
			(enabled no)
			(sheetname "")
		)
		(fill
			(thermal_gap 0.5)
			(thermal_bridge_width 0.5)
			(island_removal_mode 0)
		)
		(polygon
			(pts
				(xy 107.093258 -211.4042) (xy 107.093258 -210.3628) (xy 109.049058 -210.3628) (xy 109.049058 -211.4042)
			)
		)
	)
	(zone
		(layer "Cmts.User")
		(hatch none 0.5)
		(connect_pads
			(clearance 0)
		)
		(min_thickness 0.25)
		(keepout
			(tracks allowed)
			(vias allowed)
			(pads allowed)
			(copperpour allowed)
			(footprints allowed)
		)
		(placement
			(enabled no)
			(sheetname "")
		)
		(fill
			(thermal_gap 0.5)
			(thermal_bridge_width 0.5)
			(island_removal_mode 0)
		)
		(polygon
			(pts
				(xy 21.749004 -78.232762) (xy 21.749004 -79.274162) (xy 19.793204 -79.274162) (xy 19.793204 -78.232762)
			)
		)
	)
	(zone
		(layer "Cmts.User")
		(hatch none 0.5)
		(connect_pads
			(clearance 0)
		)
		(min_thickness 0.25)
		(keepout
			(tracks allowed)
			(vias allowed)
			(pads allowed)
			(copperpour allowed)
			(footprints allowed)
		)
		(placement
			(enabled no)
			(sheetname "")
		)
		(fill
			(thermal_gap 0.5)
			(thermal_bridge_width 0.5)
			(island_removal_mode 0)
		)
		(polygon
			(pts
				(xy 298.881038 -36.697158) (xy 298.881038 -35.655758) (xy 300.836838 -35.655758) (xy 300.836838 -36.697158)
			)
		)
	)
	(zone
		(layer "Cmts.User")
		(hatch none 0.5)
		(connect_pads
			(clearance 0)
		)
		(min_thickness 0.25)
		(keepout
			(tracks allowed)
			(vias allowed)
			(pads allowed)
			(copperpour allowed)
			(footprints allowed)
		)
		(placement
			(enabled no)
			(sheetname "")
		)
		(fill
			(thermal_gap 0.5)
			(thermal_bridge_width 0.5)
			(island_removal_mode 0)
		)
		(polygon
			(pts
				(xy 276.693376 -211.4042) (xy 276.693376 -210.3628) (xy 278.649176 -210.3628) (xy 278.649176 -211.4042)
			)
		)
	)
	(zone
		(layer "Cmts.User")
		(hatch none 0.5)
		(connect_pads
			(clearance 0)
		)
		(min_thickness 0.25)
		(keepout
			(tracks allowed)
			(vias allowed)
			(pads allowed)
			(copperpour allowed)
			(footprints allowed)
		)
		(placement
			(enabled no)
			(sheetname "")
		)
		(fill
			(thermal_gap 0.5)
			(thermal_bridge_width 0.5)
			(island_removal_mode 0)
		)
		(polygon
			(pts
				(xy 270.103346 -9.727438) (xy 270.103346 -7.797038) (xy 271.170146 -7.797038) (xy 271.170146 -9.727438)
			)
		)
	)
	(zone
		(layer "Cmts.User")
		(hatch none 0.5)
		(connect_pads
			(clearance 0)
		)
		(min_thickness 0.25)
		(keepout
			(tracks allowed)
			(vias allowed)
			(pads allowed)
			(copperpour allowed)
			(footprints allowed)
		)
		(placement
			(enabled no)
			(sheetname "")
		)
		(fill
			(thermal_gap 0.5)
			(thermal_bridge_width 0.5)
			(island_removal_mode 0)
		)
		(polygon
			(pts
				(xy 17.195038 -72.738742) (xy 17.195038 -73.780142) (xy 15.239238 -73.780142) (xy 15.239238 -72.738742)
			)
		)
	)
	(zone
		(layer "Cmts.User")
		(hatch none 0.5)
		(connect_pads
			(clearance 0)
		)
		(min_thickness 0.25)
		(keepout
			(tracks allowed)
			(vias allowed)
			(pads allowed)
			(copperpour allowed)
			(footprints allowed)
		)
		(placement
			(enabled no)
			(sheetname "")
		)
		(fill
			(thermal_gap 0.5)
			(thermal_bridge_width 0.5)
			(island_removal_mode 0)
		)
		(polygon
			(pts
				(xy 185.51017 -26.371042) (xy 185.51017 -24.440642) (xy 186.57697 -24.440642) (xy 186.57697 -26.371042)
			)
		)
	)
	(zone
		(layer "Cmts.User")
		(hatch none 0.5)
		(connect_pads
			(clearance 0)
		)
		(min_thickness 0.25)
		(keepout
			(tracks allowed)
			(vias allowed)
			(pads allowed)
			(copperpour allowed)
			(footprints allowed)
		)
		(placement
			(enabled no)
			(sheetname "")
		)
		(fill
			(thermal_gap 0.5)
			(thermal_bridge_width 0.5)
			(island_removal_mode 0)
		)
		(polygon
			(pts
				(xy 154.186128 -26.503884) (xy 154.186128 -11.625834) (xy 161.398712 -11.625834) (xy 161.398712 -26.503884)
			)
		)
	)
	(zone
		(layer "Cmts.User")
		(hatch none 0.5)
		(connect_pads
			(clearance 0)
		)
		(min_thickness 0.25)
		(keepout
			(tracks allowed)
			(vias allowed)
			(pads allowed)
			(copperpour allowed)
			(footprints allowed)
		)
		(placement
			(enabled no)
			(sheetname "")
		)
		(fill
			(thermal_gap 0.5)
			(thermal_bridge_width 0.5)
			(island_removal_mode 0)
		)
		(polygon
			(pts
				(xy 307.186076 -26.503884) (xy 307.186076 -11.625834) (xy 314.39866 -11.625834) (xy 314.39866 -26.503884)
			)
		)
	)
	(zone
		(layer "Cmts.User")
		(hatch none 0.5)
		(connect_pads
			(clearance 0)
		)
		(min_thickness 0.25)
		(keepout
			(tracks allowed)
			(vias allowed)
			(pads allowed)
			(copperpour allowed)
			(footprints allowed)
		)
		(placement
			(enabled no)
			(sheetname "")
		)
		(fill
			(thermal_gap 0.5)
			(thermal_bridge_width 0.5)
			(island_removal_mode 0)
		)
		(polygon
			(pts
				(xy 22.58568 -113.605056) (xy 23.62708 -113.605056) (xy 23.62708 -115.560856) (xy 22.58568 -115.560856)
			)
		)
	)
	(zone
		(layer "Cmts.User")
		(hatch none 0.5)
		(connect_pads
			(clearance 0)
		)
		(min_thickness 0.25)
		(keepout
			(tracks allowed)
			(vias allowed)
			(pads allowed)
			(copperpour allowed)
			(footprints allowed)
		)
		(placement
			(enabled no)
			(sheetname "")
		)
		(fill
			(thermal_gap 0.5)
			(thermal_bridge_width 0.5)
			(island_removal_mode 0)
		)
		(polygon
			(pts
				(xy 64.807084 -127.131318) (xy 66.737484 -127.131318) (xy 66.737484 -128.198118) (xy 64.807084 -128.198118)
			)
		)
	)
	(zone
		(layer "Cmts.User")
		(hatch none 0.5)
		(connect_pads
			(clearance 0)
		)
		(min_thickness 0.25)
		(keepout
			(tracks allowed)
			(vias allowed)
			(pads allowed)
			(copperpour allowed)
			(footprints allowed)
		)
		(placement
			(enabled no)
			(sheetname "")
		)
		(fill
			(thermal_gap 0.5)
			(thermal_bridge_width 0.5)
			(island_removal_mode 0)
		)
		(polygon
			(pts
				(xy 279.704546 -19.323304) (xy 279.704546 -17.392904) (xy 280.771346 -17.392904) (xy 280.771346 -19.323304)
			)
		)
	)
	(zone
		(layer "Cmts.User")
		(hatch none 0.5)
		(connect_pads
			(clearance 0)
		)
		(min_thickness 0.25)
		(keepout
			(tracks allowed)
			(vias allowed)
			(pads allowed)
			(copperpour allowed)
			(footprints allowed)
		)
		(placement
			(enabled no)
			(sheetname "")
		)
		(fill
			(thermal_gap 0.5)
			(thermal_bridge_width 0.5)
			(island_removal_mode 0)
		)
		(polygon
			(pts
				(xy 157.093412 -211.4042) (xy 157.093412 -210.3628) (xy 159.049212 -210.3628) (xy 159.049212 -211.4042)
			)
		)
	)
	(zone
		(layer "Cmts.User")
		(hatch none 0.5)
		(connect_pads
			(clearance 0)
		)
		(min_thickness 0.25)
		(keepout
			(tracks allowed)
			(vias allowed)
			(pads allowed)
			(copperpour allowed)
			(footprints allowed)
		)
		(placement
			(enabled no)
			(sheetname "")
		)
		(fill
			(thermal_gap 0.5)
			(thermal_bridge_width 0.5)
			(island_removal_mode 0)
		)
		(polygon
			(pts
				(xy 318.186054 -26.503884) (xy 318.186054 -11.625834) (xy 325.398638 -11.625834) (xy 325.398638 -26.503884)
			)
		)
	)
	(zone
		(layer "Cmts.User")
		(hatch none 0.5)
		(connect_pads
			(clearance 0)
		)
		(min_thickness 0.25)
		(keepout
			(tracks allowed)
			(vias allowed)
			(pads allowed)
			(copperpour allowed)
			(footprints allowed)
		)
		(placement
			(enabled no)
			(sheetname "")
		)
		(fill
			(thermal_gap 0.5)
			(thermal_bridge_width 0.5)
			(island_removal_mode 0)
		)
		(polygon
			(pts
				(xy 150.349204 -38.604698) (xy 150.349204 -37.563298) (xy 152.305004 -37.563298) (xy 152.305004 -38.604698)
			)
		)
	)
	(zone
		(layer "Cmts.User")
		(hatch none 0.5)
		(connect_pads
			(clearance 0)
		)
		(min_thickness 0.25)
		(keepout
			(tracks allowed)
			(vias allowed)
			(pads allowed)
			(copperpour allowed)
			(footprints allowed)
		)
		(placement
			(enabled no)
			(sheetname "")
		)
		(fill
			(thermal_gap 0.5)
			(thermal_bridge_width 0.5)
			(island_removal_mode 0)
		)
		(polygon
			(pts
				(xy 53.788818 -48.389032) (xy 51.858418 -48.389032) (xy 51.858418 -47.322232) (xy 53.788818 -47.322232)
			)
		)
	)
	(zone
		(layer "Cmts.User")
		(hatch none 0.5)
		(connect_pads
			(clearance 0)
		)
		(min_thickness 0.25)
		(keepout
			(tracks allowed)
			(vias allowed)
			(pads allowed)
			(copperpour allowed)
			(footprints allowed)
		)
		(placement
			(enabled no)
			(sheetname "")
		)
		(fill
			(thermal_gap 0.5)
			(thermal_bridge_width 0.5)
			(island_removal_mode 0)
		)
		(polygon
			(pts
				(xy 63.093092 -211.4042) (xy 63.093092 -210.3628) (xy 65.048892 -210.3628) (xy 65.048892 -211.4042)
			)
		)
	)
	(zone
		(layer "Cmts.User")
		(hatch none 0.5)
		(connect_pads
			(clearance 0)
		)
		(min_thickness 0.25)
		(keepout
			(tracks allowed)
			(vias allowed)
			(pads allowed)
			(copperpour allowed)
			(footprints allowed)
		)
		(placement
			(enabled no)
			(sheetname "")
		)
		(fill
			(thermal_gap 0.5)
			(thermal_bridge_width 0.5)
			(island_removal_mode 0)
		)
		(polygon
			(pts
				(xy 23.987506 -53.0352) (xy 23.987506 -54.0766) (xy 22.031706 -54.0766) (xy 22.031706 -53.0352)
			)
		)
	)
	(zone
		(layer "Cmts.User")
		(hatch none 0.5)
		(connect_pads
			(clearance 0)
		)
		(min_thickness 0.25)
		(keepout
			(tracks allowed)
			(vias allowed)
			(pads allowed)
			(copperpour allowed)
			(footprints allowed)
		)
		(placement
			(enabled no)
			(sheetname "")
		)
		(fill
			(thermal_gap 0.5)
			(thermal_bridge_width 0.5)
			(island_removal_mode 0)
		)
		(polygon
			(pts
				(xy 312.12663 -36.718748) (xy 312.12663 -35.677348) (xy 314.08243 -35.677348) (xy 314.08243 -36.718748)
			)
		)
	)
	(zone
		(layer "Cmts.User")
		(hatch none 0.5)
		(connect_pads
			(clearance 0)
		)
		(min_thickness 0.25)
		(keepout
			(tracks allowed)
			(vias allowed)
			(pads allowed)
			(copperpour allowed)
			(footprints allowed)
		)
		(placement
			(enabled no)
			(sheetname "")
		)
		(fill
			(thermal_gap 0.5)
			(thermal_bridge_width 0.5)
			(island_removal_mode 0)
		)
		(polygon
			(pts
				(xy 86.613746 -107.918504) (xy 86.613746 -105.988104) (xy 87.680546 -105.988104) (xy 87.680546 -107.918504)
			)
		)
	)
	(zone
		(layer "Cmts.User")
		(hatch none 0.5)
		(connect_pads
			(clearance 0)
		)
		(min_thickness 0.25)
		(keepout
			(tracks allowed)
			(vias allowed)
			(pads allowed)
			(copperpour allowed)
			(footprints allowed)
		)
		(placement
			(enabled no)
			(sheetname "")
		)
		(fill
			(thermal_gap 0.5)
			(thermal_bridge_width 0.5)
			(island_removal_mode 0)
		)
		(polygon
			(pts
				(xy 19.86534 -72.655938) (xy 19.86534 -73.697338) (xy 17.90954 -73.697338) (xy 17.90954 -72.655938)
			)
		)
	)
	(zone
		(layer "Cmts.User")
		(hatch none 0.5)
		(connect_pads
			(clearance 0)
		)
		(min_thickness 0.25)
		(keepout
			(tracks allowed)
			(vias allowed)
			(pads allowed)
			(copperpour allowed)
			(footprints allowed)
		)
		(placement
			(enabled no)
			(sheetname "")
		)
		(fill
			(thermal_gap 0.5)
			(thermal_bridge_width 0.5)
			(island_removal_mode 0)
		)
		(polygon
			(pts
				(xy 51.093116 -211.4042) (xy 51.093116 -210.3628) (xy 53.048916 -210.3628) (xy 53.048916 -211.4042)
			)
		)
	)
	(zone
		(layer "Cmts.User")
		(hatch none 0.5)
		(connect_pads
			(clearance 0)
		)
		(min_thickness 0.25)
		(keepout
			(tracks allowed)
			(vias allowed)
			(pads allowed)
			(copperpour allowed)
			(footprints allowed)
		)
		(placement
			(enabled no)
			(sheetname "")
		)
		(fill
			(thermal_gap 0.5)
			(thermal_bridge_width 0.5)
			(island_removal_mode 0)
		)
		(polygon
			(pts
				(xy 289.493198 -211.4042) (xy 289.493198 -210.3628) (xy 291.448998 -210.3628) (xy 291.448998 -211.4042)
			)
		)
	)
	(zone
		(layer "Cmts.User")
		(hatch none 0.5)
		(connect_pads
			(clearance 0)
		)
		(min_thickness 0.25)
		(keepout
			(tracks allowed)
			(vias allowed)
			(pads allowed)
			(copperpour allowed)
			(footprints allowed)
		)
		(placement
			(enabled no)
			(sheetname "")
		)
		(fill
			(thermal_gap 0.5)
			(thermal_bridge_width 0.5)
			(island_removal_mode 0)
		)
		(polygon
			(pts
				(xy 212.2932 -211.4042) (xy 212.2932 -210.3628) (xy 214.249 -210.3628) (xy 214.249 -211.4042)
			)
		)
	)
	(zone
		(layer "Cmts.User")
		(hatch none 0.5)
		(connect_pads
			(clearance 0)
		)
		(min_thickness 0.25)
		(keepout
			(tracks allowed)
			(vias allowed)
			(pads allowed)
			(copperpour allowed)
			(footprints allowed)
		)
		(placement
			(enabled no)
			(sheetname "")
		)
		(fill
			(thermal_gap 0.5)
			(thermal_bridge_width 0.5)
			(island_removal_mode 0)
		)
		(polygon
			(pts
				(xy 101.98481 -35.66541) (xy 103.02621 -35.66541) (xy 103.02621 -37.62121) (xy 101.98481 -37.62121)
			)
		)
	)
	(zone
		(layer "Cmts.User")
		(hatch none 0.5)
		(connect_pads
			(clearance 0)
		)
		(min_thickness 0.25)
		(keepout
			(tracks allowed)
			(vias allowed)
			(pads allowed)
			(copperpour allowed)
			(footprints allowed)
		)
		(placement
			(enabled no)
			(sheetname "")
		)
		(fill
			(thermal_gap 0.5)
			(thermal_bridge_width 0.5)
			(island_removal_mode 0)
		)
		(polygon
			(pts
				(xy 338.293202 -211.4042) (xy 338.293202 -210.3628) (xy 340.249002 -210.3628) (xy 340.249002 -211.4042)
			)
		)
	)
	(zone
		(layer "Cmts.User")
		(hatch none 0.5)
		(connect_pads
			(clearance 0)
		)
		(min_thickness 0.25)
		(keepout
			(tracks allowed)
			(vias allowed)
			(pads allowed)
			(copperpour allowed)
			(footprints allowed)
		)
		(placement
			(enabled no)
			(sheetname "")
		)
		(fill
			(thermal_gap 0.5)
			(thermal_bridge_width 0.5)
			(island_removal_mode 0)
		)
		(polygon
			(pts
				(xy 177.034444 -221.182946) (xy 177.034444 -220.141546) (xy 178.990244 -220.141546) (xy 178.990244 -221.182946)
			)
		)
	)
)
